(kicad_pcb
	(version 20260206)
	(generator "pcbnew")
	(generator_version "10.0")
	(general
		(thickness 1.6)
		(legacy_teardrops no)
	)
	(paper "A4")
	(layers
		(0 "F.Cu" signal "TOP")
		(4 "In1.Cu" signal "GND")
		(6 "In2.Cu" signal "IN1")
		(8 "In3.Cu" signal "GND1")
		(10 "In4.Cu" signal "IN2")
		(12 "In5.Cu" signal "GND2")
		(14 "In6.Cu" signal "IN3")
		(16 "In7.Cu" signal "GND3")
		(18 "In8.Cu" signal "VCC")
		(20 "In9.Cu" signal "VCC1")
		(22 "In10.Cu" signal "GND4")
		(24 "In11.Cu" signal "IN4")
		(26 "In12.Cu" signal "GND5")
		(28 "In13.Cu" signal "IN5")
		(30 "In14.Cu" signal "GND6")
		(32 "In15.Cu" signal "IN6")
		(34 "In16.Cu" signal "GND7")
		(2 "B.Cu" signal "BOTTOM")
		(9 "F.Adhes" user "F.Adhesive")
		(11 "B.Adhes" user "B.Adhesive")
		(13 "F.Paste" user "Package Geometry/Pastemask Top")
		(15 "B.Paste" user "Package Geometry/Pastemask Bottom")
		(5 "F.SilkS" user "Ref Des/Silkscreen Top")
		(7 "B.SilkS" user "Ref Des/Silkscreen Bottom")
		(1 "F.Mask" user "Board Geometry/Soldermask Top")
		(3 "B.Mask" user "Board Geometry/Soldermask Bottom")
		(17 "Dwgs.User" user "User.Drawings")
		(19 "Cmts.User" user "User.Comments")
		(21 "Eco1.User" user "User.Eco1")
		(23 "Eco2.User" user "User.Eco2")
		(25 "Edge.Cuts" user "Board Geometry/Outline")
		(27 "Margin" user)
		(31 "F.CrtYd" user "Package Geometry/Place Bound Top")
		(29 "B.CrtYd" user "Package Geometry/Place Bound Bottom")
		(35 "F.Fab" user "Ref Des/Assembly Top")
		(33 "B.Fab" user "Ref Des/Assembly Bottom")
	)
	(setup
		(pad_to_mask_clearance 0)
		(allow_soldermask_bridges_in_footprints no)
		(tenting
			(front yes)
			(back yes)
		)
		(covering
			(front no)
			(back no)
		)
		(plugging
			(front no)
			(back no)
		)
		(capping no)
		(filling no)
		(pcbplotparams
			(layerselection 0x00000000_00000000_55555555_5755f5ff)
			(plot_on_all_layers_selection 0x00000000_00000000_00000000_00000000)
			(disableapertmacros no)
			(usegerberextensions no)
			(usegerberattributes yes)
			(usegerberadvancedattributes yes)
			(creategerberjobfile yes)
			(dashed_line_dash_ratio 12)
			(dashed_line_gap_ratio 3)
			(svgprecision 4)
			(plotframeref no)
			(mode 1)
			(useauxorigin no)
			(pdf_front_fp_property_popups yes)
			(pdf_back_fp_property_popups yes)
			(pdf_metadata yes)
			(pdf_single_document no)
			(dxfpolygonmode yes)
			(dxfimperialunits yes)
			(dxfusepcbnewfont yes)
			(psnegative no)
			(psa4output no)
			(plot_black_and_white yes)
			(sketchpadsonfab no)
			(plotpadnumbers no)
			(hidednponfab no)
			(sketchdnponfab yes)
			(crossoutdnponfab yes)
			(subtractmaskfromsilk no)
			(outputformat 1)
			(mirror no)
			(drillshape 1)
			(scaleselection 1)
			(outputdirectory "")
		)
	)
	(gr_poly
		(pts
			(xy 122.239532 -288.757868) (xy 122.251714 -288.734558) (xy 122.281899 -288.691486) (xy 122.31809 -288.653323)
			(xy 122.359501 -288.620898) (xy 122.405231 -288.594917) (xy 122.454285 -288.575944) (xy 122.505596 -288.564393)
			(xy 122.558048 -288.560514) (xy 122.6105 -288.564393) (xy 122.661811 -288.575944) (xy 122.710865 -288.594917)
			(xy 122.756595 -288.620898) (xy 122.798006 -288.653323) (xy 122.834197 -288.691486) (xy 122.864382 -288.734558)
			(xy 122.876564 -288.757868) (xy 123.00204 -288.757868) (xy 123.017273 -288.757297) (xy 123.046387 -288.748317)
			(xy 123.071567 -288.731164) (xy 123.090581 -288.707359) (xy 123.101746 -288.679011) (xy 123.10407 -288.648633)
			(xy 123.097349 -288.618916) (xy 123.090178 -288.605468) (xy 123.00585 -288.459418) (xy 122.980958 -288.456116)
			(xy 122.955613 -288.452295) (xy 122.9063 -288.438321) (xy 122.8595 -288.41742) (xy 122.816181 -288.390023)
			(xy 122.777239 -288.356699) (xy 122.743478 -288.318134) (xy 122.715596 -288.275126) (xy 122.694169 -288.228565)
			(xy 122.679641 -288.179412) (xy 122.672312 -288.128684) (xy 122.67184 -288.103056) (xy 122.672338 -288.076407)
			(xy 122.680281 -288.023703) (xy 122.695991 -287.972773) (xy 122.719117 -287.924752) (xy 122.749141 -287.880715)
			(xy 122.785393 -287.841644) (xy 122.827064 -287.808413) (xy 122.873222 -287.781764) (xy 122.922836 -287.762292)
			(xy 122.974798 -287.750432) (xy 123.027948 -287.746449) (xy 123.081098 -287.750432) (xy 123.13306 -287.762292)
			(xy 123.182674 -287.781764) (xy 123.228832 -287.808413) (xy 123.270503 -287.841644) (xy 123.306755 -287.880715)
			(xy 123.336779 -287.924752) (xy 123.359905 -287.972773) (xy 123.375615 -288.023703) (xy 123.383558 -288.076407)
			(xy 123.384056 -288.103056) (xy 123.383683 -288.126301) (xy 123.377643 -288.172398) (xy 123.365659 -288.217318)
			(xy 123.357132 -288.238946) (xy 123.347734 -288.261806) (xy 123.5202 -288.560764) (xy 123.544838 -288.564066)
			(xy 123.569374 -288.567764) (xy 123.617173 -288.581075) (xy 123.66266 -288.600896) (xy 123.704954 -288.626843)
			(xy 123.743234 -288.658412) (xy 123.776758 -288.694992) (xy 123.804876 -288.735874) (xy 123.816364 -288.757868)
			(xy 124.119132 -288.757868) (xy 124.131314 -288.734558) (xy 124.161499 -288.691486) (xy 124.19769 -288.653323)
			(xy 124.239101 -288.620898) (xy 124.284831 -288.594917) (xy 124.333885 -288.575944) (xy 124.385196 -288.564393)
			(xy 124.437648 -288.560514) (xy 124.4901 -288.564393) (xy 124.541411 -288.575944) (xy 124.590465 -288.594917)
			(xy 124.636195 -288.620898) (xy 124.677606 -288.653323) (xy 124.713797 -288.691486) (xy 124.743982 -288.734558)
			(xy 124.756164 -288.757868) (xy 124.88164 -288.757868) (xy 124.896873 -288.757297) (xy 124.925987 -288.748317)
			(xy 124.951167 -288.731164) (xy 124.970181 -288.707359) (xy 124.981346 -288.679011) (xy 124.98367 -288.648633)
			(xy 124.976949 -288.618916) (xy 124.969778 -288.605468) (xy 124.88545 -288.459418) (xy 124.860558 -288.456116)
			(xy 124.835213 -288.452295) (xy 124.7859 -288.438321) (xy 124.7391 -288.41742) (xy 124.695781 -288.390023)
			(xy 124.656839 -288.356699) (xy 124.623078 -288.318134) (xy 124.595196 -288.275126) (xy 124.573769 -288.228565)
			(xy 124.559241 -288.179412) (xy 124.551912 -288.128684) (xy 124.55144 -288.103056) (xy 124.551938 -288.076407)
			(xy 124.559881 -288.023703) (xy 124.575591 -287.972773) (xy 124.598717 -287.924752) (xy 124.628741 -287.880715)
			(xy 124.664993 -287.841644) (xy 124.706664 -287.808413) (xy 124.752822 -287.781764) (xy 124.802436 -287.762292)
			(xy 124.854398 -287.750432) (xy 124.907548 -287.746449) (xy 124.960698 -287.750432) (xy 125.01266 -287.762292)
			(xy 125.062274 -287.781764) (xy 125.108432 -287.808413) (xy 125.150103 -287.841644) (xy 125.186355 -287.880715)
			(xy 125.216379 -287.924752) (xy 125.239505 -287.972773) (xy 125.255215 -288.023703) (xy 125.263158 -288.076407)
			(xy 125.263656 -288.103056) (xy 125.263283 -288.126301) (xy 125.257243 -288.172398) (xy 125.245259 -288.217318)
			(xy 125.236732 -288.238946) (xy 125.227334 -288.261806) (xy 125.3998 -288.560764) (xy 125.424438 -288.564066)
			(xy 125.448974 -288.567764) (xy 125.496773 -288.581075) (xy 125.54226 -288.600896) (xy 125.584554 -288.626843)
			(xy 125.622834 -288.658412) (xy 125.656358 -288.694992) (xy 125.684476 -288.735874) (xy 125.695964 -288.757868)
			(xy 125.998732 -288.757868) (xy 126.010914 -288.734558) (xy 126.041099 -288.691486) (xy 126.07729 -288.653323)
			(xy 126.118701 -288.620898) (xy 126.164431 -288.594917) (xy 126.213485 -288.575944) (xy 126.264796 -288.564393)
			(xy 126.317248 -288.560514) (xy 126.3697 -288.564393) (xy 126.421011 -288.575944) (xy 126.470065 -288.594917)
			(xy 126.515795 -288.620898) (xy 126.557206 -288.653323) (xy 126.593397 -288.691486) (xy 126.623582 -288.734558)
			(xy 126.635764 -288.757868) (xy 126.76124 -288.757868) (xy 126.776473 -288.757297) (xy 126.805587 -288.748317)
			(xy 126.830767 -288.731164) (xy 126.849781 -288.707359) (xy 126.860946 -288.679011) (xy 126.86327 -288.648633)
			(xy 126.856549 -288.618916) (xy 126.849378 -288.605468) (xy 126.76505 -288.459418) (xy 126.740158 -288.456116)
			(xy 126.714813 -288.452295) (xy 126.6655 -288.438321) (xy 126.6187 -288.41742) (xy 126.575381 -288.390023)
			(xy 126.536439 -288.356699) (xy 126.502678 -288.318134) (xy 126.474796 -288.275126) (xy 126.453369 -288.228565)
			(xy 126.438841 -288.179412) (xy 126.431512 -288.128684) (xy 126.43104 -288.103056) (xy 126.431538 -288.076407)
			(xy 126.439481 -288.023703) (xy 126.455191 -287.972773) (xy 126.478317 -287.924752) (xy 126.508341 -287.880715)
			(xy 126.544593 -287.841644) (xy 126.586264 -287.808413) (xy 126.632422 -287.781764) (xy 126.682036 -287.762292)
			(xy 126.733998 -287.750432) (xy 126.787148 -287.746449) (xy 126.840298 -287.750432) (xy 126.89226 -287.762292)
			(xy 126.941874 -287.781764) (xy 126.988032 -287.808413) (xy 127.029703 -287.841644) (xy 127.065955 -287.880715)
			(xy 127.095979 -287.924752) (xy 127.119105 -287.972773) (xy 127.134815 -288.023703) (xy 127.142758 -288.076407)
			(xy 127.143256 -288.103056) (xy 127.142883 -288.126301) (xy 127.136843 -288.172398) (xy 127.124859 -288.217318)
			(xy 127.116332 -288.238946) (xy 127.106934 -288.261806) (xy 127.2794 -288.560764) (xy 127.304038 -288.564066)
			(xy 127.328574 -288.567764) (xy 127.376373 -288.581075) (xy 127.42186 -288.600896) (xy 127.464154 -288.626843)
			(xy 127.502434 -288.658412) (xy 127.535958 -288.694992) (xy 127.564076 -288.735874) (xy 127.575564 -288.757868)
			(xy 127.878332 -288.757868) (xy 127.890514 -288.734558) (xy 127.920699 -288.691486) (xy 127.95689 -288.653323)
			(xy 127.998301 -288.620898) (xy 128.044031 -288.594917) (xy 128.093085 -288.575944) (xy 128.144396 -288.564393)
			(xy 128.196848 -288.560514) (xy 128.2493 -288.564393) (xy 128.300611 -288.575944) (xy 128.349665 -288.594917)
			(xy 128.395395 -288.620898) (xy 128.436806 -288.653323) (xy 128.472997 -288.691486) (xy 128.503182 -288.734558)
			(xy 128.515364 -288.757868) (xy 128.64084 -288.757868) (xy 128.656073 -288.757297) (xy 128.685187 -288.748317)
			(xy 128.710367 -288.731164) (xy 128.729381 -288.707359) (xy 128.740546 -288.679011) (xy 128.74287 -288.648633)
			(xy 128.736149 -288.618916) (xy 128.728978 -288.605468) (xy 128.64465 -288.459418) (xy 128.619758 -288.456116)
			(xy 128.594413 -288.452295) (xy 128.5451 -288.438321) (xy 128.4983 -288.41742) (xy 128.454981 -288.390023)
			(xy 128.416039 -288.356699) (xy 128.382278 -288.318134) (xy 128.354396 -288.275126) (xy 128.332969 -288.228565)
			(xy 128.318441 -288.179412) (xy 128.311112 -288.128684) (xy 128.31064 -288.103056) (xy 128.311138 -288.076407)
			(xy 128.319081 -288.023703) (xy 128.334791 -287.972773) (xy 128.357917 -287.924752) (xy 128.387941 -287.880715)
			(xy 128.424193 -287.841644) (xy 128.465864 -287.808413) (xy 128.512022 -287.781764) (xy 128.561636 -287.762292)
			(xy 128.613598 -287.750432) (xy 128.666748 -287.746449) (xy 128.719898 -287.750432) (xy 128.77186 -287.762292)
			(xy 128.821474 -287.781764) (xy 128.867632 -287.808413) (xy 128.909303 -287.841644) (xy 128.945555 -287.880715)
			(xy 128.975579 -287.924752) (xy 128.998705 -287.972773) (xy 129.014415 -288.023703) (xy 129.022358 -288.076407)
			(xy 129.022856 -288.103056) (xy 129.022483 -288.126301) (xy 129.016443 -288.172398) (xy 129.004459 -288.217318)
			(xy 128.995932 -288.238946) (xy 128.986534 -288.261806) (xy 129.159 -288.560764) (xy 129.183638 -288.564066)
			(xy 129.208174 -288.567764) (xy 129.255973 -288.581075) (xy 129.30146 -288.600896) (xy 129.343754 -288.626843)
			(xy 129.382034 -288.658412) (xy 129.415558 -288.694992) (xy 129.443676 -288.735874) (xy 129.455164 -288.757868)
			(xy 129.757932 -288.757868) (xy 129.770114 -288.734558) (xy 129.800299 -288.691486) (xy 129.83649 -288.653323)
			(xy 129.877901 -288.620898) (xy 129.923631 -288.594917) (xy 129.972685 -288.575944) (xy 130.023996 -288.564393)
			(xy 130.076448 -288.560514) (xy 130.1289 -288.564393) (xy 130.180211 -288.575944) (xy 130.229265 -288.594917)
			(xy 130.274995 -288.620898) (xy 130.316406 -288.653323) (xy 130.352597 -288.691486) (xy 130.382782 -288.734558)
			(xy 130.394964 -288.757868) (xy 130.52044 -288.757868) (xy 130.535673 -288.757297) (xy 130.564787 -288.748317)
			(xy 130.589967 -288.731164) (xy 130.608981 -288.707359) (xy 130.620146 -288.679011) (xy 130.62247 -288.648633)
			(xy 130.615749 -288.618916) (xy 130.608578 -288.605468) (xy 130.52425 -288.459418) (xy 130.499358 -288.456116)
			(xy 130.474013 -288.452295) (xy 130.4247 -288.438321) (xy 130.3779 -288.41742) (xy 130.334581 -288.390023)
			(xy 130.295639 -288.356699) (xy 130.261878 -288.318134) (xy 130.233996 -288.275126) (xy 130.212569 -288.228565)
			(xy 130.198041 -288.179412) (xy 130.190712 -288.128684) (xy 130.19024 -288.103056) (xy 130.190738 -288.076407)
			(xy 130.198681 -288.023703) (xy 130.214391 -287.972773) (xy 130.237517 -287.924752) (xy 130.267541 -287.880715)
			(xy 130.303793 -287.841644) (xy 130.345464 -287.808413) (xy 130.391622 -287.781764) (xy 130.441236 -287.762292)
			(xy 130.493198 -287.750432) (xy 130.546348 -287.746449) (xy 130.599498 -287.750432) (xy 130.65146 -287.762292)
			(xy 130.701074 -287.781764) (xy 130.747232 -287.808413) (xy 130.788903 -287.841644) (xy 130.825155 -287.880715)
			(xy 130.855179 -287.924752) (xy 130.878305 -287.972773) (xy 130.894015 -288.023703) (xy 130.901958 -288.076407)
			(xy 130.902456 -288.103056) (xy 130.902083 -288.126301) (xy 130.896043 -288.172398) (xy 130.884059 -288.217318)
			(xy 130.875532 -288.238946) (xy 130.866134 -288.261806) (xy 131.0386 -288.560764) (xy 131.063238 -288.564066)
			(xy 131.087774 -288.567764) (xy 131.135573 -288.581075) (xy 131.18106 -288.600896) (xy 131.223354 -288.626843)
			(xy 131.261634 -288.658412) (xy 131.295158 -288.694992) (xy 131.323276 -288.735874) (xy 131.334764 -288.757868)
			(xy 131.637532 -288.757868) (xy 131.649714 -288.734558) (xy 131.679899 -288.691486) (xy 131.71609 -288.653323)
			(xy 131.757501 -288.620898) (xy 131.803231 -288.594917) (xy 131.852285 -288.575944) (xy 131.903596 -288.564393)
			(xy 131.956048 -288.560514) (xy 132.0085 -288.564393) (xy 132.059811 -288.575944) (xy 132.108865 -288.594917)
			(xy 132.154595 -288.620898) (xy 132.196006 -288.653323) (xy 132.232197 -288.691486) (xy 132.262382 -288.734558)
			(xy 132.274564 -288.757868) (xy 132.40004 -288.757868) (xy 132.415273 -288.757297) (xy 132.444387 -288.748317)
			(xy 132.469567 -288.731164) (xy 132.488581 -288.707359) (xy 132.499746 -288.679011) (xy 132.50207 -288.648633)
			(xy 132.495349 -288.618916) (xy 132.488178 -288.605468) (xy 132.40385 -288.459418) (xy 132.378958 -288.456116)
			(xy 132.353613 -288.452295) (xy 132.3043 -288.438321) (xy 132.2575 -288.41742) (xy 132.214181 -288.390023)
			(xy 132.175239 -288.356699) (xy 132.141478 -288.318134) (xy 132.113596 -288.275126) (xy 132.092169 -288.228565)
			(xy 132.077641 -288.179412) (xy 132.070312 -288.128684) (xy 132.06984 -288.103056) (xy 132.070338 -288.076407)
			(xy 132.078281 -288.023703) (xy 132.093991 -287.972773) (xy 132.117117 -287.924752) (xy 132.147141 -287.880715)
			(xy 132.183393 -287.841644) (xy 132.225064 -287.808413) (xy 132.271222 -287.781764) (xy 132.320836 -287.762292)
			(xy 132.372798 -287.750432) (xy 132.425948 -287.746449) (xy 132.479098 -287.750432) (xy 132.53106 -287.762292)
			(xy 132.580674 -287.781764) (xy 132.626832 -287.808413) (xy 132.668503 -287.841644) (xy 132.704755 -287.880715)
			(xy 132.734779 -287.924752) (xy 132.757905 -287.972773) (xy 132.773615 -288.023703) (xy 132.781558 -288.076407)
			(xy 132.782056 -288.103056) (xy 132.781683 -288.126301) (xy 132.781237 -288.129705) (xy 133.949684 -288.129705)
			(xy 133.949684 -288.076407) (xy 133.957627 -288.023703) (xy 133.973337 -287.972773) (xy 133.996463 -287.924752)
			(xy 134.026487 -287.880715) (xy 134.062739 -287.841644) (xy 134.10441 -287.808413) (xy 134.150568 -287.781764)
			(xy 134.200182 -287.762292) (xy 134.252144 -287.750432) (xy 134.305294 -287.746449) (xy 134.358444 -287.750432)
			(xy 134.410406 -287.762292) (xy 134.46002 -287.781764) (xy 134.506178 -287.808413) (xy 134.547849 -287.841644)
			(xy 134.584101 -287.880715) (xy 134.614125 -287.924752) (xy 134.637251 -287.972773) (xy 134.652961 -288.023703)
			(xy 134.660904 -288.076407) (xy 134.661402 -288.103056) (xy 134.660904 -288.129705) (xy 134.652961 -288.182409)
			(xy 134.637251 -288.233339) (xy 134.614125 -288.28136) (xy 134.584101 -288.325397) (xy 134.547849 -288.364468)
			(xy 134.506178 -288.397699) (xy 134.46002 -288.424348) (xy 134.410406 -288.44382) (xy 134.358444 -288.45568)
			(xy 134.305294 -288.459664) (xy 134.252144 -288.45568) (xy 134.200182 -288.44382) (xy 134.150568 -288.424348)
			(xy 134.10441 -288.397699) (xy 134.062739 -288.364468) (xy 134.026487 -288.325397) (xy 133.996463 -288.28136)
			(xy 133.973337 -288.233339) (xy 133.957627 -288.182409) (xy 133.949684 -288.129705) (xy 132.781237 -288.129705)
			(xy 132.775643 -288.172398) (xy 132.763659 -288.217318) (xy 132.755132 -288.238946) (xy 132.745734 -288.261806)
			(xy 132.9182 -288.560764) (xy 132.942838 -288.564066) (xy 132.967374 -288.567764) (xy 133.015173 -288.581075)
			(xy 133.06066 -288.600896) (xy 133.102954 -288.626843) (xy 133.141234 -288.658412) (xy 133.174758 -288.694992)
			(xy 133.202876 -288.735874) (xy 133.214364 -288.757868) (xy 133.517132 -288.757868) (xy 133.529314 -288.734558)
			(xy 133.559499 -288.691486) (xy 133.59569 -288.653323) (xy 133.637101 -288.620898) (xy 133.682831 -288.594917)
			(xy 133.731885 -288.575944) (xy 133.783196 -288.564393) (xy 133.835648 -288.560514) (xy 133.8881 -288.564393)
			(xy 133.939411 -288.575944) (xy 133.988465 -288.594917) (xy 134.034195 -288.620898) (xy 134.075606 -288.653323)
			(xy 134.111797 -288.691486) (xy 134.141982 -288.734558) (xy 134.154164 -288.757868) (xy 134.456932 -288.757868)
			(xy 134.470013 -288.732905) (xy 134.502841 -288.687098) (xy 134.542475 -288.647035) (xy 134.587925 -288.613715)
			(xy 134.638056 -288.587971) (xy 134.691617 -288.570445) (xy 134.74727 -288.561575) (xy 134.775448 -288.561018)
			(xy 134.801046 -288.561437) (xy 134.851721 -288.568725) (xy 134.900827 -288.583201) (xy 134.947352 -288.604566)
			(xy 134.990334 -288.632379) (xy 135.00989 -288.648902) (xy 135.04545 -288.680398) (xy 135.132318 -288.59353)
			(xy 135.141977 -288.583227) (xy 135.155721 -288.558568) (xy 135.162197 -288.53109) (xy 135.160912 -288.502889)
			(xy 135.151963 -288.476114) (xy 135.136033 -288.452808) (xy 135.114337 -288.434746) (xy 135.101584 -288.428684)
			(xy 135.078234 -288.417899) (xy 135.034643 -288.3906) (xy 134.995436 -288.357311) (xy 134.961429 -288.318724)
			(xy 134.933331 -288.275644) (xy 134.911727 -288.228969) (xy 134.897066 -288.179669) (xy 134.889654 -288.128773)
			(xy 134.88924 -288.103056) (xy 134.889764 -288.075074) (xy 134.898525 -288.019801) (xy 134.915826 -287.966579)
			(xy 134.941239 -287.916718) (xy 134.974139 -287.871447) (xy 135.013717 -287.83188) (xy 135.058996 -287.798991)
			(xy 135.108864 -287.773591) (xy 135.16209 -287.756304) (xy 135.217366 -287.747557) (xy 135.245348 -287.746948)
			(xy 135.271066 -287.747398) (xy 135.321966 -287.754795) (xy 135.37127 -287.769444) (xy 135.417953 -287.791038)
			(xy 135.461039 -287.819129) (xy 135.499633 -287.85313) (xy 135.53293 -287.892333) (xy 135.560235 -287.935921)
			(xy 135.570976 -287.959292) (xy 135.577101 -287.972012) (xy 135.595142 -287.993713) (xy 135.618433 -288.009647)
			(xy 135.645196 -288.018599) (xy 135.673387 -288.019885) (xy 135.700854 -288.013407) (xy 135.725499 -287.999658)
			(xy 135.735822 -287.990026) (xy 136.31799 -287.407858) (xy 136.310624 -287.379664) (xy 136.305147 -287.357396)
			(xy 136.299287 -287.311915) (xy 136.29894 -287.288986) (xy 136.299462 -287.261003) (xy 136.308219 -287.205726)
			(xy 136.325517 -287.152499) (xy 136.350929 -287.102635) (xy 136.383829 -287.057359) (xy 136.423406 -287.017788)
			(xy 136.468687 -286.984896) (xy 136.518557 -286.959493) (xy 136.571786 -286.942205) (xy 136.627065 -286.933457)
			(xy 136.655048 -286.932878) (xy 136.677977 -286.93322) (xy 136.723458 -286.939086) (xy 136.745726 -286.944562)
			(xy 136.77392 -286.951928) (xy 136.86409 -286.861758) (xy 136.874794 -286.85023) (xy 136.889229 -286.822297)
			(xy 136.89451 -286.791301) (xy 136.89014 -286.760164) (xy 136.87653 -286.73182) (xy 136.866122 -286.720026)
			(xy 136.847914 -286.700067) (xy 136.817123 -286.655677) (xy 136.79339 -286.607146) (xy 136.777261 -286.555586)
			(xy 136.769105 -286.502182) (xy 136.768586 -286.47517) (xy 136.769137 -286.447188) (xy 136.777896 -286.391914)
			(xy 136.795193 -286.338691) (xy 136.820603 -286.288828) (xy 136.853499 -286.243554) (xy 136.893073 -286.203984)
			(xy 136.938349 -286.17109) (xy 136.988213 -286.145684) (xy 137.041438 -286.12839) (xy 137.096712 -286.119635)
			(xy 137.124694 -286.119062) (xy 137.151707 -286.119562) (xy 137.205113 -286.127721) (xy 137.256674 -286.143853)
			(xy 137.305207 -286.167588) (xy 137.349598 -286.198381) (xy 137.36955 -286.216598) (xy 137.381372 -286.226984)
			(xy 137.409704 -286.240639) (xy 137.440846 -286.245036) (xy 137.471851 -286.23976) (xy 137.499786 -286.22531)
			(xy 137.511282 -286.214566) (xy 137.550144 -286.175704) (xy 137.560589 -286.164541) (xy 137.57486 -286.137521)
			(xy 137.580512 -286.107491) (xy 137.577041 -286.077132) (xy 137.564756 -286.049153) (xy 137.544754 -286.026051)
			(xy 137.51882 -286.00989) (xy 137.50417 -286.005524) (xy 137.479135 -285.998462) (xy 137.431282 -285.978074)
			(xy 137.386905 -285.950941) (xy 137.346947 -285.91764) (xy 137.312259 -285.878881) (xy 137.283579 -285.835487)
			(xy 137.261517 -285.788382) (xy 137.246543 -285.738569) (xy 137.238976 -285.687108) (xy 137.238486 -285.6611)
			(xy 137.239035 -285.633117) (xy 137.24779 -285.577839) (xy 137.265084 -285.524612) (xy 137.290492 -285.474745)
			(xy 137.323388 -285.429467) (xy 137.362962 -285.389892) (xy 137.40824 -285.356996) (xy 137.458106 -285.331587)
			(xy 137.511333 -285.314291) (xy 137.566611 -285.305535) (xy 137.594594 -285.304992) (xy 137.622207 -285.305519)
			(xy 137.676771 -285.314057) (xy 137.729362 -285.330914) (xy 137.778722 -285.355686) (xy 137.823667 -285.387779)
			(xy 137.863121 -285.426424) (xy 137.896137 -285.470696) (xy 137.921925 -285.519533) (xy 137.939866 -285.571764)
			(xy 137.949531 -285.626139) (xy 137.950702 -285.653734) (xy 137.950956 -285.674054) (xy 138.001502 -285.724346)
			(xy 138.0617 -285.664148) (xy 138.0617 -285.206186) (xy 138.017504 -285.200344) (xy 137.990827 -285.196291)
			(xy 137.939029 -285.181185) (xy 137.890101 -285.158439) (xy 137.845165 -285.128573) (xy 137.805248 -285.09227)
			(xy 137.771263 -285.050362) (xy 137.743988 -285.003807) (xy 137.724048 -284.95367) (xy 137.711898 -284.9011)
			(xy 137.707818 -284.847298) (xy 137.711899 -284.793496) (xy 137.724049 -284.740926) (xy 137.74399 -284.690789)
			(xy 137.771265 -284.644235) (xy 137.80525 -284.602327) (xy 137.845168 -284.566025) (xy 137.890105 -284.536159)
			(xy 137.939033 -284.513413) (xy 137.990832 -284.498308) (xy 138.017504 -284.494224) (xy 138.0617 -284.488382)
			(xy 138.0617 -283.578808) (xy 138.017504 -283.572966) (xy 137.990836 -283.5689) (xy 137.939058 -283.553772)
			(xy 137.890153 -283.531011) (xy 137.845239 -283.501135) (xy 137.805343 -283.464829) (xy 137.771377 -283.422923)
			(xy 137.744119 -283.376374) (xy 137.72419 -283.326247) (xy 137.712048 -283.273689) (xy 137.70797 -283.219901)
			(xy 137.712048 -283.166112) (xy 137.72419 -283.113554) (xy 137.744118 -283.063427) (xy 137.771376 -283.016878)
			(xy 137.805342 -282.974972) (xy 137.845237 -282.938666) (xy 137.890151 -282.90879) (xy 137.939057 -282.886028)
			(xy 137.990835 -282.870901) (xy 138.017504 -282.866846) (xy 138.0617 -282.861004) (xy 138.0617 -281.950922)
			(xy 138.017504 -281.94508) (xy 137.992155 -281.941262) (xy 137.942833 -281.927294) (xy 137.896023 -281.906397)
			(xy 137.852694 -281.879004) (xy 137.81374 -281.845681) (xy 137.779968 -281.807116) (xy 137.752075 -281.764107)
			(xy 137.730637 -281.717542) (xy 137.716099 -281.668385) (xy 137.708759 -281.617651) (xy 137.708386 -281.59202)
			(xy 137.70864 -281.577542) (xy 137.709656 -281.555444) (xy 137.653776 -281.499564) (xy 137.643875 -281.490254)
			(xy 137.620289 -281.476771) (xy 137.59398 -281.469991) (xy 137.566815 -281.470395) (xy 137.54072 -281.477953)
			(xy 137.517545 -281.492131) (xy 137.498932 -281.511922) (xy 137.486203 -281.535923) (xy 137.480259 -281.562433)
			(xy 137.480548 -281.576018) (xy 137.480802 -281.59202) (xy 137.480295 -281.619099) (xy 137.472091 -281.672633)
			(xy 137.455875 -281.724307) (xy 137.432022 -281.77293) (xy 137.40108 -281.81738) (xy 137.363765 -281.856632)
			(xy 137.320937 -281.889781) (xy 137.273582 -281.916062) (xy 137.222794 -281.93487) (xy 137.169744 -281.94577)
			(xy 137.115654 -281.948511) (xy 137.061774 -281.943031) (xy 137.009345 -281.929454) (xy 136.959576 -281.908095)
			(xy 136.913615 -281.879446) (xy 136.872522 -281.844168) (xy 136.837246 -281.803074) (xy 136.808598 -281.757112)
			(xy 136.787241 -281.707342) (xy 136.773667 -281.654912) (xy 136.768188 -281.601031) (xy 136.770932 -281.546942)
			(xy 136.781834 -281.493892) (xy 136.800644 -281.443105) (xy 136.826927 -281.395752) (xy 136.860078 -281.352924)
			(xy 136.899331 -281.315611) (xy 136.943782 -281.284671) (xy 136.992406 -281.26082) (xy 137.044081 -281.244606)
			(xy 137.097615 -281.236404) (xy 137.124694 -281.235912) (xy 137.140696 -281.236166) (xy 137.154263 -281.23634)
			(xy 137.180719 -281.230362) (xy 137.204665 -281.217626) (xy 137.22441 -281.199032) (xy 137.23856 -281.175893)
			(xy 137.246114 -281.149843) (xy 137.246538 -281.122724) (xy 137.239804 -281.096451) (xy 137.226386 -281.07288)
			(xy 137.21715 -281.062938) (xy 137.110216 -280.956004) (xy 137.099159 -280.945707) (xy 137.072503 -280.931515)
			(xy 137.042861 -280.925746) (xy 137.012828 -280.928904) (xy 136.985035 -280.940714) (xy 136.961914 -280.96014)
			(xy 136.953244 -280.972514) (xy 136.939077 -280.993464) (xy 136.905764 -281.031518) (xy 136.867402 -281.064473)
			(xy 136.824761 -281.091668) (xy 136.778701 -281.112553) (xy 136.730149 -281.12671) (xy 136.680081 -281.133853)
			(xy 136.654794 -281.134312) (xy 136.626811 -281.133763) (xy 136.571534 -281.125007) (xy 136.518308 -281.107712)
			(xy 136.468442 -281.082303) (xy 136.423165 -281.049407) (xy 136.383591 -281.009833) (xy 136.350695 -280.964556)
			(xy 136.325287 -280.91469) (xy 136.307993 -280.861464) (xy 136.299237 -280.806187) (xy 136.298686 -280.778204)
			(xy 136.299128 -280.752916) (xy 136.306281 -280.702849) (xy 136.320444 -280.654297) (xy 136.341332 -280.608237)
			(xy 136.368524 -280.565593) (xy 136.401475 -280.527225) (xy 136.439521 -280.493903) (xy 136.460484 -280.479754)
			(xy 136.472815 -280.471056) (xy 136.492163 -280.447921) (xy 136.503921 -280.420149) (xy 136.507067 -280.390154)
			(xy 136.501327 -280.360546) (xy 136.487201 -280.333899) (xy 136.476994 -280.322782) (xy 136.402826 -280.248614)
			(xy 136.36879 -280.269188) (xy 136.347881 -280.281301) (xy 136.303493 -280.300397) (xy 136.256934 -280.313326)
			(xy 136.209055 -280.319849) (xy 136.184894 -280.320242) (xy 136.15691 -280.319693) (xy 136.101632 -280.310937)
			(xy 136.048403 -280.293642) (xy 135.998536 -280.268235) (xy 135.953256 -280.235339) (xy 135.913679 -280.195765)
			(xy 135.88078 -280.150488) (xy 135.855368 -280.100623) (xy 135.838069 -280.047395) (xy 135.82931 -279.992118)
			(xy 135.828786 -279.964134) (xy 135.829338 -279.935046) (xy 135.838751 -279.877638) (xy 135.857379 -279.822527)
			(xy 135.884726 -279.771181) (xy 135.901938 -279.747726) (xy 135.656066 -279.501854) (xy 135.641334 -279.498806)
			(xy 135.616277 -279.493048) (xy 135.568026 -279.475295) (xy 135.522829 -279.450788) (xy 135.481625 -279.420039)
			(xy 135.44527 -279.383685) (xy 135.414519 -279.342483) (xy 135.390011 -279.297287) (xy 135.372256 -279.249037)
			(xy 135.366506 -279.223978) (xy 135.363458 -279.209246) (xy 135.299704 -279.145492) (xy 135.289429 -279.135905)
			(xy 135.26487 -279.122267) (xy 135.237525 -279.115831) (xy 135.209461 -279.117081) (xy 135.182798 -279.125924)
			(xy 135.159548 -279.141692) (xy 135.141469 -279.163193) (xy 135.129926 -279.188804) (xy 135.127492 -279.202642)
			(xy 135.122827 -279.230439) (xy 135.105877 -279.28419) (xy 135.080671 -279.3346) (xy 135.047838 -279.380409)
			(xy 135.008198 -279.420474) (xy 134.96274 -279.453793) (xy 134.912602 -279.479534) (xy 134.859034 -279.497055)
			(xy 134.803374 -279.505918) (xy 134.775194 -279.506426) (xy 134.747211 -279.505877) (xy 134.691933 -279.497121)
			(xy 134.638706 -279.479826) (xy 134.588839 -279.454418) (xy 134.543561 -279.421522) (xy 134.503986 -279.381948)
			(xy 134.471088 -279.336671) (xy 134.445678 -279.286805) (xy 134.428382 -279.233578) (xy 134.419624 -279.178301)
			(xy 134.419086 -279.150318) (xy 134.419627 -279.122144) (xy 134.428511 -279.0665) (xy 134.446045 -279.012948)
			(xy 134.471792 -278.962825) (xy 134.505108 -278.917381) (xy 134.545164 -278.877748) (xy 134.590959 -278.844916)
			(xy 134.641353 -278.819704) (xy 134.695088 -278.80274) (xy 134.72287 -278.79802) (xy 134.736719 -278.795554)
			(xy 134.762386 -278.784071) (xy 134.783943 -278.766016) (xy 134.79975 -278.74276) (xy 134.808606 -278.716072)
			(xy 134.809838 -278.68798) (xy 134.803353 -278.660619) (xy 134.789642 -278.636069) (xy 134.78002 -278.625808)
			(xy 134.721092 -278.56688) (xy 134.711 -278.557318) (xy 134.686826 -278.543609) (xy 134.659847 -278.536938)
			(xy 134.63207 -278.537803) (xy 134.605558 -278.546138) (xy 134.582283 -278.561325) (xy 134.572756 -278.571452)
			(xy 134.555783 -278.59013) (xy 134.517473 -278.622984) (xy 134.474907 -278.650097) (xy 134.428938 -278.670926)
			(xy 134.380488 -278.685054) (xy 134.330528 -278.692195) (xy 134.305294 -278.69261) (xy 134.277311 -278.692061)
			(xy 134.222035 -278.683305) (xy 134.168808 -278.66601) (xy 134.118943 -278.640601) (xy 134.073666 -278.607705)
			(xy 134.034092 -278.568131) (xy 134.001197 -278.522854) (xy 133.975789 -278.472988) (xy 133.958494 -278.419762)
			(xy 133.949739 -278.364485) (xy 133.949186 -278.336502) (xy 133.949626 -278.311269) (xy 133.956759 -278.26131)
			(xy 133.97088 -278.212861) (xy 133.991707 -278.166893) (xy 134.018823 -278.124331) (xy 134.051681 -278.086028)
			(xy 134.070344 -278.06904) (xy 134.080445 -278.059505) (xy 134.095559 -278.036214) (xy 134.103852 -278.009715)
			(xy 134.104712 -277.981963) (xy 134.098077 -277.955002) (xy 134.084434 -277.93082) (xy 134.074916 -277.920704)
			(xy 133.996176 -277.841964) (xy 133.965188 -277.854156) (xy 133.93396 -277.865559) (xy 133.868631 -277.877837)
			(xy 133.835394 -277.87854) (xy 133.80741 -277.877991) (xy 133.752132 -277.869235) (xy 133.698904 -277.85194)
			(xy 133.649036 -277.826532) (xy 133.603757 -277.793637) (xy 133.56418 -277.754063) (xy 133.531281 -277.708786)
			(xy 133.50587 -277.65892) (xy 133.488571 -277.605693) (xy 133.479811 -277.550416) (xy 133.479286 -277.522432)
			(xy 133.480003 -277.489196) (xy 133.492276 -277.423868) (xy 133.50367 -277.392638) (xy 133.515862 -277.36165)
			(xy 133.127496 -276.973284) (xy 133.12648 -276.972522) (xy 133.101842 -276.947884) (xy 133.10108 -276.946868)
			(xy 132.932678 -276.778466) (xy 132.921825 -276.768316) (xy 132.895681 -276.754219) (xy 132.866587 -276.748242)
			(xy 132.837003 -276.750889) (xy 132.809432 -276.761937) (xy 132.786207 -276.780451) (xy 132.769291 -276.804866)
			(xy 132.764276 -276.818852) (xy 132.755097 -276.845278) (xy 132.729679 -276.895109) (xy 132.696782 -276.940353)
			(xy 132.657217 -276.979898) (xy 132.611957 -277.012772) (xy 132.562113 -277.038166) (xy 132.508913 -277.055455)
			(xy 132.453664 -277.064215) (xy 132.425694 -277.064724) (xy 132.397711 -277.064175) (xy 132.342433 -277.055419)
			(xy 132.289206 -277.038124) (xy 132.23934 -277.012716) (xy 132.194061 -276.97982) (xy 132.154487 -276.940246)
			(xy 132.121589 -276.894969) (xy 132.09618 -276.845103) (xy 132.078883 -276.791876) (xy 132.070126 -276.736599)
			(xy 132.069586 -276.708616) (xy 132.070133 -276.680647) (xy 132.078879 -276.625398) (xy 132.096158 -276.572196)
			(xy 132.121545 -276.522351) (xy 132.154415 -276.47709) (xy 132.193959 -276.437527) (xy 132.239204 -276.404635)
			(xy 132.289036 -276.379224) (xy 132.315458 -276.370034) (xy 132.329406 -276.364944) (xy 132.353782 -276.348016)
			(xy 132.372269 -276.3248) (xy 132.383309 -276.297252) (xy 132.385971 -276.267694) (xy 132.380031 -276.238617)
			(xy 132.36599 -276.212471) (xy 132.355844 -276.201632) (xy 132.32511 -276.170898) (xy 132.313963 -276.160548)
			(xy 132.287091 -276.14633) (xy 132.257224 -276.140653) (xy 132.227009 -276.14402) (xy 132.199124 -276.156132)
			(xy 132.187188 -276.165564) (xy 132.167743 -276.18159) (xy 132.125193 -276.208581) (xy 132.079265 -276.229309)
			(xy 132.030875 -276.243362) (xy 131.980988 -276.250458) (xy 131.955794 -276.250908) (xy 131.927811 -276.250359)
			(xy 131.872535 -276.241603) (xy 131.819309 -276.224308) (xy 131.769443 -276.198899) (xy 131.724166 -276.166003)
			(xy 131.684593 -276.126429) (xy 131.651698 -276.081152) (xy 131.62629 -276.031286) (xy 131.608996 -275.978059)
			(xy 131.600241 -275.922783) (xy 131.599686 -275.8948) (xy 131.600122 -275.869605) (xy 131.607221 -275.819718)
			(xy 131.621278 -275.771329) (xy 131.642012 -275.725403) (xy 131.669009 -275.682856) (xy 131.68503 -275.663406)
			(xy 131.694482 -275.651486) (xy 131.706574 -275.623589) (xy 131.709934 -275.59337) (xy 131.704264 -275.563499)
			(xy 131.690066 -275.536612) (xy 131.679696 -275.525484) (xy 131.57962 -275.425408) (xy 131.553204 -275.430488)
			(xy 131.536602 -275.433476) (xy 131.503016 -275.436652) (xy 131.486148 -275.436838) (xy 131.458159 -275.436322)
			(xy 131.40287 -275.427572) (xy 131.34963 -275.410281) (xy 131.299751 -275.384873) (xy 131.254461 -275.351976)
			(xy 131.214875 -275.312399) (xy 131.181967 -275.267115) (xy 131.156549 -275.217242) (xy 131.139246 -275.164006)
			(xy 131.130485 -275.108719) (xy 131.13004 -275.08073) (xy 131.130237 -275.063863) (xy 131.133414 -275.030278)
			(xy 131.13639 -275.013674) (xy 131.14147 -274.987258) (xy 130.556254 -274.402042) (xy 130.546234 -274.392657)
			(xy 130.522361 -274.379122) (xy 130.495745 -274.372435) (xy 130.468309 -274.373079) (xy 130.442036 -274.381007)
			(xy 130.418824 -274.395646) (xy 130.40035 -274.41594) (xy 130.393694 -274.42795) (xy 130.380561 -274.452717)
			(xy 130.347704 -274.498136) (xy 130.308131 -274.53784) (xy 130.262821 -274.570847) (xy 130.212895 -274.59634)
			(xy 130.15959 -274.613689) (xy 130.104223 -274.622463) (xy 130.076194 -274.623022) (xy 130.048211 -274.622473)
			(xy 129.992934 -274.613717) (xy 129.939706 -274.596422) (xy 129.88984 -274.571014) (xy 129.844562 -274.538118)
			(xy 129.804987 -274.498544) (xy 129.77209 -274.453267) (xy 129.746681 -274.403401) (xy 129.729385 -274.350174)
			(xy 129.720628 -274.294897) (xy 129.720086 -274.266914) (xy 129.720784 -274.235915) (xy 129.731559 -274.174858)
			(xy 129.752719 -274.11658) (xy 129.767584 -274.089368) (xy 129.774761 -274.07591) (xy 129.781532 -274.046185)
			(xy 129.779235 -274.015785) (xy 129.768074 -273.987415) (xy 129.749043 -273.963598) (xy 129.723834 -273.946454)
			(xy 129.69469 -273.937507) (xy 129.679446 -273.936968) (xy 129.533142 -273.936968) (xy 129.517914 -273.937542)
			(xy 129.488812 -273.946524) (xy 129.463644 -273.963676) (xy 129.44464 -273.987477) (xy 129.433485 -274.015817)
			(xy 129.431168 -274.046186) (xy 129.437893 -274.075891) (xy 129.445004 -274.089368) (xy 129.459903 -274.116564)
			(xy 129.481078 -274.174843) (xy 129.491818 -274.235911) (xy 129.492502 -274.266914) (xy 129.492004 -274.293563)
			(xy 129.484061 -274.346267) (xy 129.468351 -274.397197) (xy 129.445225 -274.445218) (xy 129.415201 -274.489255)
			(xy 129.378949 -274.528326) (xy 129.337278 -274.561557) (xy 129.29112 -274.588206) (xy 129.241506 -274.607678)
			(xy 129.189544 -274.619538) (xy 129.136394 -274.623522) (xy 129.083244 -274.619538) (xy 129.031282 -274.607678)
			(xy 128.981668 -274.588206) (xy 128.93551 -274.561557) (xy 128.893839 -274.528326) (xy 128.857587 -274.489255)
			(xy 128.827563 -274.445218) (xy 128.804437 -274.397197) (xy 128.788727 -274.346267) (xy 128.780784 -274.293563)
			(xy 128.780286 -274.266914) (xy 128.780984 -274.235915) (xy 128.791759 -274.174858) (xy 128.812919 -274.11658)
			(xy 128.827784 -274.089368) (xy 128.834961 -274.07591) (xy 128.841732 -274.046185) (xy 128.839435 -274.015785)
			(xy 128.828274 -273.987415) (xy 128.809243 -273.963598) (xy 128.784034 -273.946454) (xy 128.75489 -273.937507)
			(xy 128.739646 -273.936968) (xy 128.593342 -273.936968) (xy 128.578114 -273.937542) (xy 128.549012 -273.946524)
			(xy 128.523844 -273.963676) (xy 128.50484 -273.987477) (xy 128.493685 -274.015817) (xy 128.491368 -274.046186)
			(xy 128.498093 -274.075891) (xy 128.505204 -274.089368) (xy 128.520103 -274.116564) (xy 128.541278 -274.174843)
			(xy 128.552018 -274.235911) (xy 128.552702 -274.266914) (xy 128.552204 -274.293563) (xy 128.544261 -274.346267)
			(xy 128.528551 -274.397197) (xy 128.505425 -274.445218) (xy 128.475401 -274.489255) (xy 128.439149 -274.528326)
			(xy 128.397478 -274.561557) (xy 128.35132 -274.588206) (xy 128.301706 -274.607678) (xy 128.249744 -274.619538)
			(xy 128.196594 -274.623522) (xy 128.143444 -274.619538) (xy 128.091482 -274.607678) (xy 128.041868 -274.588206)
			(xy 127.99571 -274.561557) (xy 127.954039 -274.528326) (xy 127.917787 -274.489255) (xy 127.887763 -274.445218)
			(xy 127.864637 -274.397197) (xy 127.848927 -274.346267) (xy 127.840984 -274.293563) (xy 127.840486 -274.266914)
			(xy 127.841184 -274.235915) (xy 127.851959 -274.174858) (xy 127.873119 -274.11658) (xy 127.887984 -274.089368)
			(xy 127.895161 -274.07591) (xy 127.901932 -274.046185) (xy 127.899635 -274.015785) (xy 127.888474 -273.987415)
			(xy 127.869443 -273.963598) (xy 127.844234 -273.946454) (xy 127.81509 -273.937507) (xy 127.799846 -273.936968)
			(xy 127.653542 -273.936968) (xy 127.638314 -273.937542) (xy 127.609212 -273.946524) (xy 127.584044 -273.963676)
			(xy 127.56504 -273.987477) (xy 127.553885 -274.015817) (xy 127.551568 -274.046186) (xy 127.558293 -274.075891)
			(xy 127.565404 -274.089368) (xy 127.580303 -274.116564) (xy 127.601478 -274.174843) (xy 127.612218 -274.235911)
			(xy 127.612902 -274.266914) (xy 127.612404 -274.293563) (xy 127.604461 -274.346267) (xy 127.588751 -274.397197)
			(xy 127.565625 -274.445218) (xy 127.535601 -274.489255) (xy 127.499349 -274.528326) (xy 127.457678 -274.561557)
			(xy 127.41152 -274.588206) (xy 127.361906 -274.607678) (xy 127.309944 -274.619538) (xy 127.256794 -274.623522)
			(xy 127.203644 -274.619538) (xy 127.151682 -274.607678) (xy 127.102068 -274.588206) (xy 127.05591 -274.561557)
			(xy 127.014239 -274.528326) (xy 126.977987 -274.489255) (xy 126.947963 -274.445218) (xy 126.924837 -274.397197)
			(xy 126.909127 -274.346267) (xy 126.901184 -274.293563) (xy 126.900686 -274.266914) (xy 126.901384 -274.235915)
			(xy 126.912159 -274.174858) (xy 126.933319 -274.11658) (xy 126.948184 -274.089368) (xy 126.955361 -274.07591)
			(xy 126.962132 -274.046185) (xy 126.959835 -274.015785) (xy 126.948674 -273.987415) (xy 126.929643 -273.963598)
			(xy 126.904434 -273.946454) (xy 126.87529 -273.937507) (xy 126.860046 -273.936968) (xy 126.713996 -273.936968)
			(xy 126.698773 -273.937548) (xy 126.669684 -273.946538) (xy 126.644528 -273.963691) (xy 126.625534 -273.987487)
			(xy 126.614385 -274.015819) (xy 126.612067 -274.046178) (xy 126.618786 -274.075874) (xy 126.625858 -274.089368)
			(xy 126.640755 -274.116565) (xy 126.661926 -274.174844) (xy 126.672665 -274.235911) (xy 126.673356 -274.266914)
			(xy 126.672858 -274.293563) (xy 126.664915 -274.346267) (xy 126.649205 -274.397197) (xy 126.626079 -274.445218)
			(xy 126.596055 -274.489255) (xy 126.559803 -274.528326) (xy 126.518132 -274.561557) (xy 126.471974 -274.588206)
			(xy 126.42236 -274.607678) (xy 126.370398 -274.619538) (xy 126.317248 -274.623522) (xy 126.264098 -274.619538)
			(xy 126.212136 -274.607678) (xy 126.162522 -274.588206) (xy 126.116364 -274.561557) (xy 126.074693 -274.528326)
			(xy 126.038441 -274.489255) (xy 126.008417 -274.445218) (xy 125.985291 -274.397197) (xy 125.969581 -274.346267)
			(xy 125.961638 -274.293563) (xy 125.96114 -274.266914) (xy 125.961838 -274.235914) (xy 125.972612 -274.174857)
			(xy 125.993769 -274.116578) (xy 126.008638 -274.089368) (xy 126.015812 -274.075908) (xy 126.022579 -274.046179)
			(xy 126.020281 -274.015777) (xy 126.009122 -273.987403) (xy 125.990094 -273.963581) (xy 125.964888 -273.946427)
			(xy 125.935745 -273.937467) (xy 125.9205 -273.936968) (xy 125.773942 -273.936968) (xy 125.758714 -273.937542)
			(xy 125.729612 -273.946524) (xy 125.704444 -273.963676) (xy 125.68544 -273.987477) (xy 125.674285 -274.015817)
			(xy 125.671968 -274.046186) (xy 125.678693 -274.075891) (xy 125.685804 -274.089368) (xy 125.700703 -274.116564)
			(xy 125.721878 -274.174843) (xy 125.732618 -274.235911) (xy 125.733302 -274.266914) (xy 125.732804 -274.293563)
			(xy 125.724861 -274.346267) (xy 125.709151 -274.397197) (xy 125.686025 -274.445218) (xy 125.656001 -274.489255)
			(xy 125.619749 -274.528326) (xy 125.578078 -274.561557) (xy 125.53192 -274.588206) (xy 125.482306 -274.607678)
			(xy 125.430344 -274.619538) (xy 125.377194 -274.623522) (xy 125.324044 -274.619538) (xy 125.272082 -274.607678)
			(xy 125.222468 -274.588206) (xy 125.17631 -274.561557) (xy 125.134639 -274.528326) (xy 125.098387 -274.489255)
			(xy 125.068363 -274.445218) (xy 125.045237 -274.397197) (xy 125.029527 -274.346267) (xy 125.021584 -274.293563)
			(xy 125.021086 -274.266914) (xy 125.021784 -274.235915) (xy 125.032559 -274.174858) (xy 125.053719 -274.11658)
			(xy 125.068584 -274.089368) (xy 125.075761 -274.07591) (xy 125.082532 -274.046185) (xy 125.080235 -274.015785)
			(xy 125.069074 -273.987415) (xy 125.050043 -273.963598) (xy 125.024834 -273.946454) (xy 124.99569 -273.937507)
			(xy 124.980446 -273.936968) (xy 124.834142 -273.936968) (xy 124.818914 -273.937542) (xy 124.789812 -273.946524)
			(xy 124.764644 -273.963676) (xy 124.74564 -273.987477) (xy 124.734485 -274.015817) (xy 124.732168 -274.046186)
			(xy 124.738893 -274.075891) (xy 124.746004 -274.089368) (xy 124.760903 -274.116564) (xy 124.782078 -274.174843)
			(xy 124.792818 -274.235911) (xy 124.793502 -274.266914) (xy 124.793004 -274.293563) (xy 124.785061 -274.346267)
			(xy 124.769351 -274.397197) (xy 124.746225 -274.445218) (xy 124.716201 -274.489255) (xy 124.679949 -274.528326)
			(xy 124.638278 -274.561557) (xy 124.59212 -274.588206) (xy 124.542506 -274.607678) (xy 124.490544 -274.619538)
			(xy 124.437394 -274.623522) (xy 124.384244 -274.619538) (xy 124.332282 -274.607678) (xy 124.282668 -274.588206)
			(xy 124.23651 -274.561557) (xy 124.194839 -274.528326) (xy 124.158587 -274.489255) (xy 124.128563 -274.445218)
			(xy 124.105437 -274.397197) (xy 124.089727 -274.346267) (xy 124.081784 -274.293563) (xy 124.081286 -274.266914)
			(xy 124.081984 -274.235915) (xy 124.092759 -274.174858) (xy 124.113919 -274.11658) (xy 124.128784 -274.089368)
			(xy 124.135961 -274.07591) (xy 124.142732 -274.046185) (xy 124.140435 -274.015785) (xy 124.129274 -273.987415)
			(xy 124.110243 -273.963598) (xy 124.085034 -273.946454) (xy 124.05589 -273.937507) (xy 124.040646 -273.936968)
			(xy 123.894342 -273.936968) (xy 123.879114 -273.937542) (xy 123.850012 -273.946524) (xy 123.824844 -273.963676)
			(xy 123.80584 -273.987477) (xy 123.794685 -274.015817) (xy 123.792368 -274.046186) (xy 123.799093 -274.075891)
			(xy 123.806204 -274.089368) (xy 123.821103 -274.116564) (xy 123.842278 -274.174843) (xy 123.853018 -274.235911)
			(xy 123.853702 -274.266914) (xy 123.853204 -274.293563) (xy 123.845261 -274.346267) (xy 123.829551 -274.397197)
			(xy 123.806425 -274.445218) (xy 123.776401 -274.489255) (xy 123.740149 -274.528326) (xy 123.698478 -274.561557)
			(xy 123.65232 -274.588206) (xy 123.602706 -274.607678) (xy 123.550744 -274.619538) (xy 123.497594 -274.623522)
			(xy 123.444444 -274.619538) (xy 123.392482 -274.607678) (xy 123.342868 -274.588206) (xy 123.29671 -274.561557)
			(xy 123.255039 -274.528326) (xy 123.218787 -274.489255) (xy 123.188763 -274.445218) (xy 123.165637 -274.397197)
			(xy 123.149927 -274.346267) (xy 123.141984 -274.293563) (xy 123.141486 -274.266914) (xy 123.142184 -274.235915)
			(xy 123.152959 -274.174858) (xy 123.174119 -274.11658) (xy 123.188984 -274.089368) (xy 123.196161 -274.07591)
			(xy 123.202932 -274.046185) (xy 123.200635 -274.015785) (xy 123.189474 -273.987415) (xy 123.170443 -273.963598)
			(xy 123.145234 -273.946454) (xy 123.11609 -273.937507) (xy 123.100846 -273.936968) (xy 122.954542 -273.936968)
			(xy 122.939314 -273.937542) (xy 122.910212 -273.946524) (xy 122.885044 -273.963676) (xy 122.86604 -273.987477)
			(xy 122.854885 -274.015817) (xy 122.852568 -274.046186) (xy 122.859293 -274.075891) (xy 122.866404 -274.089368)
			(xy 122.881303 -274.116564) (xy 122.902478 -274.174843) (xy 122.913218 -274.235911) (xy 122.913902 -274.266914)
			(xy 122.913404 -274.293563) (xy 122.905461 -274.346267) (xy 122.889751 -274.397197) (xy 122.866625 -274.445218)
			(xy 122.836601 -274.489255) (xy 122.800349 -274.528326) (xy 122.758678 -274.561557) (xy 122.71252 -274.588206)
			(xy 122.662906 -274.607678) (xy 122.610944 -274.619538) (xy 122.557794 -274.623522) (xy 122.504644 -274.619538)
			(xy 122.452682 -274.607678) (xy 122.403068 -274.588206) (xy 122.35691 -274.561557) (xy 122.315239 -274.528326)
			(xy 122.278987 -274.489255) (xy 122.248963 -274.445218) (xy 122.225837 -274.397197) (xy 122.210127 -274.346267)
			(xy 122.202184 -274.293563) (xy 122.201686 -274.266914) (xy 122.202384 -274.235915) (xy 122.213159 -274.174858)
			(xy 122.234319 -274.11658) (xy 122.249184 -274.089368) (xy 122.256361 -274.07591) (xy 122.263132 -274.046185)
			(xy 122.260835 -274.015785) (xy 122.249674 -273.987415) (xy 122.230643 -273.963598) (xy 122.205434 -273.946454)
			(xy 122.17629 -273.937507) (xy 122.161046 -273.936968) (xy 122.014996 -273.936968) (xy 121.999773 -273.937548)
			(xy 121.970684 -273.946538) (xy 121.945528 -273.963691) (xy 121.926534 -273.987487) (xy 121.915385 -274.015819)
			(xy 121.913067 -274.046178) (xy 121.919786 -274.075874) (xy 121.926858 -274.089368) (xy 121.941755 -274.116565)
			(xy 121.962926 -274.174844) (xy 121.973665 -274.235911) (xy 121.974356 -274.266914) (xy 121.973858 -274.293563)
			(xy 121.965915 -274.346267) (xy 121.950205 -274.397197) (xy 121.927079 -274.445218) (xy 121.897055 -274.489255)
			(xy 121.860803 -274.528326) (xy 121.819132 -274.561557) (xy 121.772974 -274.588206) (xy 121.72336 -274.607678)
			(xy 121.671398 -274.619538) (xy 121.618248 -274.623522) (xy 121.565098 -274.619538) (xy 121.513136 -274.607678)
			(xy 121.463522 -274.588206) (xy 121.417364 -274.561557) (xy 121.375693 -274.528326) (xy 121.339441 -274.489255)
			(xy 121.309417 -274.445218) (xy 121.286291 -274.397197) (xy 121.270581 -274.346267) (xy 121.262638 -274.293563)
			(xy 121.26214 -274.266914) (xy 121.262838 -274.235914) (xy 121.273612 -274.174857) (xy 121.294769 -274.116578)
			(xy 121.309638 -274.089368) (xy 121.316812 -274.075908) (xy 121.323579 -274.046179) (xy 121.321281 -274.015777)
			(xy 121.310122 -273.987403) (xy 121.291094 -273.963581) (xy 121.265888 -273.946427) (xy 121.236745 -273.937467)
			(xy 121.2215 -273.936968) (xy 121.074942 -273.936968) (xy 121.059714 -273.937542) (xy 121.030612 -273.946524)
			(xy 121.005444 -273.963676) (xy 120.98644 -273.987477) (xy 120.975285 -274.015817) (xy 120.972968 -274.046186)
			(xy 120.979693 -274.075891) (xy 120.986804 -274.089368) (xy 121.001703 -274.116564) (xy 121.022878 -274.174843)
			(xy 121.033618 -274.235911) (xy 121.034302 -274.266914) (xy 121.033804 -274.293563) (xy 121.025861 -274.346267)
			(xy 121.010151 -274.397197) (xy 120.987025 -274.445218) (xy 120.957001 -274.489255) (xy 120.920749 -274.528326)
			(xy 120.879078 -274.561557) (xy 120.83292 -274.588206) (xy 120.783306 -274.607678) (xy 120.731344 -274.619538)
			(xy 120.678194 -274.623522) (xy 120.625044 -274.619538) (xy 120.573082 -274.607678) (xy 120.523468 -274.588206)
			(xy 120.47731 -274.561557) (xy 120.435639 -274.528326) (xy 120.399387 -274.489255) (xy 120.369363 -274.445218)
			(xy 120.346237 -274.397197) (xy 120.330527 -274.346267) (xy 120.322584 -274.293563) (xy 120.322086 -274.266914)
			(xy 120.322784 -274.235915) (xy 120.333559 -274.174858) (xy 120.354719 -274.11658) (xy 120.369584 -274.089368)
			(xy 120.376761 -274.07591) (xy 120.383532 -274.046185) (xy 120.381235 -274.015785) (xy 120.370074 -273.987415)
			(xy 120.351043 -273.963598) (xy 120.325834 -273.946454) (xy 120.29669 -273.937507) (xy 120.281446 -273.936968)
			(xy 120.135142 -273.936968) (xy 120.119914 -273.937542) (xy 120.090812 -273.946524) (xy 120.065644 -273.963676)
			(xy 120.04664 -273.987477) (xy 120.035485 -274.015817) (xy 120.033168 -274.046186) (xy 120.039893 -274.075891)
			(xy 120.047004 -274.089368) (xy 120.061903 -274.116564) (xy 120.083078 -274.174843) (xy 120.093818 -274.235911)
			(xy 120.094502 -274.266914) (xy 120.094004 -274.293563) (xy 120.086061 -274.346267) (xy 120.070351 -274.397197)
			(xy 120.047225 -274.445218) (xy 120.017201 -274.489255) (xy 119.980949 -274.528326) (xy 119.939278 -274.561557)
			(xy 119.89312 -274.588206) (xy 119.843506 -274.607678) (xy 119.791544 -274.619538) (xy 119.738394 -274.623522)
			(xy 119.685244 -274.619538) (xy 119.633282 -274.607678) (xy 119.583668 -274.588206) (xy 119.53751 -274.561557)
			(xy 119.495839 -274.528326) (xy 119.459587 -274.489255) (xy 119.429563 -274.445218) (xy 119.406437 -274.397197)
			(xy 119.390727 -274.346267) (xy 119.382784 -274.293563) (xy 119.382286 -274.266914) (xy 119.382984 -274.235915)
			(xy 119.393759 -274.174858) (xy 119.414919 -274.11658) (xy 119.429784 -274.089368) (xy 119.436961 -274.07591)
			(xy 119.443732 -274.046185) (xy 119.441435 -274.015785) (xy 119.430274 -273.987415) (xy 119.411243 -273.963598)
			(xy 119.386034 -273.946454) (xy 119.35689 -273.937507) (xy 119.341646 -273.936968) (xy 119.195342 -273.936968)
			(xy 119.180114 -273.937542) (xy 119.151012 -273.946524) (xy 119.125844 -273.963676) (xy 119.10684 -273.987477)
			(xy 119.095685 -274.015817) (xy 119.093368 -274.046186) (xy 119.100093 -274.075891) (xy 119.107204 -274.089368)
			(xy 119.122103 -274.116564) (xy 119.143278 -274.174843) (xy 119.154018 -274.235911) (xy 119.154702 -274.266914)
			(xy 119.154204 -274.293563) (xy 119.146261 -274.346267) (xy 119.130551 -274.397197) (xy 119.107425 -274.445218)
			(xy 119.077401 -274.489255) (xy 119.041149 -274.528326) (xy 118.999478 -274.561557) (xy 118.95332 -274.588206)
			(xy 118.903706 -274.607678) (xy 118.851744 -274.619538) (xy 118.798594 -274.623522) (xy 118.745444 -274.619538)
			(xy 118.693482 -274.607678) (xy 118.643868 -274.588206) (xy 118.59771 -274.561557) (xy 118.556039 -274.528326)
			(xy 118.519787 -274.489255) (xy 118.489763 -274.445218) (xy 118.466637 -274.397197) (xy 118.450927 -274.346267)
			(xy 118.442984 -274.293563) (xy 118.442486 -274.266914) (xy 118.443184 -274.235915) (xy 118.453959 -274.174858)
			(xy 118.475119 -274.11658) (xy 118.489984 -274.089368) (xy 118.497161 -274.07591) (xy 118.503932 -274.046185)
			(xy 118.501635 -274.015785) (xy 118.490474 -273.987415) (xy 118.471443 -273.963598) (xy 118.446234 -273.946454)
			(xy 118.41709 -273.937507) (xy 118.401846 -273.936968) (xy 118.255796 -273.936968) (xy 118.240573 -273.937548)
			(xy 118.211484 -273.946538) (xy 118.186328 -273.963691) (xy 118.167334 -273.987487) (xy 118.156185 -274.015819)
			(xy 118.153867 -274.046178) (xy 118.160586 -274.075874) (xy 118.167658 -274.089368) (xy 118.182555 -274.116565)
			(xy 118.203726 -274.174844) (xy 118.214465 -274.235911) (xy 118.215156 -274.266914) (xy 118.214658 -274.293563)
			(xy 118.206715 -274.346267) (xy 118.191005 -274.397197) (xy 118.167879 -274.445218) (xy 118.137855 -274.489255)
			(xy 118.101603 -274.528326) (xy 118.059932 -274.561557) (xy 118.013774 -274.588206) (xy 117.96416 -274.607678)
			(xy 117.912198 -274.619538) (xy 117.859048 -274.623522) (xy 117.805898 -274.619538) (xy 117.753936 -274.607678)
			(xy 117.704322 -274.588206) (xy 117.658164 -274.561557) (xy 117.616493 -274.528326) (xy 117.580241 -274.489255)
			(xy 117.550217 -274.445218) (xy 117.527091 -274.397197) (xy 117.511381 -274.346267) (xy 117.503438 -274.293563)
			(xy 117.50294 -274.266914) (xy 117.503638 -274.235914) (xy 117.514412 -274.174857) (xy 117.535569 -274.116578)
			(xy 117.550438 -274.089368) (xy 117.557612 -274.075908) (xy 117.564379 -274.046179) (xy 117.562081 -274.015777)
			(xy 117.550922 -273.987403) (xy 117.531894 -273.963581) (xy 117.506688 -273.946427) (xy 117.477545 -273.937467)
			(xy 117.4623 -273.936968) (xy 117.315996 -273.936968) (xy 117.300773 -273.937548) (xy 117.271684 -273.946538)
			(xy 117.246528 -273.963691) (xy 117.227534 -273.987487) (xy 117.216385 -274.015819) (xy 117.214067 -274.046178)
			(xy 117.220786 -274.075874) (xy 117.227858 -274.089368) (xy 117.242755 -274.116565) (xy 117.263926 -274.174844)
			(xy 117.274665 -274.235911) (xy 117.275356 -274.266914) (xy 117.274858 -274.293563) (xy 117.266915 -274.346267)
			(xy 117.251205 -274.397197) (xy 117.228079 -274.445218) (xy 117.198055 -274.489255) (xy 117.161803 -274.528326)
			(xy 117.120132 -274.561557) (xy 117.073974 -274.588206) (xy 117.02436 -274.607678) (xy 116.972398 -274.619538)
			(xy 116.919248 -274.623522) (xy 116.866098 -274.619538) (xy 116.814136 -274.607678) (xy 116.764522 -274.588206)
			(xy 116.718364 -274.561557) (xy 116.676693 -274.528326) (xy 116.640441 -274.489255) (xy 116.610417 -274.445218)
			(xy 116.587291 -274.397197) (xy 116.571581 -274.346267) (xy 116.563638 -274.293563) (xy 116.56314 -274.266914)
			(xy 116.563838 -274.235914) (xy 116.574612 -274.174857) (xy 116.595769 -274.116578) (xy 116.610638 -274.089368)
			(xy 116.617812 -274.075908) (xy 116.624579 -274.046179) (xy 116.622281 -274.015777) (xy 116.611122 -273.987403)
			(xy 116.592094 -273.963581) (xy 116.566888 -273.946427) (xy 116.537745 -273.937467) (xy 116.5225 -273.936968)
			(xy 116.376196 -273.936968) (xy 116.360973 -273.937548) (xy 116.331884 -273.946538) (xy 116.306728 -273.963691)
			(xy 116.287734 -273.987487) (xy 116.276585 -274.015819) (xy 116.274267 -274.046178) (xy 116.280986 -274.075874)
			(xy 116.288058 -274.089368) (xy 116.302955 -274.116565) (xy 116.324126 -274.174844) (xy 116.334865 -274.235911)
			(xy 116.335556 -274.266914) (xy 116.335058 -274.293563) (xy 116.327115 -274.346267) (xy 116.311405 -274.397197)
			(xy 116.288279 -274.445218) (xy 116.258255 -274.489255) (xy 116.222003 -274.528326) (xy 116.180332 -274.561557)
			(xy 116.134174 -274.588206) (xy 116.08456 -274.607678) (xy 116.032598 -274.619538) (xy 115.979448 -274.623522)
			(xy 115.926298 -274.619538) (xy 115.874336 -274.607678) (xy 115.824722 -274.588206) (xy 115.778564 -274.561557)
			(xy 115.736893 -274.528326) (xy 115.700641 -274.489255) (xy 115.670617 -274.445218) (xy 115.647491 -274.397197)
			(xy 115.631781 -274.346267) (xy 115.623838 -274.293563) (xy 115.62334 -274.266914) (xy 115.624038 -274.235914)
			(xy 115.634812 -274.174857) (xy 115.655969 -274.116578) (xy 115.670838 -274.089368) (xy 115.678012 -274.075908)
			(xy 115.684779 -274.046179) (xy 115.682481 -274.015777) (xy 115.671322 -273.987403) (xy 115.652294 -273.963581)
			(xy 115.627088 -273.946427) (xy 115.597945 -273.937467) (xy 115.5827 -273.936968) (xy 115.436142 -273.936968)
			(xy 115.420914 -273.937542) (xy 115.391812 -273.946524) (xy 115.366644 -273.963676) (xy 115.34764 -273.987477)
			(xy 115.336485 -274.015817) (xy 115.334168 -274.046186) (xy 115.340893 -274.075891) (xy 115.348004 -274.089368)
			(xy 115.362903 -274.116564) (xy 115.384078 -274.174843) (xy 115.394818 -274.235911) (xy 115.395502 -274.266914)
			(xy 115.394952 -274.294896) (xy 115.386195 -274.350171) (xy 115.368899 -274.403396) (xy 115.34349 -274.45326)
			(xy 115.310594 -274.498535) (xy 115.27102 -274.538107) (xy 115.225743 -274.571001) (xy 115.175878 -274.596407)
			(xy 115.122652 -274.6137) (xy 115.067376 -274.622454) (xy 115.039394 -274.623022) (xy 115.013424 -274.62255)
			(xy 114.962034 -274.615002) (xy 114.912287 -274.600066) (xy 114.865238 -274.57806) (xy 114.821886 -274.549451)
			(xy 114.783152 -274.514846) (xy 114.749857 -274.47498) (xy 114.735864 -274.453096) (xy 114.7274 -274.440305)
			(xy 114.704341 -274.420102) (xy 114.676332 -274.407636) (xy 114.645887 -274.404027) (xy 114.61574 -274.409599)
			(xy 114.588596 -274.423851) (xy 114.577368 -274.4343) (xy 114.37874 -274.632928) (xy 114.37874 -274.74926)
			(xy 114.43843 -274.74926) (xy 114.447066 -274.746212) (xy 114.476594 -274.736119) (xy 114.538041 -274.725268)
			(xy 114.56924 -274.724622) (xy 114.595885 -274.725123) (xy 114.648579 -274.733071) (xy 114.699501 -274.748783)
			(xy 114.747512 -274.771909) (xy 114.79154 -274.801931) (xy 114.830602 -274.83818) (xy 114.863826 -274.879846)
			(xy 114.89047 -274.925997) (xy 114.909938 -274.975604) (xy 114.921795 -275.027559) (xy 114.925777 -275.0807)
			(xy 114.923778 -275.107379) (xy 115.15343 -275.107379) (xy 115.15343 -275.054081) (xy 115.161373 -275.001377)
			(xy 115.177083 -274.950447) (xy 115.200209 -274.902426) (xy 115.230233 -274.858389) (xy 115.266485 -274.819318)
			(xy 115.308156 -274.786087) (xy 115.354314 -274.759438) (xy 115.403928 -274.739966) (xy 115.45589 -274.728106)
			(xy 115.50904 -274.724123) (xy 115.56219 -274.728106) (xy 115.614152 -274.739966) (xy 115.663766 -274.759438)
			(xy 115.709924 -274.786087) (xy 115.751595 -274.819318) (xy 115.787847 -274.858389) (xy 115.817871 -274.902426)
			(xy 115.840997 -274.950447) (xy 115.856707 -275.001377) (xy 115.86465 -275.054081) (xy 115.865148 -275.08073)
			(xy 115.86465 -275.107379) (xy 116.093484 -275.107379) (xy 116.093484 -275.054081) (xy 116.101427 -275.001377)
			(xy 116.117137 -274.950447) (xy 116.140263 -274.902426) (xy 116.170287 -274.858389) (xy 116.206539 -274.819318)
			(xy 116.24821 -274.786087) (xy 116.294368 -274.759438) (xy 116.343982 -274.739966) (xy 116.395944 -274.728106)
			(xy 116.449094 -274.724123) (xy 116.502244 -274.728106) (xy 116.554206 -274.739966) (xy 116.60382 -274.759438)
			(xy 116.649978 -274.786087) (xy 116.691649 -274.819318) (xy 116.727901 -274.858389) (xy 116.757925 -274.902426)
			(xy 116.781051 -274.950447) (xy 116.796761 -275.001377) (xy 116.804704 -275.054081) (xy 116.805202 -275.08073)
			(xy 116.804704 -275.107379) (xy 119.852938 -275.107379) (xy 119.852938 -275.054081) (xy 119.860881 -275.001377)
			(xy 119.876591 -274.950447) (xy 119.899717 -274.902426) (xy 119.929741 -274.858389) (xy 119.965993 -274.819318)
			(xy 120.007664 -274.786087) (xy 120.053822 -274.759438) (xy 120.103436 -274.739966) (xy 120.155398 -274.728106)
			(xy 120.208548 -274.724123) (xy 120.261698 -274.728106) (xy 120.31366 -274.739966) (xy 120.363274 -274.759438)
			(xy 120.409432 -274.786087) (xy 120.451103 -274.819318) (xy 120.487355 -274.858389) (xy 120.517379 -274.902426)
			(xy 120.540505 -274.950447) (xy 120.556215 -275.001377) (xy 120.564158 -275.054081) (xy 120.564656 -275.08073)
			(xy 120.564163 -275.107125) (xy 120.792484 -275.107125) (xy 120.792484 -275.053827) (xy 120.800427 -275.001123)
			(xy 120.816137 -274.950193) (xy 120.839263 -274.902172) (xy 120.869287 -274.858135) (xy 120.905539 -274.819064)
			(xy 120.94721 -274.785833) (xy 120.993368 -274.759184) (xy 121.042982 -274.739712) (xy 121.094944 -274.727852)
			(xy 121.148094 -274.723869) (xy 121.201244 -274.727852) (xy 121.253206 -274.739712) (xy 121.30282 -274.759184)
			(xy 121.348978 -274.785833) (xy 121.390649 -274.819064) (xy 121.426901 -274.858135) (xy 121.456925 -274.902172)
			(xy 121.480051 -274.950193) (xy 121.495761 -275.001123) (xy 121.503704 -275.053827) (xy 121.504202 -275.080476)
			(xy 121.503704 -275.107125) (xy 121.503666 -275.107379) (xy 121.732538 -275.107379) (xy 121.732538 -275.054081)
			(xy 121.740481 -275.001377) (xy 121.756191 -274.950447) (xy 121.779317 -274.902426) (xy 121.809341 -274.858389)
			(xy 121.845593 -274.819318) (xy 121.887264 -274.786087) (xy 121.933422 -274.759438) (xy 121.983036 -274.739966)
			(xy 122.034998 -274.728106) (xy 122.088148 -274.724123) (xy 122.141298 -274.728106) (xy 122.19326 -274.739966)
			(xy 122.242874 -274.759438) (xy 122.289032 -274.786087) (xy 122.330703 -274.819318) (xy 122.366955 -274.858389)
			(xy 122.396979 -274.902426) (xy 122.420105 -274.950447) (xy 122.435815 -275.001377) (xy 122.443758 -275.054081)
			(xy 122.444256 -275.08073) (xy 122.443758 -275.107379) (xy 122.672338 -275.107379) (xy 122.672338 -275.054081)
			(xy 122.680281 -275.001377) (xy 122.695991 -274.950447) (xy 122.719117 -274.902426) (xy 122.749141 -274.858389)
			(xy 122.785393 -274.819318) (xy 122.827064 -274.786087) (xy 122.873222 -274.759438) (xy 122.922836 -274.739966)
			(xy 122.974798 -274.728106) (xy 123.027948 -274.724123) (xy 123.081098 -274.728106) (xy 123.13306 -274.739966)
			(xy 123.182674 -274.759438) (xy 123.228832 -274.786087) (xy 123.270503 -274.819318) (xy 123.306755 -274.858389)
			(xy 123.336779 -274.902426) (xy 123.359905 -274.950447) (xy 123.375615 -275.001377) (xy 123.383558 -275.054081)
			(xy 123.384056 -275.08073) (xy 123.383558 -275.107379) (xy 123.612138 -275.107379) (xy 123.612138 -275.054081)
			(xy 123.620081 -275.001377) (xy 123.635791 -274.950447) (xy 123.658917 -274.902426) (xy 123.688941 -274.858389)
			(xy 123.725193 -274.819318) (xy 123.766864 -274.786087) (xy 123.813022 -274.759438) (xy 123.862636 -274.739966)
			(xy 123.914598 -274.728106) (xy 123.967748 -274.724123) (xy 124.020898 -274.728106) (xy 124.07286 -274.739966)
			(xy 124.122474 -274.759438) (xy 124.168632 -274.786087) (xy 124.210303 -274.819318) (xy 124.246555 -274.858389)
			(xy 124.276579 -274.902426) (xy 124.299705 -274.950447) (xy 124.315415 -275.001377) (xy 124.323358 -275.054081)
			(xy 124.323856 -275.08073) (xy 124.323358 -275.107379) (xy 124.551938 -275.107379) (xy 124.551938 -275.054081)
			(xy 124.559881 -275.001377) (xy 124.575591 -274.950447) (xy 124.598717 -274.902426) (xy 124.628741 -274.858389)
			(xy 124.664993 -274.819318) (xy 124.706664 -274.786087) (xy 124.752822 -274.759438) (xy 124.802436 -274.739966)
			(xy 124.854398 -274.728106) (xy 124.907548 -274.724123) (xy 124.960698 -274.728106) (xy 125.01266 -274.739966)
			(xy 125.062274 -274.759438) (xy 125.108432 -274.786087) (xy 125.150103 -274.819318) (xy 125.186355 -274.858389)
			(xy 125.216379 -274.902426) (xy 125.239505 -274.950447) (xy 125.255215 -275.001377) (xy 125.263158 -275.054081)
			(xy 125.263656 -275.08073) (xy 125.263158 -275.107379) (xy 125.491738 -275.107379) (xy 125.491738 -275.054081)
			(xy 125.499681 -275.001377) (xy 125.515391 -274.950447) (xy 125.538517 -274.902426) (xy 125.568541 -274.858389)
			(xy 125.604793 -274.819318) (xy 125.646464 -274.786087) (xy 125.692622 -274.759438) (xy 125.742236 -274.739966)
			(xy 125.794198 -274.728106) (xy 125.847348 -274.724123) (xy 125.900498 -274.728106) (xy 125.95246 -274.739966)
			(xy 126.002074 -274.759438) (xy 126.048232 -274.786087) (xy 126.089903 -274.819318) (xy 126.126155 -274.858389)
			(xy 126.156179 -274.902426) (xy 126.179305 -274.950447) (xy 126.195015 -275.001377) (xy 126.202958 -275.054081)
			(xy 126.203456 -275.08073) (xy 126.202958 -275.107379) (xy 126.431284 -275.107379) (xy 126.431284 -275.054081)
			(xy 126.439227 -275.001377) (xy 126.454937 -274.950447) (xy 126.478063 -274.902426) (xy 126.508087 -274.858389)
			(xy 126.544339 -274.819318) (xy 126.58601 -274.786087) (xy 126.632168 -274.759438) (xy 126.681782 -274.739966)
			(xy 126.733744 -274.728106) (xy 126.786894 -274.724123) (xy 126.840044 -274.728106) (xy 126.892006 -274.739966)
			(xy 126.94162 -274.759438) (xy 126.987778 -274.786087) (xy 127.029449 -274.819318) (xy 127.065701 -274.858389)
			(xy 127.095725 -274.902426) (xy 127.118851 -274.950447) (xy 127.134561 -275.001377) (xy 127.142504 -275.054081)
			(xy 127.143002 -275.08073) (xy 127.142504 -275.107379) (xy 127.371338 -275.107379) (xy 127.371338 -275.054081)
			(xy 127.379281 -275.001377) (xy 127.394991 -274.950447) (xy 127.418117 -274.902426) (xy 127.448141 -274.858389)
			(xy 127.484393 -274.819318) (xy 127.526064 -274.786087) (xy 127.572222 -274.759438) (xy 127.621836 -274.739966)
			(xy 127.673798 -274.728106) (xy 127.726948 -274.724123) (xy 127.780098 -274.728106) (xy 127.83206 -274.739966)
			(xy 127.881674 -274.759438) (xy 127.927832 -274.786087) (xy 127.969503 -274.819318) (xy 128.005755 -274.858389)
			(xy 128.035779 -274.902426) (xy 128.058905 -274.950447) (xy 128.074615 -275.001377) (xy 128.082558 -275.054081)
			(xy 128.083056 -275.08073) (xy 128.082558 -275.107379) (xy 128.311138 -275.107379) (xy 128.311138 -275.054081)
			(xy 128.319081 -275.001377) (xy 128.334791 -274.950447) (xy 128.357917 -274.902426) (xy 128.387941 -274.858389)
			(xy 128.424193 -274.819318) (xy 128.465864 -274.786087) (xy 128.512022 -274.759438) (xy 128.561636 -274.739966)
			(xy 128.613598 -274.728106) (xy 128.666748 -274.724123) (xy 128.719898 -274.728106) (xy 128.77186 -274.739966)
			(xy 128.821474 -274.759438) (xy 128.867632 -274.786087) (xy 128.909303 -274.819318) (xy 128.945555 -274.858389)
			(xy 128.975579 -274.902426) (xy 128.998705 -274.950447) (xy 129.014415 -275.001377) (xy 129.022358 -275.054081)
			(xy 129.022856 -275.08073) (xy 129.022358 -275.107379) (xy 129.250938 -275.107379) (xy 129.250938 -275.054081)
			(xy 129.258881 -275.001377) (xy 129.274591 -274.950447) (xy 129.297717 -274.902426) (xy 129.327741 -274.858389)
			(xy 129.363993 -274.819318) (xy 129.405664 -274.786087) (xy 129.451822 -274.759438) (xy 129.501436 -274.739966)
			(xy 129.553398 -274.728106) (xy 129.606548 -274.724123) (xy 129.659698 -274.728106) (xy 129.71166 -274.739966)
			(xy 129.761274 -274.759438) (xy 129.807432 -274.786087) (xy 129.849103 -274.819318) (xy 129.885355 -274.858389)
			(xy 129.915379 -274.902426) (xy 129.938505 -274.950447) (xy 129.954215 -275.001377) (xy 129.962158 -275.054081)
			(xy 129.962656 -275.08073) (xy 129.962158 -275.107379) (xy 130.190738 -275.107379) (xy 130.190738 -275.054081)
			(xy 130.198681 -275.001377) (xy 130.214391 -274.950447) (xy 130.237517 -274.902426) (xy 130.267541 -274.858389)
			(xy 130.303793 -274.819318) (xy 130.345464 -274.786087) (xy 130.391622 -274.759438) (xy 130.441236 -274.739966)
			(xy 130.493198 -274.728106) (xy 130.546348 -274.724123) (xy 130.599498 -274.728106) (xy 130.65146 -274.739966)
			(xy 130.701074 -274.759438) (xy 130.747232 -274.786087) (xy 130.788903 -274.819318) (xy 130.825155 -274.858389)
			(xy 130.855179 -274.902426) (xy 130.878305 -274.950447) (xy 130.894015 -275.001377) (xy 130.901958 -275.054081)
			(xy 130.902456 -275.08073) (xy 130.901958 -275.107379) (xy 130.894015 -275.160083) (xy 130.878305 -275.211013)
			(xy 130.855179 -275.259034) (xy 130.825155 -275.303071) (xy 130.788903 -275.342142) (xy 130.747232 -275.375373)
			(xy 130.701074 -275.402022) (xy 130.65146 -275.421494) (xy 130.599498 -275.433354) (xy 130.546348 -275.437338)
			(xy 130.493198 -275.433354) (xy 130.441236 -275.421494) (xy 130.391622 -275.402022) (xy 130.345464 -275.375373)
			(xy 130.303793 -275.342142) (xy 130.267541 -275.303071) (xy 130.237517 -275.259034) (xy 130.214391 -275.211013)
			(xy 130.198681 -275.160083) (xy 130.190738 -275.107379) (xy 129.962158 -275.107379) (xy 129.954215 -275.160083)
			(xy 129.938505 -275.211013) (xy 129.915379 -275.259034) (xy 129.885355 -275.303071) (xy 129.849103 -275.342142)
			(xy 129.807432 -275.375373) (xy 129.761274 -275.402022) (xy 129.71166 -275.421494) (xy 129.659698 -275.433354)
			(xy 129.606548 -275.437338) (xy 129.553398 -275.433354) (xy 129.501436 -275.421494) (xy 129.451822 -275.402022)
			(xy 129.405664 -275.375373) (xy 129.363993 -275.342142) (xy 129.327741 -275.303071) (xy 129.297717 -275.259034)
			(xy 129.274591 -275.211013) (xy 129.258881 -275.160083) (xy 129.250938 -275.107379) (xy 129.022358 -275.107379)
			(xy 129.014415 -275.160083) (xy 128.998705 -275.211013) (xy 128.975579 -275.259034) (xy 128.945555 -275.303071)
			(xy 128.909303 -275.342142) (xy 128.867632 -275.375373) (xy 128.821474 -275.402022) (xy 128.77186 -275.421494)
			(xy 128.719898 -275.433354) (xy 128.666748 -275.437338) (xy 128.613598 -275.433354) (xy 128.561636 -275.421494)
			(xy 128.512022 -275.402022) (xy 128.465864 -275.375373) (xy 128.424193 -275.342142) (xy 128.387941 -275.303071)
			(xy 128.357917 -275.259034) (xy 128.334791 -275.211013) (xy 128.319081 -275.160083) (xy 128.311138 -275.107379)
			(xy 128.082558 -275.107379) (xy 128.074615 -275.160083) (xy 128.058905 -275.211013) (xy 128.035779 -275.259034)
			(xy 128.005755 -275.303071) (xy 127.969503 -275.342142) (xy 127.927832 -275.375373) (xy 127.881674 -275.402022)
			(xy 127.83206 -275.421494) (xy 127.780098 -275.433354) (xy 127.726948 -275.437338) (xy 127.673798 -275.433354)
			(xy 127.621836 -275.421494) (xy 127.572222 -275.402022) (xy 127.526064 -275.375373) (xy 127.484393 -275.342142)
			(xy 127.448141 -275.303071) (xy 127.418117 -275.259034) (xy 127.394991 -275.211013) (xy 127.379281 -275.160083)
			(xy 127.371338 -275.107379) (xy 127.142504 -275.107379) (xy 127.134561 -275.160083) (xy 127.118851 -275.211013)
			(xy 127.095725 -275.259034) (xy 127.065701 -275.303071) (xy 127.029449 -275.342142) (xy 126.987778 -275.375373)
			(xy 126.94162 -275.402022) (xy 126.892006 -275.421494) (xy 126.840044 -275.433354) (xy 126.786894 -275.437338)
			(xy 126.733744 -275.433354) (xy 126.681782 -275.421494) (xy 126.632168 -275.402022) (xy 126.58601 -275.375373)
			(xy 126.544339 -275.342142) (xy 126.508087 -275.303071) (xy 126.478063 -275.259034) (xy 126.454937 -275.211013)
			(xy 126.439227 -275.160083) (xy 126.431284 -275.107379) (xy 126.202958 -275.107379) (xy 126.195015 -275.160083)
			(xy 126.179305 -275.211013) (xy 126.156179 -275.259034) (xy 126.126155 -275.303071) (xy 126.089903 -275.342142)
			(xy 126.048232 -275.375373) (xy 126.002074 -275.402022) (xy 125.95246 -275.421494) (xy 125.900498 -275.433354)
			(xy 125.847348 -275.437338) (xy 125.794198 -275.433354) (xy 125.742236 -275.421494) (xy 125.692622 -275.402022)
			(xy 125.646464 -275.375373) (xy 125.604793 -275.342142) (xy 125.568541 -275.303071) (xy 125.538517 -275.259034)
			(xy 125.515391 -275.211013) (xy 125.499681 -275.160083) (xy 125.491738 -275.107379) (xy 125.263158 -275.107379)
			(xy 125.255215 -275.160083) (xy 125.239505 -275.211013) (xy 125.216379 -275.259034) (xy 125.186355 -275.303071)
			(xy 125.150103 -275.342142) (xy 125.108432 -275.375373) (xy 125.062274 -275.402022) (xy 125.01266 -275.421494)
			(xy 124.960698 -275.433354) (xy 124.907548 -275.437338) (xy 124.854398 -275.433354) (xy 124.802436 -275.421494)
			(xy 124.752822 -275.402022) (xy 124.706664 -275.375373) (xy 124.664993 -275.342142) (xy 124.628741 -275.303071)
			(xy 124.598717 -275.259034) (xy 124.575591 -275.211013) (xy 124.559881 -275.160083) (xy 124.551938 -275.107379)
			(xy 124.323358 -275.107379) (xy 124.315415 -275.160083) (xy 124.299705 -275.211013) (xy 124.276579 -275.259034)
			(xy 124.246555 -275.303071) (xy 124.210303 -275.342142) (xy 124.168632 -275.375373) (xy 124.122474 -275.402022)
			(xy 124.07286 -275.421494) (xy 124.020898 -275.433354) (xy 123.967748 -275.437338) (xy 123.914598 -275.433354)
			(xy 123.862636 -275.421494) (xy 123.813022 -275.402022) (xy 123.766864 -275.375373) (xy 123.725193 -275.342142)
			(xy 123.688941 -275.303071) (xy 123.658917 -275.259034) (xy 123.635791 -275.211013) (xy 123.620081 -275.160083)
			(xy 123.612138 -275.107379) (xy 123.383558 -275.107379) (xy 123.375615 -275.160083) (xy 123.359905 -275.211013)
			(xy 123.336779 -275.259034) (xy 123.306755 -275.303071) (xy 123.270503 -275.342142) (xy 123.228832 -275.375373)
			(xy 123.182674 -275.402022) (xy 123.13306 -275.421494) (xy 123.081098 -275.433354) (xy 123.027948 -275.437338)
			(xy 122.974798 -275.433354) (xy 122.922836 -275.421494) (xy 122.873222 -275.402022) (xy 122.827064 -275.375373)
			(xy 122.785393 -275.342142) (xy 122.749141 -275.303071) (xy 122.719117 -275.259034) (xy 122.695991 -275.211013)
			(xy 122.680281 -275.160083) (xy 122.672338 -275.107379) (xy 122.443758 -275.107379) (xy 122.435815 -275.160083)
			(xy 122.420105 -275.211013) (xy 122.396979 -275.259034) (xy 122.366955 -275.303071) (xy 122.330703 -275.342142)
			(xy 122.289032 -275.375373) (xy 122.242874 -275.402022) (xy 122.19326 -275.421494) (xy 122.141298 -275.433354)
			(xy 122.088148 -275.437338) (xy 122.034998 -275.433354) (xy 121.983036 -275.421494) (xy 121.933422 -275.402022)
			(xy 121.887264 -275.375373) (xy 121.845593 -275.342142) (xy 121.809341 -275.303071) (xy 121.779317 -275.259034)
			(xy 121.756191 -275.211013) (xy 121.740481 -275.160083) (xy 121.732538 -275.107379) (xy 121.503666 -275.107379)
			(xy 121.495761 -275.159829) (xy 121.480051 -275.210759) (xy 121.456925 -275.25878) (xy 121.426901 -275.302817)
			(xy 121.390649 -275.341888) (xy 121.348978 -275.375119) (xy 121.30282 -275.401768) (xy 121.253206 -275.42124)
			(xy 121.201244 -275.4331) (xy 121.148094 -275.437084) (xy 121.094944 -275.4331) (xy 121.042982 -275.42124)
			(xy 120.993368 -275.401768) (xy 120.94721 -275.375119) (xy 120.905539 -275.341888) (xy 120.869287 -275.302817)
			(xy 120.839263 -275.25878) (xy 120.816137 -275.210759) (xy 120.800427 -275.159829) (xy 120.792484 -275.107125)
			(xy 120.564163 -275.107125) (xy 120.564158 -275.107379) (xy 120.556215 -275.160083) (xy 120.540505 -275.211013)
			(xy 120.517379 -275.259034) (xy 120.487355 -275.303071) (xy 120.451103 -275.342142) (xy 120.409432 -275.375373)
			(xy 120.363274 -275.402022) (xy 120.31366 -275.421494) (xy 120.261698 -275.433354) (xy 120.208548 -275.437338)
			(xy 120.155398 -275.433354) (xy 120.103436 -275.421494) (xy 120.053822 -275.402022) (xy 120.007664 -275.375373)
			(xy 119.965993 -275.342142) (xy 119.929741 -275.303071) (xy 119.899717 -275.259034) (xy 119.876591 -275.211013)
			(xy 119.860881 -275.160083) (xy 119.852938 -275.107379) (xy 116.804704 -275.107379) (xy 116.796761 -275.160083)
			(xy 116.781051 -275.211013) (xy 116.757925 -275.259034) (xy 116.727901 -275.303071) (xy 116.691649 -275.342142)
			(xy 116.649978 -275.375373) (xy 116.60382 -275.402022) (xy 116.554206 -275.421494) (xy 116.502244 -275.433354)
			(xy 116.449094 -275.437338) (xy 116.395944 -275.433354) (xy 116.343982 -275.421494) (xy 116.294368 -275.402022)
			(xy 116.24821 -275.375373) (xy 116.206539 -275.342142) (xy 116.170287 -275.303071) (xy 116.140263 -275.259034)
			(xy 116.117137 -275.211013) (xy 116.101427 -275.160083) (xy 116.093484 -275.107379) (xy 115.86465 -275.107379)
			(xy 115.856707 -275.160083) (xy 115.840997 -275.211013) (xy 115.817871 -275.259034) (xy 115.787847 -275.303071)
			(xy 115.751595 -275.342142) (xy 115.709924 -275.375373) (xy 115.663766 -275.402022) (xy 115.614152 -275.421494)
			(xy 115.56219 -275.433354) (xy 115.50904 -275.437338) (xy 115.45589 -275.433354) (xy 115.403928 -275.421494)
			(xy 115.354314 -275.402022) (xy 115.308156 -275.375373) (xy 115.266485 -275.342142) (xy 115.230233 -275.303071)
			(xy 115.200209 -275.259034) (xy 115.177083 -275.211013) (xy 115.161373 -275.160083) (xy 115.15343 -275.107379)
			(xy 114.923778 -275.107379) (xy 114.921795 -275.133841) (xy 114.909938 -275.185796) (xy 114.89047 -275.235403)
			(xy 114.863826 -275.281554) (xy 114.830602 -275.32322) (xy 114.79154 -275.359469) (xy 114.747512 -275.389491)
			(xy 114.699501 -275.412617) (xy 114.648579 -275.428329) (xy 114.595885 -275.436277) (xy 114.56924 -275.436838)
			(xy 114.551852 -275.436602) (xy 114.517247 -275.433166) (xy 114.500152 -275.42998) (xy 114.485332 -275.427588)
			(xy 114.455475 -275.430554) (xy 114.427765 -275.44206) (xy 114.404588 -275.461115) (xy 114.387942 -275.486079)
			(xy 114.37926 -275.514799) (xy 114.37874 -275.529802) (xy 114.37874 -275.673312) (xy 114.39487 -275.694431)
			(xy 114.421352 -275.740501) (xy 114.440698 -275.789993) (xy 114.45248 -275.841809) (xy 114.456437 -275.8948)
			(xy 114.454447 -275.921449) (xy 115.623584 -275.921449) (xy 115.623584 -275.868151) (xy 115.631527 -275.815447)
			(xy 115.647237 -275.764517) (xy 115.670363 -275.716496) (xy 115.700387 -275.672459) (xy 115.736639 -275.633388)
			(xy 115.77831 -275.600157) (xy 115.824468 -275.573508) (xy 115.874082 -275.554036) (xy 115.926044 -275.542176)
			(xy 115.979194 -275.538193) (xy 116.032344 -275.542176) (xy 116.084306 -275.554036) (xy 116.13392 -275.573508)
			(xy 116.180078 -275.600157) (xy 116.221749 -275.633388) (xy 116.258001 -275.672459) (xy 116.288025 -275.716496)
			(xy 116.311151 -275.764517) (xy 116.326861 -275.815447) (xy 116.334804 -275.868151) (xy 116.335302 -275.8948)
			(xy 116.334804 -275.921449) (xy 116.563384 -275.921449) (xy 116.563384 -275.868151) (xy 116.571327 -275.815447)
			(xy 116.587037 -275.764517) (xy 116.610163 -275.716496) (xy 116.640187 -275.672459) (xy 116.676439 -275.633388)
			(xy 116.71811 -275.600157) (xy 116.764268 -275.573508) (xy 116.813882 -275.554036) (xy 116.865844 -275.542176)
			(xy 116.918994 -275.538193) (xy 116.972144 -275.542176) (xy 117.024106 -275.554036) (xy 117.07372 -275.573508)
			(xy 117.119878 -275.600157) (xy 117.161549 -275.633388) (xy 117.197801 -275.672459) (xy 117.227825 -275.716496)
			(xy 117.250951 -275.764517) (xy 117.266661 -275.815447) (xy 117.274604 -275.868151) (xy 117.275102 -275.8948)
			(xy 117.274604 -275.921449) (xy 117.503184 -275.921449) (xy 117.503184 -275.868151) (xy 117.511127 -275.815447)
			(xy 117.526837 -275.764517) (xy 117.549963 -275.716496) (xy 117.579987 -275.672459) (xy 117.616239 -275.633388)
			(xy 117.65791 -275.600157) (xy 117.704068 -275.573508) (xy 117.753682 -275.554036) (xy 117.805644 -275.542176)
			(xy 117.858794 -275.538193) (xy 117.911944 -275.542176) (xy 117.963906 -275.554036) (xy 118.01352 -275.573508)
			(xy 118.059678 -275.600157) (xy 118.101349 -275.633388) (xy 118.137601 -275.672459) (xy 118.167625 -275.716496)
			(xy 118.190751 -275.764517) (xy 118.206461 -275.815447) (xy 118.214404 -275.868151) (xy 118.214902 -275.8948)
			(xy 118.214404 -275.921449) (xy 118.443238 -275.921449) (xy 118.443238 -275.868151) (xy 118.451181 -275.815447)
			(xy 118.466891 -275.764517) (xy 118.490017 -275.716496) (xy 118.520041 -275.672459) (xy 118.556293 -275.633388)
			(xy 118.597964 -275.600157) (xy 118.644122 -275.573508) (xy 118.693736 -275.554036) (xy 118.745698 -275.542176)
			(xy 118.798848 -275.538193) (xy 118.851998 -275.542176) (xy 118.90396 -275.554036) (xy 118.953574 -275.573508)
			(xy 118.999732 -275.600157) (xy 119.041403 -275.633388) (xy 119.077655 -275.672459) (xy 119.107679 -275.716496)
			(xy 119.130805 -275.764517) (xy 119.146515 -275.815447) (xy 119.154458 -275.868151) (xy 119.154956 -275.8948)
			(xy 119.154463 -275.921195) (xy 119.383038 -275.921195) (xy 119.383038 -275.867897) (xy 119.390981 -275.815193)
			(xy 119.406691 -275.764263) (xy 119.429817 -275.716242) (xy 119.459841 -275.672205) (xy 119.496093 -275.633134)
			(xy 119.537764 -275.599903) (xy 119.583922 -275.573254) (xy 119.633536 -275.553782) (xy 119.685498 -275.541922)
			(xy 119.738648 -275.537939) (xy 119.791798 -275.541922) (xy 119.84376 -275.553782) (xy 119.893374 -275.573254)
			(xy 119.939532 -275.599903) (xy 119.981203 -275.633134) (xy 120.017455 -275.672205) (xy 120.047479 -275.716242)
			(xy 120.070605 -275.764263) (xy 120.086315 -275.815193) (xy 120.094258 -275.867897) (xy 120.094756 -275.894546)
			(xy 120.094258 -275.921195) (xy 120.322838 -275.921195) (xy 120.322838 -275.867897) (xy 120.330781 -275.815193)
			(xy 120.346491 -275.764263) (xy 120.369617 -275.716242) (xy 120.399641 -275.672205) (xy 120.435893 -275.633134)
			(xy 120.477564 -275.599903) (xy 120.523722 -275.573254) (xy 120.573336 -275.553782) (xy 120.625298 -275.541922)
			(xy 120.678448 -275.537939) (xy 120.731598 -275.541922) (xy 120.78356 -275.553782) (xy 120.833174 -275.573254)
			(xy 120.879332 -275.599903) (xy 120.921003 -275.633134) (xy 120.957255 -275.672205) (xy 120.987279 -275.716242)
			(xy 121.010405 -275.764263) (xy 121.026115 -275.815193) (xy 121.034058 -275.867897) (xy 121.034556 -275.894546)
			(xy 121.034058 -275.921195) (xy 121.262638 -275.921195) (xy 121.262638 -275.867897) (xy 121.270581 -275.815193)
			(xy 121.286291 -275.764263) (xy 121.309417 -275.716242) (xy 121.339441 -275.672205) (xy 121.375693 -275.633134)
			(xy 121.417364 -275.599903) (xy 121.463522 -275.573254) (xy 121.513136 -275.553782) (xy 121.565098 -275.541922)
			(xy 121.618248 -275.537939) (xy 121.671398 -275.541922) (xy 121.72336 -275.553782) (xy 121.772974 -275.573254)
			(xy 121.819132 -275.599903) (xy 121.860803 -275.633134) (xy 121.897055 -275.672205) (xy 121.927079 -275.716242)
			(xy 121.950205 -275.764263) (xy 121.965915 -275.815193) (xy 121.973858 -275.867897) (xy 121.974356 -275.894546)
			(xy 121.973858 -275.921195) (xy 121.97382 -275.921449) (xy 122.202438 -275.921449) (xy 122.202438 -275.868151)
			(xy 122.210381 -275.815447) (xy 122.226091 -275.764517) (xy 122.249217 -275.716496) (xy 122.279241 -275.672459)
			(xy 122.315493 -275.633388) (xy 122.357164 -275.600157) (xy 122.403322 -275.573508) (xy 122.452936 -275.554036)
			(xy 122.504898 -275.542176) (xy 122.558048 -275.538193) (xy 122.611198 -275.542176) (xy 122.66316 -275.554036)
			(xy 122.712774 -275.573508) (xy 122.758932 -275.600157) (xy 122.800603 -275.633388) (xy 122.836855 -275.672459)
			(xy 122.866879 -275.716496) (xy 122.890005 -275.764517) (xy 122.905715 -275.815447) (xy 122.913658 -275.868151)
			(xy 122.914156 -275.8948) (xy 122.913658 -275.921449) (xy 123.141984 -275.921449) (xy 123.141984 -275.868151)
			(xy 123.149927 -275.815447) (xy 123.165637 -275.764517) (xy 123.188763 -275.716496) (xy 123.218787 -275.672459)
			(xy 123.255039 -275.633388) (xy 123.29671 -275.600157) (xy 123.342868 -275.573508) (xy 123.392482 -275.554036)
			(xy 123.444444 -275.542176) (xy 123.497594 -275.538193) (xy 123.550744 -275.542176) (xy 123.602706 -275.554036)
			(xy 123.65232 -275.573508) (xy 123.698478 -275.600157) (xy 123.740149 -275.633388) (xy 123.776401 -275.672459)
			(xy 123.806425 -275.716496) (xy 123.829551 -275.764517) (xy 123.845261 -275.815447) (xy 123.853204 -275.868151)
			(xy 123.853702 -275.8948) (xy 123.853204 -275.921449) (xy 124.081784 -275.921449) (xy 124.081784 -275.868151)
			(xy 124.089727 -275.815447) (xy 124.105437 -275.764517) (xy 124.128563 -275.716496) (xy 124.158587 -275.672459)
			(xy 124.194839 -275.633388) (xy 124.23651 -275.600157) (xy 124.282668 -275.573508) (xy 124.332282 -275.554036)
			(xy 124.384244 -275.542176) (xy 124.437394 -275.538193) (xy 124.490544 -275.542176) (xy 124.542506 -275.554036)
			(xy 124.59212 -275.573508) (xy 124.638278 -275.600157) (xy 124.679949 -275.633388) (xy 124.716201 -275.672459)
			(xy 124.746225 -275.716496) (xy 124.769351 -275.764517) (xy 124.785061 -275.815447) (xy 124.793004 -275.868151)
			(xy 124.793502 -275.8948) (xy 124.793004 -275.921449) (xy 125.021584 -275.921449) (xy 125.021584 -275.868151)
			(xy 125.029527 -275.815447) (xy 125.045237 -275.764517) (xy 125.068363 -275.716496) (xy 125.098387 -275.672459)
			(xy 125.134639 -275.633388) (xy 125.17631 -275.600157) (xy 125.222468 -275.573508) (xy 125.272082 -275.554036)
			(xy 125.324044 -275.542176) (xy 125.377194 -275.538193) (xy 125.430344 -275.542176) (xy 125.482306 -275.554036)
			(xy 125.53192 -275.573508) (xy 125.578078 -275.600157) (xy 125.619749 -275.633388) (xy 125.656001 -275.672459)
			(xy 125.686025 -275.716496) (xy 125.709151 -275.764517) (xy 125.724861 -275.815447) (xy 125.732804 -275.868151)
			(xy 125.733302 -275.8948) (xy 125.732804 -275.921449) (xy 125.961384 -275.921449) (xy 125.961384 -275.868151)
			(xy 125.969327 -275.815447) (xy 125.985037 -275.764517) (xy 126.008163 -275.716496) (xy 126.038187 -275.672459)
			(xy 126.074439 -275.633388) (xy 126.11611 -275.600157) (xy 126.162268 -275.573508) (xy 126.211882 -275.554036)
			(xy 126.263844 -275.542176) (xy 126.316994 -275.538193) (xy 126.370144 -275.542176) (xy 126.422106 -275.554036)
			(xy 126.47172 -275.573508) (xy 126.517878 -275.600157) (xy 126.559549 -275.633388) (xy 126.595801 -275.672459)
			(xy 126.625825 -275.716496) (xy 126.648951 -275.764517) (xy 126.664661 -275.815447) (xy 126.672604 -275.868151)
			(xy 126.673102 -275.8948) (xy 126.672604 -275.921449) (xy 126.901184 -275.921449) (xy 126.901184 -275.868151)
			(xy 126.909127 -275.815447) (xy 126.924837 -275.764517) (xy 126.947963 -275.716496) (xy 126.977987 -275.672459)
			(xy 127.014239 -275.633388) (xy 127.05591 -275.600157) (xy 127.102068 -275.573508) (xy 127.151682 -275.554036)
			(xy 127.203644 -275.542176) (xy 127.256794 -275.538193) (xy 127.309944 -275.542176) (xy 127.361906 -275.554036)
			(xy 127.41152 -275.573508) (xy 127.457678 -275.600157) (xy 127.499349 -275.633388) (xy 127.535601 -275.672459)
			(xy 127.565625 -275.716496) (xy 127.588751 -275.764517) (xy 127.604461 -275.815447) (xy 127.612404 -275.868151)
			(xy 127.612902 -275.8948) (xy 127.612404 -275.921449) (xy 127.840984 -275.921449) (xy 127.840984 -275.868151)
			(xy 127.848927 -275.815447) (xy 127.864637 -275.764517) (xy 127.887763 -275.716496) (xy 127.917787 -275.672459)
			(xy 127.954039 -275.633388) (xy 127.99571 -275.600157) (xy 128.041868 -275.573508) (xy 128.091482 -275.554036)
			(xy 128.143444 -275.542176) (xy 128.196594 -275.538193) (xy 128.249744 -275.542176) (xy 128.301706 -275.554036)
			(xy 128.35132 -275.573508) (xy 128.397478 -275.600157) (xy 128.439149 -275.633388) (xy 128.475401 -275.672459)
			(xy 128.505425 -275.716496) (xy 128.528551 -275.764517) (xy 128.544261 -275.815447) (xy 128.552204 -275.868151)
			(xy 128.552702 -275.8948) (xy 128.552204 -275.921449) (xy 128.781038 -275.921449) (xy 128.781038 -275.868151)
			(xy 128.788981 -275.815447) (xy 128.804691 -275.764517) (xy 128.827817 -275.716496) (xy 128.857841 -275.672459)
			(xy 128.894093 -275.633388) (xy 128.935764 -275.600157) (xy 128.981922 -275.573508) (xy 129.031536 -275.554036)
			(xy 129.083498 -275.542176) (xy 129.136648 -275.538193) (xy 129.189798 -275.542176) (xy 129.24176 -275.554036)
			(xy 129.291374 -275.573508) (xy 129.337532 -275.600157) (xy 129.379203 -275.633388) (xy 129.415455 -275.672459)
			(xy 129.445479 -275.716496) (xy 129.468605 -275.764517) (xy 129.484315 -275.815447) (xy 129.492258 -275.868151)
			(xy 129.492756 -275.8948) (xy 129.492258 -275.921449) (xy 129.720584 -275.921449) (xy 129.720584 -275.868151)
			(xy 129.728527 -275.815447) (xy 129.744237 -275.764517) (xy 129.767363 -275.716496) (xy 129.797387 -275.672459)
			(xy 129.833639 -275.633388) (xy 129.87531 -275.600157) (xy 129.921468 -275.573508) (xy 129.971082 -275.554036)
			(xy 130.023044 -275.542176) (xy 130.076194 -275.538193) (xy 130.129344 -275.542176) (xy 130.181306 -275.554036)
			(xy 130.23092 -275.573508) (xy 130.277078 -275.600157) (xy 130.318749 -275.633388) (xy 130.355001 -275.672459)
			(xy 130.385025 -275.716496) (xy 130.408151 -275.764517) (xy 130.423861 -275.815447) (xy 130.431804 -275.868151)
			(xy 130.432302 -275.8948) (xy 130.431804 -275.921449) (xy 130.660384 -275.921449) (xy 130.660384 -275.868151)
			(xy 130.668327 -275.815447) (xy 130.684037 -275.764517) (xy 130.707163 -275.716496) (xy 130.737187 -275.672459)
			(xy 130.773439 -275.633388) (xy 130.81511 -275.600157) (xy 130.861268 -275.573508) (xy 130.910882 -275.554036)
			(xy 130.962844 -275.542176) (xy 131.015994 -275.538193) (xy 131.069144 -275.542176) (xy 131.121106 -275.554036)
			(xy 131.17072 -275.573508) (xy 131.216878 -275.600157) (xy 131.258549 -275.633388) (xy 131.294801 -275.672459)
			(xy 131.324825 -275.716496) (xy 131.347951 -275.764517) (xy 131.363661 -275.815447) (xy 131.371604 -275.868151)
			(xy 131.372102 -275.8948) (xy 131.371604 -275.921449) (xy 131.363661 -275.974153) (xy 131.347951 -276.025083)
			(xy 131.324825 -276.073104) (xy 131.294801 -276.117141) (xy 131.258549 -276.156212) (xy 131.216878 -276.189443)
			(xy 131.17072 -276.216092) (xy 131.121106 -276.235564) (xy 131.069144 -276.247424) (xy 131.015994 -276.251408)
			(xy 130.962844 -276.247424) (xy 130.910882 -276.235564) (xy 130.861268 -276.216092) (xy 130.81511 -276.189443)
			(xy 130.773439 -276.156212) (xy 130.737187 -276.117141) (xy 130.707163 -276.073104) (xy 130.684037 -276.025083)
			(xy 130.668327 -275.974153) (xy 130.660384 -275.921449) (xy 130.431804 -275.921449) (xy 130.423861 -275.974153)
			(xy 130.408151 -276.025083) (xy 130.385025 -276.073104) (xy 130.355001 -276.117141) (xy 130.318749 -276.156212)
			(xy 130.277078 -276.189443) (xy 130.23092 -276.216092) (xy 130.181306 -276.235564) (xy 130.129344 -276.247424)
			(xy 130.076194 -276.251408) (xy 130.023044 -276.247424) (xy 129.971082 -276.235564) (xy 129.921468 -276.216092)
			(xy 129.87531 -276.189443) (xy 129.833639 -276.156212) (xy 129.797387 -276.117141) (xy 129.767363 -276.073104)
			(xy 129.744237 -276.025083) (xy 129.728527 -275.974153) (xy 129.720584 -275.921449) (xy 129.492258 -275.921449)
			(xy 129.484315 -275.974153) (xy 129.468605 -276.025083) (xy 129.445479 -276.073104) (xy 129.415455 -276.117141)
			(xy 129.379203 -276.156212) (xy 129.337532 -276.189443) (xy 129.291374 -276.216092) (xy 129.24176 -276.235564)
			(xy 129.189798 -276.247424) (xy 129.136648 -276.251408) (xy 129.083498 -276.247424) (xy 129.031536 -276.235564)
			(xy 128.981922 -276.216092) (xy 128.935764 -276.189443) (xy 128.894093 -276.156212) (xy 128.857841 -276.117141)
			(xy 128.827817 -276.073104) (xy 128.804691 -276.025083) (xy 128.788981 -275.974153) (xy 128.781038 -275.921449)
			(xy 128.552204 -275.921449) (xy 128.544261 -275.974153) (xy 128.528551 -276.025083) (xy 128.505425 -276.073104)
			(xy 128.475401 -276.117141) (xy 128.439149 -276.156212) (xy 128.397478 -276.189443) (xy 128.35132 -276.216092)
			(xy 128.301706 -276.235564) (xy 128.249744 -276.247424) (xy 128.196594 -276.251408) (xy 128.143444 -276.247424)
			(xy 128.091482 -276.235564) (xy 128.041868 -276.216092) (xy 127.99571 -276.189443) (xy 127.954039 -276.156212)
			(xy 127.917787 -276.117141) (xy 127.887763 -276.073104) (xy 127.864637 -276.025083) (xy 127.848927 -275.974153)
			(xy 127.840984 -275.921449) (xy 127.612404 -275.921449) (xy 127.604461 -275.974153) (xy 127.588751 -276.025083)
			(xy 127.565625 -276.073104) (xy 127.535601 -276.117141) (xy 127.499349 -276.156212) (xy 127.457678 -276.189443)
			(xy 127.41152 -276.216092) (xy 127.361906 -276.235564) (xy 127.309944 -276.247424) (xy 127.256794 -276.251408)
			(xy 127.203644 -276.247424) (xy 127.151682 -276.235564) (xy 127.102068 -276.216092) (xy 127.05591 -276.189443)
			(xy 127.014239 -276.156212) (xy 126.977987 -276.117141) (xy 126.947963 -276.073104) (xy 126.924837 -276.025083)
			(xy 126.909127 -275.974153) (xy 126.901184 -275.921449) (xy 126.672604 -275.921449) (xy 126.664661 -275.974153)
			(xy 126.648951 -276.025083) (xy 126.625825 -276.073104) (xy 126.595801 -276.117141) (xy 126.559549 -276.156212)
			(xy 126.517878 -276.189443) (xy 126.47172 -276.216092) (xy 126.422106 -276.235564) (xy 126.370144 -276.247424)
			(xy 126.316994 -276.251408) (xy 126.263844 -276.247424) (xy 126.211882 -276.235564) (xy 126.162268 -276.216092)
			(xy 126.11611 -276.189443) (xy 126.074439 -276.156212) (xy 126.038187 -276.117141) (xy 126.008163 -276.073104)
			(xy 125.985037 -276.025083) (xy 125.969327 -275.974153) (xy 125.961384 -275.921449) (xy 125.732804 -275.921449)
			(xy 125.724861 -275.974153) (xy 125.709151 -276.025083) (xy 125.686025 -276.073104) (xy 125.656001 -276.117141)
			(xy 125.619749 -276.156212) (xy 125.578078 -276.189443) (xy 125.53192 -276.216092) (xy 125.482306 -276.235564)
			(xy 125.430344 -276.247424) (xy 125.377194 -276.251408) (xy 125.324044 -276.247424) (xy 125.272082 -276.235564)
			(xy 125.222468 -276.216092) (xy 125.17631 -276.189443) (xy 125.134639 -276.156212) (xy 125.098387 -276.117141)
			(xy 125.068363 -276.073104) (xy 125.045237 -276.025083) (xy 125.029527 -275.974153) (xy 125.021584 -275.921449)
			(xy 124.793004 -275.921449) (xy 124.785061 -275.974153) (xy 124.769351 -276.025083) (xy 124.746225 -276.073104)
			(xy 124.716201 -276.117141) (xy 124.679949 -276.156212) (xy 124.638278 -276.189443) (xy 124.59212 -276.216092)
			(xy 124.542506 -276.235564) (xy 124.490544 -276.247424) (xy 124.437394 -276.251408) (xy 124.384244 -276.247424)
			(xy 124.332282 -276.235564) (xy 124.282668 -276.216092) (xy 124.23651 -276.189443) (xy 124.194839 -276.156212)
			(xy 124.158587 -276.117141) (xy 124.128563 -276.073104) (xy 124.105437 -276.025083) (xy 124.089727 -275.974153)
			(xy 124.081784 -275.921449) (xy 123.853204 -275.921449) (xy 123.845261 -275.974153) (xy 123.829551 -276.025083)
			(xy 123.806425 -276.073104) (xy 123.776401 -276.117141) (xy 123.740149 -276.156212) (xy 123.698478 -276.189443)
			(xy 123.65232 -276.216092) (xy 123.602706 -276.235564) (xy 123.550744 -276.247424) (xy 123.497594 -276.251408)
			(xy 123.444444 -276.247424) (xy 123.392482 -276.235564) (xy 123.342868 -276.216092) (xy 123.29671 -276.189443)
			(xy 123.255039 -276.156212) (xy 123.218787 -276.117141) (xy 123.188763 -276.073104) (xy 123.165637 -276.025083)
			(xy 123.149927 -275.974153) (xy 123.141984 -275.921449) (xy 122.913658 -275.921449) (xy 122.905715 -275.974153)
			(xy 122.890005 -276.025083) (xy 122.866879 -276.073104) (xy 122.836855 -276.117141) (xy 122.800603 -276.156212)
			(xy 122.758932 -276.189443) (xy 122.712774 -276.216092) (xy 122.66316 -276.235564) (xy 122.611198 -276.247424)
			(xy 122.558048 -276.251408) (xy 122.504898 -276.247424) (xy 122.452936 -276.235564) (xy 122.403322 -276.216092)
			(xy 122.357164 -276.189443) (xy 122.315493 -276.156212) (xy 122.279241 -276.117141) (xy 122.249217 -276.073104)
			(xy 122.226091 -276.025083) (xy 122.210381 -275.974153) (xy 122.202438 -275.921449) (xy 121.97382 -275.921449)
			(xy 121.965915 -275.973899) (xy 121.950205 -276.024829) (xy 121.927079 -276.07285) (xy 121.897055 -276.116887)
			(xy 121.860803 -276.155958) (xy 121.819132 -276.189189) (xy 121.772974 -276.215838) (xy 121.72336 -276.23531)
			(xy 121.671398 -276.24717) (xy 121.618248 -276.251154) (xy 121.565098 -276.24717) (xy 121.513136 -276.23531)
			(xy 121.463522 -276.215838) (xy 121.417364 -276.189189) (xy 121.375693 -276.155958) (xy 121.339441 -276.116887)
			(xy 121.309417 -276.07285) (xy 121.286291 -276.024829) (xy 121.270581 -275.973899) (xy 121.262638 -275.921195)
			(xy 121.034058 -275.921195) (xy 121.026115 -275.973899) (xy 121.010405 -276.024829) (xy 120.987279 -276.07285)
			(xy 120.957255 -276.116887) (xy 120.921003 -276.155958) (xy 120.879332 -276.189189) (xy 120.833174 -276.215838)
			(xy 120.78356 -276.23531) (xy 120.731598 -276.24717) (xy 120.678448 -276.251154) (xy 120.625298 -276.24717)
			(xy 120.573336 -276.23531) (xy 120.523722 -276.215838) (xy 120.477564 -276.189189) (xy 120.435893 -276.155958)
			(xy 120.399641 -276.116887) (xy 120.369617 -276.07285) (xy 120.346491 -276.024829) (xy 120.330781 -275.973899)
			(xy 120.322838 -275.921195) (xy 120.094258 -275.921195) (xy 120.086315 -275.973899) (xy 120.070605 -276.024829)
			(xy 120.047479 -276.07285) (xy 120.017455 -276.116887) (xy 119.981203 -276.155958) (xy 119.939532 -276.189189)
			(xy 119.893374 -276.215838) (xy 119.84376 -276.23531) (xy 119.791798 -276.24717) (xy 119.738648 -276.251154)
			(xy 119.685498 -276.24717) (xy 119.633536 -276.23531) (xy 119.583922 -276.215838) (xy 119.537764 -276.189189)
			(xy 119.496093 -276.155958) (xy 119.459841 -276.116887) (xy 119.429817 -276.07285) (xy 119.406691 -276.024829)
			(xy 119.390981 -275.973899) (xy 119.383038 -275.921195) (xy 119.154463 -275.921195) (xy 119.154458 -275.921449)
			(xy 119.146515 -275.974153) (xy 119.130805 -276.025083) (xy 119.107679 -276.073104) (xy 119.077655 -276.117141)
			(xy 119.041403 -276.156212) (xy 118.999732 -276.189443) (xy 118.953574 -276.216092) (xy 118.90396 -276.235564)
			(xy 118.851998 -276.247424) (xy 118.798848 -276.251408) (xy 118.745698 -276.247424) (xy 118.693736 -276.235564)
			(xy 118.644122 -276.216092) (xy 118.597964 -276.189443) (xy 118.556293 -276.156212) (xy 118.520041 -276.117141)
			(xy 118.490017 -276.073104) (xy 118.466891 -276.025083) (xy 118.451181 -275.974153) (xy 118.443238 -275.921449)
			(xy 118.214404 -275.921449) (xy 118.206461 -275.974153) (xy 118.190751 -276.025083) (xy 118.167625 -276.073104)
			(xy 118.137601 -276.117141) (xy 118.101349 -276.156212) (xy 118.059678 -276.189443) (xy 118.01352 -276.216092)
			(xy 117.963906 -276.235564) (xy 117.911944 -276.247424) (xy 117.858794 -276.251408) (xy 117.805644 -276.247424)
			(xy 117.753682 -276.235564) (xy 117.704068 -276.216092) (xy 117.65791 -276.189443) (xy 117.616239 -276.156212)
			(xy 117.579987 -276.117141) (xy 117.549963 -276.073104) (xy 117.526837 -276.025083) (xy 117.511127 -275.974153)
			(xy 117.503184 -275.921449) (xy 117.274604 -275.921449) (xy 117.266661 -275.974153) (xy 117.250951 -276.025083)
			(xy 117.227825 -276.073104) (xy 117.197801 -276.117141) (xy 117.161549 -276.156212) (xy 117.119878 -276.189443)
			(xy 117.07372 -276.216092) (xy 117.024106 -276.235564) (xy 116.972144 -276.247424) (xy 116.918994 -276.251408)
			(xy 116.865844 -276.247424) (xy 116.813882 -276.235564) (xy 116.764268 -276.216092) (xy 116.71811 -276.189443)
			(xy 116.676439 -276.156212) (xy 116.640187 -276.117141) (xy 116.610163 -276.073104) (xy 116.587037 -276.025083)
			(xy 116.571327 -275.974153) (xy 116.563384 -275.921449) (xy 116.334804 -275.921449) (xy 116.326861 -275.974153)
			(xy 116.311151 -276.025083) (xy 116.288025 -276.073104) (xy 116.258001 -276.117141) (xy 116.221749 -276.156212)
			(xy 116.180078 -276.189443) (xy 116.13392 -276.216092) (xy 116.084306 -276.235564) (xy 116.032344 -276.247424)
			(xy 115.979194 -276.251408) (xy 115.926044 -276.247424) (xy 115.874082 -276.235564) (xy 115.824468 -276.216092)
			(xy 115.77831 -276.189443) (xy 115.736639 -276.156212) (xy 115.700387 -276.117141) (xy 115.670363 -276.073104)
			(xy 115.647237 -276.025083) (xy 115.631527 -275.974153) (xy 115.623584 -275.921449) (xy 114.454447 -275.921449)
			(xy 114.45248 -275.947791) (xy 114.440698 -275.999607) (xy 114.421352 -276.049099) (xy 114.39487 -276.095169)
			(xy 114.37874 -276.116288) (xy 114.37874 -276.259798) (xy 114.37926 -276.274792) (xy 114.387948 -276.303492)
			(xy 114.404604 -276.328428) (xy 114.42779 -276.347444) (xy 114.455503 -276.358899) (xy 114.485349 -276.361803)
			(xy 114.500152 -276.359366) (xy 114.517371 -276.356148) (xy 114.552233 -276.352714) (xy 114.569748 -276.352508)
			(xy 114.597728 -276.353061) (xy 114.652999 -276.361822) (xy 114.706218 -276.379121) (xy 114.756077 -276.404532)
			(xy 114.801346 -276.437429) (xy 114.840913 -276.477002) (xy 114.873802 -276.522278) (xy 114.899204 -276.572141)
			(xy 114.916493 -276.625364) (xy 114.925244 -276.680636) (xy 114.925856 -276.708616) (xy 114.92539 -276.735011)
			(xy 115.153684 -276.735011) (xy 115.153684 -276.681713) (xy 115.161627 -276.629009) (xy 115.177337 -276.578079)
			(xy 115.200463 -276.530058) (xy 115.230487 -276.486021) (xy 115.266739 -276.44695) (xy 115.30841 -276.413719)
			(xy 115.354568 -276.38707) (xy 115.404182 -276.367598) (xy 115.456144 -276.355738) (xy 115.509294 -276.351755)
			(xy 115.562444 -276.355738) (xy 115.614406 -276.367598) (xy 115.66402 -276.38707) (xy 115.710178 -276.413719)
			(xy 115.751849 -276.44695) (xy 115.788101 -276.486021) (xy 115.818125 -276.530058) (xy 115.841251 -276.578079)
			(xy 115.856961 -276.629009) (xy 115.864904 -276.681713) (xy 115.865402 -276.708362) (xy 115.864904 -276.735011)
			(xy 116.093484 -276.735011) (xy 116.093484 -276.681713) (xy 116.101427 -276.629009) (xy 116.117137 -276.578079)
			(xy 116.140263 -276.530058) (xy 116.170287 -276.486021) (xy 116.206539 -276.44695) (xy 116.24821 -276.413719)
			(xy 116.294368 -276.38707) (xy 116.343982 -276.367598) (xy 116.395944 -276.355738) (xy 116.449094 -276.351755)
			(xy 116.502244 -276.355738) (xy 116.554206 -276.367598) (xy 116.60382 -276.38707) (xy 116.649978 -276.413719)
			(xy 116.691649 -276.44695) (xy 116.727901 -276.486021) (xy 116.757925 -276.530058) (xy 116.781051 -276.578079)
			(xy 116.796761 -276.629009) (xy 116.804704 -276.681713) (xy 116.805202 -276.708362) (xy 116.804704 -276.735011)
			(xy 117.033284 -276.735011) (xy 117.033284 -276.681713) (xy 117.041227 -276.629009) (xy 117.056937 -276.578079)
			(xy 117.080063 -276.530058) (xy 117.110087 -276.486021) (xy 117.146339 -276.44695) (xy 117.18801 -276.413719)
			(xy 117.234168 -276.38707) (xy 117.283782 -276.367598) (xy 117.335744 -276.355738) (xy 117.388894 -276.351755)
			(xy 117.442044 -276.355738) (xy 117.494006 -276.367598) (xy 117.54362 -276.38707) (xy 117.589778 -276.413719)
			(xy 117.631449 -276.44695) (xy 117.667701 -276.486021) (xy 117.697725 -276.530058) (xy 117.720851 -276.578079)
			(xy 117.736561 -276.629009) (xy 117.744504 -276.681713) (xy 117.745002 -276.708362) (xy 117.744504 -276.735011)
			(xy 117.973084 -276.735011) (xy 117.973084 -276.681713) (xy 117.981027 -276.629009) (xy 117.996737 -276.578079)
			(xy 118.019863 -276.530058) (xy 118.049887 -276.486021) (xy 118.086139 -276.44695) (xy 118.12781 -276.413719)
			(xy 118.173968 -276.38707) (xy 118.223582 -276.367598) (xy 118.275544 -276.355738) (xy 118.328694 -276.351755)
			(xy 118.381844 -276.355738) (xy 118.433806 -276.367598) (xy 118.48342 -276.38707) (xy 118.529578 -276.413719)
			(xy 118.571249 -276.44695) (xy 118.607501 -276.486021) (xy 118.637525 -276.530058) (xy 118.660651 -276.578079)
			(xy 118.676361 -276.629009) (xy 118.684304 -276.681713) (xy 118.684802 -276.708362) (xy 118.684304 -276.735011)
			(xy 118.684266 -276.735265) (xy 118.912884 -276.735265) (xy 118.912884 -276.681967) (xy 118.920827 -276.629263)
			(xy 118.936537 -276.578333) (xy 118.959663 -276.530312) (xy 118.989687 -276.486275) (xy 119.025939 -276.447204)
			(xy 119.06761 -276.413973) (xy 119.113768 -276.387324) (xy 119.163382 -276.367852) (xy 119.215344 -276.355992)
			(xy 119.268494 -276.352009) (xy 119.321644 -276.355992) (xy 119.373606 -276.367852) (xy 119.42322 -276.387324)
			(xy 119.469378 -276.413973) (xy 119.511049 -276.447204) (xy 119.547301 -276.486275) (xy 119.577325 -276.530312)
			(xy 119.600451 -276.578333) (xy 119.616161 -276.629263) (xy 119.624104 -276.681967) (xy 119.624602 -276.708616)
			(xy 119.624109 -276.735011) (xy 119.852684 -276.735011) (xy 119.852684 -276.681713) (xy 119.860627 -276.629009)
			(xy 119.876337 -276.578079) (xy 119.899463 -276.530058) (xy 119.929487 -276.486021) (xy 119.965739 -276.44695)
			(xy 120.00741 -276.413719) (xy 120.053568 -276.38707) (xy 120.103182 -276.367598) (xy 120.155144 -276.355738)
			(xy 120.208294 -276.351755) (xy 120.261444 -276.355738) (xy 120.313406 -276.367598) (xy 120.36302 -276.38707)
			(xy 120.409178 -276.413719) (xy 120.450849 -276.44695) (xy 120.487101 -276.486021) (xy 120.517125 -276.530058)
			(xy 120.540251 -276.578079) (xy 120.555961 -276.629009) (xy 120.563904 -276.681713) (xy 120.564402 -276.708362)
			(xy 120.563904 -276.735011) (xy 120.563866 -276.735265) (xy 120.792738 -276.735265) (xy 120.792738 -276.681967)
			(xy 120.800681 -276.629263) (xy 120.816391 -276.578333) (xy 120.839517 -276.530312) (xy 120.869541 -276.486275)
			(xy 120.905793 -276.447204) (xy 120.947464 -276.413973) (xy 120.993622 -276.387324) (xy 121.043236 -276.367852)
			(xy 121.095198 -276.355992) (xy 121.148348 -276.352009) (xy 121.201498 -276.355992) (xy 121.25346 -276.367852)
			(xy 121.303074 -276.387324) (xy 121.349232 -276.413973) (xy 121.390903 -276.447204) (xy 121.427155 -276.486275)
			(xy 121.457179 -276.530312) (xy 121.480305 -276.578333) (xy 121.496015 -276.629263) (xy 121.503958 -276.681967)
			(xy 121.504456 -276.708616) (xy 121.503958 -276.735265) (xy 122.672338 -276.735265) (xy 122.672338 -276.681967)
			(xy 122.680281 -276.629263) (xy 122.695991 -276.578333) (xy 122.719117 -276.530312) (xy 122.749141 -276.486275)
			(xy 122.785393 -276.447204) (xy 122.827064 -276.413973) (xy 122.873222 -276.387324) (xy 122.922836 -276.367852)
			(xy 122.974798 -276.355992) (xy 123.027948 -276.352009) (xy 123.081098 -276.355992) (xy 123.13306 -276.367852)
			(xy 123.182674 -276.387324) (xy 123.228832 -276.413973) (xy 123.270503 -276.447204) (xy 123.306755 -276.486275)
			(xy 123.336779 -276.530312) (xy 123.359905 -276.578333) (xy 123.375615 -276.629263) (xy 123.383558 -276.681967)
			(xy 123.384056 -276.708616) (xy 123.383558 -276.735265) (xy 123.612138 -276.735265) (xy 123.612138 -276.681967)
			(xy 123.620081 -276.629263) (xy 123.635791 -276.578333) (xy 123.658917 -276.530312) (xy 123.688941 -276.486275)
			(xy 123.725193 -276.447204) (xy 123.766864 -276.413973) (xy 123.813022 -276.387324) (xy 123.862636 -276.367852)
			(xy 123.914598 -276.355992) (xy 123.967748 -276.352009) (xy 124.020898 -276.355992) (xy 124.07286 -276.367852)
			(xy 124.122474 -276.387324) (xy 124.168632 -276.413973) (xy 124.210303 -276.447204) (xy 124.246555 -276.486275)
			(xy 124.276579 -276.530312) (xy 124.299705 -276.578333) (xy 124.315415 -276.629263) (xy 124.323358 -276.681967)
			(xy 124.323856 -276.708616) (xy 124.323358 -276.735265) (xy 124.551938 -276.735265) (xy 124.551938 -276.681967)
			(xy 124.559881 -276.629263) (xy 124.575591 -276.578333) (xy 124.598717 -276.530312) (xy 124.628741 -276.486275)
			(xy 124.664993 -276.447204) (xy 124.706664 -276.413973) (xy 124.752822 -276.387324) (xy 124.802436 -276.367852)
			(xy 124.854398 -276.355992) (xy 124.907548 -276.352009) (xy 124.960698 -276.355992) (xy 125.01266 -276.367852)
			(xy 125.062274 -276.387324) (xy 125.108432 -276.413973) (xy 125.150103 -276.447204) (xy 125.186355 -276.486275)
			(xy 125.216379 -276.530312) (xy 125.239505 -276.578333) (xy 125.255215 -276.629263) (xy 125.263158 -276.681967)
			(xy 125.263656 -276.708616) (xy 125.263158 -276.735265) (xy 125.491484 -276.735265) (xy 125.491484 -276.681967)
			(xy 125.499427 -276.629263) (xy 125.515137 -276.578333) (xy 125.538263 -276.530312) (xy 125.568287 -276.486275)
			(xy 125.604539 -276.447204) (xy 125.64621 -276.413973) (xy 125.692368 -276.387324) (xy 125.741982 -276.367852)
			(xy 125.793944 -276.355992) (xy 125.847094 -276.352009) (xy 125.900244 -276.355992) (xy 125.952206 -276.367852)
			(xy 126.00182 -276.387324) (xy 126.047978 -276.413973) (xy 126.089649 -276.447204) (xy 126.125901 -276.486275)
			(xy 126.155925 -276.530312) (xy 126.179051 -276.578333) (xy 126.194761 -276.629263) (xy 126.202704 -276.681967)
			(xy 126.203202 -276.708616) (xy 126.202704 -276.735265) (xy 126.431538 -276.735265) (xy 126.431538 -276.681967)
			(xy 126.439481 -276.629263) (xy 126.455191 -276.578333) (xy 126.478317 -276.530312) (xy 126.508341 -276.486275)
			(xy 126.544593 -276.447204) (xy 126.586264 -276.413973) (xy 126.632422 -276.387324) (xy 126.682036 -276.367852)
			(xy 126.733998 -276.355992) (xy 126.787148 -276.352009) (xy 126.840298 -276.355992) (xy 126.89226 -276.367852)
			(xy 126.941874 -276.387324) (xy 126.988032 -276.413973) (xy 127.029703 -276.447204) (xy 127.065955 -276.486275)
			(xy 127.095979 -276.530312) (xy 127.119105 -276.578333) (xy 127.134815 -276.629263) (xy 127.142758 -276.681967)
			(xy 127.143256 -276.708616) (xy 127.142758 -276.735265) (xy 127.371338 -276.735265) (xy 127.371338 -276.681967)
			(xy 127.379281 -276.629263) (xy 127.394991 -276.578333) (xy 127.418117 -276.530312) (xy 127.448141 -276.486275)
			(xy 127.484393 -276.447204) (xy 127.526064 -276.413973) (xy 127.572222 -276.387324) (xy 127.621836 -276.367852)
			(xy 127.673798 -276.355992) (xy 127.726948 -276.352009) (xy 127.780098 -276.355992) (xy 127.83206 -276.367852)
			(xy 127.881674 -276.387324) (xy 127.927832 -276.413973) (xy 127.969503 -276.447204) (xy 128.005755 -276.486275)
			(xy 128.035779 -276.530312) (xy 128.058905 -276.578333) (xy 128.074615 -276.629263) (xy 128.082558 -276.681967)
			(xy 128.083056 -276.708616) (xy 128.082558 -276.735265) (xy 128.311138 -276.735265) (xy 128.311138 -276.681967)
			(xy 128.319081 -276.629263) (xy 128.334791 -276.578333) (xy 128.357917 -276.530312) (xy 128.387941 -276.486275)
			(xy 128.424193 -276.447204) (xy 128.465864 -276.413973) (xy 128.512022 -276.387324) (xy 128.561636 -276.367852)
			(xy 128.613598 -276.355992) (xy 128.666748 -276.352009) (xy 128.719898 -276.355992) (xy 128.77186 -276.367852)
			(xy 128.821474 -276.387324) (xy 128.867632 -276.413973) (xy 128.909303 -276.447204) (xy 128.945555 -276.486275)
			(xy 128.975579 -276.530312) (xy 128.998705 -276.578333) (xy 129.014415 -276.629263) (xy 129.022358 -276.681967)
			(xy 129.022856 -276.708616) (xy 129.022358 -276.735265) (xy 129.250938 -276.735265) (xy 129.250938 -276.681967)
			(xy 129.258881 -276.629263) (xy 129.274591 -276.578333) (xy 129.297717 -276.530312) (xy 129.327741 -276.486275)
			(xy 129.363993 -276.447204) (xy 129.405664 -276.413973) (xy 129.451822 -276.387324) (xy 129.501436 -276.367852)
			(xy 129.553398 -276.355992) (xy 129.606548 -276.352009) (xy 129.659698 -276.355992) (xy 129.71166 -276.367852)
			(xy 129.761274 -276.387324) (xy 129.807432 -276.413973) (xy 129.849103 -276.447204) (xy 129.885355 -276.486275)
			(xy 129.915379 -276.530312) (xy 129.938505 -276.578333) (xy 129.954215 -276.629263) (xy 129.962158 -276.681967)
			(xy 129.962656 -276.708616) (xy 129.962158 -276.735265) (xy 130.190738 -276.735265) (xy 130.190738 -276.681967)
			(xy 130.198681 -276.629263) (xy 130.214391 -276.578333) (xy 130.237517 -276.530312) (xy 130.267541 -276.486275)
			(xy 130.303793 -276.447204) (xy 130.345464 -276.413973) (xy 130.391622 -276.387324) (xy 130.441236 -276.367852)
			(xy 130.493198 -276.355992) (xy 130.546348 -276.352009) (xy 130.599498 -276.355992) (xy 130.65146 -276.367852)
			(xy 130.701074 -276.387324) (xy 130.747232 -276.413973) (xy 130.788903 -276.447204) (xy 130.825155 -276.486275)
			(xy 130.855179 -276.530312) (xy 130.878305 -276.578333) (xy 130.894015 -276.629263) (xy 130.901958 -276.681967)
			(xy 130.902456 -276.708616) (xy 130.901958 -276.735265) (xy 131.130538 -276.735265) (xy 131.130538 -276.681967)
			(xy 131.138481 -276.629263) (xy 131.154191 -276.578333) (xy 131.177317 -276.530312) (xy 131.207341 -276.486275)
			(xy 131.243593 -276.447204) (xy 131.285264 -276.413973) (xy 131.331422 -276.387324) (xy 131.381036 -276.367852)
			(xy 131.432998 -276.355992) (xy 131.486148 -276.352009) (xy 131.539298 -276.355992) (xy 131.59126 -276.367852)
			(xy 131.640874 -276.387324) (xy 131.687032 -276.413973) (xy 131.728703 -276.447204) (xy 131.764955 -276.486275)
			(xy 131.794979 -276.530312) (xy 131.818105 -276.578333) (xy 131.833815 -276.629263) (xy 131.841758 -276.681967)
			(xy 131.842256 -276.708616) (xy 131.841758 -276.735265) (xy 131.833815 -276.787969) (xy 131.818105 -276.838899)
			(xy 131.794979 -276.88692) (xy 131.764955 -276.930957) (xy 131.728703 -276.970028) (xy 131.687032 -277.003259)
			(xy 131.640874 -277.029908) (xy 131.59126 -277.04938) (xy 131.539298 -277.06124) (xy 131.486148 -277.065224)
			(xy 131.432998 -277.06124) (xy 131.381036 -277.04938) (xy 131.331422 -277.029908) (xy 131.285264 -277.003259)
			(xy 131.243593 -276.970028) (xy 131.207341 -276.930957) (xy 131.177317 -276.88692) (xy 131.154191 -276.838899)
			(xy 131.138481 -276.787969) (xy 131.130538 -276.735265) (xy 130.901958 -276.735265) (xy 130.894015 -276.787969)
			(xy 130.878305 -276.838899) (xy 130.855179 -276.88692) (xy 130.825155 -276.930957) (xy 130.788903 -276.970028)
			(xy 130.747232 -277.003259) (xy 130.701074 -277.029908) (xy 130.65146 -277.04938) (xy 130.599498 -277.06124)
			(xy 130.546348 -277.065224) (xy 130.493198 -277.06124) (xy 130.441236 -277.04938) (xy 130.391622 -277.029908)
			(xy 130.345464 -277.003259) (xy 130.303793 -276.970028) (xy 130.267541 -276.930957) (xy 130.237517 -276.88692)
			(xy 130.214391 -276.838899) (xy 130.198681 -276.787969) (xy 130.190738 -276.735265) (xy 129.962158 -276.735265)
			(xy 129.954215 -276.787969) (xy 129.938505 -276.838899) (xy 129.915379 -276.88692) (xy 129.885355 -276.930957)
			(xy 129.849103 -276.970028) (xy 129.807432 -277.003259) (xy 129.761274 -277.029908) (xy 129.71166 -277.04938)
			(xy 129.659698 -277.06124) (xy 129.606548 -277.065224) (xy 129.553398 -277.06124) (xy 129.501436 -277.04938)
			(xy 129.451822 -277.029908) (xy 129.405664 -277.003259) (xy 129.363993 -276.970028) (xy 129.327741 -276.930957)
			(xy 129.297717 -276.88692) (xy 129.274591 -276.838899) (xy 129.258881 -276.787969) (xy 129.250938 -276.735265)
			(xy 129.022358 -276.735265) (xy 129.014415 -276.787969) (xy 128.998705 -276.838899) (xy 128.975579 -276.88692)
			(xy 128.945555 -276.930957) (xy 128.909303 -276.970028) (xy 128.867632 -277.003259) (xy 128.821474 -277.029908)
			(xy 128.77186 -277.04938) (xy 128.719898 -277.06124) (xy 128.666748 -277.065224) (xy 128.613598 -277.06124)
			(xy 128.561636 -277.04938) (xy 128.512022 -277.029908) (xy 128.465864 -277.003259) (xy 128.424193 -276.970028)
			(xy 128.387941 -276.930957) (xy 128.357917 -276.88692) (xy 128.334791 -276.838899) (xy 128.319081 -276.787969)
			(xy 128.311138 -276.735265) (xy 128.082558 -276.735265) (xy 128.074615 -276.787969) (xy 128.058905 -276.838899)
			(xy 128.035779 -276.88692) (xy 128.005755 -276.930957) (xy 127.969503 -276.970028) (xy 127.927832 -277.003259)
			(xy 127.881674 -277.029908) (xy 127.83206 -277.04938) (xy 127.780098 -277.06124) (xy 127.726948 -277.065224)
			(xy 127.673798 -277.06124) (xy 127.621836 -277.04938) (xy 127.572222 -277.029908) (xy 127.526064 -277.003259)
			(xy 127.484393 -276.970028) (xy 127.448141 -276.930957) (xy 127.418117 -276.88692) (xy 127.394991 -276.838899)
			(xy 127.379281 -276.787969) (xy 127.371338 -276.735265) (xy 127.142758 -276.735265) (xy 127.134815 -276.787969)
			(xy 127.119105 -276.838899) (xy 127.095979 -276.88692) (xy 127.065955 -276.930957) (xy 127.029703 -276.970028)
			(xy 126.988032 -277.003259) (xy 126.941874 -277.029908) (xy 126.89226 -277.04938) (xy 126.840298 -277.06124)
			(xy 126.787148 -277.065224) (xy 126.733998 -277.06124) (xy 126.682036 -277.04938) (xy 126.632422 -277.029908)
			(xy 126.586264 -277.003259) (xy 126.544593 -276.970028) (xy 126.508341 -276.930957) (xy 126.478317 -276.88692)
			(xy 126.455191 -276.838899) (xy 126.439481 -276.787969) (xy 126.431538 -276.735265) (xy 126.202704 -276.735265)
			(xy 126.194761 -276.787969) (xy 126.179051 -276.838899) (xy 126.155925 -276.88692) (xy 126.125901 -276.930957)
			(xy 126.089649 -276.970028) (xy 126.047978 -277.003259) (xy 126.00182 -277.029908) (xy 125.952206 -277.04938)
			(xy 125.900244 -277.06124) (xy 125.847094 -277.065224) (xy 125.793944 -277.06124) (xy 125.741982 -277.04938)
			(xy 125.692368 -277.029908) (xy 125.64621 -277.003259) (xy 125.604539 -276.970028) (xy 125.568287 -276.930957)
			(xy 125.538263 -276.88692) (xy 125.515137 -276.838899) (xy 125.499427 -276.787969) (xy 125.491484 -276.735265)
			(xy 125.263158 -276.735265) (xy 125.255215 -276.787969) (xy 125.239505 -276.838899) (xy 125.216379 -276.88692)
			(xy 125.186355 -276.930957) (xy 125.150103 -276.970028) (xy 125.108432 -277.003259) (xy 125.062274 -277.029908)
			(xy 125.01266 -277.04938) (xy 124.960698 -277.06124) (xy 124.907548 -277.065224) (xy 124.854398 -277.06124)
			(xy 124.802436 -277.04938) (xy 124.752822 -277.029908) (xy 124.706664 -277.003259) (xy 124.664993 -276.970028)
			(xy 124.628741 -276.930957) (xy 124.598717 -276.88692) (xy 124.575591 -276.838899) (xy 124.559881 -276.787969)
			(xy 124.551938 -276.735265) (xy 124.323358 -276.735265) (xy 124.315415 -276.787969) (xy 124.299705 -276.838899)
			(xy 124.276579 -276.88692) (xy 124.246555 -276.930957) (xy 124.210303 -276.970028) (xy 124.168632 -277.003259)
			(xy 124.122474 -277.029908) (xy 124.07286 -277.04938) (xy 124.020898 -277.06124) (xy 123.967748 -277.065224)
			(xy 123.914598 -277.06124) (xy 123.862636 -277.04938) (xy 123.813022 -277.029908) (xy 123.766864 -277.003259)
			(xy 123.725193 -276.970028) (xy 123.688941 -276.930957) (xy 123.658917 -276.88692) (xy 123.635791 -276.838899)
			(xy 123.620081 -276.787969) (xy 123.612138 -276.735265) (xy 123.383558 -276.735265) (xy 123.375615 -276.787969)
			(xy 123.359905 -276.838899) (xy 123.336779 -276.88692) (xy 123.306755 -276.930957) (xy 123.270503 -276.970028)
			(xy 123.228832 -277.003259) (xy 123.182674 -277.029908) (xy 123.13306 -277.04938) (xy 123.081098 -277.06124)
			(xy 123.027948 -277.065224) (xy 122.974798 -277.06124) (xy 122.922836 -277.04938) (xy 122.873222 -277.029908)
			(xy 122.827064 -277.003259) (xy 122.785393 -276.970028) (xy 122.749141 -276.930957) (xy 122.719117 -276.88692)
			(xy 122.695991 -276.838899) (xy 122.680281 -276.787969) (xy 122.672338 -276.735265) (xy 121.503958 -276.735265)
			(xy 121.496015 -276.787969) (xy 121.480305 -276.838899) (xy 121.457179 -276.88692) (xy 121.427155 -276.930957)
			(xy 121.390903 -276.970028) (xy 121.349232 -277.003259) (xy 121.303074 -277.029908) (xy 121.25346 -277.04938)
			(xy 121.201498 -277.06124) (xy 121.148348 -277.065224) (xy 121.095198 -277.06124) (xy 121.043236 -277.04938)
			(xy 120.993622 -277.029908) (xy 120.947464 -277.003259) (xy 120.905793 -276.970028) (xy 120.869541 -276.930957)
			(xy 120.839517 -276.88692) (xy 120.816391 -276.838899) (xy 120.800681 -276.787969) (xy 120.792738 -276.735265)
			(xy 120.563866 -276.735265) (xy 120.555961 -276.787715) (xy 120.540251 -276.838645) (xy 120.517125 -276.886666)
			(xy 120.487101 -276.930703) (xy 120.450849 -276.969774) (xy 120.409178 -277.003005) (xy 120.36302 -277.029654)
			(xy 120.313406 -277.049126) (xy 120.261444 -277.060986) (xy 120.208294 -277.06497) (xy 120.155144 -277.060986)
			(xy 120.103182 -277.049126) (xy 120.053568 -277.029654) (xy 120.00741 -277.003005) (xy 119.965739 -276.969774)
			(xy 119.929487 -276.930703) (xy 119.899463 -276.886666) (xy 119.876337 -276.838645) (xy 119.860627 -276.787715)
			(xy 119.852684 -276.735011) (xy 119.624109 -276.735011) (xy 119.624104 -276.735265) (xy 119.616161 -276.787969)
			(xy 119.600451 -276.838899) (xy 119.577325 -276.88692) (xy 119.547301 -276.930957) (xy 119.511049 -276.970028)
			(xy 119.469378 -277.003259) (xy 119.42322 -277.029908) (xy 119.373606 -277.04938) (xy 119.321644 -277.06124)
			(xy 119.268494 -277.065224) (xy 119.215344 -277.06124) (xy 119.163382 -277.04938) (xy 119.113768 -277.029908)
			(xy 119.06761 -277.003259) (xy 119.025939 -276.970028) (xy 118.989687 -276.930957) (xy 118.959663 -276.88692)
			(xy 118.936537 -276.838899) (xy 118.920827 -276.787969) (xy 118.912884 -276.735265) (xy 118.684266 -276.735265)
			(xy 118.676361 -276.787715) (xy 118.660651 -276.838645) (xy 118.637525 -276.886666) (xy 118.607501 -276.930703)
			(xy 118.571249 -276.969774) (xy 118.529578 -277.003005) (xy 118.48342 -277.029654) (xy 118.433806 -277.049126)
			(xy 118.381844 -277.060986) (xy 118.328694 -277.06497) (xy 118.275544 -277.060986) (xy 118.223582 -277.049126)
			(xy 118.173968 -277.029654) (xy 118.12781 -277.003005) (xy 118.086139 -276.969774) (xy 118.049887 -276.930703)
			(xy 118.019863 -276.886666) (xy 117.996737 -276.838645) (xy 117.981027 -276.787715) (xy 117.973084 -276.735011)
			(xy 117.744504 -276.735011) (xy 117.736561 -276.787715) (xy 117.720851 -276.838645) (xy 117.697725 -276.886666)
			(xy 117.667701 -276.930703) (xy 117.631449 -276.969774) (xy 117.589778 -277.003005) (xy 117.54362 -277.029654)
			(xy 117.494006 -277.049126) (xy 117.442044 -277.060986) (xy 117.388894 -277.06497) (xy 117.335744 -277.060986)
			(xy 117.283782 -277.049126) (xy 117.234168 -277.029654) (xy 117.18801 -277.003005) (xy 117.146339 -276.969774)
			(xy 117.110087 -276.930703) (xy 117.080063 -276.886666) (xy 117.056937 -276.838645) (xy 117.041227 -276.787715)
			(xy 117.033284 -276.735011) (xy 116.804704 -276.735011) (xy 116.796761 -276.787715) (xy 116.781051 -276.838645)
			(xy 116.757925 -276.886666) (xy 116.727901 -276.930703) (xy 116.691649 -276.969774) (xy 116.649978 -277.003005)
			(xy 116.60382 -277.029654) (xy 116.554206 -277.049126) (xy 116.502244 -277.060986) (xy 116.449094 -277.06497)
			(xy 116.395944 -277.060986) (xy 116.343982 -277.049126) (xy 116.294368 -277.029654) (xy 116.24821 -277.003005)
			(xy 116.206539 -276.969774) (xy 116.170287 -276.930703) (xy 116.140263 -276.886666) (xy 116.117137 -276.838645)
			(xy 116.101427 -276.787715) (xy 116.093484 -276.735011) (xy 115.864904 -276.735011) (xy 115.856961 -276.787715)
			(xy 115.841251 -276.838645) (xy 115.818125 -276.886666) (xy 115.788101 -276.930703) (xy 115.751849 -276.969774)
			(xy 115.710178 -277.003005) (xy 115.66402 -277.029654) (xy 115.614406 -277.049126) (xy 115.562444 -277.060986)
			(xy 115.509294 -277.06497) (xy 115.456144 -277.060986) (xy 115.404182 -277.049126) (xy 115.354568 -277.029654)
			(xy 115.30841 -277.003005) (xy 115.266739 -276.969774) (xy 115.230487 -276.930703) (xy 115.200463 -276.886666)
			(xy 115.177337 -276.838645) (xy 115.161627 -276.787715) (xy 115.153684 -276.735011) (xy 114.92539 -276.735011)
			(xy 114.925372 -276.736044) (xy 114.917002 -276.790258) (xy 114.900416 -276.842547) (xy 114.876006 -276.891673)
			(xy 114.860578 -276.914356) (xy 114.835686 -276.949154) (xy 115.052602 -277.16607) (xy 115.07089 -277.167848)
			(xy 115.098312 -277.170803) (xy 115.151836 -277.184097) (xy 115.20267 -277.205487) (xy 115.249596 -277.234462)
			(xy 115.291492 -277.270328) (xy 115.327355 -277.312226) (xy 115.356326 -277.359155) (xy 115.377712 -277.409991)
			(xy 115.391002 -277.463516) (xy 115.393978 -277.490936) (xy 115.395756 -277.509224) (xy 115.450874 -277.564342)
			(xy 115.461514 -277.574324) (xy 115.487116 -277.588289) (xy 115.515622 -277.594446) (xy 115.544706 -277.592292)
			(xy 115.571994 -277.582002) (xy 115.59526 -277.564418) (xy 115.612604 -277.540973) (xy 115.622612 -277.51358)
			(xy 115.624102 -277.499064) (xy 115.62633 -277.472326) (xy 115.637806 -277.419916) (xy 115.657014 -277.369821)
			(xy 115.683519 -277.323173) (xy 115.716721 -277.281029) (xy 115.755868 -277.244341) (xy 115.800076 -277.213941)
			(xy 115.848343 -277.190516) (xy 115.899579 -277.174595) (xy 115.952622 -277.16654) (xy 115.979448 -277.16607)
			(xy 116.007429 -277.166623) (xy 116.062702 -277.175383) (xy 116.115924 -277.192682) (xy 116.165785 -277.218092)
			(xy 116.211058 -277.250989) (xy 116.250628 -277.290562) (xy 116.283521 -277.335837) (xy 116.308928 -277.3857)
			(xy 116.326223 -277.438923) (xy 116.33498 -277.494197) (xy 116.335556 -277.522178) (xy 116.335071 -277.549004)
			(xy 116.335059 -277.549081) (xy 116.563384 -277.549081) (xy 116.563384 -277.495783) (xy 116.571327 -277.443079)
			(xy 116.587037 -277.392149) (xy 116.610163 -277.344128) (xy 116.640187 -277.300091) (xy 116.676439 -277.26102)
			(xy 116.71811 -277.227789) (xy 116.764268 -277.20114) (xy 116.813882 -277.181668) (xy 116.865844 -277.169808)
			(xy 116.918994 -277.165825) (xy 116.972144 -277.169808) (xy 117.024106 -277.181668) (xy 117.07372 -277.20114)
			(xy 117.119878 -277.227789) (xy 117.161549 -277.26102) (xy 117.197801 -277.300091) (xy 117.227825 -277.344128)
			(xy 117.250951 -277.392149) (xy 117.266661 -277.443079) (xy 117.274604 -277.495783) (xy 117.275102 -277.522432)
			(xy 117.274609 -277.548827) (xy 117.503438 -277.548827) (xy 117.503438 -277.495529) (xy 117.511381 -277.442825)
			(xy 117.527091 -277.391895) (xy 117.550217 -277.343874) (xy 117.580241 -277.299837) (xy 117.616493 -277.260766)
			(xy 117.658164 -277.227535) (xy 117.704322 -277.200886) (xy 117.753936 -277.181414) (xy 117.805898 -277.169554)
			(xy 117.859048 -277.165571) (xy 117.912198 -277.169554) (xy 117.96416 -277.181414) (xy 118.013774 -277.200886)
			(xy 118.059932 -277.227535) (xy 118.101603 -277.260766) (xy 118.137855 -277.299837) (xy 118.167879 -277.343874)
			(xy 118.191005 -277.391895) (xy 118.206715 -277.442825) (xy 118.214658 -277.495529) (xy 118.215156 -277.522178)
			(xy 118.214658 -277.548827) (xy 118.21462 -277.549081) (xy 118.443238 -277.549081) (xy 118.443238 -277.495783)
			(xy 118.451181 -277.443079) (xy 118.466891 -277.392149) (xy 118.490017 -277.344128) (xy 118.520041 -277.300091)
			(xy 118.556293 -277.26102) (xy 118.597964 -277.227789) (xy 118.644122 -277.20114) (xy 118.693736 -277.181668)
			(xy 118.745698 -277.169808) (xy 118.798848 -277.165825) (xy 118.851998 -277.169808) (xy 118.90396 -277.181668)
			(xy 118.953574 -277.20114) (xy 118.999732 -277.227789) (xy 119.041403 -277.26102) (xy 119.077655 -277.300091)
			(xy 119.107679 -277.344128) (xy 119.130805 -277.392149) (xy 119.146515 -277.443079) (xy 119.154458 -277.495783)
			(xy 119.154956 -277.522432) (xy 119.154463 -277.548827) (xy 119.383038 -277.548827) (xy 119.383038 -277.495529)
			(xy 119.390981 -277.442825) (xy 119.406691 -277.391895) (xy 119.429817 -277.343874) (xy 119.459841 -277.299837)
			(xy 119.496093 -277.260766) (xy 119.537764 -277.227535) (xy 119.583922 -277.200886) (xy 119.633536 -277.181414)
			(xy 119.685498 -277.169554) (xy 119.738648 -277.165571) (xy 119.791798 -277.169554) (xy 119.84376 -277.181414)
			(xy 119.893374 -277.200886) (xy 119.939532 -277.227535) (xy 119.981203 -277.260766) (xy 120.017455 -277.299837)
			(xy 120.047479 -277.343874) (xy 120.070605 -277.391895) (xy 120.086315 -277.442825) (xy 120.094258 -277.495529)
			(xy 120.094756 -277.522178) (xy 120.094258 -277.548827) (xy 120.322838 -277.548827) (xy 120.322838 -277.495529)
			(xy 120.330781 -277.442825) (xy 120.346491 -277.391895) (xy 120.369617 -277.343874) (xy 120.399641 -277.299837)
			(xy 120.435893 -277.260766) (xy 120.477564 -277.227535) (xy 120.523722 -277.200886) (xy 120.573336 -277.181414)
			(xy 120.625298 -277.169554) (xy 120.678448 -277.165571) (xy 120.731598 -277.169554) (xy 120.78356 -277.181414)
			(xy 120.833174 -277.200886) (xy 120.879332 -277.227535) (xy 120.921003 -277.260766) (xy 120.957255 -277.299837)
			(xy 120.987279 -277.343874) (xy 121.010405 -277.391895) (xy 121.026115 -277.442825) (xy 121.034058 -277.495529)
			(xy 121.034556 -277.522178) (xy 121.034058 -277.548827) (xy 121.262638 -277.548827) (xy 121.262638 -277.495529)
			(xy 121.270581 -277.442825) (xy 121.286291 -277.391895) (xy 121.309417 -277.343874) (xy 121.339441 -277.299837)
			(xy 121.375693 -277.260766) (xy 121.417364 -277.227535) (xy 121.463522 -277.200886) (xy 121.513136 -277.181414)
			(xy 121.565098 -277.169554) (xy 121.618248 -277.165571) (xy 121.671398 -277.169554) (xy 121.72336 -277.181414)
			(xy 121.772974 -277.200886) (xy 121.819132 -277.227535) (xy 121.860803 -277.260766) (xy 121.897055 -277.299837)
			(xy 121.927079 -277.343874) (xy 121.950205 -277.391895) (xy 121.965915 -277.442825) (xy 121.973858 -277.495529)
			(xy 121.974356 -277.522178) (xy 121.973858 -277.548827) (xy 122.202438 -277.548827) (xy 122.202438 -277.495529)
			(xy 122.210381 -277.442825) (xy 122.226091 -277.391895) (xy 122.249217 -277.343874) (xy 122.279241 -277.299837)
			(xy 122.315493 -277.260766) (xy 122.357164 -277.227535) (xy 122.403322 -277.200886) (xy 122.452936 -277.181414)
			(xy 122.504898 -277.169554) (xy 122.558048 -277.165571) (xy 122.611198 -277.169554) (xy 122.66316 -277.181414)
			(xy 122.712774 -277.200886) (xy 122.758932 -277.227535) (xy 122.800603 -277.260766) (xy 122.836855 -277.299837)
			(xy 122.866879 -277.343874) (xy 122.890005 -277.391895) (xy 122.905715 -277.442825) (xy 122.913658 -277.495529)
			(xy 122.914156 -277.522178) (xy 122.913658 -277.548827) (xy 122.91362 -277.549081) (xy 123.141984 -277.549081)
			(xy 123.141984 -277.495783) (xy 123.149927 -277.443079) (xy 123.165637 -277.392149) (xy 123.188763 -277.344128)
			(xy 123.218787 -277.300091) (xy 123.255039 -277.26102) (xy 123.29671 -277.227789) (xy 123.342868 -277.20114)
			(xy 123.392482 -277.181668) (xy 123.444444 -277.169808) (xy 123.497594 -277.165825) (xy 123.550744 -277.169808)
			(xy 123.602706 -277.181668) (xy 123.65232 -277.20114) (xy 123.698478 -277.227789) (xy 123.740149 -277.26102)
			(xy 123.776401 -277.300091) (xy 123.806425 -277.344128) (xy 123.829551 -277.392149) (xy 123.845261 -277.443079)
			(xy 123.853204 -277.495783) (xy 123.853702 -277.522432) (xy 123.853204 -277.549081) (xy 124.081784 -277.549081)
			(xy 124.081784 -277.495783) (xy 124.089727 -277.443079) (xy 124.105437 -277.392149) (xy 124.128563 -277.344128)
			(xy 124.158587 -277.300091) (xy 124.194839 -277.26102) (xy 124.23651 -277.227789) (xy 124.282668 -277.20114)
			(xy 124.332282 -277.181668) (xy 124.384244 -277.169808) (xy 124.437394 -277.165825) (xy 124.490544 -277.169808)
			(xy 124.542506 -277.181668) (xy 124.59212 -277.20114) (xy 124.638278 -277.227789) (xy 124.679949 -277.26102)
			(xy 124.716201 -277.300091) (xy 124.746225 -277.344128) (xy 124.769351 -277.392149) (xy 124.785061 -277.443079)
			(xy 124.793004 -277.495783) (xy 124.793502 -277.522432) (xy 124.793004 -277.549081) (xy 125.021838 -277.549081)
			(xy 125.021838 -277.495783) (xy 125.029781 -277.443079) (xy 125.045491 -277.392149) (xy 125.068617 -277.344128)
			(xy 125.098641 -277.300091) (xy 125.134893 -277.26102) (xy 125.176564 -277.227789) (xy 125.222722 -277.20114)
			(xy 125.272336 -277.181668) (xy 125.324298 -277.169808) (xy 125.377448 -277.165825) (xy 125.430598 -277.169808)
			(xy 125.48256 -277.181668) (xy 125.532174 -277.20114) (xy 125.578332 -277.227789) (xy 125.620003 -277.26102)
			(xy 125.656255 -277.300091) (xy 125.686279 -277.344128) (xy 125.709405 -277.392149) (xy 125.725115 -277.443079)
			(xy 125.733058 -277.495783) (xy 125.733556 -277.522432) (xy 125.733058 -277.549081) (xy 125.961384 -277.549081)
			(xy 125.961384 -277.495783) (xy 125.969327 -277.443079) (xy 125.985037 -277.392149) (xy 126.008163 -277.344128)
			(xy 126.038187 -277.300091) (xy 126.074439 -277.26102) (xy 126.11611 -277.227789) (xy 126.162268 -277.20114)
			(xy 126.211882 -277.181668) (xy 126.263844 -277.169808) (xy 126.316994 -277.165825) (xy 126.370144 -277.169808)
			(xy 126.422106 -277.181668) (xy 126.47172 -277.20114) (xy 126.517878 -277.227789) (xy 126.559549 -277.26102)
			(xy 126.595801 -277.300091) (xy 126.625825 -277.344128) (xy 126.648951 -277.392149) (xy 126.664661 -277.443079)
			(xy 126.672604 -277.495783) (xy 126.673102 -277.522432) (xy 126.672604 -277.549081) (xy 126.901184 -277.549081)
			(xy 126.901184 -277.495783) (xy 126.909127 -277.443079) (xy 126.924837 -277.392149) (xy 126.947963 -277.344128)
			(xy 126.977987 -277.300091) (xy 127.014239 -277.26102) (xy 127.05591 -277.227789) (xy 127.102068 -277.20114)
			(xy 127.151682 -277.181668) (xy 127.203644 -277.169808) (xy 127.256794 -277.165825) (xy 127.309944 -277.169808)
			(xy 127.361906 -277.181668) (xy 127.41152 -277.20114) (xy 127.457678 -277.227789) (xy 127.499349 -277.26102)
			(xy 127.535601 -277.300091) (xy 127.565625 -277.344128) (xy 127.588751 -277.392149) (xy 127.604461 -277.443079)
			(xy 127.612404 -277.495783) (xy 127.612902 -277.522432) (xy 127.612404 -277.549081) (xy 127.840984 -277.549081)
			(xy 127.840984 -277.495783) (xy 127.848927 -277.443079) (xy 127.864637 -277.392149) (xy 127.887763 -277.344128)
			(xy 127.917787 -277.300091) (xy 127.954039 -277.26102) (xy 127.99571 -277.227789) (xy 128.041868 -277.20114)
			(xy 128.091482 -277.181668) (xy 128.143444 -277.169808) (xy 128.196594 -277.165825) (xy 128.249744 -277.169808)
			(xy 128.301706 -277.181668) (xy 128.35132 -277.20114) (xy 128.397478 -277.227789) (xy 128.439149 -277.26102)
			(xy 128.475401 -277.300091) (xy 128.505425 -277.344128) (xy 128.528551 -277.392149) (xy 128.544261 -277.443079)
			(xy 128.552204 -277.495783) (xy 128.552702 -277.522432) (xy 128.552204 -277.549081) (xy 128.780784 -277.549081)
			(xy 128.780784 -277.495783) (xy 128.788727 -277.443079) (xy 128.804437 -277.392149) (xy 128.827563 -277.344128)
			(xy 128.857587 -277.300091) (xy 128.893839 -277.26102) (xy 128.93551 -277.227789) (xy 128.981668 -277.20114)
			(xy 129.031282 -277.181668) (xy 129.083244 -277.169808) (xy 129.136394 -277.165825) (xy 129.189544 -277.169808)
			(xy 129.241506 -277.181668) (xy 129.29112 -277.20114) (xy 129.337278 -277.227789) (xy 129.378949 -277.26102)
			(xy 129.415201 -277.300091) (xy 129.445225 -277.344128) (xy 129.468351 -277.392149) (xy 129.484061 -277.443079)
			(xy 129.492004 -277.495783) (xy 129.492502 -277.522432) (xy 129.492004 -277.549081) (xy 129.720838 -277.549081)
			(xy 129.720838 -277.495783) (xy 129.728781 -277.443079) (xy 129.744491 -277.392149) (xy 129.767617 -277.344128)
			(xy 129.797641 -277.300091) (xy 129.833893 -277.26102) (xy 129.875564 -277.227789) (xy 129.921722 -277.20114)
			(xy 129.971336 -277.181668) (xy 130.023298 -277.169808) (xy 130.076448 -277.165825) (xy 130.129598 -277.169808)
			(xy 130.18156 -277.181668) (xy 130.231174 -277.20114) (xy 130.277332 -277.227789) (xy 130.319003 -277.26102)
			(xy 130.355255 -277.300091) (xy 130.385279 -277.344128) (xy 130.408405 -277.392149) (xy 130.424115 -277.443079)
			(xy 130.432058 -277.495783) (xy 130.432556 -277.522432) (xy 130.432058 -277.549081) (xy 130.660638 -277.549081)
			(xy 130.660638 -277.495783) (xy 130.668581 -277.443079) (xy 130.684291 -277.392149) (xy 130.707417 -277.344128)
			(xy 130.737441 -277.300091) (xy 130.773693 -277.26102) (xy 130.815364 -277.227789) (xy 130.861522 -277.20114)
			(xy 130.911136 -277.181668) (xy 130.963098 -277.169808) (xy 131.016248 -277.165825) (xy 131.069398 -277.169808)
			(xy 131.12136 -277.181668) (xy 131.170974 -277.20114) (xy 131.217132 -277.227789) (xy 131.258803 -277.26102)
			(xy 131.295055 -277.300091) (xy 131.325079 -277.344128) (xy 131.348205 -277.392149) (xy 131.363915 -277.443079)
			(xy 131.371858 -277.495783) (xy 131.372356 -277.522432) (xy 131.371858 -277.549081) (xy 131.600184 -277.549081)
			(xy 131.600184 -277.495783) (xy 131.608127 -277.443079) (xy 131.623837 -277.392149) (xy 131.646963 -277.344128)
			(xy 131.676987 -277.300091) (xy 131.713239 -277.26102) (xy 131.75491 -277.227789) (xy 131.801068 -277.20114)
			(xy 131.850682 -277.181668) (xy 131.902644 -277.169808) (xy 131.955794 -277.165825) (xy 132.008944 -277.169808)
			(xy 132.060906 -277.181668) (xy 132.11052 -277.20114) (xy 132.156678 -277.227789) (xy 132.198349 -277.26102)
			(xy 132.234601 -277.300091) (xy 132.264625 -277.344128) (xy 132.287751 -277.392149) (xy 132.303461 -277.443079)
			(xy 132.311404 -277.495783) (xy 132.311902 -277.522432) (xy 132.311404 -277.549081) (xy 132.539984 -277.549081)
			(xy 132.539984 -277.495783) (xy 132.547927 -277.443079) (xy 132.563637 -277.392149) (xy 132.586763 -277.344128)
			(xy 132.616787 -277.300091) (xy 132.653039 -277.26102) (xy 132.69471 -277.227789) (xy 132.740868 -277.20114)
			(xy 132.790482 -277.181668) (xy 132.842444 -277.169808) (xy 132.895594 -277.165825) (xy 132.948744 -277.169808)
			(xy 133.000706 -277.181668) (xy 133.05032 -277.20114) (xy 133.096478 -277.227789) (xy 133.138149 -277.26102)
			(xy 133.174401 -277.300091) (xy 133.204425 -277.344128) (xy 133.227551 -277.392149) (xy 133.243261 -277.443079)
			(xy 133.251204 -277.495783) (xy 133.251702 -277.522432) (xy 133.251204 -277.549081) (xy 133.243261 -277.601785)
			(xy 133.227551 -277.652715) (xy 133.204425 -277.700736) (xy 133.174401 -277.744773) (xy 133.138149 -277.783844)
			(xy 133.096478 -277.817075) (xy 133.05032 -277.843724) (xy 133.000706 -277.863196) (xy 132.948744 -277.875056)
			(xy 132.895594 -277.87904) (xy 132.842444 -277.875056) (xy 132.790482 -277.863196) (xy 132.740868 -277.843724)
			(xy 132.69471 -277.817075) (xy 132.653039 -277.783844) (xy 132.616787 -277.744773) (xy 132.586763 -277.700736)
			(xy 132.563637 -277.652715) (xy 132.547927 -277.601785) (xy 132.539984 -277.549081) (xy 132.311404 -277.549081)
			(xy 132.303461 -277.601785) (xy 132.287751 -277.652715) (xy 132.264625 -277.700736) (xy 132.234601 -277.744773)
			(xy 132.198349 -277.783844) (xy 132.156678 -277.817075) (xy 132.11052 -277.843724) (xy 132.060906 -277.863196)
			(xy 132.008944 -277.875056) (xy 131.955794 -277.87904) (xy 131.902644 -277.875056) (xy 131.850682 -277.863196)
			(xy 131.801068 -277.843724) (xy 131.75491 -277.817075) (xy 131.713239 -277.783844) (xy 131.676987 -277.744773)
			(xy 131.646963 -277.700736) (xy 131.623837 -277.652715) (xy 131.608127 -277.601785) (xy 131.600184 -277.549081)
			(xy 131.371858 -277.549081) (xy 131.363915 -277.601785) (xy 131.348205 -277.652715) (xy 131.325079 -277.700736)
			(xy 131.295055 -277.744773) (xy 131.258803 -277.783844) (xy 131.217132 -277.817075) (xy 131.170974 -277.843724)
			(xy 131.12136 -277.863196) (xy 131.069398 -277.875056) (xy 131.016248 -277.87904) (xy 130.963098 -277.875056)
			(xy 130.911136 -277.863196) (xy 130.861522 -277.843724) (xy 130.815364 -277.817075) (xy 130.773693 -277.783844)
			(xy 130.737441 -277.744773) (xy 130.707417 -277.700736) (xy 130.684291 -277.652715) (xy 130.668581 -277.601785)
			(xy 130.660638 -277.549081) (xy 130.432058 -277.549081) (xy 130.424115 -277.601785) (xy 130.408405 -277.652715)
			(xy 130.385279 -277.700736) (xy 130.355255 -277.744773) (xy 130.319003 -277.783844) (xy 130.277332 -277.817075)
			(xy 130.231174 -277.843724) (xy 130.18156 -277.863196) (xy 130.129598 -277.875056) (xy 130.076448 -277.87904)
			(xy 130.023298 -277.875056) (xy 129.971336 -277.863196) (xy 129.921722 -277.843724) (xy 129.875564 -277.817075)
			(xy 129.833893 -277.783844) (xy 129.797641 -277.744773) (xy 129.767617 -277.700736) (xy 129.744491 -277.652715)
			(xy 129.728781 -277.601785) (xy 129.720838 -277.549081) (xy 129.492004 -277.549081) (xy 129.484061 -277.601785)
			(xy 129.468351 -277.652715) (xy 129.445225 -277.700736) (xy 129.415201 -277.744773) (xy 129.378949 -277.783844)
			(xy 129.337278 -277.817075) (xy 129.29112 -277.843724) (xy 129.241506 -277.863196) (xy 129.189544 -277.875056)
			(xy 129.136394 -277.87904) (xy 129.083244 -277.875056) (xy 129.031282 -277.863196) (xy 128.981668 -277.843724)
			(xy 128.93551 -277.817075) (xy 128.893839 -277.783844) (xy 128.857587 -277.744773) (xy 128.827563 -277.700736)
			(xy 128.804437 -277.652715) (xy 128.788727 -277.601785) (xy 128.780784 -277.549081) (xy 128.552204 -277.549081)
			(xy 128.544261 -277.601785) (xy 128.528551 -277.652715) (xy 128.505425 -277.700736) (xy 128.475401 -277.744773)
			(xy 128.439149 -277.783844) (xy 128.397478 -277.817075) (xy 128.35132 -277.843724) (xy 128.301706 -277.863196)
			(xy 128.249744 -277.875056) (xy 128.196594 -277.87904) (xy 128.143444 -277.875056) (xy 128.091482 -277.863196)
			(xy 128.041868 -277.843724) (xy 127.99571 -277.817075) (xy 127.954039 -277.783844) (xy 127.917787 -277.744773)
			(xy 127.887763 -277.700736) (xy 127.864637 -277.652715) (xy 127.848927 -277.601785) (xy 127.840984 -277.549081)
			(xy 127.612404 -277.549081) (xy 127.604461 -277.601785) (xy 127.588751 -277.652715) (xy 127.565625 -277.700736)
			(xy 127.535601 -277.744773) (xy 127.499349 -277.783844) (xy 127.457678 -277.817075) (xy 127.41152 -277.843724)
			(xy 127.361906 -277.863196) (xy 127.309944 -277.875056) (xy 127.256794 -277.87904) (xy 127.203644 -277.875056)
			(xy 127.151682 -277.863196) (xy 127.102068 -277.843724) (xy 127.05591 -277.817075) (xy 127.014239 -277.783844)
			(xy 126.977987 -277.744773) (xy 126.947963 -277.700736) (xy 126.924837 -277.652715) (xy 126.909127 -277.601785)
			(xy 126.901184 -277.549081) (xy 126.672604 -277.549081) (xy 126.664661 -277.601785) (xy 126.648951 -277.652715)
			(xy 126.625825 -277.700736) (xy 126.595801 -277.744773) (xy 126.559549 -277.783844) (xy 126.517878 -277.817075)
			(xy 126.47172 -277.843724) (xy 126.422106 -277.863196) (xy 126.370144 -277.875056) (xy 126.316994 -277.87904)
			(xy 126.263844 -277.875056) (xy 126.211882 -277.863196) (xy 126.162268 -277.843724) (xy 126.11611 -277.817075)
			(xy 126.074439 -277.783844) (xy 126.038187 -277.744773) (xy 126.008163 -277.700736) (xy 125.985037 -277.652715)
			(xy 125.969327 -277.601785) (xy 125.961384 -277.549081) (xy 125.733058 -277.549081) (xy 125.725115 -277.601785)
			(xy 125.709405 -277.652715) (xy 125.686279 -277.700736) (xy 125.656255 -277.744773) (xy 125.620003 -277.783844)
			(xy 125.578332 -277.817075) (xy 125.532174 -277.843724) (xy 125.48256 -277.863196) (xy 125.430598 -277.875056)
			(xy 125.377448 -277.87904) (xy 125.324298 -277.875056) (xy 125.272336 -277.863196) (xy 125.222722 -277.843724)
			(xy 125.176564 -277.817075) (xy 125.134893 -277.783844) (xy 125.098641 -277.744773) (xy 125.068617 -277.700736)
			(xy 125.045491 -277.652715) (xy 125.029781 -277.601785) (xy 125.021838 -277.549081) (xy 124.793004 -277.549081)
			(xy 124.785061 -277.601785) (xy 124.769351 -277.652715) (xy 124.746225 -277.700736) (xy 124.716201 -277.744773)
			(xy 124.679949 -277.783844) (xy 124.638278 -277.817075) (xy 124.59212 -277.843724) (xy 124.542506 -277.863196)
			(xy 124.490544 -277.875056) (xy 124.437394 -277.87904) (xy 124.384244 -277.875056) (xy 124.332282 -277.863196)
			(xy 124.282668 -277.843724) (xy 124.23651 -277.817075) (xy 124.194839 -277.783844) (xy 124.158587 -277.744773)
			(xy 124.128563 -277.700736) (xy 124.105437 -277.652715) (xy 124.089727 -277.601785) (xy 124.081784 -277.549081)
			(xy 123.853204 -277.549081) (xy 123.845261 -277.601785) (xy 123.829551 -277.652715) (xy 123.806425 -277.700736)
			(xy 123.776401 -277.744773) (xy 123.740149 -277.783844) (xy 123.698478 -277.817075) (xy 123.65232 -277.843724)
			(xy 123.602706 -277.863196) (xy 123.550744 -277.875056) (xy 123.497594 -277.87904) (xy 123.444444 -277.875056)
			(xy 123.392482 -277.863196) (xy 123.342868 -277.843724) (xy 123.29671 -277.817075) (xy 123.255039 -277.783844)
			(xy 123.218787 -277.744773) (xy 123.188763 -277.700736) (xy 123.165637 -277.652715) (xy 123.149927 -277.601785)
			(xy 123.141984 -277.549081) (xy 122.91362 -277.549081) (xy 122.905715 -277.601531) (xy 122.890005 -277.652461)
			(xy 122.866879 -277.700482) (xy 122.836855 -277.744519) (xy 122.800603 -277.78359) (xy 122.758932 -277.816821)
			(xy 122.712774 -277.84347) (xy 122.66316 -277.862942) (xy 122.611198 -277.874802) (xy 122.558048 -277.878786)
			(xy 122.504898 -277.874802) (xy 122.452936 -277.862942) (xy 122.403322 -277.84347) (xy 122.357164 -277.816821)
			(xy 122.315493 -277.78359) (xy 122.279241 -277.744519) (xy 122.249217 -277.700482) (xy 122.226091 -277.652461)
			(xy 122.210381 -277.601531) (xy 122.202438 -277.548827) (xy 121.973858 -277.548827) (xy 121.965915 -277.601531)
			(xy 121.950205 -277.652461) (xy 121.927079 -277.700482) (xy 121.897055 -277.744519) (xy 121.860803 -277.78359)
			(xy 121.819132 -277.816821) (xy 121.772974 -277.84347) (xy 121.72336 -277.862942) (xy 121.671398 -277.874802)
			(xy 121.618248 -277.878786) (xy 121.565098 -277.874802) (xy 121.513136 -277.862942) (xy 121.463522 -277.84347)
			(xy 121.417364 -277.816821) (xy 121.375693 -277.78359) (xy 121.339441 -277.744519) (xy 121.309417 -277.700482)
			(xy 121.286291 -277.652461) (xy 121.270581 -277.601531) (xy 121.262638 -277.548827) (xy 121.034058 -277.548827)
			(xy 121.026115 -277.601531) (xy 121.010405 -277.652461) (xy 120.987279 -277.700482) (xy 120.957255 -277.744519)
			(xy 120.921003 -277.78359) (xy 120.879332 -277.816821) (xy 120.833174 -277.84347) (xy 120.78356 -277.862942)
			(xy 120.731598 -277.874802) (xy 120.678448 -277.878786) (xy 120.625298 -277.874802) (xy 120.573336 -277.862942)
			(xy 120.523722 -277.84347) (xy 120.477564 -277.816821) (xy 120.435893 -277.78359) (xy 120.399641 -277.744519)
			(xy 120.369617 -277.700482) (xy 120.346491 -277.652461) (xy 120.330781 -277.601531) (xy 120.322838 -277.548827)
			(xy 120.094258 -277.548827) (xy 120.086315 -277.601531) (xy 120.070605 -277.652461) (xy 120.047479 -277.700482)
			(xy 120.017455 -277.744519) (xy 119.981203 -277.78359) (xy 119.939532 -277.816821) (xy 119.893374 -277.84347)
			(xy 119.84376 -277.862942) (xy 119.791798 -277.874802) (xy 119.738648 -277.878786) (xy 119.685498 -277.874802)
			(xy 119.633536 -277.862942) (xy 119.583922 -277.84347) (xy 119.537764 -277.816821) (xy 119.496093 -277.78359)
			(xy 119.459841 -277.744519) (xy 119.429817 -277.700482) (xy 119.406691 -277.652461) (xy 119.390981 -277.601531)
			(xy 119.383038 -277.548827) (xy 119.154463 -277.548827) (xy 119.154458 -277.549081) (xy 119.146515 -277.601785)
			(xy 119.130805 -277.652715) (xy 119.107679 -277.700736) (xy 119.077655 -277.744773) (xy 119.041403 -277.783844)
			(xy 118.999732 -277.817075) (xy 118.953574 -277.843724) (xy 118.90396 -277.863196) (xy 118.851998 -277.875056)
			(xy 118.798848 -277.87904) (xy 118.745698 -277.875056) (xy 118.693736 -277.863196) (xy 118.644122 -277.843724)
			(xy 118.597964 -277.817075) (xy 118.556293 -277.783844) (xy 118.520041 -277.744773) (xy 118.490017 -277.700736)
			(xy 118.466891 -277.652715) (xy 118.451181 -277.601785) (xy 118.443238 -277.549081) (xy 118.21462 -277.549081)
			(xy 118.206715 -277.601531) (xy 118.191005 -277.652461) (xy 118.167879 -277.700482) (xy 118.137855 -277.744519)
			(xy 118.101603 -277.78359) (xy 118.059932 -277.816821) (xy 118.013774 -277.84347) (xy 117.96416 -277.862942)
			(xy 117.912198 -277.874802) (xy 117.859048 -277.878786) (xy 117.805898 -277.874802) (xy 117.753936 -277.862942)
			(xy 117.704322 -277.84347) (xy 117.658164 -277.816821) (xy 117.616493 -277.78359) (xy 117.580241 -277.744519)
			(xy 117.550217 -277.700482) (xy 117.527091 -277.652461) (xy 117.511381 -277.601531) (xy 117.503438 -277.548827)
			(xy 117.274609 -277.548827) (xy 117.274604 -277.549081) (xy 117.266661 -277.601785) (xy 117.250951 -277.652715)
			(xy 117.227825 -277.700736) (xy 117.197801 -277.744773) (xy 117.161549 -277.783844) (xy 117.119878 -277.817075)
			(xy 117.07372 -277.843724) (xy 117.024106 -277.863196) (xy 116.972144 -277.875056) (xy 116.918994 -277.87904)
			(xy 116.865844 -277.875056) (xy 116.813882 -277.863196) (xy 116.764268 -277.843724) (xy 116.71811 -277.817075)
			(xy 116.676439 -277.783844) (xy 116.640187 -277.744773) (xy 116.610163 -277.700736) (xy 116.587037 -277.652715)
			(xy 116.571327 -277.601785) (xy 116.563384 -277.549081) (xy 116.335059 -277.549081) (xy 116.327025 -277.602049)
			(xy 116.311111 -277.653286) (xy 116.287689 -277.701556) (xy 116.257291 -277.745765) (xy 116.220604 -277.784913)
			(xy 116.178458 -277.818114) (xy 116.131809 -277.844615) (xy 116.081711 -277.863817) (xy 116.029299 -277.875285)
			(xy 116.002562 -277.877524) (xy 115.988049 -277.878946) (xy 115.960683 -277.888988) (xy 115.937266 -277.906349)
			(xy 115.919706 -277.929616) (xy 115.909431 -277.956895) (xy 115.907278 -277.985966) (xy 115.913422 -278.014461)
			(xy 115.927362 -278.040062) (xy 115.937284 -278.050752) (xy 116.015008 -278.128476) (xy 116.025561 -278.138273)
			(xy 116.050817 -278.152074) (xy 116.07892 -278.158286) (xy 116.10764 -278.156414) (xy 116.134699 -278.146607)
			(xy 116.15795 -278.129644) (xy 116.167154 -278.11857) (xy 116.184143 -278.097429) (xy 116.223437 -278.060048)
			(xy 116.26794 -278.029052) (xy 116.316626 -278.005156) (xy 116.368369 -277.988911) (xy 116.421977 -277.980694)
			(xy 116.449094 -277.98014) (xy 116.477078 -277.98066) (xy 116.532358 -277.989415) (xy 116.585587 -278.006711)
			(xy 116.635454 -278.032122) (xy 116.680732 -278.065021) (xy 116.720306 -278.1046) (xy 116.7532 -278.149881)
			(xy 116.778605 -278.199752) (xy 116.795894 -278.252983) (xy 116.804643 -278.308264) (xy 116.805202 -278.336248)
			(xy 116.804707 -278.362897) (xy 117.033284 -278.362897) (xy 117.033284 -278.309599) (xy 117.041227 -278.256895)
			(xy 117.056937 -278.205965) (xy 117.080063 -278.157944) (xy 117.110087 -278.113907) (xy 117.146339 -278.074836)
			(xy 117.18801 -278.041605) (xy 117.234168 -278.014956) (xy 117.283782 -277.995484) (xy 117.335744 -277.983624)
			(xy 117.388894 -277.979641) (xy 117.442044 -277.983624) (xy 117.494006 -277.995484) (xy 117.54362 -278.014956)
			(xy 117.589778 -278.041605) (xy 117.631449 -278.074836) (xy 117.667701 -278.113907) (xy 117.697725 -278.157944)
			(xy 117.720851 -278.205965) (xy 117.736561 -278.256895) (xy 117.744504 -278.309599) (xy 117.745002 -278.336248)
			(xy 117.744504 -278.362897) (xy 117.973084 -278.362897) (xy 117.973084 -278.309599) (xy 117.981027 -278.256895)
			(xy 117.996737 -278.205965) (xy 118.019863 -278.157944) (xy 118.049887 -278.113907) (xy 118.086139 -278.074836)
			(xy 118.12781 -278.041605) (xy 118.173968 -278.014956) (xy 118.223582 -277.995484) (xy 118.275544 -277.983624)
			(xy 118.328694 -277.979641) (xy 118.381844 -277.983624) (xy 118.433806 -277.995484) (xy 118.48342 -278.014956)
			(xy 118.529578 -278.041605) (xy 118.571249 -278.074836) (xy 118.607501 -278.113907) (xy 118.637525 -278.157944)
			(xy 118.660651 -278.205965) (xy 118.676361 -278.256895) (xy 118.684304 -278.309599) (xy 118.684802 -278.336248)
			(xy 118.684304 -278.362897) (xy 118.684266 -278.363151) (xy 118.913138 -278.363151) (xy 118.913138 -278.309853)
			(xy 118.921081 -278.257149) (xy 118.936791 -278.206219) (xy 118.959917 -278.158198) (xy 118.989941 -278.114161)
			(xy 119.026193 -278.07509) (xy 119.067864 -278.041859) (xy 119.114022 -278.01521) (xy 119.163636 -277.995738)
			(xy 119.215598 -277.983878) (xy 119.268748 -277.979895) (xy 119.321898 -277.983878) (xy 119.37386 -277.995738)
			(xy 119.423474 -278.01521) (xy 119.469632 -278.041859) (xy 119.511303 -278.07509) (xy 119.547555 -278.114161)
			(xy 119.577579 -278.158198) (xy 119.600705 -278.206219) (xy 119.616415 -278.257149) (xy 119.624358 -278.309853)
			(xy 119.624856 -278.336502) (xy 119.624363 -278.362897) (xy 120.792484 -278.362897) (xy 120.792484 -278.309599)
			(xy 120.800427 -278.256895) (xy 120.816137 -278.205965) (xy 120.839263 -278.157944) (xy 120.869287 -278.113907)
			(xy 120.905539 -278.074836) (xy 120.94721 -278.041605) (xy 120.993368 -278.014956) (xy 121.042982 -277.995484)
			(xy 121.094944 -277.983624) (xy 121.148094 -277.979641) (xy 121.201244 -277.983624) (xy 121.253206 -277.995484)
			(xy 121.30282 -278.014956) (xy 121.348978 -278.041605) (xy 121.390649 -278.074836) (xy 121.426901 -278.113907)
			(xy 121.456925 -278.157944) (xy 121.480051 -278.205965) (xy 121.495761 -278.256895) (xy 121.503704 -278.309599)
			(xy 121.504202 -278.336248) (xy 121.503704 -278.362897) (xy 121.503666 -278.363151) (xy 121.732284 -278.363151)
			(xy 121.732284 -278.309853) (xy 121.740227 -278.257149) (xy 121.755937 -278.206219) (xy 121.779063 -278.158198)
			(xy 121.809087 -278.114161) (xy 121.845339 -278.07509) (xy 121.88701 -278.041859) (xy 121.933168 -278.01521)
			(xy 121.982782 -277.995738) (xy 122.034744 -277.983878) (xy 122.087894 -277.979895) (xy 122.141044 -277.983878)
			(xy 122.193006 -277.995738) (xy 122.24262 -278.01521) (xy 122.288778 -278.041859) (xy 122.330449 -278.07509)
			(xy 122.366701 -278.114161) (xy 122.396725 -278.158198) (xy 122.419851 -278.206219) (xy 122.435561 -278.257149)
			(xy 122.443504 -278.309853) (xy 122.444002 -278.336502) (xy 122.443504 -278.363151) (xy 122.672338 -278.363151)
			(xy 122.672338 -278.309853) (xy 122.680281 -278.257149) (xy 122.695991 -278.206219) (xy 122.719117 -278.158198)
			(xy 122.749141 -278.114161) (xy 122.785393 -278.07509) (xy 122.827064 -278.041859) (xy 122.873222 -278.01521)
			(xy 122.922836 -277.995738) (xy 122.974798 -277.983878) (xy 123.027948 -277.979895) (xy 123.081098 -277.983878)
			(xy 123.13306 -277.995738) (xy 123.182674 -278.01521) (xy 123.228832 -278.041859) (xy 123.270503 -278.07509)
			(xy 123.306755 -278.114161) (xy 123.336779 -278.158198) (xy 123.359905 -278.206219) (xy 123.375615 -278.257149)
			(xy 123.383558 -278.309853) (xy 123.384056 -278.336502) (xy 123.383558 -278.363151) (xy 124.551938 -278.363151)
			(xy 124.551938 -278.309853) (xy 124.559881 -278.257149) (xy 124.575591 -278.206219) (xy 124.598717 -278.158198)
			(xy 124.628741 -278.114161) (xy 124.664993 -278.07509) (xy 124.706664 -278.041859) (xy 124.752822 -278.01521)
			(xy 124.802436 -277.995738) (xy 124.854398 -277.983878) (xy 124.907548 -277.979895) (xy 124.960698 -277.983878)
			(xy 125.01266 -277.995738) (xy 125.062274 -278.01521) (xy 125.108432 -278.041859) (xy 125.150103 -278.07509)
			(xy 125.186355 -278.114161) (xy 125.216379 -278.158198) (xy 125.239505 -278.206219) (xy 125.255215 -278.257149)
			(xy 125.263158 -278.309853) (xy 125.263656 -278.336502) (xy 125.263158 -278.363151) (xy 125.491738 -278.363151)
			(xy 125.491738 -278.309853) (xy 125.499681 -278.257149) (xy 125.515391 -278.206219) (xy 125.538517 -278.158198)
			(xy 125.568541 -278.114161) (xy 125.604793 -278.07509) (xy 125.646464 -278.041859) (xy 125.692622 -278.01521)
			(xy 125.742236 -277.995738) (xy 125.794198 -277.983878) (xy 125.847348 -277.979895) (xy 125.900498 -277.983878)
			(xy 125.95246 -277.995738) (xy 126.002074 -278.01521) (xy 126.048232 -278.041859) (xy 126.089903 -278.07509)
			(xy 126.126155 -278.114161) (xy 126.156179 -278.158198) (xy 126.179305 -278.206219) (xy 126.195015 -278.257149)
			(xy 126.202958 -278.309853) (xy 126.203456 -278.336502) (xy 126.202958 -278.363151) (xy 126.431538 -278.363151)
			(xy 126.431538 -278.309853) (xy 126.439481 -278.257149) (xy 126.455191 -278.206219) (xy 126.478317 -278.158198)
			(xy 126.508341 -278.114161) (xy 126.544593 -278.07509) (xy 126.586264 -278.041859) (xy 126.632422 -278.01521)
			(xy 126.682036 -277.995738) (xy 126.733998 -277.983878) (xy 126.787148 -277.979895) (xy 126.840298 -277.983878)
			(xy 126.89226 -277.995738) (xy 126.941874 -278.01521) (xy 126.988032 -278.041859) (xy 127.029703 -278.07509)
			(xy 127.065955 -278.114161) (xy 127.095979 -278.158198) (xy 127.119105 -278.206219) (xy 127.134815 -278.257149)
			(xy 127.142758 -278.309853) (xy 127.143256 -278.336502) (xy 127.142758 -278.363151) (xy 127.371338 -278.363151)
			(xy 127.371338 -278.309853) (xy 127.379281 -278.257149) (xy 127.394991 -278.206219) (xy 127.418117 -278.158198)
			(xy 127.448141 -278.114161) (xy 127.484393 -278.07509) (xy 127.526064 -278.041859) (xy 127.572222 -278.01521)
			(xy 127.621836 -277.995738) (xy 127.673798 -277.983878) (xy 127.726948 -277.979895) (xy 127.780098 -277.983878)
			(xy 127.83206 -277.995738) (xy 127.881674 -278.01521) (xy 127.927832 -278.041859) (xy 127.969503 -278.07509)
			(xy 128.005755 -278.114161) (xy 128.035779 -278.158198) (xy 128.058905 -278.206219) (xy 128.074615 -278.257149)
			(xy 128.082558 -278.309853) (xy 128.083056 -278.336502) (xy 128.082558 -278.363151) (xy 128.310884 -278.363151)
			(xy 128.310884 -278.309853) (xy 128.318827 -278.257149) (xy 128.334537 -278.206219) (xy 128.357663 -278.158198)
			(xy 128.387687 -278.114161) (xy 128.423939 -278.07509) (xy 128.46561 -278.041859) (xy 128.511768 -278.01521)
			(xy 128.561382 -277.995738) (xy 128.613344 -277.983878) (xy 128.666494 -277.979895) (xy 128.719644 -277.983878)
			(xy 128.771606 -277.995738) (xy 128.82122 -278.01521) (xy 128.867378 -278.041859) (xy 128.909049 -278.07509)
			(xy 128.945301 -278.114161) (xy 128.975325 -278.158198) (xy 128.998451 -278.206219) (xy 129.014161 -278.257149)
			(xy 129.022104 -278.309853) (xy 129.022602 -278.336502) (xy 129.022104 -278.363151) (xy 129.250938 -278.363151)
			(xy 129.250938 -278.309853) (xy 129.258881 -278.257149) (xy 129.274591 -278.206219) (xy 129.297717 -278.158198)
			(xy 129.327741 -278.114161) (xy 129.363993 -278.07509) (xy 129.405664 -278.041859) (xy 129.451822 -278.01521)
			(xy 129.501436 -277.995738) (xy 129.553398 -277.983878) (xy 129.606548 -277.979895) (xy 129.659698 -277.983878)
			(xy 129.71166 -277.995738) (xy 129.761274 -278.01521) (xy 129.807432 -278.041859) (xy 129.849103 -278.07509)
			(xy 129.885355 -278.114161) (xy 129.915379 -278.158198) (xy 129.938505 -278.206219) (xy 129.954215 -278.257149)
			(xy 129.962158 -278.309853) (xy 129.962656 -278.336502) (xy 129.962158 -278.363151) (xy 130.190484 -278.363151)
			(xy 130.190484 -278.309853) (xy 130.198427 -278.257149) (xy 130.214137 -278.206219) (xy 130.237263 -278.158198)
			(xy 130.267287 -278.114161) (xy 130.303539 -278.07509) (xy 130.34521 -278.041859) (xy 130.391368 -278.01521)
			(xy 130.440982 -277.995738) (xy 130.492944 -277.983878) (xy 130.546094 -277.979895) (xy 130.599244 -277.983878)
			(xy 130.651206 -277.995738) (xy 130.70082 -278.01521) (xy 130.746978 -278.041859) (xy 130.788649 -278.07509)
			(xy 130.824901 -278.114161) (xy 130.854925 -278.158198) (xy 130.878051 -278.206219) (xy 130.893761 -278.257149)
			(xy 130.901704 -278.309853) (xy 130.902202 -278.336502) (xy 130.901704 -278.363151) (xy 131.130538 -278.363151)
			(xy 131.130538 -278.309853) (xy 131.138481 -278.257149) (xy 131.154191 -278.206219) (xy 131.177317 -278.158198)
			(xy 131.207341 -278.114161) (xy 131.243593 -278.07509) (xy 131.285264 -278.041859) (xy 131.331422 -278.01521)
			(xy 131.381036 -277.995738) (xy 131.432998 -277.983878) (xy 131.486148 -277.979895) (xy 131.539298 -277.983878)
			(xy 131.59126 -277.995738) (xy 131.640874 -278.01521) (xy 131.687032 -278.041859) (xy 131.728703 -278.07509)
			(xy 131.764955 -278.114161) (xy 131.794979 -278.158198) (xy 131.818105 -278.206219) (xy 131.833815 -278.257149)
			(xy 131.841758 -278.309853) (xy 131.842256 -278.336502) (xy 131.841758 -278.363151) (xy 132.070338 -278.363151)
			(xy 132.070338 -278.309853) (xy 132.078281 -278.257149) (xy 132.093991 -278.206219) (xy 132.117117 -278.158198)
			(xy 132.147141 -278.114161) (xy 132.183393 -278.07509) (xy 132.225064 -278.041859) (xy 132.271222 -278.01521)
			(xy 132.320836 -277.995738) (xy 132.372798 -277.983878) (xy 132.425948 -277.979895) (xy 132.479098 -277.983878)
			(xy 132.53106 -277.995738) (xy 132.580674 -278.01521) (xy 132.626832 -278.041859) (xy 132.668503 -278.07509)
			(xy 132.704755 -278.114161) (xy 132.734779 -278.158198) (xy 132.757905 -278.206219) (xy 132.773615 -278.257149)
			(xy 132.781558 -278.309853) (xy 132.782056 -278.336502) (xy 132.781558 -278.363151) (xy 133.010138 -278.363151)
			(xy 133.010138 -278.309853) (xy 133.018081 -278.257149) (xy 133.033791 -278.206219) (xy 133.056917 -278.158198)
			(xy 133.086941 -278.114161) (xy 133.123193 -278.07509) (xy 133.164864 -278.041859) (xy 133.211022 -278.01521)
			(xy 133.260636 -277.995738) (xy 133.312598 -277.983878) (xy 133.365748 -277.979895) (xy 133.418898 -277.983878)
			(xy 133.47086 -277.995738) (xy 133.520474 -278.01521) (xy 133.566632 -278.041859) (xy 133.608303 -278.07509)
			(xy 133.644555 -278.114161) (xy 133.674579 -278.158198) (xy 133.697705 -278.206219) (xy 133.713415 -278.257149)
			(xy 133.721358 -278.309853) (xy 133.721856 -278.336502) (xy 133.721358 -278.363151) (xy 133.713415 -278.415855)
			(xy 133.697705 -278.466785) (xy 133.674579 -278.514806) (xy 133.644555 -278.558843) (xy 133.608303 -278.597914)
			(xy 133.566632 -278.631145) (xy 133.520474 -278.657794) (xy 133.47086 -278.677266) (xy 133.418898 -278.689126)
			(xy 133.365748 -278.69311) (xy 133.312598 -278.689126) (xy 133.260636 -278.677266) (xy 133.211022 -278.657794)
			(xy 133.164864 -278.631145) (xy 133.123193 -278.597914) (xy 133.086941 -278.558843) (xy 133.056917 -278.514806)
			(xy 133.033791 -278.466785) (xy 133.018081 -278.415855) (xy 133.010138 -278.363151) (xy 132.781558 -278.363151)
			(xy 132.773615 -278.415855) (xy 132.757905 -278.466785) (xy 132.734779 -278.514806) (xy 132.704755 -278.558843)
			(xy 132.668503 -278.597914) (xy 132.626832 -278.631145) (xy 132.580674 -278.657794) (xy 132.53106 -278.677266)
			(xy 132.479098 -278.689126) (xy 132.425948 -278.69311) (xy 132.372798 -278.689126) (xy 132.320836 -278.677266)
			(xy 132.271222 -278.657794) (xy 132.225064 -278.631145) (xy 132.183393 -278.597914) (xy 132.147141 -278.558843)
			(xy 132.117117 -278.514806) (xy 132.093991 -278.466785) (xy 132.078281 -278.415855) (xy 132.070338 -278.363151)
			(xy 131.841758 -278.363151) (xy 131.833815 -278.415855) (xy 131.818105 -278.466785) (xy 131.794979 -278.514806)
			(xy 131.764955 -278.558843) (xy 131.728703 -278.597914) (xy 131.687032 -278.631145) (xy 131.640874 -278.657794)
			(xy 131.59126 -278.677266) (xy 131.539298 -278.689126) (xy 131.486148 -278.69311) (xy 131.432998 -278.689126)
			(xy 131.381036 -278.677266) (xy 131.331422 -278.657794) (xy 131.285264 -278.631145) (xy 131.243593 -278.597914)
			(xy 131.207341 -278.558843) (xy 131.177317 -278.514806) (xy 131.154191 -278.466785) (xy 131.138481 -278.415855)
			(xy 131.130538 -278.363151) (xy 130.901704 -278.363151) (xy 130.893761 -278.415855) (xy 130.878051 -278.466785)
			(xy 130.854925 -278.514806) (xy 130.824901 -278.558843) (xy 130.788649 -278.597914) (xy 130.746978 -278.631145)
			(xy 130.70082 -278.657794) (xy 130.651206 -278.677266) (xy 130.599244 -278.689126) (xy 130.546094 -278.69311)
			(xy 130.492944 -278.689126) (xy 130.440982 -278.677266) (xy 130.391368 -278.657794) (xy 130.34521 -278.631145)
			(xy 130.303539 -278.597914) (xy 130.267287 -278.558843) (xy 130.237263 -278.514806) (xy 130.214137 -278.466785)
			(xy 130.198427 -278.415855) (xy 130.190484 -278.363151) (xy 129.962158 -278.363151) (xy 129.954215 -278.415855)
			(xy 129.938505 -278.466785) (xy 129.915379 -278.514806) (xy 129.885355 -278.558843) (xy 129.849103 -278.597914)
			(xy 129.807432 -278.631145) (xy 129.761274 -278.657794) (xy 129.71166 -278.677266) (xy 129.659698 -278.689126)
			(xy 129.606548 -278.69311) (xy 129.553398 -278.689126) (xy 129.501436 -278.677266) (xy 129.451822 -278.657794)
			(xy 129.405664 -278.631145) (xy 129.363993 -278.597914) (xy 129.327741 -278.558843) (xy 129.297717 -278.514806)
			(xy 129.274591 -278.466785) (xy 129.258881 -278.415855) (xy 129.250938 -278.363151) (xy 129.022104 -278.363151)
			(xy 129.014161 -278.415855) (xy 128.998451 -278.466785) (xy 128.975325 -278.514806) (xy 128.945301 -278.558843)
			(xy 128.909049 -278.597914) (xy 128.867378 -278.631145) (xy 128.82122 -278.657794) (xy 128.771606 -278.677266)
			(xy 128.719644 -278.689126) (xy 128.666494 -278.69311) (xy 128.613344 -278.689126) (xy 128.561382 -278.677266)
			(xy 128.511768 -278.657794) (xy 128.46561 -278.631145) (xy 128.423939 -278.597914) (xy 128.387687 -278.558843)
			(xy 128.357663 -278.514806) (xy 128.334537 -278.466785) (xy 128.318827 -278.415855) (xy 128.310884 -278.363151)
			(xy 128.082558 -278.363151) (xy 128.074615 -278.415855) (xy 128.058905 -278.466785) (xy 128.035779 -278.514806)
			(xy 128.005755 -278.558843) (xy 127.969503 -278.597914) (xy 127.927832 -278.631145) (xy 127.881674 -278.657794)
			(xy 127.83206 -278.677266) (xy 127.780098 -278.689126) (xy 127.726948 -278.69311) (xy 127.673798 -278.689126)
			(xy 127.621836 -278.677266) (xy 127.572222 -278.657794) (xy 127.526064 -278.631145) (xy 127.484393 -278.597914)
			(xy 127.448141 -278.558843) (xy 127.418117 -278.514806) (xy 127.394991 -278.466785) (xy 127.379281 -278.415855)
			(xy 127.371338 -278.363151) (xy 127.142758 -278.363151) (xy 127.134815 -278.415855) (xy 127.119105 -278.466785)
			(xy 127.095979 -278.514806) (xy 127.065955 -278.558843) (xy 127.029703 -278.597914) (xy 126.988032 -278.631145)
			(xy 126.941874 -278.657794) (xy 126.89226 -278.677266) (xy 126.840298 -278.689126) (xy 126.787148 -278.69311)
			(xy 126.733998 -278.689126) (xy 126.682036 -278.677266) (xy 126.632422 -278.657794) (xy 126.586264 -278.631145)
			(xy 126.544593 -278.597914) (xy 126.508341 -278.558843) (xy 126.478317 -278.514806) (xy 126.455191 -278.466785)
			(xy 126.439481 -278.415855) (xy 126.431538 -278.363151) (xy 126.202958 -278.363151) (xy 126.195015 -278.415855)
			(xy 126.179305 -278.466785) (xy 126.156179 -278.514806) (xy 126.126155 -278.558843) (xy 126.089903 -278.597914)
			(xy 126.048232 -278.631145) (xy 126.002074 -278.657794) (xy 125.95246 -278.677266) (xy 125.900498 -278.689126)
			(xy 125.847348 -278.69311) (xy 125.794198 -278.689126) (xy 125.742236 -278.677266) (xy 125.692622 -278.657794)
			(xy 125.646464 -278.631145) (xy 125.604793 -278.597914) (xy 125.568541 -278.558843) (xy 125.538517 -278.514806)
			(xy 125.515391 -278.466785) (xy 125.499681 -278.415855) (xy 125.491738 -278.363151) (xy 125.263158 -278.363151)
			(xy 125.255215 -278.415855) (xy 125.239505 -278.466785) (xy 125.216379 -278.514806) (xy 125.186355 -278.558843)
			(xy 125.150103 -278.597914) (xy 125.108432 -278.631145) (xy 125.062274 -278.657794) (xy 125.01266 -278.677266)
			(xy 124.960698 -278.689126) (xy 124.907548 -278.69311) (xy 124.854398 -278.689126) (xy 124.802436 -278.677266)
			(xy 124.752822 -278.657794) (xy 124.706664 -278.631145) (xy 124.664993 -278.597914) (xy 124.628741 -278.558843)
			(xy 124.598717 -278.514806) (xy 124.575591 -278.466785) (xy 124.559881 -278.415855) (xy 124.551938 -278.363151)
			(xy 123.383558 -278.363151) (xy 123.375615 -278.415855) (xy 123.359905 -278.466785) (xy 123.336779 -278.514806)
			(xy 123.306755 -278.558843) (xy 123.270503 -278.597914) (xy 123.228832 -278.631145) (xy 123.182674 -278.657794)
			(xy 123.13306 -278.677266) (xy 123.081098 -278.689126) (xy 123.027948 -278.69311) (xy 122.974798 -278.689126)
			(xy 122.922836 -278.677266) (xy 122.873222 -278.657794) (xy 122.827064 -278.631145) (xy 122.785393 -278.597914)
			(xy 122.749141 -278.558843) (xy 122.719117 -278.514806) (xy 122.695991 -278.466785) (xy 122.680281 -278.415855)
			(xy 122.672338 -278.363151) (xy 122.443504 -278.363151) (xy 122.435561 -278.415855) (xy 122.419851 -278.466785)
			(xy 122.396725 -278.514806) (xy 122.366701 -278.558843) (xy 122.330449 -278.597914) (xy 122.288778 -278.631145)
			(xy 122.24262 -278.657794) (xy 122.193006 -278.677266) (xy 122.141044 -278.689126) (xy 122.087894 -278.69311)
			(xy 122.034744 -278.689126) (xy 121.982782 -278.677266) (xy 121.933168 -278.657794) (xy 121.88701 -278.631145)
			(xy 121.845339 -278.597914) (xy 121.809087 -278.558843) (xy 121.779063 -278.514806) (xy 121.755937 -278.466785)
			(xy 121.740227 -278.415855) (xy 121.732284 -278.363151) (xy 121.503666 -278.363151) (xy 121.495761 -278.415601)
			(xy 121.480051 -278.466531) (xy 121.456925 -278.514552) (xy 121.426901 -278.558589) (xy 121.390649 -278.59766)
			(xy 121.348978 -278.630891) (xy 121.30282 -278.65754) (xy 121.253206 -278.677012) (xy 121.201244 -278.688872)
			(xy 121.148094 -278.692856) (xy 121.094944 -278.688872) (xy 121.042982 -278.677012) (xy 120.993368 -278.65754)
			(xy 120.94721 -278.630891) (xy 120.905539 -278.59766) (xy 120.869287 -278.558589) (xy 120.839263 -278.514552)
			(xy 120.816137 -278.466531) (xy 120.800427 -278.415601) (xy 120.792484 -278.362897) (xy 119.624363 -278.362897)
			(xy 119.624358 -278.363151) (xy 119.616415 -278.415855) (xy 119.600705 -278.466785) (xy 119.577579 -278.514806)
			(xy 119.547555 -278.558843) (xy 119.511303 -278.597914) (xy 119.469632 -278.631145) (xy 119.423474 -278.657794)
			(xy 119.37386 -278.677266) (xy 119.321898 -278.689126) (xy 119.268748 -278.69311) (xy 119.215598 -278.689126)
			(xy 119.163636 -278.677266) (xy 119.114022 -278.657794) (xy 119.067864 -278.631145) (xy 119.026193 -278.597914)
			(xy 118.989941 -278.558843) (xy 118.959917 -278.514806) (xy 118.936791 -278.466785) (xy 118.921081 -278.415855)
			(xy 118.913138 -278.363151) (xy 118.684266 -278.363151) (xy 118.676361 -278.415601) (xy 118.660651 -278.466531)
			(xy 118.637525 -278.514552) (xy 118.607501 -278.558589) (xy 118.571249 -278.59766) (xy 118.529578 -278.630891)
			(xy 118.48342 -278.65754) (xy 118.433806 -278.677012) (xy 118.381844 -278.688872) (xy 118.328694 -278.692856)
			(xy 118.275544 -278.688872) (xy 118.223582 -278.677012) (xy 118.173968 -278.65754) (xy 118.12781 -278.630891)
			(xy 118.086139 -278.59766) (xy 118.049887 -278.558589) (xy 118.019863 -278.514552) (xy 117.996737 -278.466531)
			(xy 117.981027 -278.415601) (xy 117.973084 -278.362897) (xy 117.744504 -278.362897) (xy 117.736561 -278.415601)
			(xy 117.720851 -278.466531) (xy 117.697725 -278.514552) (xy 117.667701 -278.558589) (xy 117.631449 -278.59766)
			(xy 117.589778 -278.630891) (xy 117.54362 -278.65754) (xy 117.494006 -278.677012) (xy 117.442044 -278.688872)
			(xy 117.388894 -278.692856) (xy 117.335744 -278.688872) (xy 117.283782 -278.677012) (xy 117.234168 -278.65754)
			(xy 117.18801 -278.630891) (xy 117.146339 -278.59766) (xy 117.110087 -278.558589) (xy 117.080063 -278.514552)
			(xy 117.056937 -278.466531) (xy 117.041227 -278.415601) (xy 117.033284 -278.362897) (xy 116.804707 -278.362897)
			(xy 116.804698 -278.363369) (xy 116.796485 -278.416985) (xy 116.780239 -278.468736) (xy 116.756338 -278.517427)
			(xy 116.725332 -278.561933) (xy 116.687939 -278.601226) (xy 116.666772 -278.618188) (xy 116.65566 -278.627363)
			(xy 116.638648 -278.650605) (xy 116.628815 -278.677677) (xy 116.626945 -278.706419) (xy 116.633188 -278.734537)
			(xy 116.647046 -278.759787) (xy 116.656866 -278.770334) (xy 116.731796 -278.845264) (xy 116.764308 -278.829516)
			(xy 116.788579 -278.818295) (xy 116.839648 -278.802455) (xy 116.892513 -278.794441) (xy 116.919248 -278.793956)
			(xy 116.94723 -278.794509) (xy 117.002503 -278.803269) (xy 117.055726 -278.820568) (xy 117.105588 -278.845978)
			(xy 117.150862 -278.878874) (xy 117.190434 -278.918447) (xy 117.223329 -278.963722) (xy 117.248737 -279.013585)
			(xy 117.266034 -279.066809) (xy 117.274792 -279.122082) (xy 117.275356 -279.150064) (xy 117.274857 -279.176967)
			(xy 117.503438 -279.176967) (xy 117.503438 -279.123669) (xy 117.511381 -279.070965) (xy 117.527091 -279.020035)
			(xy 117.550217 -278.972014) (xy 117.580241 -278.927977) (xy 117.616493 -278.888906) (xy 117.658164 -278.855675)
			(xy 117.704322 -278.829026) (xy 117.753936 -278.809554) (xy 117.805898 -278.797694) (xy 117.859048 -278.793711)
			(xy 117.912198 -278.797694) (xy 117.96416 -278.809554) (xy 118.013774 -278.829026) (xy 118.059932 -278.855675)
			(xy 118.101603 -278.888906) (xy 118.137855 -278.927977) (xy 118.167879 -278.972014) (xy 118.191005 -279.020035)
			(xy 118.206715 -279.070965) (xy 118.214658 -279.123669) (xy 118.215156 -279.150318) (xy 118.214658 -279.176967)
			(xy 119.382784 -279.176967) (xy 119.382784 -279.123669) (xy 119.390727 -279.070965) (xy 119.406437 -279.020035)
			(xy 119.429563 -278.972014) (xy 119.459587 -278.927977) (xy 119.495839 -278.888906) (xy 119.53751 -278.855675)
			(xy 119.583668 -278.829026) (xy 119.633282 -278.809554) (xy 119.685244 -278.797694) (xy 119.738394 -278.793711)
			(xy 119.791544 -278.797694) (xy 119.843506 -278.809554) (xy 119.89312 -278.829026) (xy 119.939278 -278.855675)
			(xy 119.980949 -278.888906) (xy 120.017201 -278.927977) (xy 120.047225 -278.972014) (xy 120.070351 -279.020035)
			(xy 120.086061 -279.070965) (xy 120.094004 -279.123669) (xy 120.094502 -279.150318) (xy 120.094004 -279.176967)
			(xy 120.322838 -279.176967) (xy 120.322838 -279.123669) (xy 120.330781 -279.070965) (xy 120.346491 -279.020035)
			(xy 120.369617 -278.972014) (xy 120.399641 -278.927977) (xy 120.435893 -278.888906) (xy 120.477564 -278.855675)
			(xy 120.523722 -278.829026) (xy 120.573336 -278.809554) (xy 120.625298 -278.797694) (xy 120.678448 -278.793711)
			(xy 120.731598 -278.797694) (xy 120.78356 -278.809554) (xy 120.833174 -278.829026) (xy 120.879332 -278.855675)
			(xy 120.921003 -278.888906) (xy 120.957255 -278.927977) (xy 120.987279 -278.972014) (xy 121.010405 -279.020035)
			(xy 121.026115 -279.070965) (xy 121.034058 -279.123669) (xy 121.034556 -279.150318) (xy 121.034058 -279.176967)
			(xy 121.262384 -279.176967) (xy 121.262384 -279.123669) (xy 121.270327 -279.070965) (xy 121.286037 -279.020035)
			(xy 121.309163 -278.972014) (xy 121.339187 -278.927977) (xy 121.375439 -278.888906) (xy 121.41711 -278.855675)
			(xy 121.463268 -278.829026) (xy 121.512882 -278.809554) (xy 121.564844 -278.797694) (xy 121.617994 -278.793711)
			(xy 121.671144 -278.797694) (xy 121.723106 -278.809554) (xy 121.77272 -278.829026) (xy 121.818878 -278.855675)
			(xy 121.860549 -278.888906) (xy 121.896801 -278.927977) (xy 121.926825 -278.972014) (xy 121.949951 -279.020035)
			(xy 121.965661 -279.070965) (xy 121.973604 -279.123669) (xy 121.974102 -279.150318) (xy 121.973604 -279.176967)
			(xy 122.202184 -279.176967) (xy 122.202184 -279.123669) (xy 122.210127 -279.070965) (xy 122.225837 -279.020035)
			(xy 122.248963 -278.972014) (xy 122.278987 -278.927977) (xy 122.315239 -278.888906) (xy 122.35691 -278.855675)
			(xy 122.403068 -278.829026) (xy 122.452682 -278.809554) (xy 122.504644 -278.797694) (xy 122.557794 -278.793711)
			(xy 122.610944 -278.797694) (xy 122.662906 -278.809554) (xy 122.71252 -278.829026) (xy 122.758678 -278.855675)
			(xy 122.800349 -278.888906) (xy 122.836601 -278.927977) (xy 122.866625 -278.972014) (xy 122.889751 -279.020035)
			(xy 122.905461 -279.070965) (xy 122.913404 -279.123669) (xy 122.913902 -279.150318) (xy 122.913404 -279.176967)
			(xy 123.142238 -279.176967) (xy 123.142238 -279.123669) (xy 123.150181 -279.070965) (xy 123.165891 -279.020035)
			(xy 123.189017 -278.972014) (xy 123.219041 -278.927977) (xy 123.255293 -278.888906) (xy 123.296964 -278.855675)
			(xy 123.343122 -278.829026) (xy 123.392736 -278.809554) (xy 123.444698 -278.797694) (xy 123.497848 -278.793711)
			(xy 123.550998 -278.797694) (xy 123.60296 -278.809554) (xy 123.652574 -278.829026) (xy 123.698732 -278.855675)
			(xy 123.740403 -278.888906) (xy 123.776655 -278.927977) (xy 123.806679 -278.972014) (xy 123.829805 -279.020035)
			(xy 123.845515 -279.070965) (xy 123.853458 -279.123669) (xy 123.853956 -279.150318) (xy 123.853458 -279.176967)
			(xy 124.081784 -279.176967) (xy 124.081784 -279.123669) (xy 124.089727 -279.070965) (xy 124.105437 -279.020035)
			(xy 124.128563 -278.972014) (xy 124.158587 -278.927977) (xy 124.194839 -278.888906) (xy 124.23651 -278.855675)
			(xy 124.282668 -278.829026) (xy 124.332282 -278.809554) (xy 124.384244 -278.797694) (xy 124.437394 -278.793711)
			(xy 124.490544 -278.797694) (xy 124.542506 -278.809554) (xy 124.59212 -278.829026) (xy 124.638278 -278.855675)
			(xy 124.679949 -278.888906) (xy 124.716201 -278.927977) (xy 124.746225 -278.972014) (xy 124.769351 -279.020035)
			(xy 124.785061 -279.070965) (xy 124.793004 -279.123669) (xy 124.793502 -279.150318) (xy 124.793004 -279.176967)
			(xy 125.021584 -279.176967) (xy 125.021584 -279.123669) (xy 125.029527 -279.070965) (xy 125.045237 -279.020035)
			(xy 125.068363 -278.972014) (xy 125.098387 -278.927977) (xy 125.134639 -278.888906) (xy 125.17631 -278.855675)
			(xy 125.222468 -278.829026) (xy 125.272082 -278.809554) (xy 125.324044 -278.797694) (xy 125.377194 -278.793711)
			(xy 125.430344 -278.797694) (xy 125.482306 -278.809554) (xy 125.53192 -278.829026) (xy 125.578078 -278.855675)
			(xy 125.619749 -278.888906) (xy 125.656001 -278.927977) (xy 125.686025 -278.972014) (xy 125.709151 -279.020035)
			(xy 125.724861 -279.070965) (xy 125.732804 -279.123669) (xy 125.733302 -279.150318) (xy 125.732804 -279.176967)
			(xy 125.961384 -279.176967) (xy 125.961384 -279.123669) (xy 125.969327 -279.070965) (xy 125.985037 -279.020035)
			(xy 126.008163 -278.972014) (xy 126.038187 -278.927977) (xy 126.074439 -278.888906) (xy 126.11611 -278.855675)
			(xy 126.162268 -278.829026) (xy 126.211882 -278.809554) (xy 126.263844 -278.797694) (xy 126.316994 -278.793711)
			(xy 126.370144 -278.797694) (xy 126.422106 -278.809554) (xy 126.47172 -278.829026) (xy 126.517878 -278.855675)
			(xy 126.559549 -278.888906) (xy 126.595801 -278.927977) (xy 126.625825 -278.972014) (xy 126.648951 -279.020035)
			(xy 126.664661 -279.070965) (xy 126.672604 -279.123669) (xy 126.673102 -279.150318) (xy 126.672604 -279.176967)
			(xy 126.901184 -279.176967) (xy 126.901184 -279.123669) (xy 126.909127 -279.070965) (xy 126.924837 -279.020035)
			(xy 126.947963 -278.972014) (xy 126.977987 -278.927977) (xy 127.014239 -278.888906) (xy 127.05591 -278.855675)
			(xy 127.102068 -278.829026) (xy 127.151682 -278.809554) (xy 127.203644 -278.797694) (xy 127.256794 -278.793711)
			(xy 127.309944 -278.797694) (xy 127.361906 -278.809554) (xy 127.41152 -278.829026) (xy 127.457678 -278.855675)
			(xy 127.499349 -278.888906) (xy 127.535601 -278.927977) (xy 127.565625 -278.972014) (xy 127.588751 -279.020035)
			(xy 127.604461 -279.070965) (xy 127.612404 -279.123669) (xy 127.612902 -279.150318) (xy 127.612404 -279.176967)
			(xy 127.840984 -279.176967) (xy 127.840984 -279.123669) (xy 127.848927 -279.070965) (xy 127.864637 -279.020035)
			(xy 127.887763 -278.972014) (xy 127.917787 -278.927977) (xy 127.954039 -278.888906) (xy 127.99571 -278.855675)
			(xy 128.041868 -278.829026) (xy 128.091482 -278.809554) (xy 128.143444 -278.797694) (xy 128.196594 -278.793711)
			(xy 128.249744 -278.797694) (xy 128.301706 -278.809554) (xy 128.35132 -278.829026) (xy 128.397478 -278.855675)
			(xy 128.439149 -278.888906) (xy 128.475401 -278.927977) (xy 128.505425 -278.972014) (xy 128.528551 -279.020035)
			(xy 128.544261 -279.070965) (xy 128.552204 -279.123669) (xy 128.552702 -279.150318) (xy 128.552204 -279.176967)
			(xy 128.780784 -279.176967) (xy 128.780784 -279.123669) (xy 128.788727 -279.070965) (xy 128.804437 -279.020035)
			(xy 128.827563 -278.972014) (xy 128.857587 -278.927977) (xy 128.893839 -278.888906) (xy 128.93551 -278.855675)
			(xy 128.981668 -278.829026) (xy 129.031282 -278.809554) (xy 129.083244 -278.797694) (xy 129.136394 -278.793711)
			(xy 129.189544 -278.797694) (xy 129.241506 -278.809554) (xy 129.29112 -278.829026) (xy 129.337278 -278.855675)
			(xy 129.378949 -278.888906) (xy 129.415201 -278.927977) (xy 129.445225 -278.972014) (xy 129.468351 -279.020035)
			(xy 129.484061 -279.070965) (xy 129.492004 -279.123669) (xy 129.492502 -279.150318) (xy 129.492004 -279.176967)
			(xy 129.720838 -279.176967) (xy 129.720838 -279.123669) (xy 129.728781 -279.070965) (xy 129.744491 -279.020035)
			(xy 129.767617 -278.972014) (xy 129.797641 -278.927977) (xy 129.833893 -278.888906) (xy 129.875564 -278.855675)
			(xy 129.921722 -278.829026) (xy 129.971336 -278.809554) (xy 130.023298 -278.797694) (xy 130.076448 -278.793711)
			(xy 130.129598 -278.797694) (xy 130.18156 -278.809554) (xy 130.231174 -278.829026) (xy 130.277332 -278.855675)
			(xy 130.319003 -278.888906) (xy 130.355255 -278.927977) (xy 130.385279 -278.972014) (xy 130.408405 -279.020035)
			(xy 130.424115 -279.070965) (xy 130.432058 -279.123669) (xy 130.432556 -279.150318) (xy 130.432058 -279.176967)
			(xy 130.660384 -279.176967) (xy 130.660384 -279.123669) (xy 130.668327 -279.070965) (xy 130.684037 -279.020035)
			(xy 130.707163 -278.972014) (xy 130.737187 -278.927977) (xy 130.773439 -278.888906) (xy 130.81511 -278.855675)
			(xy 130.861268 -278.829026) (xy 130.910882 -278.809554) (xy 130.962844 -278.797694) (xy 131.015994 -278.793711)
			(xy 131.069144 -278.797694) (xy 131.121106 -278.809554) (xy 131.17072 -278.829026) (xy 131.216878 -278.855675)
			(xy 131.258549 -278.888906) (xy 131.294801 -278.927977) (xy 131.324825 -278.972014) (xy 131.347951 -279.020035)
			(xy 131.363661 -279.070965) (xy 131.371604 -279.123669) (xy 131.372102 -279.150318) (xy 131.371604 -279.176967)
			(xy 131.600438 -279.176967) (xy 131.600438 -279.123669) (xy 131.608381 -279.070965) (xy 131.624091 -279.020035)
			(xy 131.647217 -278.972014) (xy 131.677241 -278.927977) (xy 131.713493 -278.888906) (xy 131.755164 -278.855675)
			(xy 131.801322 -278.829026) (xy 131.850936 -278.809554) (xy 131.902898 -278.797694) (xy 131.956048 -278.793711)
			(xy 132.009198 -278.797694) (xy 132.06116 -278.809554) (xy 132.110774 -278.829026) (xy 132.156932 -278.855675)
			(xy 132.198603 -278.888906) (xy 132.234855 -278.927977) (xy 132.264879 -278.972014) (xy 132.288005 -279.020035)
			(xy 132.303715 -279.070965) (xy 132.311658 -279.123669) (xy 132.312156 -279.150318) (xy 132.311658 -279.176967)
			(xy 133.479784 -279.176967) (xy 133.479784 -279.123669) (xy 133.487727 -279.070965) (xy 133.503437 -279.020035)
			(xy 133.526563 -278.972014) (xy 133.556587 -278.927977) (xy 133.592839 -278.888906) (xy 133.63451 -278.855675)
			(xy 133.680668 -278.829026) (xy 133.730282 -278.809554) (xy 133.782244 -278.797694) (xy 133.835394 -278.793711)
			(xy 133.888544 -278.797694) (xy 133.940506 -278.809554) (xy 133.99012 -278.829026) (xy 134.036278 -278.855675)
			(xy 134.077949 -278.888906) (xy 134.114201 -278.927977) (xy 134.144225 -278.972014) (xy 134.167351 -279.020035)
			(xy 134.183061 -279.070965) (xy 134.191004 -279.123669) (xy 134.191502 -279.150318) (xy 134.191004 -279.176967)
			(xy 134.183061 -279.229671) (xy 134.167351 -279.280601) (xy 134.144225 -279.328622) (xy 134.114201 -279.372659)
			(xy 134.077949 -279.41173) (xy 134.036278 -279.444961) (xy 133.99012 -279.47161) (xy 133.940506 -279.491082)
			(xy 133.888544 -279.502942) (xy 133.835394 -279.506926) (xy 133.782244 -279.502942) (xy 133.730282 -279.491082)
			(xy 133.680668 -279.47161) (xy 133.63451 -279.444961) (xy 133.592839 -279.41173) (xy 133.556587 -279.372659)
			(xy 133.526563 -279.328622) (xy 133.503437 -279.280601) (xy 133.487727 -279.229671) (xy 133.479784 -279.176967)
			(xy 132.311658 -279.176967) (xy 132.303715 -279.229671) (xy 132.288005 -279.280601) (xy 132.264879 -279.328622)
			(xy 132.234855 -279.372659) (xy 132.198603 -279.41173) (xy 132.156932 -279.444961) (xy 132.110774 -279.47161)
			(xy 132.06116 -279.491082) (xy 132.009198 -279.502942) (xy 131.956048 -279.506926) (xy 131.902898 -279.502942)
			(xy 131.850936 -279.491082) (xy 131.801322 -279.47161) (xy 131.755164 -279.444961) (xy 131.713493 -279.41173)
			(xy 131.677241 -279.372659) (xy 131.647217 -279.328622) (xy 131.624091 -279.280601) (xy 131.608381 -279.229671)
			(xy 131.600438 -279.176967) (xy 131.371604 -279.176967) (xy 131.363661 -279.229671) (xy 131.347951 -279.280601)
			(xy 131.324825 -279.328622) (xy 131.294801 -279.372659) (xy 131.258549 -279.41173) (xy 131.216878 -279.444961)
			(xy 131.17072 -279.47161) (xy 131.121106 -279.491082) (xy 131.069144 -279.502942) (xy 131.015994 -279.506926)
			(xy 130.962844 -279.502942) (xy 130.910882 -279.491082) (xy 130.861268 -279.47161) (xy 130.81511 -279.444961)
			(xy 130.773439 -279.41173) (xy 130.737187 -279.372659) (xy 130.707163 -279.328622) (xy 130.684037 -279.280601)
			(xy 130.668327 -279.229671) (xy 130.660384 -279.176967) (xy 130.432058 -279.176967) (xy 130.424115 -279.229671)
			(xy 130.408405 -279.280601) (xy 130.385279 -279.328622) (xy 130.355255 -279.372659) (xy 130.319003 -279.41173)
			(xy 130.277332 -279.444961) (xy 130.231174 -279.47161) (xy 130.18156 -279.491082) (xy 130.129598 -279.502942)
			(xy 130.076448 -279.506926) (xy 130.023298 -279.502942) (xy 129.971336 -279.491082) (xy 129.921722 -279.47161)
			(xy 129.875564 -279.444961) (xy 129.833893 -279.41173) (xy 129.797641 -279.372659) (xy 129.767617 -279.328622)
			(xy 129.744491 -279.280601) (xy 129.728781 -279.229671) (xy 129.720838 -279.176967) (xy 129.492004 -279.176967)
			(xy 129.484061 -279.229671) (xy 129.468351 -279.280601) (xy 129.445225 -279.328622) (xy 129.415201 -279.372659)
			(xy 129.378949 -279.41173) (xy 129.337278 -279.444961) (xy 129.29112 -279.47161) (xy 129.241506 -279.491082)
			(xy 129.189544 -279.502942) (xy 129.136394 -279.506926) (xy 129.083244 -279.502942) (xy 129.031282 -279.491082)
			(xy 128.981668 -279.47161) (xy 128.93551 -279.444961) (xy 128.893839 -279.41173) (xy 128.857587 -279.372659)
			(xy 128.827563 -279.328622) (xy 128.804437 -279.280601) (xy 128.788727 -279.229671) (xy 128.780784 -279.176967)
			(xy 128.552204 -279.176967) (xy 128.544261 -279.229671) (xy 128.528551 -279.280601) (xy 128.505425 -279.328622)
			(xy 128.475401 -279.372659) (xy 128.439149 -279.41173) (xy 128.397478 -279.444961) (xy 128.35132 -279.47161)
			(xy 128.301706 -279.491082) (xy 128.249744 -279.502942) (xy 128.196594 -279.506926) (xy 128.143444 -279.502942)
			(xy 128.091482 -279.491082) (xy 128.041868 -279.47161) (xy 127.99571 -279.444961) (xy 127.954039 -279.41173)
			(xy 127.917787 -279.372659) (xy 127.887763 -279.328622) (xy 127.864637 -279.280601) (xy 127.848927 -279.229671)
			(xy 127.840984 -279.176967) (xy 127.612404 -279.176967) (xy 127.604461 -279.229671) (xy 127.588751 -279.280601)
			(xy 127.565625 -279.328622) (xy 127.535601 -279.372659) (xy 127.499349 -279.41173) (xy 127.457678 -279.444961)
			(xy 127.41152 -279.47161) (xy 127.361906 -279.491082) (xy 127.309944 -279.502942) (xy 127.256794 -279.506926)
			(xy 127.203644 -279.502942) (xy 127.151682 -279.491082) (xy 127.102068 -279.47161) (xy 127.05591 -279.444961)
			(xy 127.014239 -279.41173) (xy 126.977987 -279.372659) (xy 126.947963 -279.328622) (xy 126.924837 -279.280601)
			(xy 126.909127 -279.229671) (xy 126.901184 -279.176967) (xy 126.672604 -279.176967) (xy 126.664661 -279.229671)
			(xy 126.648951 -279.280601) (xy 126.625825 -279.328622) (xy 126.595801 -279.372659) (xy 126.559549 -279.41173)
			(xy 126.517878 -279.444961) (xy 126.47172 -279.47161) (xy 126.422106 -279.491082) (xy 126.370144 -279.502942)
			(xy 126.316994 -279.506926) (xy 126.263844 -279.502942) (xy 126.211882 -279.491082) (xy 126.162268 -279.47161)
			(xy 126.11611 -279.444961) (xy 126.074439 -279.41173) (xy 126.038187 -279.372659) (xy 126.008163 -279.328622)
			(xy 125.985037 -279.280601) (xy 125.969327 -279.229671) (xy 125.961384 -279.176967) (xy 125.732804 -279.176967)
			(xy 125.724861 -279.229671) (xy 125.709151 -279.280601) (xy 125.686025 -279.328622) (xy 125.656001 -279.372659)
			(xy 125.619749 -279.41173) (xy 125.578078 -279.444961) (xy 125.53192 -279.47161) (xy 125.482306 -279.491082)
			(xy 125.430344 -279.502942) (xy 125.377194 -279.506926) (xy 125.324044 -279.502942) (xy 125.272082 -279.491082)
			(xy 125.222468 -279.47161) (xy 125.17631 -279.444961) (xy 125.134639 -279.41173) (xy 125.098387 -279.372659)
			(xy 125.068363 -279.328622) (xy 125.045237 -279.280601) (xy 125.029527 -279.229671) (xy 125.021584 -279.176967)
			(xy 124.793004 -279.176967) (xy 124.785061 -279.229671) (xy 124.769351 -279.280601) (xy 124.746225 -279.328622)
			(xy 124.716201 -279.372659) (xy 124.679949 -279.41173) (xy 124.638278 -279.444961) (xy 124.59212 -279.47161)
			(xy 124.542506 -279.491082) (xy 124.490544 -279.502942) (xy 124.437394 -279.506926) (xy 124.384244 -279.502942)
			(xy 124.332282 -279.491082) (xy 124.282668 -279.47161) (xy 124.23651 -279.444961) (xy 124.194839 -279.41173)
			(xy 124.158587 -279.372659) (xy 124.128563 -279.328622) (xy 124.105437 -279.280601) (xy 124.089727 -279.229671)
			(xy 124.081784 -279.176967) (xy 123.853458 -279.176967) (xy 123.845515 -279.229671) (xy 123.829805 -279.280601)
			(xy 123.806679 -279.328622) (xy 123.776655 -279.372659) (xy 123.740403 -279.41173) (xy 123.698732 -279.444961)
			(xy 123.652574 -279.47161) (xy 123.60296 -279.491082) (xy 123.550998 -279.502942) (xy 123.497848 -279.506926)
			(xy 123.444698 -279.502942) (xy 123.392736 -279.491082) (xy 123.343122 -279.47161) (xy 123.296964 -279.444961)
			(xy 123.255293 -279.41173) (xy 123.219041 -279.372659) (xy 123.189017 -279.328622) (xy 123.165891 -279.280601)
			(xy 123.150181 -279.229671) (xy 123.142238 -279.176967) (xy 122.913404 -279.176967) (xy 122.905461 -279.229671)
			(xy 122.889751 -279.280601) (xy 122.866625 -279.328622) (xy 122.836601 -279.372659) (xy 122.800349 -279.41173)
			(xy 122.758678 -279.444961) (xy 122.71252 -279.47161) (xy 122.662906 -279.491082) (xy 122.610944 -279.502942)
			(xy 122.557794 -279.506926) (xy 122.504644 -279.502942) (xy 122.452682 -279.491082) (xy 122.403068 -279.47161)
			(xy 122.35691 -279.444961) (xy 122.315239 -279.41173) (xy 122.278987 -279.372659) (xy 122.248963 -279.328622)
			(xy 122.225837 -279.280601) (xy 122.210127 -279.229671) (xy 122.202184 -279.176967) (xy 121.973604 -279.176967)
			(xy 121.965661 -279.229671) (xy 121.949951 -279.280601) (xy 121.926825 -279.328622) (xy 121.896801 -279.372659)
			(xy 121.860549 -279.41173) (xy 121.818878 -279.444961) (xy 121.77272 -279.47161) (xy 121.723106 -279.491082)
			(xy 121.671144 -279.502942) (xy 121.617994 -279.506926) (xy 121.564844 -279.502942) (xy 121.512882 -279.491082)
			(xy 121.463268 -279.47161) (xy 121.41711 -279.444961) (xy 121.375439 -279.41173) (xy 121.339187 -279.372659)
			(xy 121.309163 -279.328622) (xy 121.286037 -279.280601) (xy 121.270327 -279.229671) (xy 121.262384 -279.176967)
			(xy 121.034058 -279.176967) (xy 121.026115 -279.229671) (xy 121.010405 -279.280601) (xy 120.987279 -279.328622)
			(xy 120.957255 -279.372659) (xy 120.921003 -279.41173) (xy 120.879332 -279.444961) (xy 120.833174 -279.47161)
			(xy 120.78356 -279.491082) (xy 120.731598 -279.502942) (xy 120.678448 -279.506926) (xy 120.625298 -279.502942)
			(xy 120.573336 -279.491082) (xy 120.523722 -279.47161) (xy 120.477564 -279.444961) (xy 120.435893 -279.41173)
			(xy 120.399641 -279.372659) (xy 120.369617 -279.328622) (xy 120.346491 -279.280601) (xy 120.330781 -279.229671)
			(xy 120.322838 -279.176967) (xy 120.094004 -279.176967) (xy 120.086061 -279.229671) (xy 120.070351 -279.280601)
			(xy 120.047225 -279.328622) (xy 120.017201 -279.372659) (xy 119.980949 -279.41173) (xy 119.939278 -279.444961)
			(xy 119.89312 -279.47161) (xy 119.843506 -279.491082) (xy 119.791544 -279.502942) (xy 119.738394 -279.506926)
			(xy 119.685244 -279.502942) (xy 119.633282 -279.491082) (xy 119.583668 -279.47161) (xy 119.53751 -279.444961)
			(xy 119.495839 -279.41173) (xy 119.459587 -279.372659) (xy 119.429563 -279.328622) (xy 119.406437 -279.280601)
			(xy 119.390727 -279.229671) (xy 119.382784 -279.176967) (xy 118.214658 -279.176967) (xy 118.206715 -279.229671)
			(xy 118.191005 -279.280601) (xy 118.167879 -279.328622) (xy 118.137855 -279.372659) (xy 118.101603 -279.41173)
			(xy 118.059932 -279.444961) (xy 118.013774 -279.47161) (xy 117.96416 -279.491082) (xy 117.912198 -279.502942)
			(xy 117.859048 -279.506926) (xy 117.805898 -279.502942) (xy 117.753936 -279.491082) (xy 117.704322 -279.47161)
			(xy 117.658164 -279.444961) (xy 117.616493 -279.41173) (xy 117.580241 -279.372659) (xy 117.550217 -279.328622)
			(xy 117.527091 -279.280601) (xy 117.511381 -279.229671) (xy 117.503438 -279.176967) (xy 117.274857 -279.176967)
			(xy 117.274854 -279.177121) (xy 117.266666 -279.230613) (xy 117.250473 -279.282248) (xy 117.22665 -279.330836)
			(xy 117.195744 -279.375257) (xy 117.158469 -279.414486) (xy 117.115685 -279.44762) (xy 117.068377 -279.473893)
			(xy 117.0432 -279.48382) (xy 117.01018 -279.496266) (xy 117.01018 -279.990783) (xy 117.973084 -279.990783)
			(xy 117.973084 -279.937485) (xy 117.981027 -279.884781) (xy 117.996737 -279.833851) (xy 118.019863 -279.78583)
			(xy 118.049887 -279.741793) (xy 118.086139 -279.702722) (xy 118.12781 -279.669491) (xy 118.173968 -279.642842)
			(xy 118.223582 -279.62337) (xy 118.275544 -279.61151) (xy 118.328694 -279.607527) (xy 118.381844 -279.61151)
			(xy 118.433806 -279.62337) (xy 118.48342 -279.642842) (xy 118.529578 -279.669491) (xy 118.571249 -279.702722)
			(xy 118.607501 -279.741793) (xy 118.637525 -279.78583) (xy 118.660651 -279.833851) (xy 118.676361 -279.884781)
			(xy 118.684304 -279.937485) (xy 118.684802 -279.964134) (xy 118.684304 -279.990783) (xy 118.913138 -279.990783)
			(xy 118.913138 -279.937485) (xy 118.921081 -279.884781) (xy 118.936791 -279.833851) (xy 118.959917 -279.78583)
			(xy 118.989941 -279.741793) (xy 119.026193 -279.702722) (xy 119.067864 -279.669491) (xy 119.114022 -279.642842)
			(xy 119.163636 -279.62337) (xy 119.215598 -279.61151) (xy 119.268748 -279.607527) (xy 119.321898 -279.61151)
			(xy 119.37386 -279.62337) (xy 119.423474 -279.642842) (xy 119.469632 -279.669491) (xy 119.511303 -279.702722)
			(xy 119.547555 -279.741793) (xy 119.577579 -279.78583) (xy 119.600705 -279.833851) (xy 119.616415 -279.884781)
			(xy 119.624358 -279.937485) (xy 119.624856 -279.964134) (xy 119.624358 -279.990783) (xy 119.852938 -279.990783)
			(xy 119.852938 -279.937485) (xy 119.860881 -279.884781) (xy 119.876591 -279.833851) (xy 119.899717 -279.78583)
			(xy 119.929741 -279.741793) (xy 119.965993 -279.702722) (xy 120.007664 -279.669491) (xy 120.053822 -279.642842)
			(xy 120.103436 -279.62337) (xy 120.155398 -279.61151) (xy 120.208548 -279.607527) (xy 120.261698 -279.61151)
			(xy 120.31366 -279.62337) (xy 120.363274 -279.642842) (xy 120.409432 -279.669491) (xy 120.451103 -279.702722)
			(xy 120.487355 -279.741793) (xy 120.517379 -279.78583) (xy 120.540505 -279.833851) (xy 120.556215 -279.884781)
			(xy 120.564158 -279.937485) (xy 120.564656 -279.964134) (xy 120.564158 -279.990783) (xy 120.792738 -279.990783)
			(xy 120.792738 -279.937485) (xy 120.800681 -279.884781) (xy 120.816391 -279.833851) (xy 120.839517 -279.78583)
			(xy 120.869541 -279.741793) (xy 120.905793 -279.702722) (xy 120.947464 -279.669491) (xy 120.993622 -279.642842)
			(xy 121.043236 -279.62337) (xy 121.095198 -279.61151) (xy 121.148348 -279.607527) (xy 121.201498 -279.61151)
			(xy 121.25346 -279.62337) (xy 121.303074 -279.642842) (xy 121.349232 -279.669491) (xy 121.390903 -279.702722)
			(xy 121.427155 -279.741793) (xy 121.457179 -279.78583) (xy 121.480305 -279.833851) (xy 121.496015 -279.884781)
			(xy 121.503958 -279.937485) (xy 121.504456 -279.964134) (xy 121.503958 -279.990783) (xy 122.672338 -279.990783)
			(xy 122.672338 -279.937485) (xy 122.680281 -279.884781) (xy 122.695991 -279.833851) (xy 122.719117 -279.78583)
			(xy 122.749141 -279.741793) (xy 122.785393 -279.702722) (xy 122.827064 -279.669491) (xy 122.873222 -279.642842)
			(xy 122.922836 -279.62337) (xy 122.974798 -279.61151) (xy 123.027948 -279.607527) (xy 123.081098 -279.61151)
			(xy 123.13306 -279.62337) (xy 123.182674 -279.642842) (xy 123.228832 -279.669491) (xy 123.270503 -279.702722)
			(xy 123.306755 -279.741793) (xy 123.336779 -279.78583) (xy 123.359905 -279.833851) (xy 123.375615 -279.884781)
			(xy 123.383558 -279.937485) (xy 123.384056 -279.964134) (xy 123.383558 -279.990783) (xy 123.611884 -279.990783)
			(xy 123.611884 -279.937485) (xy 123.619827 -279.884781) (xy 123.635537 -279.833851) (xy 123.658663 -279.78583)
			(xy 123.688687 -279.741793) (xy 123.724939 -279.702722) (xy 123.76661 -279.669491) (xy 123.812768 -279.642842)
			(xy 123.862382 -279.62337) (xy 123.914344 -279.61151) (xy 123.967494 -279.607527) (xy 124.020644 -279.61151)
			(xy 124.072606 -279.62337) (xy 124.12222 -279.642842) (xy 124.168378 -279.669491) (xy 124.210049 -279.702722)
			(xy 124.246301 -279.741793) (xy 124.276325 -279.78583) (xy 124.299451 -279.833851) (xy 124.315161 -279.884781)
			(xy 124.323104 -279.937485) (xy 124.323602 -279.964134) (xy 124.323104 -279.990783) (xy 124.551938 -279.990783)
			(xy 124.551938 -279.937485) (xy 124.559881 -279.884781) (xy 124.575591 -279.833851) (xy 124.598717 -279.78583)
			(xy 124.628741 -279.741793) (xy 124.664993 -279.702722) (xy 124.706664 -279.669491) (xy 124.752822 -279.642842)
			(xy 124.802436 -279.62337) (xy 124.854398 -279.61151) (xy 124.907548 -279.607527) (xy 124.960698 -279.61151)
			(xy 125.01266 -279.62337) (xy 125.062274 -279.642842) (xy 125.108432 -279.669491) (xy 125.150103 -279.702722)
			(xy 125.186355 -279.741793) (xy 125.216379 -279.78583) (xy 125.239505 -279.833851) (xy 125.255215 -279.884781)
			(xy 125.263158 -279.937485) (xy 125.263656 -279.964134) (xy 125.263158 -279.990783) (xy 125.491738 -279.990783)
			(xy 125.491738 -279.937485) (xy 125.499681 -279.884781) (xy 125.515391 -279.833851) (xy 125.538517 -279.78583)
			(xy 125.568541 -279.741793) (xy 125.604793 -279.702722) (xy 125.646464 -279.669491) (xy 125.692622 -279.642842)
			(xy 125.742236 -279.62337) (xy 125.794198 -279.61151) (xy 125.847348 -279.607527) (xy 125.900498 -279.61151)
			(xy 125.95246 -279.62337) (xy 126.002074 -279.642842) (xy 126.048232 -279.669491) (xy 126.089903 -279.702722)
			(xy 126.126155 -279.741793) (xy 126.156179 -279.78583) (xy 126.179305 -279.833851) (xy 126.195015 -279.884781)
			(xy 126.202958 -279.937485) (xy 126.203456 -279.964134) (xy 126.202958 -279.990783) (xy 126.431284 -279.990783)
			(xy 126.431284 -279.937485) (xy 126.439227 -279.884781) (xy 126.454937 -279.833851) (xy 126.478063 -279.78583)
			(xy 126.508087 -279.741793) (xy 126.544339 -279.702722) (xy 126.58601 -279.669491) (xy 126.632168 -279.642842)
			(xy 126.681782 -279.62337) (xy 126.733744 -279.61151) (xy 126.786894 -279.607527) (xy 126.840044 -279.61151)
			(xy 126.892006 -279.62337) (xy 126.94162 -279.642842) (xy 126.987778 -279.669491) (xy 127.029449 -279.702722)
			(xy 127.065701 -279.741793) (xy 127.095725 -279.78583) (xy 127.118851 -279.833851) (xy 127.134561 -279.884781)
			(xy 127.142504 -279.937485) (xy 127.143002 -279.964134) (xy 127.142504 -279.990783) (xy 127.371338 -279.990783)
			(xy 127.371338 -279.937485) (xy 127.379281 -279.884781) (xy 127.394991 -279.833851) (xy 127.418117 -279.78583)
			(xy 127.448141 -279.741793) (xy 127.484393 -279.702722) (xy 127.526064 -279.669491) (xy 127.572222 -279.642842)
			(xy 127.621836 -279.62337) (xy 127.673798 -279.61151) (xy 127.726948 -279.607527) (xy 127.780098 -279.61151)
			(xy 127.83206 -279.62337) (xy 127.881674 -279.642842) (xy 127.927832 -279.669491) (xy 127.969503 -279.702722)
			(xy 128.005755 -279.741793) (xy 128.035779 -279.78583) (xy 128.058905 -279.833851) (xy 128.074615 -279.884781)
			(xy 128.082558 -279.937485) (xy 128.083056 -279.964134) (xy 128.082563 -279.990529) (xy 128.310884 -279.990529)
			(xy 128.310884 -279.937231) (xy 128.318827 -279.884527) (xy 128.334537 -279.833597) (xy 128.357663 -279.785576)
			(xy 128.387687 -279.741539) (xy 128.423939 -279.702468) (xy 128.46561 -279.669237) (xy 128.511768 -279.642588)
			(xy 128.561382 -279.623116) (xy 128.613344 -279.611256) (xy 128.666494 -279.607273) (xy 128.719644 -279.611256)
			(xy 128.771606 -279.623116) (xy 128.82122 -279.642588) (xy 128.867378 -279.669237) (xy 128.909049 -279.702468)
			(xy 128.945301 -279.741539) (xy 128.975325 -279.785576) (xy 128.998451 -279.833597) (xy 129.014161 -279.884527)
			(xy 129.022104 -279.937231) (xy 129.022602 -279.96388) (xy 129.022104 -279.990529) (xy 129.022066 -279.990783)
			(xy 130.190738 -279.990783) (xy 130.190738 -279.937485) (xy 130.198681 -279.884781) (xy 130.214391 -279.833851)
			(xy 130.237517 -279.78583) (xy 130.267541 -279.741793) (xy 130.303793 -279.702722) (xy 130.345464 -279.669491)
			(xy 130.391622 -279.642842) (xy 130.441236 -279.62337) (xy 130.493198 -279.61151) (xy 130.546348 -279.607527)
			(xy 130.599498 -279.61151) (xy 130.65146 -279.62337) (xy 130.701074 -279.642842) (xy 130.747232 -279.669491)
			(xy 130.788903 -279.702722) (xy 130.825155 -279.741793) (xy 130.855179 -279.78583) (xy 130.878305 -279.833851)
			(xy 130.894015 -279.884781) (xy 130.901958 -279.937485) (xy 130.902456 -279.964134) (xy 130.901958 -279.990783)
			(xy 131.130538 -279.990783) (xy 131.130538 -279.937485) (xy 131.138481 -279.884781) (xy 131.154191 -279.833851)
			(xy 131.177317 -279.78583) (xy 131.207341 -279.741793) (xy 131.243593 -279.702722) (xy 131.285264 -279.669491)
			(xy 131.331422 -279.642842) (xy 131.381036 -279.62337) (xy 131.432998 -279.61151) (xy 131.486148 -279.607527)
			(xy 131.539298 -279.61151) (xy 131.59126 -279.62337) (xy 131.640874 -279.642842) (xy 131.687032 -279.669491)
			(xy 131.728703 -279.702722) (xy 131.764955 -279.741793) (xy 131.794979 -279.78583) (xy 131.818105 -279.833851)
			(xy 131.833815 -279.884781) (xy 131.841758 -279.937485) (xy 131.842256 -279.964134) (xy 131.841758 -279.990783)
			(xy 132.070084 -279.990783) (xy 132.070084 -279.937485) (xy 132.078027 -279.884781) (xy 132.093737 -279.833851)
			(xy 132.116863 -279.78583) (xy 132.146887 -279.741793) (xy 132.183139 -279.702722) (xy 132.22481 -279.669491)
			(xy 132.270968 -279.642842) (xy 132.320582 -279.62337) (xy 132.372544 -279.61151) (xy 132.425694 -279.607527)
			(xy 132.478844 -279.61151) (xy 132.530806 -279.62337) (xy 132.58042 -279.642842) (xy 132.626578 -279.669491)
			(xy 132.668249 -279.702722) (xy 132.704501 -279.741793) (xy 132.734525 -279.78583) (xy 132.757651 -279.833851)
			(xy 132.773361 -279.884781) (xy 132.781304 -279.937485) (xy 132.781802 -279.964134) (xy 132.781304 -279.990783)
			(xy 134.88923 -279.990783) (xy 134.88923 -279.937485) (xy 134.897173 -279.884781) (xy 134.912883 -279.833851)
			(xy 134.936009 -279.78583) (xy 134.966033 -279.741793) (xy 135.002285 -279.702722) (xy 135.043956 -279.669491)
			(xy 135.090114 -279.642842) (xy 135.139728 -279.62337) (xy 135.19169 -279.61151) (xy 135.24484 -279.607527)
			(xy 135.29799 -279.61151) (xy 135.349952 -279.62337) (xy 135.399566 -279.642842) (xy 135.445724 -279.669491)
			(xy 135.487395 -279.702722) (xy 135.523647 -279.741793) (xy 135.553671 -279.78583) (xy 135.576797 -279.833851)
			(xy 135.592507 -279.884781) (xy 135.60045 -279.937485) (xy 135.600948 -279.964134) (xy 135.60045 -279.990783)
			(xy 135.592507 -280.043487) (xy 135.576797 -280.094417) (xy 135.553671 -280.142438) (xy 135.523647 -280.186475)
			(xy 135.487395 -280.225546) (xy 135.445724 -280.258777) (xy 135.399566 -280.285426) (xy 135.349952 -280.304898)
			(xy 135.29799 -280.316758) (xy 135.24484 -280.320742) (xy 135.19169 -280.316758) (xy 135.139728 -280.304898)
			(xy 135.090114 -280.285426) (xy 135.043956 -280.258777) (xy 135.002285 -280.225546) (xy 134.966033 -280.186475)
			(xy 134.936009 -280.142438) (xy 134.912883 -280.094417) (xy 134.897173 -280.043487) (xy 134.88923 -279.990783)
			(xy 132.781304 -279.990783) (xy 132.773361 -280.043487) (xy 132.757651 -280.094417) (xy 132.734525 -280.142438)
			(xy 132.704501 -280.186475) (xy 132.668249 -280.225546) (xy 132.626578 -280.258777) (xy 132.58042 -280.285426)
			(xy 132.530806 -280.304898) (xy 132.478844 -280.316758) (xy 132.425694 -280.320742) (xy 132.372544 -280.316758)
			(xy 132.320582 -280.304898) (xy 132.270968 -280.285426) (xy 132.22481 -280.258777) (xy 132.183139 -280.225546)
			(xy 132.146887 -280.186475) (xy 132.116863 -280.142438) (xy 132.093737 -280.094417) (xy 132.078027 -280.043487)
			(xy 132.070084 -279.990783) (xy 131.841758 -279.990783) (xy 131.833815 -280.043487) (xy 131.818105 -280.094417)
			(xy 131.794979 -280.142438) (xy 131.764955 -280.186475) (xy 131.728703 -280.225546) (xy 131.687032 -280.258777)
			(xy 131.640874 -280.285426) (xy 131.59126 -280.304898) (xy 131.539298 -280.316758) (xy 131.486148 -280.320742)
			(xy 131.432998 -280.316758) (xy 131.381036 -280.304898) (xy 131.331422 -280.285426) (xy 131.285264 -280.258777)
			(xy 131.243593 -280.225546) (xy 131.207341 -280.186475) (xy 131.177317 -280.142438) (xy 131.154191 -280.094417)
			(xy 131.138481 -280.043487) (xy 131.130538 -279.990783) (xy 130.901958 -279.990783) (xy 130.894015 -280.043487)
			(xy 130.878305 -280.094417) (xy 130.855179 -280.142438) (xy 130.825155 -280.186475) (xy 130.788903 -280.225546)
			(xy 130.747232 -280.258777) (xy 130.701074 -280.285426) (xy 130.65146 -280.304898) (xy 130.599498 -280.316758)
			(xy 130.546348 -280.320742) (xy 130.493198 -280.316758) (xy 130.441236 -280.304898) (xy 130.391622 -280.285426)
			(xy 130.345464 -280.258777) (xy 130.303793 -280.225546) (xy 130.267541 -280.186475) (xy 130.237517 -280.142438)
			(xy 130.214391 -280.094417) (xy 130.198681 -280.043487) (xy 130.190738 -279.990783) (xy 129.022066 -279.990783)
			(xy 129.014161 -280.043233) (xy 128.998451 -280.094163) (xy 128.975325 -280.142184) (xy 128.945301 -280.186221)
			(xy 128.909049 -280.225292) (xy 128.867378 -280.258523) (xy 128.82122 -280.285172) (xy 128.771606 -280.304644)
			(xy 128.719644 -280.316504) (xy 128.666494 -280.320488) (xy 128.613344 -280.316504) (xy 128.561382 -280.304644)
			(xy 128.511768 -280.285172) (xy 128.46561 -280.258523) (xy 128.423939 -280.225292) (xy 128.387687 -280.186221)
			(xy 128.357663 -280.142184) (xy 128.334537 -280.094163) (xy 128.318827 -280.043233) (xy 128.310884 -279.990529)
			(xy 128.082563 -279.990529) (xy 128.082558 -279.990783) (xy 128.074615 -280.043487) (xy 128.058905 -280.094417)
			(xy 128.035779 -280.142438) (xy 128.005755 -280.186475) (xy 127.969503 -280.225546) (xy 127.927832 -280.258777)
			(xy 127.881674 -280.285426) (xy 127.83206 -280.304898) (xy 127.780098 -280.316758) (xy 127.726948 -280.320742)
			(xy 127.673798 -280.316758) (xy 127.621836 -280.304898) (xy 127.572222 -280.285426) (xy 127.526064 -280.258777)
			(xy 127.484393 -280.225546) (xy 127.448141 -280.186475) (xy 127.418117 -280.142438) (xy 127.394991 -280.094417)
			(xy 127.379281 -280.043487) (xy 127.371338 -279.990783) (xy 127.142504 -279.990783) (xy 127.134561 -280.043487)
			(xy 127.118851 -280.094417) (xy 127.095725 -280.142438) (xy 127.065701 -280.186475) (xy 127.029449 -280.225546)
			(xy 126.987778 -280.258777) (xy 126.94162 -280.285426) (xy 126.892006 -280.304898) (xy 126.840044 -280.316758)
			(xy 126.786894 -280.320742) (xy 126.733744 -280.316758) (xy 126.681782 -280.304898) (xy 126.632168 -280.285426)
			(xy 126.58601 -280.258777) (xy 126.544339 -280.225546) (xy 126.508087 -280.186475) (xy 126.478063 -280.142438)
			(xy 126.454937 -280.094417) (xy 126.439227 -280.043487) (xy 126.431284 -279.990783) (xy 126.202958 -279.990783)
			(xy 126.195015 -280.043487) (xy 126.179305 -280.094417) (xy 126.156179 -280.142438) (xy 126.126155 -280.186475)
			(xy 126.089903 -280.225546) (xy 126.048232 -280.258777) (xy 126.002074 -280.285426) (xy 125.95246 -280.304898)
			(xy 125.900498 -280.316758) (xy 125.847348 -280.320742) (xy 125.794198 -280.316758) (xy 125.742236 -280.304898)
			(xy 125.692622 -280.285426) (xy 125.646464 -280.258777) (xy 125.604793 -280.225546) (xy 125.568541 -280.186475)
			(xy 125.538517 -280.142438) (xy 125.515391 -280.094417) (xy 125.499681 -280.043487) (xy 125.491738 -279.990783)
			(xy 125.263158 -279.990783) (xy 125.255215 -280.043487) (xy 125.239505 -280.094417) (xy 125.216379 -280.142438)
			(xy 125.186355 -280.186475) (xy 125.150103 -280.225546) (xy 125.108432 -280.258777) (xy 125.062274 -280.285426)
			(xy 125.01266 -280.304898) (xy 124.960698 -280.316758) (xy 124.907548 -280.320742) (xy 124.854398 -280.316758)
			(xy 124.802436 -280.304898) (xy 124.752822 -280.285426) (xy 124.706664 -280.258777) (xy 124.664993 -280.225546)
			(xy 124.628741 -280.186475) (xy 124.598717 -280.142438) (xy 124.575591 -280.094417) (xy 124.559881 -280.043487)
			(xy 124.551938 -279.990783) (xy 124.323104 -279.990783) (xy 124.315161 -280.043487) (xy 124.299451 -280.094417)
			(xy 124.276325 -280.142438) (xy 124.246301 -280.186475) (xy 124.210049 -280.225546) (xy 124.168378 -280.258777)
			(xy 124.12222 -280.285426) (xy 124.072606 -280.304898) (xy 124.020644 -280.316758) (xy 123.967494 -280.320742)
			(xy 123.914344 -280.316758) (xy 123.862382 -280.304898) (xy 123.812768 -280.285426) (xy 123.76661 -280.258777)
			(xy 123.724939 -280.225546) (xy 123.688687 -280.186475) (xy 123.658663 -280.142438) (xy 123.635537 -280.094417)
			(xy 123.619827 -280.043487) (xy 123.611884 -279.990783) (xy 123.383558 -279.990783) (xy 123.375615 -280.043487)
			(xy 123.359905 -280.094417) (xy 123.336779 -280.142438) (xy 123.306755 -280.186475) (xy 123.270503 -280.225546)
			(xy 123.228832 -280.258777) (xy 123.182674 -280.285426) (xy 123.13306 -280.304898) (xy 123.081098 -280.316758)
			(xy 123.027948 -280.320742) (xy 122.974798 -280.316758) (xy 122.922836 -280.304898) (xy 122.873222 -280.285426)
			(xy 122.827064 -280.258777) (xy 122.785393 -280.225546) (xy 122.749141 -280.186475) (xy 122.719117 -280.142438)
			(xy 122.695991 -280.094417) (xy 122.680281 -280.043487) (xy 122.672338 -279.990783) (xy 121.503958 -279.990783)
			(xy 121.496015 -280.043487) (xy 121.480305 -280.094417) (xy 121.457179 -280.142438) (xy 121.427155 -280.186475)
			(xy 121.390903 -280.225546) (xy 121.349232 -280.258777) (xy 121.303074 -280.285426) (xy 121.25346 -280.304898)
			(xy 121.201498 -280.316758) (xy 121.148348 -280.320742) (xy 121.095198 -280.316758) (xy 121.043236 -280.304898)
			(xy 120.993622 -280.285426) (xy 120.947464 -280.258777) (xy 120.905793 -280.225546) (xy 120.869541 -280.186475)
			(xy 120.839517 -280.142438) (xy 120.816391 -280.094417) (xy 120.800681 -280.043487) (xy 120.792738 -279.990783)
			(xy 120.564158 -279.990783) (xy 120.556215 -280.043487) (xy 120.540505 -280.094417) (xy 120.517379 -280.142438)
			(xy 120.487355 -280.186475) (xy 120.451103 -280.225546) (xy 120.409432 -280.258777) (xy 120.363274 -280.285426)
			(xy 120.31366 -280.304898) (xy 120.261698 -280.316758) (xy 120.208548 -280.320742) (xy 120.155398 -280.316758)
			(xy 120.103436 -280.304898) (xy 120.053822 -280.285426) (xy 120.007664 -280.258777) (xy 119.965993 -280.225546)
			(xy 119.929741 -280.186475) (xy 119.899717 -280.142438) (xy 119.876591 -280.094417) (xy 119.860881 -280.043487)
			(xy 119.852938 -279.990783) (xy 119.624358 -279.990783) (xy 119.616415 -280.043487) (xy 119.600705 -280.094417)
			(xy 119.577579 -280.142438) (xy 119.547555 -280.186475) (xy 119.511303 -280.225546) (xy 119.469632 -280.258777)
			(xy 119.423474 -280.285426) (xy 119.37386 -280.304898) (xy 119.321898 -280.316758) (xy 119.268748 -280.320742)
			(xy 119.215598 -280.316758) (xy 119.163636 -280.304898) (xy 119.114022 -280.285426) (xy 119.067864 -280.258777)
			(xy 119.026193 -280.225546) (xy 118.989941 -280.186475) (xy 118.959917 -280.142438) (xy 118.936791 -280.094417)
			(xy 118.921081 -280.043487) (xy 118.913138 -279.990783) (xy 118.684304 -279.990783) (xy 118.676361 -280.043487)
			(xy 118.660651 -280.094417) (xy 118.637525 -280.142438) (xy 118.607501 -280.186475) (xy 118.571249 -280.225546)
			(xy 118.529578 -280.258777) (xy 118.48342 -280.285426) (xy 118.433806 -280.304898) (xy 118.381844 -280.316758)
			(xy 118.328694 -280.320742) (xy 118.275544 -280.316758) (xy 118.223582 -280.304898) (xy 118.173968 -280.285426)
			(xy 118.12781 -280.258777) (xy 118.086139 -280.225546) (xy 118.049887 -280.186475) (xy 118.019863 -280.142438)
			(xy 117.996737 -280.094417) (xy 117.981027 -280.043487) (xy 117.973084 -279.990783) (xy 117.01018 -279.990783)
			(xy 117.01018 -280.432002) (xy 117.0432 -280.444448) (xy 117.068386 -280.454344) (xy 117.115674 -280.480647)
			(xy 117.158441 -280.513797) (xy 117.195702 -280.553035) (xy 117.226602 -280.597455) (xy 117.250429 -280.646038)
			(xy 117.266634 -280.697665) (xy 117.274847 -280.751149) (xy 117.275356 -280.778204) (xy 117.274844 -280.804853)
			(xy 117.503438 -280.804853) (xy 117.503438 -280.751555) (xy 117.511381 -280.698851) (xy 117.527091 -280.647921)
			(xy 117.550217 -280.5999) (xy 117.580241 -280.555863) (xy 117.616493 -280.516792) (xy 117.658164 -280.483561)
			(xy 117.704322 -280.456912) (xy 117.753936 -280.43744) (xy 117.805898 -280.42558) (xy 117.859048 -280.421597)
			(xy 117.912198 -280.42558) (xy 117.96416 -280.43744) (xy 118.013774 -280.456912) (xy 118.059932 -280.483561)
			(xy 118.101603 -280.516792) (xy 118.137855 -280.555863) (xy 118.167879 -280.5999) (xy 118.191005 -280.647921)
			(xy 118.206715 -280.698851) (xy 118.214658 -280.751555) (xy 118.215156 -280.778204) (xy 118.214658 -280.804853)
			(xy 118.442984 -280.804853) (xy 118.442984 -280.751555) (xy 118.450927 -280.698851) (xy 118.466637 -280.647921)
			(xy 118.489763 -280.5999) (xy 118.519787 -280.555863) (xy 118.556039 -280.516792) (xy 118.59771 -280.483561)
			(xy 118.643868 -280.456912) (xy 118.693482 -280.43744) (xy 118.745444 -280.42558) (xy 118.798594 -280.421597)
			(xy 118.851744 -280.42558) (xy 118.903706 -280.43744) (xy 118.95332 -280.456912) (xy 118.999478 -280.483561)
			(xy 119.041149 -280.516792) (xy 119.077401 -280.555863) (xy 119.107425 -280.5999) (xy 119.130551 -280.647921)
			(xy 119.146261 -280.698851) (xy 119.154204 -280.751555) (xy 119.154702 -280.778204) (xy 119.154204 -280.804853)
			(xy 119.382784 -280.804853) (xy 119.382784 -280.751555) (xy 119.390727 -280.698851) (xy 119.406437 -280.647921)
			(xy 119.429563 -280.5999) (xy 119.459587 -280.555863) (xy 119.495839 -280.516792) (xy 119.53751 -280.483561)
			(xy 119.583668 -280.456912) (xy 119.633282 -280.43744) (xy 119.685244 -280.42558) (xy 119.738394 -280.421597)
			(xy 119.791544 -280.42558) (xy 119.843506 -280.43744) (xy 119.89312 -280.456912) (xy 119.939278 -280.483561)
			(xy 119.980949 -280.516792) (xy 120.017201 -280.555863) (xy 120.047225 -280.5999) (xy 120.070351 -280.647921)
			(xy 120.086061 -280.698851) (xy 120.094004 -280.751555) (xy 120.094502 -280.778204) (xy 120.094004 -280.804853)
			(xy 120.322584 -280.804853) (xy 120.322584 -280.751555) (xy 120.330527 -280.698851) (xy 120.346237 -280.647921)
			(xy 120.369363 -280.5999) (xy 120.399387 -280.555863) (xy 120.435639 -280.516792) (xy 120.47731 -280.483561)
			(xy 120.523468 -280.456912) (xy 120.573082 -280.43744) (xy 120.625044 -280.42558) (xy 120.678194 -280.421597)
			(xy 120.731344 -280.42558) (xy 120.783306 -280.43744) (xy 120.83292 -280.456912) (xy 120.879078 -280.483561)
			(xy 120.920749 -280.516792) (xy 120.957001 -280.555863) (xy 120.987025 -280.5999) (xy 121.010151 -280.647921)
			(xy 121.025861 -280.698851) (xy 121.033804 -280.751555) (xy 121.034302 -280.778204) (xy 121.033804 -280.804853)
			(xy 121.262384 -280.804853) (xy 121.262384 -280.751555) (xy 121.270327 -280.698851) (xy 121.286037 -280.647921)
			(xy 121.309163 -280.5999) (xy 121.339187 -280.555863) (xy 121.375439 -280.516792) (xy 121.41711 -280.483561)
			(xy 121.463268 -280.456912) (xy 121.512882 -280.43744) (xy 121.564844 -280.42558) (xy 121.617994 -280.421597)
			(xy 121.671144 -280.42558) (xy 121.723106 -280.43744) (xy 121.77272 -280.456912) (xy 121.818878 -280.483561)
			(xy 121.860549 -280.516792) (xy 121.896801 -280.555863) (xy 121.926825 -280.5999) (xy 121.949951 -280.647921)
			(xy 121.965661 -280.698851) (xy 121.973604 -280.751555) (xy 121.974102 -280.778204) (xy 121.973604 -280.804853)
			(xy 122.202184 -280.804853) (xy 122.202184 -280.751555) (xy 122.210127 -280.698851) (xy 122.225837 -280.647921)
			(xy 122.248963 -280.5999) (xy 122.278987 -280.555863) (xy 122.315239 -280.516792) (xy 122.35691 -280.483561)
			(xy 122.403068 -280.456912) (xy 122.452682 -280.43744) (xy 122.504644 -280.42558) (xy 122.557794 -280.421597)
			(xy 122.610944 -280.42558) (xy 122.662906 -280.43744) (xy 122.71252 -280.456912) (xy 122.758678 -280.483561)
			(xy 122.800349 -280.516792) (xy 122.836601 -280.555863) (xy 122.866625 -280.5999) (xy 122.889751 -280.647921)
			(xy 122.905461 -280.698851) (xy 122.913404 -280.751555) (xy 122.913902 -280.778204) (xy 122.913404 -280.804853)
			(xy 123.141984 -280.804853) (xy 123.141984 -280.751555) (xy 123.149927 -280.698851) (xy 123.165637 -280.647921)
			(xy 123.188763 -280.5999) (xy 123.218787 -280.555863) (xy 123.255039 -280.516792) (xy 123.29671 -280.483561)
			(xy 123.342868 -280.456912) (xy 123.392482 -280.43744) (xy 123.444444 -280.42558) (xy 123.497594 -280.421597)
			(xy 123.550744 -280.42558) (xy 123.602706 -280.43744) (xy 123.65232 -280.456912) (xy 123.698478 -280.483561)
			(xy 123.740149 -280.516792) (xy 123.776401 -280.555863) (xy 123.806425 -280.5999) (xy 123.829551 -280.647921)
			(xy 123.845261 -280.698851) (xy 123.853204 -280.751555) (xy 123.853702 -280.778204) (xy 123.853204 -280.804853)
			(xy 124.081784 -280.804853) (xy 124.081784 -280.751555) (xy 124.089727 -280.698851) (xy 124.105437 -280.647921)
			(xy 124.128563 -280.5999) (xy 124.158587 -280.555863) (xy 124.194839 -280.516792) (xy 124.23651 -280.483561)
			(xy 124.282668 -280.456912) (xy 124.332282 -280.43744) (xy 124.384244 -280.42558) (xy 124.437394 -280.421597)
			(xy 124.490544 -280.42558) (xy 124.542506 -280.43744) (xy 124.59212 -280.456912) (xy 124.638278 -280.483561)
			(xy 124.679949 -280.516792) (xy 124.716201 -280.555863) (xy 124.746225 -280.5999) (xy 124.769351 -280.647921)
			(xy 124.785061 -280.698851) (xy 124.793004 -280.751555) (xy 124.793502 -280.778204) (xy 124.793004 -280.804853)
			(xy 125.021584 -280.804853) (xy 125.021584 -280.751555) (xy 125.029527 -280.698851) (xy 125.045237 -280.647921)
			(xy 125.068363 -280.5999) (xy 125.098387 -280.555863) (xy 125.134639 -280.516792) (xy 125.17631 -280.483561)
			(xy 125.222468 -280.456912) (xy 125.272082 -280.43744) (xy 125.324044 -280.42558) (xy 125.377194 -280.421597)
			(xy 125.430344 -280.42558) (xy 125.482306 -280.43744) (xy 125.53192 -280.456912) (xy 125.578078 -280.483561)
			(xy 125.619749 -280.516792) (xy 125.656001 -280.555863) (xy 125.686025 -280.5999) (xy 125.709151 -280.647921)
			(xy 125.724861 -280.698851) (xy 125.732804 -280.751555) (xy 125.733302 -280.778204) (xy 125.732804 -280.804853)
			(xy 125.961638 -280.804853) (xy 125.961638 -280.751555) (xy 125.969581 -280.698851) (xy 125.985291 -280.647921)
			(xy 126.008417 -280.5999) (xy 126.038441 -280.555863) (xy 126.074693 -280.516792) (xy 126.116364 -280.483561)
			(xy 126.162522 -280.456912) (xy 126.212136 -280.43744) (xy 126.264098 -280.42558) (xy 126.317248 -280.421597)
			(xy 126.370398 -280.42558) (xy 126.42236 -280.43744) (xy 126.471974 -280.456912) (xy 126.518132 -280.483561)
			(xy 126.559803 -280.516792) (xy 126.596055 -280.555863) (xy 126.626079 -280.5999) (xy 126.649205 -280.647921)
			(xy 126.664915 -280.698851) (xy 126.672858 -280.751555) (xy 126.673356 -280.778204) (xy 126.672858 -280.804853)
			(xy 126.901438 -280.804853) (xy 126.901438 -280.751555) (xy 126.909381 -280.698851) (xy 126.925091 -280.647921)
			(xy 126.948217 -280.5999) (xy 126.978241 -280.555863) (xy 127.014493 -280.516792) (xy 127.056164 -280.483561)
			(xy 127.102322 -280.456912) (xy 127.151936 -280.43744) (xy 127.203898 -280.42558) (xy 127.257048 -280.421597)
			(xy 127.310198 -280.42558) (xy 127.36216 -280.43744) (xy 127.411774 -280.456912) (xy 127.457932 -280.483561)
			(xy 127.499603 -280.516792) (xy 127.535855 -280.555863) (xy 127.565879 -280.5999) (xy 127.589005 -280.647921)
			(xy 127.604715 -280.698851) (xy 127.612658 -280.751555) (xy 127.613156 -280.778204) (xy 127.612658 -280.804853)
			(xy 127.841238 -280.804853) (xy 127.841238 -280.751555) (xy 127.849181 -280.698851) (xy 127.864891 -280.647921)
			(xy 127.888017 -280.5999) (xy 127.918041 -280.555863) (xy 127.954293 -280.516792) (xy 127.995964 -280.483561)
			(xy 128.042122 -280.456912) (xy 128.091736 -280.43744) (xy 128.143698 -280.42558) (xy 128.196848 -280.421597)
			(xy 128.249998 -280.42558) (xy 128.30196 -280.43744) (xy 128.351574 -280.456912) (xy 128.397732 -280.483561)
			(xy 128.439403 -280.516792) (xy 128.475655 -280.555863) (xy 128.505679 -280.5999) (xy 128.528805 -280.647921)
			(xy 128.544515 -280.698851) (xy 128.552458 -280.751555) (xy 128.552956 -280.778204) (xy 128.552458 -280.804853)
			(xy 128.781038 -280.804853) (xy 128.781038 -280.751555) (xy 128.788981 -280.698851) (xy 128.804691 -280.647921)
			(xy 128.827817 -280.5999) (xy 128.857841 -280.555863) (xy 128.894093 -280.516792) (xy 128.935764 -280.483561)
			(xy 128.981922 -280.456912) (xy 129.031536 -280.43744) (xy 129.083498 -280.42558) (xy 129.136648 -280.421597)
			(xy 129.189798 -280.42558) (xy 129.24176 -280.43744) (xy 129.291374 -280.456912) (xy 129.337532 -280.483561)
			(xy 129.379203 -280.516792) (xy 129.415455 -280.555863) (xy 129.445479 -280.5999) (xy 129.468605 -280.647921)
			(xy 129.484315 -280.698851) (xy 129.492258 -280.751555) (xy 129.492756 -280.778204) (xy 129.492258 -280.804853)
			(xy 129.720838 -280.804853) (xy 129.720838 -280.751555) (xy 129.728781 -280.698851) (xy 129.744491 -280.647921)
			(xy 129.767617 -280.5999) (xy 129.797641 -280.555863) (xy 129.833893 -280.516792) (xy 129.875564 -280.483561)
			(xy 129.921722 -280.456912) (xy 129.971336 -280.43744) (xy 130.023298 -280.42558) (xy 130.076448 -280.421597)
			(xy 130.129598 -280.42558) (xy 130.18156 -280.43744) (xy 130.231174 -280.456912) (xy 130.277332 -280.483561)
			(xy 130.319003 -280.516792) (xy 130.355255 -280.555863) (xy 130.385279 -280.5999) (xy 130.408405 -280.647921)
			(xy 130.424115 -280.698851) (xy 130.432058 -280.751555) (xy 130.432556 -280.778204) (xy 130.432058 -280.804853)
			(xy 130.660384 -280.804853) (xy 130.660384 -280.751555) (xy 130.668327 -280.698851) (xy 130.684037 -280.647921)
			(xy 130.707163 -280.5999) (xy 130.737187 -280.555863) (xy 130.773439 -280.516792) (xy 130.81511 -280.483561)
			(xy 130.861268 -280.456912) (xy 130.910882 -280.43744) (xy 130.962844 -280.42558) (xy 131.015994 -280.421597)
			(xy 131.069144 -280.42558) (xy 131.121106 -280.43744) (xy 131.17072 -280.456912) (xy 131.216878 -280.483561)
			(xy 131.258549 -280.516792) (xy 131.294801 -280.555863) (xy 131.324825 -280.5999) (xy 131.347951 -280.647921)
			(xy 131.363661 -280.698851) (xy 131.371604 -280.751555) (xy 131.372102 -280.778204) (xy 131.371604 -280.804853)
			(xy 131.600184 -280.804853) (xy 131.600184 -280.751555) (xy 131.608127 -280.698851) (xy 131.623837 -280.647921)
			(xy 131.646963 -280.5999) (xy 131.676987 -280.555863) (xy 131.713239 -280.516792) (xy 131.75491 -280.483561)
			(xy 131.801068 -280.456912) (xy 131.850682 -280.43744) (xy 131.902644 -280.42558) (xy 131.955794 -280.421597)
			(xy 132.008944 -280.42558) (xy 132.060906 -280.43744) (xy 132.11052 -280.456912) (xy 132.156678 -280.483561)
			(xy 132.198349 -280.516792) (xy 132.234601 -280.555863) (xy 132.264625 -280.5999) (xy 132.287751 -280.647921)
			(xy 132.303461 -280.698851) (xy 132.311404 -280.751555) (xy 132.311902 -280.778204) (xy 132.311404 -280.804853)
			(xy 132.539984 -280.804853) (xy 132.539984 -280.751555) (xy 132.547927 -280.698851) (xy 132.563637 -280.647921)
			(xy 132.586763 -280.5999) (xy 132.616787 -280.555863) (xy 132.653039 -280.516792) (xy 132.69471 -280.483561)
			(xy 132.740868 -280.456912) (xy 132.790482 -280.43744) (xy 132.842444 -280.42558) (xy 132.895594 -280.421597)
			(xy 132.948744 -280.42558) (xy 133.000706 -280.43744) (xy 133.05032 -280.456912) (xy 133.096478 -280.483561)
			(xy 133.138149 -280.516792) (xy 133.174401 -280.555863) (xy 133.204425 -280.5999) (xy 133.227551 -280.647921)
			(xy 133.243261 -280.698851) (xy 133.251204 -280.751555) (xy 133.251702 -280.778204) (xy 133.251204 -280.804853)
			(xy 133.479784 -280.804853) (xy 133.479784 -280.751555) (xy 133.487727 -280.698851) (xy 133.503437 -280.647921)
			(xy 133.526563 -280.5999) (xy 133.556587 -280.555863) (xy 133.592839 -280.516792) (xy 133.63451 -280.483561)
			(xy 133.680668 -280.456912) (xy 133.730282 -280.43744) (xy 133.782244 -280.42558) (xy 133.835394 -280.421597)
			(xy 133.888544 -280.42558) (xy 133.940506 -280.43744) (xy 133.99012 -280.456912) (xy 134.036278 -280.483561)
			(xy 134.077949 -280.516792) (xy 134.114201 -280.555863) (xy 134.144225 -280.5999) (xy 134.167351 -280.647921)
			(xy 134.183061 -280.698851) (xy 134.191004 -280.751555) (xy 134.191502 -280.778204) (xy 134.191004 -280.804853)
			(xy 135.359384 -280.804853) (xy 135.359384 -280.751555) (xy 135.367327 -280.698851) (xy 135.383037 -280.647921)
			(xy 135.406163 -280.5999) (xy 135.436187 -280.555863) (xy 135.472439 -280.516792) (xy 135.51411 -280.483561)
			(xy 135.560268 -280.456912) (xy 135.609882 -280.43744) (xy 135.661844 -280.42558) (xy 135.714994 -280.421597)
			(xy 135.768144 -280.42558) (xy 135.820106 -280.43744) (xy 135.86972 -280.456912) (xy 135.915878 -280.483561)
			(xy 135.957549 -280.516792) (xy 135.993801 -280.555863) (xy 136.023825 -280.5999) (xy 136.046951 -280.647921)
			(xy 136.062661 -280.698851) (xy 136.070604 -280.751555) (xy 136.071102 -280.778204) (xy 136.070604 -280.804853)
			(xy 136.062661 -280.857557) (xy 136.046951 -280.908487) (xy 136.023825 -280.956508) (xy 135.993801 -281.000545)
			(xy 135.957549 -281.039616) (xy 135.915878 -281.072847) (xy 135.86972 -281.099496) (xy 135.820106 -281.118968)
			(xy 135.768144 -281.130828) (xy 135.714994 -281.134812) (xy 135.661844 -281.130828) (xy 135.609882 -281.118968)
			(xy 135.560268 -281.099496) (xy 135.51411 -281.072847) (xy 135.472439 -281.039616) (xy 135.436187 -281.000545)
			(xy 135.406163 -280.956508) (xy 135.383037 -280.908487) (xy 135.367327 -280.857557) (xy 135.359384 -280.804853)
			(xy 134.191004 -280.804853) (xy 134.183061 -280.857557) (xy 134.167351 -280.908487) (xy 134.144225 -280.956508)
			(xy 134.114201 -281.000545) (xy 134.077949 -281.039616) (xy 134.036278 -281.072847) (xy 133.99012 -281.099496)
			(xy 133.940506 -281.118968) (xy 133.888544 -281.130828) (xy 133.835394 -281.134812) (xy 133.782244 -281.130828)
			(xy 133.730282 -281.118968) (xy 133.680668 -281.099496) (xy 133.63451 -281.072847) (xy 133.592839 -281.039616)
			(xy 133.556587 -281.000545) (xy 133.526563 -280.956508) (xy 133.503437 -280.908487) (xy 133.487727 -280.857557)
			(xy 133.479784 -280.804853) (xy 133.251204 -280.804853) (xy 133.243261 -280.857557) (xy 133.227551 -280.908487)
			(xy 133.204425 -280.956508) (xy 133.174401 -281.000545) (xy 133.138149 -281.039616) (xy 133.096478 -281.072847)
			(xy 133.05032 -281.099496) (xy 133.000706 -281.118968) (xy 132.948744 -281.130828) (xy 132.895594 -281.134812)
			(xy 132.842444 -281.130828) (xy 132.790482 -281.118968) (xy 132.740868 -281.099496) (xy 132.69471 -281.072847)
			(xy 132.653039 -281.039616) (xy 132.616787 -281.000545) (xy 132.586763 -280.956508) (xy 132.563637 -280.908487)
			(xy 132.547927 -280.857557) (xy 132.539984 -280.804853) (xy 132.311404 -280.804853) (xy 132.303461 -280.857557)
			(xy 132.287751 -280.908487) (xy 132.264625 -280.956508) (xy 132.234601 -281.000545) (xy 132.198349 -281.039616)
			(xy 132.156678 -281.072847) (xy 132.11052 -281.099496) (xy 132.060906 -281.118968) (xy 132.008944 -281.130828)
			(xy 131.955794 -281.134812) (xy 131.902644 -281.130828) (xy 131.850682 -281.118968) (xy 131.801068 -281.099496)
			(xy 131.75491 -281.072847) (xy 131.713239 -281.039616) (xy 131.676987 -281.000545) (xy 131.646963 -280.956508)
			(xy 131.623837 -280.908487) (xy 131.608127 -280.857557) (xy 131.600184 -280.804853) (xy 131.371604 -280.804853)
			(xy 131.363661 -280.857557) (xy 131.347951 -280.908487) (xy 131.324825 -280.956508) (xy 131.294801 -281.000545)
			(xy 131.258549 -281.039616) (xy 131.216878 -281.072847) (xy 131.17072 -281.099496) (xy 131.121106 -281.118968)
			(xy 131.069144 -281.130828) (xy 131.015994 -281.134812) (xy 130.962844 -281.130828) (xy 130.910882 -281.118968)
			(xy 130.861268 -281.099496) (xy 130.81511 -281.072847) (xy 130.773439 -281.039616) (xy 130.737187 -281.000545)
			(xy 130.707163 -280.956508) (xy 130.684037 -280.908487) (xy 130.668327 -280.857557) (xy 130.660384 -280.804853)
			(xy 130.432058 -280.804853) (xy 130.424115 -280.857557) (xy 130.408405 -280.908487) (xy 130.385279 -280.956508)
			(xy 130.355255 -281.000545) (xy 130.319003 -281.039616) (xy 130.277332 -281.072847) (xy 130.231174 -281.099496)
			(xy 130.18156 -281.118968) (xy 130.129598 -281.130828) (xy 130.076448 -281.134812) (xy 130.023298 -281.130828)
			(xy 129.971336 -281.118968) (xy 129.921722 -281.099496) (xy 129.875564 -281.072847) (xy 129.833893 -281.039616)
			(xy 129.797641 -281.000545) (xy 129.767617 -280.956508) (xy 129.744491 -280.908487) (xy 129.728781 -280.857557)
			(xy 129.720838 -280.804853) (xy 129.492258 -280.804853) (xy 129.484315 -280.857557) (xy 129.468605 -280.908487)
			(xy 129.445479 -280.956508) (xy 129.415455 -281.000545) (xy 129.379203 -281.039616) (xy 129.337532 -281.072847)
			(xy 129.291374 -281.099496) (xy 129.24176 -281.118968) (xy 129.189798 -281.130828) (xy 129.136648 -281.134812)
			(xy 129.083498 -281.130828) (xy 129.031536 -281.118968) (xy 128.981922 -281.099496) (xy 128.935764 -281.072847)
			(xy 128.894093 -281.039616) (xy 128.857841 -281.000545) (xy 128.827817 -280.956508) (xy 128.804691 -280.908487)
			(xy 128.788981 -280.857557) (xy 128.781038 -280.804853) (xy 128.552458 -280.804853) (xy 128.544515 -280.857557)
			(xy 128.528805 -280.908487) (xy 128.505679 -280.956508) (xy 128.475655 -281.000545) (xy 128.439403 -281.039616)
			(xy 128.397732 -281.072847) (xy 128.351574 -281.099496) (xy 128.30196 -281.118968) (xy 128.249998 -281.130828)
			(xy 128.196848 -281.134812) (xy 128.143698 -281.130828) (xy 128.091736 -281.118968) (xy 128.042122 -281.099496)
			(xy 127.995964 -281.072847) (xy 127.954293 -281.039616) (xy 127.918041 -281.000545) (xy 127.888017 -280.956508)
			(xy 127.864891 -280.908487) (xy 127.849181 -280.857557) (xy 127.841238 -280.804853) (xy 127.612658 -280.804853)
			(xy 127.604715 -280.857557) (xy 127.589005 -280.908487) (xy 127.565879 -280.956508) (xy 127.535855 -281.000545)
			(xy 127.499603 -281.039616) (xy 127.457932 -281.072847) (xy 127.411774 -281.099496) (xy 127.36216 -281.118968)
			(xy 127.310198 -281.130828) (xy 127.257048 -281.134812) (xy 127.203898 -281.130828) (xy 127.151936 -281.118968)
			(xy 127.102322 -281.099496) (xy 127.056164 -281.072847) (xy 127.014493 -281.039616) (xy 126.978241 -281.000545)
			(xy 126.948217 -280.956508) (xy 126.925091 -280.908487) (xy 126.909381 -280.857557) (xy 126.901438 -280.804853)
			(xy 126.672858 -280.804853) (xy 126.664915 -280.857557) (xy 126.649205 -280.908487) (xy 126.626079 -280.956508)
			(xy 126.596055 -281.000545) (xy 126.559803 -281.039616) (xy 126.518132 -281.072847) (xy 126.471974 -281.099496)
			(xy 126.42236 -281.118968) (xy 126.370398 -281.130828) (xy 126.317248 -281.134812) (xy 126.264098 -281.130828)
			(xy 126.212136 -281.118968) (xy 126.162522 -281.099496) (xy 126.116364 -281.072847) (xy 126.074693 -281.039616)
			(xy 126.038441 -281.000545) (xy 126.008417 -280.956508) (xy 125.985291 -280.908487) (xy 125.969581 -280.857557)
			(xy 125.961638 -280.804853) (xy 125.732804 -280.804853) (xy 125.724861 -280.857557) (xy 125.709151 -280.908487)
			(xy 125.686025 -280.956508) (xy 125.656001 -281.000545) (xy 125.619749 -281.039616) (xy 125.578078 -281.072847)
			(xy 125.53192 -281.099496) (xy 125.482306 -281.118968) (xy 125.430344 -281.130828) (xy 125.377194 -281.134812)
			(xy 125.324044 -281.130828) (xy 125.272082 -281.118968) (xy 125.222468 -281.099496) (xy 125.17631 -281.072847)
			(xy 125.134639 -281.039616) (xy 125.098387 -281.000545) (xy 125.068363 -280.956508) (xy 125.045237 -280.908487)
			(xy 125.029527 -280.857557) (xy 125.021584 -280.804853) (xy 124.793004 -280.804853) (xy 124.785061 -280.857557)
			(xy 124.769351 -280.908487) (xy 124.746225 -280.956508) (xy 124.716201 -281.000545) (xy 124.679949 -281.039616)
			(xy 124.638278 -281.072847) (xy 124.59212 -281.099496) (xy 124.542506 -281.118968) (xy 124.490544 -281.130828)
			(xy 124.437394 -281.134812) (xy 124.384244 -281.130828) (xy 124.332282 -281.118968) (xy 124.282668 -281.099496)
			(xy 124.23651 -281.072847) (xy 124.194839 -281.039616) (xy 124.158587 -281.000545) (xy 124.128563 -280.956508)
			(xy 124.105437 -280.908487) (xy 124.089727 -280.857557) (xy 124.081784 -280.804853) (xy 123.853204 -280.804853)
			(xy 123.845261 -280.857557) (xy 123.829551 -280.908487) (xy 123.806425 -280.956508) (xy 123.776401 -281.000545)
			(xy 123.740149 -281.039616) (xy 123.698478 -281.072847) (xy 123.65232 -281.099496) (xy 123.602706 -281.118968)
			(xy 123.550744 -281.130828) (xy 123.497594 -281.134812) (xy 123.444444 -281.130828) (xy 123.392482 -281.118968)
			(xy 123.342868 -281.099496) (xy 123.29671 -281.072847) (xy 123.255039 -281.039616) (xy 123.218787 -281.000545)
			(xy 123.188763 -280.956508) (xy 123.165637 -280.908487) (xy 123.149927 -280.857557) (xy 123.141984 -280.804853)
			(xy 122.913404 -280.804853) (xy 122.905461 -280.857557) (xy 122.889751 -280.908487) (xy 122.866625 -280.956508)
			(xy 122.836601 -281.000545) (xy 122.800349 -281.039616) (xy 122.758678 -281.072847) (xy 122.71252 -281.099496)
			(xy 122.662906 -281.118968) (xy 122.610944 -281.130828) (xy 122.557794 -281.134812) (xy 122.504644 -281.130828)
			(xy 122.452682 -281.118968) (xy 122.403068 -281.099496) (xy 122.35691 -281.072847) (xy 122.315239 -281.039616)
			(xy 122.278987 -281.000545) (xy 122.248963 -280.956508) (xy 122.225837 -280.908487) (xy 122.210127 -280.857557)
			(xy 122.202184 -280.804853) (xy 121.973604 -280.804853) (xy 121.965661 -280.857557) (xy 121.949951 -280.908487)
			(xy 121.926825 -280.956508) (xy 121.896801 -281.000545) (xy 121.860549 -281.039616) (xy 121.818878 -281.072847)
			(xy 121.77272 -281.099496) (xy 121.723106 -281.118968) (xy 121.671144 -281.130828) (xy 121.617994 -281.134812)
			(xy 121.564844 -281.130828) (xy 121.512882 -281.118968) (xy 121.463268 -281.099496) (xy 121.41711 -281.072847)
			(xy 121.375439 -281.039616) (xy 121.339187 -281.000545) (xy 121.309163 -280.956508) (xy 121.286037 -280.908487)
			(xy 121.270327 -280.857557) (xy 121.262384 -280.804853) (xy 121.033804 -280.804853) (xy 121.025861 -280.857557)
			(xy 121.010151 -280.908487) (xy 120.987025 -280.956508) (xy 120.957001 -281.000545) (xy 120.920749 -281.039616)
			(xy 120.879078 -281.072847) (xy 120.83292 -281.099496) (xy 120.783306 -281.118968) (xy 120.731344 -281.130828)
			(xy 120.678194 -281.134812) (xy 120.625044 -281.130828) (xy 120.573082 -281.118968) (xy 120.523468 -281.099496)
			(xy 120.47731 -281.072847) (xy 120.435639 -281.039616) (xy 120.399387 -281.000545) (xy 120.369363 -280.956508)
			(xy 120.346237 -280.908487) (xy 120.330527 -280.857557) (xy 120.322584 -280.804853) (xy 120.094004 -280.804853)
			(xy 120.086061 -280.857557) (xy 120.070351 -280.908487) (xy 120.047225 -280.956508) (xy 120.017201 -281.000545)
			(xy 119.980949 -281.039616) (xy 119.939278 -281.072847) (xy 119.89312 -281.099496) (xy 119.843506 -281.118968)
			(xy 119.791544 -281.130828) (xy 119.738394 -281.134812) (xy 119.685244 -281.130828) (xy 119.633282 -281.118968)
			(xy 119.583668 -281.099496) (xy 119.53751 -281.072847) (xy 119.495839 -281.039616) (xy 119.459587 -281.000545)
			(xy 119.429563 -280.956508) (xy 119.406437 -280.908487) (xy 119.390727 -280.857557) (xy 119.382784 -280.804853)
			(xy 119.154204 -280.804853) (xy 119.146261 -280.857557) (xy 119.130551 -280.908487) (xy 119.107425 -280.956508)
			(xy 119.077401 -281.000545) (xy 119.041149 -281.039616) (xy 118.999478 -281.072847) (xy 118.95332 -281.099496)
			(xy 118.903706 -281.118968) (xy 118.851744 -281.130828) (xy 118.798594 -281.134812) (xy 118.745444 -281.130828)
			(xy 118.693482 -281.118968) (xy 118.643868 -281.099496) (xy 118.59771 -281.072847) (xy 118.556039 -281.039616)
			(xy 118.519787 -281.000545) (xy 118.489763 -280.956508) (xy 118.466637 -280.908487) (xy 118.450927 -280.857557)
			(xy 118.442984 -280.804853) (xy 118.214658 -280.804853) (xy 118.206715 -280.857557) (xy 118.191005 -280.908487)
			(xy 118.167879 -280.956508) (xy 118.137855 -281.000545) (xy 118.101603 -281.039616) (xy 118.059932 -281.072847)
			(xy 118.013774 -281.099496) (xy 117.96416 -281.118968) (xy 117.912198 -281.130828) (xy 117.859048 -281.134812)
			(xy 117.805898 -281.130828) (xy 117.753936 -281.118968) (xy 117.704322 -281.099496) (xy 117.658164 -281.072847)
			(xy 117.616493 -281.039616) (xy 117.580241 -281.000545) (xy 117.550217 -280.956508) (xy 117.527091 -280.908487)
			(xy 117.511381 -280.857557) (xy 117.503438 -280.804853) (xy 117.274844 -280.804853) (xy 117.274812 -280.806495)
			(xy 117.265867 -280.862366) (xy 117.248204 -280.916121) (xy 117.222265 -280.966408) (xy 117.188704 -281.011963)
			(xy 117.16893 -281.032204) (xy 117.159673 -281.041882) (xy 117.146126 -281.064974) (xy 117.139041 -281.090792)
			(xy 117.138903 -281.117564) (xy 117.145722 -281.143454) (xy 117.15903 -281.166684) (xy 117.168168 -281.176476)
			(xy 117.253258 -281.261566) (xy 117.282468 -281.252168) (xy 117.308477 -281.244555) (xy 117.362051 -281.236395)
			(xy 117.389148 -281.235912) (xy 117.417128 -281.236465) (xy 117.472398 -281.245226) (xy 117.525618 -281.262525)
			(xy 117.575476 -281.287936) (xy 117.620745 -281.320833) (xy 117.660311 -281.360407) (xy 117.6932 -281.405682)
			(xy 117.718601 -281.455545) (xy 117.73589 -281.508768) (xy 117.744641 -281.56404) (xy 117.745256 -281.59202)
			(xy 117.744774 -281.618669) (xy 117.973084 -281.618669) (xy 117.973084 -281.565371) (xy 117.981027 -281.512667)
			(xy 117.996737 -281.461737) (xy 118.019863 -281.413716) (xy 118.049887 -281.369679) (xy 118.086139 -281.330608)
			(xy 118.12781 -281.297377) (xy 118.173968 -281.270728) (xy 118.223582 -281.251256) (xy 118.275544 -281.239396)
			(xy 118.328694 -281.235413) (xy 118.381844 -281.239396) (xy 118.433806 -281.251256) (xy 118.48342 -281.270728)
			(xy 118.529578 -281.297377) (xy 118.571249 -281.330608) (xy 118.607501 -281.369679) (xy 118.637525 -281.413716)
			(xy 118.660651 -281.461737) (xy 118.676361 -281.512667) (xy 118.684304 -281.565371) (xy 118.684802 -281.59202)
			(xy 118.684304 -281.618669) (xy 118.913138 -281.618669) (xy 118.913138 -281.565371) (xy 118.921081 -281.512667)
			(xy 118.936791 -281.461737) (xy 118.959917 -281.413716) (xy 118.989941 -281.369679) (xy 119.026193 -281.330608)
			(xy 119.067864 -281.297377) (xy 119.114022 -281.270728) (xy 119.163636 -281.251256) (xy 119.215598 -281.239396)
			(xy 119.268748 -281.235413) (xy 119.321898 -281.239396) (xy 119.37386 -281.251256) (xy 119.423474 -281.270728)
			(xy 119.469632 -281.297377) (xy 119.511303 -281.330608) (xy 119.547555 -281.369679) (xy 119.577579 -281.413716)
			(xy 119.600705 -281.461737) (xy 119.616415 -281.512667) (xy 119.624358 -281.565371) (xy 119.624856 -281.59202)
			(xy 119.624358 -281.618669) (xy 119.852938 -281.618669) (xy 119.852938 -281.565371) (xy 119.860881 -281.512667)
			(xy 119.876591 -281.461737) (xy 119.899717 -281.413716) (xy 119.929741 -281.369679) (xy 119.965993 -281.330608)
			(xy 120.007664 -281.297377) (xy 120.053822 -281.270728) (xy 120.103436 -281.251256) (xy 120.155398 -281.239396)
			(xy 120.208548 -281.235413) (xy 120.261698 -281.239396) (xy 120.31366 -281.251256) (xy 120.363274 -281.270728)
			(xy 120.409432 -281.297377) (xy 120.451103 -281.330608) (xy 120.487355 -281.369679) (xy 120.517379 -281.413716)
			(xy 120.540505 -281.461737) (xy 120.556215 -281.512667) (xy 120.564158 -281.565371) (xy 120.564656 -281.59202)
			(xy 120.564158 -281.618669) (xy 120.792738 -281.618669) (xy 120.792738 -281.565371) (xy 120.800681 -281.512667)
			(xy 120.816391 -281.461737) (xy 120.839517 -281.413716) (xy 120.869541 -281.369679) (xy 120.905793 -281.330608)
			(xy 120.947464 -281.297377) (xy 120.993622 -281.270728) (xy 121.043236 -281.251256) (xy 121.095198 -281.239396)
			(xy 121.148348 -281.235413) (xy 121.201498 -281.239396) (xy 121.25346 -281.251256) (xy 121.303074 -281.270728)
			(xy 121.349232 -281.297377) (xy 121.390903 -281.330608) (xy 121.427155 -281.369679) (xy 121.457179 -281.413716)
			(xy 121.480305 -281.461737) (xy 121.496015 -281.512667) (xy 121.503958 -281.565371) (xy 121.504456 -281.59202)
			(xy 121.503958 -281.618669) (xy 121.732538 -281.618669) (xy 121.732538 -281.565371) (xy 121.740481 -281.512667)
			(xy 121.756191 -281.461737) (xy 121.779317 -281.413716) (xy 121.809341 -281.369679) (xy 121.845593 -281.330608)
			(xy 121.887264 -281.297377) (xy 121.933422 -281.270728) (xy 121.983036 -281.251256) (xy 122.034998 -281.239396)
			(xy 122.088148 -281.235413) (xy 122.141298 -281.239396) (xy 122.19326 -281.251256) (xy 122.242874 -281.270728)
			(xy 122.289032 -281.297377) (xy 122.330703 -281.330608) (xy 122.366955 -281.369679) (xy 122.396979 -281.413716)
			(xy 122.420105 -281.461737) (xy 122.435815 -281.512667) (xy 122.443758 -281.565371) (xy 122.444256 -281.59202)
			(xy 122.443758 -281.618669) (xy 122.672338 -281.618669) (xy 122.672338 -281.565371) (xy 122.680281 -281.512667)
			(xy 122.695991 -281.461737) (xy 122.719117 -281.413716) (xy 122.749141 -281.369679) (xy 122.785393 -281.330608)
			(xy 122.827064 -281.297377) (xy 122.873222 -281.270728) (xy 122.922836 -281.251256) (xy 122.974798 -281.239396)
			(xy 123.027948 -281.235413) (xy 123.081098 -281.239396) (xy 123.13306 -281.251256) (xy 123.182674 -281.270728)
			(xy 123.228832 -281.297377) (xy 123.270503 -281.330608) (xy 123.306755 -281.369679) (xy 123.336779 -281.413716)
			(xy 123.359905 -281.461737) (xy 123.375615 -281.512667) (xy 123.383558 -281.565371) (xy 123.384056 -281.59202)
			(xy 123.383558 -281.618669) (xy 123.612138 -281.618669) (xy 123.612138 -281.565371) (xy 123.620081 -281.512667)
			(xy 123.635791 -281.461737) (xy 123.658917 -281.413716) (xy 123.688941 -281.369679) (xy 123.725193 -281.330608)
			(xy 123.766864 -281.297377) (xy 123.813022 -281.270728) (xy 123.862636 -281.251256) (xy 123.914598 -281.239396)
			(xy 123.967748 -281.235413) (xy 124.020898 -281.239396) (xy 124.07286 -281.251256) (xy 124.122474 -281.270728)
			(xy 124.168632 -281.297377) (xy 124.210303 -281.330608) (xy 124.246555 -281.369679) (xy 124.276579 -281.413716)
			(xy 124.299705 -281.461737) (xy 124.315415 -281.512667) (xy 124.323358 -281.565371) (xy 124.323856 -281.59202)
			(xy 124.323358 -281.618669) (xy 124.551938 -281.618669) (xy 124.551938 -281.565371) (xy 124.559881 -281.512667)
			(xy 124.575591 -281.461737) (xy 124.598717 -281.413716) (xy 124.628741 -281.369679) (xy 124.664993 -281.330608)
			(xy 124.706664 -281.297377) (xy 124.752822 -281.270728) (xy 124.802436 -281.251256) (xy 124.854398 -281.239396)
			(xy 124.907548 -281.235413) (xy 124.960698 -281.239396) (xy 125.01266 -281.251256) (xy 125.062274 -281.270728)
			(xy 125.108432 -281.297377) (xy 125.150103 -281.330608) (xy 125.186355 -281.369679) (xy 125.216379 -281.413716)
			(xy 125.239505 -281.461737) (xy 125.255215 -281.512667) (xy 125.263158 -281.565371) (xy 125.263656 -281.59202)
			(xy 125.263158 -281.618669) (xy 125.491738 -281.618669) (xy 125.491738 -281.565371) (xy 125.499681 -281.512667)
			(xy 125.515391 -281.461737) (xy 125.538517 -281.413716) (xy 125.568541 -281.369679) (xy 125.604793 -281.330608)
			(xy 125.646464 -281.297377) (xy 125.692622 -281.270728) (xy 125.742236 -281.251256) (xy 125.794198 -281.239396)
			(xy 125.847348 -281.235413) (xy 125.900498 -281.239396) (xy 125.95246 -281.251256) (xy 126.002074 -281.270728)
			(xy 126.048232 -281.297377) (xy 126.089903 -281.330608) (xy 126.126155 -281.369679) (xy 126.156179 -281.413716)
			(xy 126.179305 -281.461737) (xy 126.195015 -281.512667) (xy 126.202958 -281.565371) (xy 126.203456 -281.59202)
			(xy 126.202958 -281.618669) (xy 126.431284 -281.618669) (xy 126.431284 -281.565371) (xy 126.439227 -281.512667)
			(xy 126.454937 -281.461737) (xy 126.478063 -281.413716) (xy 126.508087 -281.369679) (xy 126.544339 -281.330608)
			(xy 126.58601 -281.297377) (xy 126.632168 -281.270728) (xy 126.681782 -281.251256) (xy 126.733744 -281.239396)
			(xy 126.786894 -281.235413) (xy 126.840044 -281.239396) (xy 126.892006 -281.251256) (xy 126.94162 -281.270728)
			(xy 126.987778 -281.297377) (xy 127.029449 -281.330608) (xy 127.065701 -281.369679) (xy 127.095725 -281.413716)
			(xy 127.118851 -281.461737) (xy 127.134561 -281.512667) (xy 127.142504 -281.565371) (xy 127.143002 -281.59202)
			(xy 127.142509 -281.618415) (xy 127.371084 -281.618415) (xy 127.371084 -281.565117) (xy 127.379027 -281.512413)
			(xy 127.394737 -281.461483) (xy 127.417863 -281.413462) (xy 127.447887 -281.369425) (xy 127.484139 -281.330354)
			(xy 127.52581 -281.297123) (xy 127.571968 -281.270474) (xy 127.621582 -281.251002) (xy 127.673544 -281.239142)
			(xy 127.726694 -281.235159) (xy 127.779844 -281.239142) (xy 127.831806 -281.251002) (xy 127.88142 -281.270474)
			(xy 127.927578 -281.297123) (xy 127.969249 -281.330354) (xy 128.005501 -281.369425) (xy 128.035525 -281.413462)
			(xy 128.058651 -281.461483) (xy 128.074361 -281.512413) (xy 128.082304 -281.565117) (xy 128.082802 -281.591766)
			(xy 128.082304 -281.618415) (xy 128.082266 -281.618669) (xy 128.311138 -281.618669) (xy 128.311138 -281.565371)
			(xy 128.319081 -281.512667) (xy 128.334791 -281.461737) (xy 128.357917 -281.413716) (xy 128.387941 -281.369679)
			(xy 128.424193 -281.330608) (xy 128.465864 -281.297377) (xy 128.512022 -281.270728) (xy 128.561636 -281.251256)
			(xy 128.613598 -281.239396) (xy 128.666748 -281.235413) (xy 128.719898 -281.239396) (xy 128.77186 -281.251256)
			(xy 128.821474 -281.270728) (xy 128.867632 -281.297377) (xy 128.909303 -281.330608) (xy 128.945555 -281.369679)
			(xy 128.975579 -281.413716) (xy 128.998705 -281.461737) (xy 129.014415 -281.512667) (xy 129.022358 -281.565371)
			(xy 129.022856 -281.59202) (xy 129.022358 -281.618669) (xy 129.250684 -281.618669) (xy 129.250684 -281.565371)
			(xy 129.258627 -281.512667) (xy 129.274337 -281.461737) (xy 129.297463 -281.413716) (xy 129.327487 -281.369679)
			(xy 129.363739 -281.330608) (xy 129.40541 -281.297377) (xy 129.451568 -281.270728) (xy 129.501182 -281.251256)
			(xy 129.553144 -281.239396) (xy 129.606294 -281.235413) (xy 129.659444 -281.239396) (xy 129.711406 -281.251256)
			(xy 129.76102 -281.270728) (xy 129.807178 -281.297377) (xy 129.848849 -281.330608) (xy 129.885101 -281.369679)
			(xy 129.915125 -281.413716) (xy 129.938251 -281.461737) (xy 129.953961 -281.512667) (xy 129.961904 -281.565371)
			(xy 129.962402 -281.59202) (xy 129.961904 -281.618669) (xy 130.190738 -281.618669) (xy 130.190738 -281.565371)
			(xy 130.198681 -281.512667) (xy 130.214391 -281.461737) (xy 130.237517 -281.413716) (xy 130.267541 -281.369679)
			(xy 130.303793 -281.330608) (xy 130.345464 -281.297377) (xy 130.391622 -281.270728) (xy 130.441236 -281.251256)
			(xy 130.493198 -281.239396) (xy 130.546348 -281.235413) (xy 130.599498 -281.239396) (xy 130.65146 -281.251256)
			(xy 130.701074 -281.270728) (xy 130.747232 -281.297377) (xy 130.788903 -281.330608) (xy 130.825155 -281.369679)
			(xy 130.855179 -281.413716) (xy 130.878305 -281.461737) (xy 130.894015 -281.512667) (xy 130.901958 -281.565371)
			(xy 130.902456 -281.59202) (xy 130.901958 -281.618669) (xy 131.130538 -281.618669) (xy 131.130538 -281.565371)
			(xy 131.138481 -281.512667) (xy 131.154191 -281.461737) (xy 131.177317 -281.413716) (xy 131.207341 -281.369679)
			(xy 131.243593 -281.330608) (xy 131.285264 -281.297377) (xy 131.331422 -281.270728) (xy 131.381036 -281.251256)
			(xy 131.432998 -281.239396) (xy 131.486148 -281.235413) (xy 131.539298 -281.239396) (xy 131.59126 -281.251256)
			(xy 131.640874 -281.270728) (xy 131.687032 -281.297377) (xy 131.728703 -281.330608) (xy 131.764955 -281.369679)
			(xy 131.794979 -281.413716) (xy 131.818105 -281.461737) (xy 131.833815 -281.512667) (xy 131.841758 -281.565371)
			(xy 131.842256 -281.59202) (xy 131.841758 -281.618669) (xy 132.070338 -281.618669) (xy 132.070338 -281.565371)
			(xy 132.078281 -281.512667) (xy 132.093991 -281.461737) (xy 132.117117 -281.413716) (xy 132.147141 -281.369679)
			(xy 132.183393 -281.330608) (xy 132.225064 -281.297377) (xy 132.271222 -281.270728) (xy 132.320836 -281.251256)
			(xy 132.372798 -281.239396) (xy 132.425948 -281.235413) (xy 132.479098 -281.239396) (xy 132.53106 -281.251256)
			(xy 132.580674 -281.270728) (xy 132.626832 -281.297377) (xy 132.668503 -281.330608) (xy 132.704755 -281.369679)
			(xy 132.734779 -281.413716) (xy 132.757905 -281.461737) (xy 132.773615 -281.512667) (xy 132.781558 -281.565371)
			(xy 132.782056 -281.59202) (xy 132.781558 -281.618669) (xy 133.010138 -281.618669) (xy 133.010138 -281.565371)
			(xy 133.018081 -281.512667) (xy 133.033791 -281.461737) (xy 133.056917 -281.413716) (xy 133.086941 -281.369679)
			(xy 133.123193 -281.330608) (xy 133.164864 -281.297377) (xy 133.211022 -281.270728) (xy 133.260636 -281.251256)
			(xy 133.312598 -281.239396) (xy 133.365748 -281.235413) (xy 133.418898 -281.239396) (xy 133.47086 -281.251256)
			(xy 133.520474 -281.270728) (xy 133.566632 -281.297377) (xy 133.608303 -281.330608) (xy 133.644555 -281.369679)
			(xy 133.674579 -281.413716) (xy 133.697705 -281.461737) (xy 133.713415 -281.512667) (xy 133.721358 -281.565371)
			(xy 133.721856 -281.59202) (xy 133.721358 -281.618669) (xy 133.949938 -281.618669) (xy 133.949938 -281.565371)
			(xy 133.957881 -281.512667) (xy 133.973591 -281.461737) (xy 133.996717 -281.413716) (xy 134.026741 -281.369679)
			(xy 134.062993 -281.330608) (xy 134.104664 -281.297377) (xy 134.150822 -281.270728) (xy 134.200436 -281.251256)
			(xy 134.252398 -281.239396) (xy 134.305548 -281.235413) (xy 134.358698 -281.239396) (xy 134.41066 -281.251256)
			(xy 134.460274 -281.270728) (xy 134.506432 -281.297377) (xy 134.548103 -281.330608) (xy 134.584355 -281.369679)
			(xy 134.614379 -281.413716) (xy 134.637505 -281.461737) (xy 134.653215 -281.512667) (xy 134.661158 -281.565371)
			(xy 134.661656 -281.59202) (xy 134.661158 -281.618669) (xy 134.889484 -281.618669) (xy 134.889484 -281.565371)
			(xy 134.897427 -281.512667) (xy 134.913137 -281.461737) (xy 134.936263 -281.413716) (xy 134.966287 -281.369679)
			(xy 135.002539 -281.330608) (xy 135.04421 -281.297377) (xy 135.090368 -281.270728) (xy 135.139982 -281.251256)
			(xy 135.191944 -281.239396) (xy 135.245094 -281.235413) (xy 135.298244 -281.239396) (xy 135.350206 -281.251256)
			(xy 135.39982 -281.270728) (xy 135.445978 -281.297377) (xy 135.487649 -281.330608) (xy 135.523901 -281.369679)
			(xy 135.553925 -281.413716) (xy 135.577051 -281.461737) (xy 135.592761 -281.512667) (xy 135.600704 -281.565371)
			(xy 135.601202 -281.59202) (xy 135.600704 -281.618669) (xy 135.829284 -281.618669) (xy 135.829284 -281.565371)
			(xy 135.837227 -281.512667) (xy 135.852937 -281.461737) (xy 135.876063 -281.413716) (xy 135.906087 -281.369679)
			(xy 135.942339 -281.330608) (xy 135.98401 -281.297377) (xy 136.030168 -281.270728) (xy 136.079782 -281.251256)
			(xy 136.131744 -281.239396) (xy 136.184894 -281.235413) (xy 136.238044 -281.239396) (xy 136.290006 -281.251256)
			(xy 136.33962 -281.270728) (xy 136.385778 -281.297377) (xy 136.427449 -281.330608) (xy 136.463701 -281.369679)
			(xy 136.493725 -281.413716) (xy 136.516851 -281.461737) (xy 136.532561 -281.512667) (xy 136.540504 -281.565371)
			(xy 136.541002 -281.59202) (xy 136.540504 -281.618669) (xy 136.532561 -281.671373) (xy 136.516851 -281.722303)
			(xy 136.493725 -281.770324) (xy 136.463701 -281.814361) (xy 136.427449 -281.853432) (xy 136.385778 -281.886663)
			(xy 136.33962 -281.913312) (xy 136.290006 -281.932784) (xy 136.238044 -281.944644) (xy 136.184894 -281.948628)
			(xy 136.131744 -281.944644) (xy 136.079782 -281.932784) (xy 136.030168 -281.913312) (xy 135.98401 -281.886663)
			(xy 135.942339 -281.853432) (xy 135.906087 -281.814361) (xy 135.876063 -281.770324) (xy 135.852937 -281.722303)
			(xy 135.837227 -281.671373) (xy 135.829284 -281.618669) (xy 135.600704 -281.618669) (xy 135.592761 -281.671373)
			(xy 135.577051 -281.722303) (xy 135.553925 -281.770324) (xy 135.523901 -281.814361) (xy 135.487649 -281.853432)
			(xy 135.445978 -281.886663) (xy 135.39982 -281.913312) (xy 135.350206 -281.932784) (xy 135.298244 -281.944644)
			(xy 135.245094 -281.948628) (xy 135.191944 -281.944644) (xy 135.139982 -281.932784) (xy 135.090368 -281.913312)
			(xy 135.04421 -281.886663) (xy 135.002539 -281.853432) (xy 134.966287 -281.814361) (xy 134.936263 -281.770324)
			(xy 134.913137 -281.722303) (xy 134.897427 -281.671373) (xy 134.889484 -281.618669) (xy 134.661158 -281.618669)
			(xy 134.653215 -281.671373) (xy 134.637505 -281.722303) (xy 134.614379 -281.770324) (xy 134.584355 -281.814361)
			(xy 134.548103 -281.853432) (xy 134.506432 -281.886663) (xy 134.460274 -281.913312) (xy 134.41066 -281.932784)
			(xy 134.358698 -281.944644) (xy 134.305548 -281.948628) (xy 134.252398 -281.944644) (xy 134.200436 -281.932784)
			(xy 134.150822 -281.913312) (xy 134.104664 -281.886663) (xy 134.062993 -281.853432) (xy 134.026741 -281.814361)
			(xy 133.996717 -281.770324) (xy 133.973591 -281.722303) (xy 133.957881 -281.671373) (xy 133.949938 -281.618669)
			(xy 133.721358 -281.618669) (xy 133.713415 -281.671373) (xy 133.697705 -281.722303) (xy 133.674579 -281.770324)
			(xy 133.644555 -281.814361) (xy 133.608303 -281.853432) (xy 133.566632 -281.886663) (xy 133.520474 -281.913312)
			(xy 133.47086 -281.932784) (xy 133.418898 -281.944644) (xy 133.365748 -281.948628) (xy 133.312598 -281.944644)
			(xy 133.260636 -281.932784) (xy 133.211022 -281.913312) (xy 133.164864 -281.886663) (xy 133.123193 -281.853432)
			(xy 133.086941 -281.814361) (xy 133.056917 -281.770324) (xy 133.033791 -281.722303) (xy 133.018081 -281.671373)
			(xy 133.010138 -281.618669) (xy 132.781558 -281.618669) (xy 132.773615 -281.671373) (xy 132.757905 -281.722303)
			(xy 132.734779 -281.770324) (xy 132.704755 -281.814361) (xy 132.668503 -281.853432) (xy 132.626832 -281.886663)
			(xy 132.580674 -281.913312) (xy 132.53106 -281.932784) (xy 132.479098 -281.944644) (xy 132.425948 -281.948628)
			(xy 132.372798 -281.944644) (xy 132.320836 -281.932784) (xy 132.271222 -281.913312) (xy 132.225064 -281.886663)
			(xy 132.183393 -281.853432) (xy 132.147141 -281.814361) (xy 132.117117 -281.770324) (xy 132.093991 -281.722303)
			(xy 132.078281 -281.671373) (xy 132.070338 -281.618669) (xy 131.841758 -281.618669) (xy 131.833815 -281.671373)
			(xy 131.818105 -281.722303) (xy 131.794979 -281.770324) (xy 131.764955 -281.814361) (xy 131.728703 -281.853432)
			(xy 131.687032 -281.886663) (xy 131.640874 -281.913312) (xy 131.59126 -281.932784) (xy 131.539298 -281.944644)
			(xy 131.486148 -281.948628) (xy 131.432998 -281.944644) (xy 131.381036 -281.932784) (xy 131.331422 -281.913312)
			(xy 131.285264 -281.886663) (xy 131.243593 -281.853432) (xy 131.207341 -281.814361) (xy 131.177317 -281.770324)
			(xy 131.154191 -281.722303) (xy 131.138481 -281.671373) (xy 131.130538 -281.618669) (xy 130.901958 -281.618669)
			(xy 130.894015 -281.671373) (xy 130.878305 -281.722303) (xy 130.855179 -281.770324) (xy 130.825155 -281.814361)
			(xy 130.788903 -281.853432) (xy 130.747232 -281.886663) (xy 130.701074 -281.913312) (xy 130.65146 -281.932784)
			(xy 130.599498 -281.944644) (xy 130.546348 -281.948628) (xy 130.493198 -281.944644) (xy 130.441236 -281.932784)
			(xy 130.391622 -281.913312) (xy 130.345464 -281.886663) (xy 130.303793 -281.853432) (xy 130.267541 -281.814361)
			(xy 130.237517 -281.770324) (xy 130.214391 -281.722303) (xy 130.198681 -281.671373) (xy 130.190738 -281.618669)
			(xy 129.961904 -281.618669) (xy 129.953961 -281.671373) (xy 129.938251 -281.722303) (xy 129.915125 -281.770324)
			(xy 129.885101 -281.814361) (xy 129.848849 -281.853432) (xy 129.807178 -281.886663) (xy 129.76102 -281.913312)
			(xy 129.711406 -281.932784) (xy 129.659444 -281.944644) (xy 129.606294 -281.948628) (xy 129.553144 -281.944644)
			(xy 129.501182 -281.932784) (xy 129.451568 -281.913312) (xy 129.40541 -281.886663) (xy 129.363739 -281.853432)
			(xy 129.327487 -281.814361) (xy 129.297463 -281.770324) (xy 129.274337 -281.722303) (xy 129.258627 -281.671373)
			(xy 129.250684 -281.618669) (xy 129.022358 -281.618669) (xy 129.014415 -281.671373) (xy 128.998705 -281.722303)
			(xy 128.975579 -281.770324) (xy 128.945555 -281.814361) (xy 128.909303 -281.853432) (xy 128.867632 -281.886663)
			(xy 128.821474 -281.913312) (xy 128.77186 -281.932784) (xy 128.719898 -281.944644) (xy 128.666748 -281.948628)
			(xy 128.613598 -281.944644) (xy 128.561636 -281.932784) (xy 128.512022 -281.913312) (xy 128.465864 -281.886663)
			(xy 128.424193 -281.853432) (xy 128.387941 -281.814361) (xy 128.357917 -281.770324) (xy 128.334791 -281.722303)
			(xy 128.319081 -281.671373) (xy 128.311138 -281.618669) (xy 128.082266 -281.618669) (xy 128.074361 -281.671119)
			(xy 128.058651 -281.722049) (xy 128.035525 -281.77007) (xy 128.005501 -281.814107) (xy 127.969249 -281.853178)
			(xy 127.927578 -281.886409) (xy 127.88142 -281.913058) (xy 127.831806 -281.93253) (xy 127.779844 -281.94439)
			(xy 127.726694 -281.948374) (xy 127.673544 -281.94439) (xy 127.621582 -281.93253) (xy 127.571968 -281.913058)
			(xy 127.52581 -281.886409) (xy 127.484139 -281.853178) (xy 127.447887 -281.814107) (xy 127.417863 -281.77007)
			(xy 127.394737 -281.722049) (xy 127.379027 -281.671119) (xy 127.371084 -281.618415) (xy 127.142509 -281.618415)
			(xy 127.142504 -281.618669) (xy 127.134561 -281.671373) (xy 127.118851 -281.722303) (xy 127.095725 -281.770324)
			(xy 127.065701 -281.814361) (xy 127.029449 -281.853432) (xy 126.987778 -281.886663) (xy 126.94162 -281.913312)
			(xy 126.892006 -281.932784) (xy 126.840044 -281.944644) (xy 126.786894 -281.948628) (xy 126.733744 -281.944644)
			(xy 126.681782 -281.932784) (xy 126.632168 -281.913312) (xy 126.58601 -281.886663) (xy 126.544339 -281.853432)
			(xy 126.508087 -281.814361) (xy 126.478063 -281.770324) (xy 126.454937 -281.722303) (xy 126.439227 -281.671373)
			(xy 126.431284 -281.618669) (xy 126.202958 -281.618669) (xy 126.195015 -281.671373) (xy 126.179305 -281.722303)
			(xy 126.156179 -281.770324) (xy 126.126155 -281.814361) (xy 126.089903 -281.853432) (xy 126.048232 -281.886663)
			(xy 126.002074 -281.913312) (xy 125.95246 -281.932784) (xy 125.900498 -281.944644) (xy 125.847348 -281.948628)
			(xy 125.794198 -281.944644) (xy 125.742236 -281.932784) (xy 125.692622 -281.913312) (xy 125.646464 -281.886663)
			(xy 125.604793 -281.853432) (xy 125.568541 -281.814361) (xy 125.538517 -281.770324) (xy 125.515391 -281.722303)
			(xy 125.499681 -281.671373) (xy 125.491738 -281.618669) (xy 125.263158 -281.618669) (xy 125.255215 -281.671373)
			(xy 125.239505 -281.722303) (xy 125.216379 -281.770324) (xy 125.186355 -281.814361) (xy 125.150103 -281.853432)
			(xy 125.108432 -281.886663) (xy 125.062274 -281.913312) (xy 125.01266 -281.932784) (xy 124.960698 -281.944644)
			(xy 124.907548 -281.948628) (xy 124.854398 -281.944644) (xy 124.802436 -281.932784) (xy 124.752822 -281.913312)
			(xy 124.706664 -281.886663) (xy 124.664993 -281.853432) (xy 124.628741 -281.814361) (xy 124.598717 -281.770324)
			(xy 124.575591 -281.722303) (xy 124.559881 -281.671373) (xy 124.551938 -281.618669) (xy 124.323358 -281.618669)
			(xy 124.315415 -281.671373) (xy 124.299705 -281.722303) (xy 124.276579 -281.770324) (xy 124.246555 -281.814361)
			(xy 124.210303 -281.853432) (xy 124.168632 -281.886663) (xy 124.122474 -281.913312) (xy 124.07286 -281.932784)
			(xy 124.020898 -281.944644) (xy 123.967748 -281.948628) (xy 123.914598 -281.944644) (xy 123.862636 -281.932784)
			(xy 123.813022 -281.913312) (xy 123.766864 -281.886663) (xy 123.725193 -281.853432) (xy 123.688941 -281.814361)
			(xy 123.658917 -281.770324) (xy 123.635791 -281.722303) (xy 123.620081 -281.671373) (xy 123.612138 -281.618669)
			(xy 123.383558 -281.618669) (xy 123.375615 -281.671373) (xy 123.359905 -281.722303) (xy 123.336779 -281.770324)
			(xy 123.306755 -281.814361) (xy 123.270503 -281.853432) (xy 123.228832 -281.886663) (xy 123.182674 -281.913312)
			(xy 123.13306 -281.932784) (xy 123.081098 -281.944644) (xy 123.027948 -281.948628) (xy 122.974798 -281.944644)
			(xy 122.922836 -281.932784) (xy 122.873222 -281.913312) (xy 122.827064 -281.886663) (xy 122.785393 -281.853432)
			(xy 122.749141 -281.814361) (xy 122.719117 -281.770324) (xy 122.695991 -281.722303) (xy 122.680281 -281.671373)
			(xy 122.672338 -281.618669) (xy 122.443758 -281.618669) (xy 122.435815 -281.671373) (xy 122.420105 -281.722303)
			(xy 122.396979 -281.770324) (xy 122.366955 -281.814361) (xy 122.330703 -281.853432) (xy 122.289032 -281.886663)
			(xy 122.242874 -281.913312) (xy 122.19326 -281.932784) (xy 122.141298 -281.944644) (xy 122.088148 -281.948628)
			(xy 122.034998 -281.944644) (xy 121.983036 -281.932784) (xy 121.933422 -281.913312) (xy 121.887264 -281.886663)
			(xy 121.845593 -281.853432) (xy 121.809341 -281.814361) (xy 121.779317 -281.770324) (xy 121.756191 -281.722303)
			(xy 121.740481 -281.671373) (xy 121.732538 -281.618669) (xy 121.503958 -281.618669) (xy 121.496015 -281.671373)
			(xy 121.480305 -281.722303) (xy 121.457179 -281.770324) (xy 121.427155 -281.814361) (xy 121.390903 -281.853432)
			(xy 121.349232 -281.886663) (xy 121.303074 -281.913312) (xy 121.25346 -281.932784) (xy 121.201498 -281.944644)
			(xy 121.148348 -281.948628) (xy 121.095198 -281.944644) (xy 121.043236 -281.932784) (xy 120.993622 -281.913312)
			(xy 120.947464 -281.886663) (xy 120.905793 -281.853432) (xy 120.869541 -281.814361) (xy 120.839517 -281.770324)
			(xy 120.816391 -281.722303) (xy 120.800681 -281.671373) (xy 120.792738 -281.618669) (xy 120.564158 -281.618669)
			(xy 120.556215 -281.671373) (xy 120.540505 -281.722303) (xy 120.517379 -281.770324) (xy 120.487355 -281.814361)
			(xy 120.451103 -281.853432) (xy 120.409432 -281.886663) (xy 120.363274 -281.913312) (xy 120.31366 -281.932784)
			(xy 120.261698 -281.944644) (xy 120.208548 -281.948628) (xy 120.155398 -281.944644) (xy 120.103436 -281.932784)
			(xy 120.053822 -281.913312) (xy 120.007664 -281.886663) (xy 119.965993 -281.853432) (xy 119.929741 -281.814361)
			(xy 119.899717 -281.770324) (xy 119.876591 -281.722303) (xy 119.860881 -281.671373) (xy 119.852938 -281.618669)
			(xy 119.624358 -281.618669) (xy 119.616415 -281.671373) (xy 119.600705 -281.722303) (xy 119.577579 -281.770324)
			(xy 119.547555 -281.814361) (xy 119.511303 -281.853432) (xy 119.469632 -281.886663) (xy 119.423474 -281.913312)
			(xy 119.37386 -281.932784) (xy 119.321898 -281.944644) (xy 119.268748 -281.948628) (xy 119.215598 -281.944644)
			(xy 119.163636 -281.932784) (xy 119.114022 -281.913312) (xy 119.067864 -281.886663) (xy 119.026193 -281.853432)
			(xy 118.989941 -281.814361) (xy 118.959917 -281.770324) (xy 118.936791 -281.722303) (xy 118.921081 -281.671373)
			(xy 118.913138 -281.618669) (xy 118.684304 -281.618669) (xy 118.676361 -281.671373) (xy 118.660651 -281.722303)
			(xy 118.637525 -281.770324) (xy 118.607501 -281.814361) (xy 118.571249 -281.853432) (xy 118.529578 -281.886663)
			(xy 118.48342 -281.913312) (xy 118.433806 -281.932784) (xy 118.381844 -281.944644) (xy 118.328694 -281.948628)
			(xy 118.275544 -281.944644) (xy 118.223582 -281.932784) (xy 118.173968 -281.913312) (xy 118.12781 -281.886663)
			(xy 118.086139 -281.853432) (xy 118.049887 -281.814361) (xy 118.019863 -281.770324) (xy 117.996737 -281.722303)
			(xy 117.981027 -281.671373) (xy 117.973084 -281.618669) (xy 117.744774 -281.618669) (xy 117.744766 -281.619116)
			(xy 117.736602 -281.672688) (xy 117.729 -281.6987) (xy 117.719602 -281.72791) (xy 118.301008 -282.309316)
			(xy 118.311527 -282.319144) (xy 118.336734 -282.333022) (xy 118.364812 -282.339319) (xy 118.393531 -282.337534)
			(xy 118.420614 -282.32781) (xy 118.443909 -282.310918) (xy 118.461568 -282.288199) (xy 118.467378 -282.275026)
			(xy 118.477607 -282.250463) (xy 118.504293 -282.204432) (xy 118.53753 -282.162884) (xy 118.576579 -282.126744)
			(xy 118.620571 -282.096816) (xy 118.668526 -282.073766) (xy 118.719376 -282.058108) (xy 118.771991 -282.050191)
			(xy 118.798594 -282.049728) (xy 118.826579 -282.050248) (xy 118.881859 -282.059003) (xy 118.935089 -282.076299)
			(xy 118.984957 -282.10171) (xy 119.030236 -282.134609) (xy 119.069811 -282.174187) (xy 119.102706 -282.219469)
			(xy 119.128112 -282.269339) (xy 119.145404 -282.32257) (xy 119.154154 -282.377851) (xy 119.154702 -282.405836)
			(xy 119.154205 -282.432436) (xy 119.154198 -282.432485) (xy 119.382784 -282.432485) (xy 119.382784 -282.379187)
			(xy 119.390727 -282.326483) (xy 119.406437 -282.275553) (xy 119.429563 -282.227532) (xy 119.459587 -282.183495)
			(xy 119.495839 -282.144424) (xy 119.53751 -282.111193) (xy 119.583668 -282.084544) (xy 119.633282 -282.065072)
			(xy 119.685244 -282.053212) (xy 119.738394 -282.049229) (xy 119.791544 -282.053212) (xy 119.843506 -282.065072)
			(xy 119.89312 -282.084544) (xy 119.939278 -282.111193) (xy 119.980949 -282.144424) (xy 120.017201 -282.183495)
			(xy 120.047225 -282.227532) (xy 120.070351 -282.275553) (xy 120.086061 -282.326483) (xy 120.094004 -282.379187)
			(xy 120.094502 -282.405836) (xy 120.094004 -282.432485) (xy 120.322584 -282.432485) (xy 120.322584 -282.379187)
			(xy 120.330527 -282.326483) (xy 120.346237 -282.275553) (xy 120.369363 -282.227532) (xy 120.399387 -282.183495)
			(xy 120.435639 -282.144424) (xy 120.47731 -282.111193) (xy 120.523468 -282.084544) (xy 120.573082 -282.065072)
			(xy 120.625044 -282.053212) (xy 120.678194 -282.049229) (xy 120.731344 -282.053212) (xy 120.783306 -282.065072)
			(xy 120.83292 -282.084544) (xy 120.879078 -282.111193) (xy 120.920749 -282.144424) (xy 120.957001 -282.183495)
			(xy 120.987025 -282.227532) (xy 121.010151 -282.275553) (xy 121.025861 -282.326483) (xy 121.033804 -282.379187)
			(xy 121.034302 -282.405836) (xy 121.033804 -282.432485) (xy 121.262384 -282.432485) (xy 121.262384 -282.379187)
			(xy 121.270327 -282.326483) (xy 121.286037 -282.275553) (xy 121.309163 -282.227532) (xy 121.339187 -282.183495)
			(xy 121.375439 -282.144424) (xy 121.41711 -282.111193) (xy 121.463268 -282.084544) (xy 121.512882 -282.065072)
			(xy 121.564844 -282.053212) (xy 121.617994 -282.049229) (xy 121.671144 -282.053212) (xy 121.723106 -282.065072)
			(xy 121.77272 -282.084544) (xy 121.818878 -282.111193) (xy 121.860549 -282.144424) (xy 121.896801 -282.183495)
			(xy 121.926825 -282.227532) (xy 121.949951 -282.275553) (xy 121.965661 -282.326483) (xy 121.973604 -282.379187)
			(xy 121.974102 -282.405836) (xy 121.973604 -282.432485) (xy 122.202184 -282.432485) (xy 122.202184 -282.379187)
			(xy 122.210127 -282.326483) (xy 122.225837 -282.275553) (xy 122.248963 -282.227532) (xy 122.278987 -282.183495)
			(xy 122.315239 -282.144424) (xy 122.35691 -282.111193) (xy 122.403068 -282.084544) (xy 122.452682 -282.065072)
			(xy 122.504644 -282.053212) (xy 122.557794 -282.049229) (xy 122.610944 -282.053212) (xy 122.662906 -282.065072)
			(xy 122.71252 -282.084544) (xy 122.758678 -282.111193) (xy 122.800349 -282.144424) (xy 122.836601 -282.183495)
			(xy 122.866625 -282.227532) (xy 122.889751 -282.275553) (xy 122.905461 -282.326483) (xy 122.913404 -282.379187)
			(xy 122.913902 -282.405836) (xy 122.913404 -282.432485) (xy 123.141984 -282.432485) (xy 123.141984 -282.379187)
			(xy 123.149927 -282.326483) (xy 123.165637 -282.275553) (xy 123.188763 -282.227532) (xy 123.218787 -282.183495)
			(xy 123.255039 -282.144424) (xy 123.29671 -282.111193) (xy 123.342868 -282.084544) (xy 123.392482 -282.065072)
			(xy 123.444444 -282.053212) (xy 123.497594 -282.049229) (xy 123.550744 -282.053212) (xy 123.602706 -282.065072)
			(xy 123.65232 -282.084544) (xy 123.698478 -282.111193) (xy 123.740149 -282.144424) (xy 123.776401 -282.183495)
			(xy 123.806425 -282.227532) (xy 123.829551 -282.275553) (xy 123.845261 -282.326483) (xy 123.853204 -282.379187)
			(xy 123.853702 -282.405836) (xy 123.853204 -282.432485) (xy 124.081784 -282.432485) (xy 124.081784 -282.379187)
			(xy 124.089727 -282.326483) (xy 124.105437 -282.275553) (xy 124.128563 -282.227532) (xy 124.158587 -282.183495)
			(xy 124.194839 -282.144424) (xy 124.23651 -282.111193) (xy 124.282668 -282.084544) (xy 124.332282 -282.065072)
			(xy 124.384244 -282.053212) (xy 124.437394 -282.049229) (xy 124.490544 -282.053212) (xy 124.542506 -282.065072)
			(xy 124.59212 -282.084544) (xy 124.638278 -282.111193) (xy 124.679949 -282.144424) (xy 124.716201 -282.183495)
			(xy 124.746225 -282.227532) (xy 124.769351 -282.275553) (xy 124.785061 -282.326483) (xy 124.793004 -282.379187)
			(xy 124.793502 -282.405836) (xy 124.793004 -282.432485) (xy 125.021584 -282.432485) (xy 125.021584 -282.379187)
			(xy 125.029527 -282.326483) (xy 125.045237 -282.275553) (xy 125.068363 -282.227532) (xy 125.098387 -282.183495)
			(xy 125.134639 -282.144424) (xy 125.17631 -282.111193) (xy 125.222468 -282.084544) (xy 125.272082 -282.065072)
			(xy 125.324044 -282.053212) (xy 125.377194 -282.049229) (xy 125.430344 -282.053212) (xy 125.482306 -282.065072)
			(xy 125.53192 -282.084544) (xy 125.578078 -282.111193) (xy 125.619749 -282.144424) (xy 125.656001 -282.183495)
			(xy 125.686025 -282.227532) (xy 125.709151 -282.275553) (xy 125.724861 -282.326483) (xy 125.732804 -282.379187)
			(xy 125.733302 -282.405836) (xy 125.732804 -282.432485) (xy 125.961638 -282.432485) (xy 125.961638 -282.379187)
			(xy 125.969581 -282.326483) (xy 125.985291 -282.275553) (xy 126.008417 -282.227532) (xy 126.038441 -282.183495)
			(xy 126.074693 -282.144424) (xy 126.116364 -282.111193) (xy 126.162522 -282.084544) (xy 126.212136 -282.065072)
			(xy 126.264098 -282.053212) (xy 126.317248 -282.049229) (xy 126.370398 -282.053212) (xy 126.42236 -282.065072)
			(xy 126.471974 -282.084544) (xy 126.518132 -282.111193) (xy 126.559803 -282.144424) (xy 126.596055 -282.183495)
			(xy 126.626079 -282.227532) (xy 126.649205 -282.275553) (xy 126.664915 -282.326483) (xy 126.672858 -282.379187)
			(xy 126.673356 -282.405836) (xy 126.672863 -282.432231) (xy 126.901438 -282.432231) (xy 126.901438 -282.378933)
			(xy 126.909381 -282.326229) (xy 126.925091 -282.275299) (xy 126.948217 -282.227278) (xy 126.978241 -282.183241)
			(xy 127.014493 -282.14417) (xy 127.056164 -282.110939) (xy 127.102322 -282.08429) (xy 127.151936 -282.064818)
			(xy 127.203898 -282.052958) (xy 127.257048 -282.048975) (xy 127.310198 -282.052958) (xy 127.36216 -282.064818)
			(xy 127.411774 -282.08429) (xy 127.457932 -282.110939) (xy 127.499603 -282.14417) (xy 127.535855 -282.183241)
			(xy 127.565879 -282.227278) (xy 127.589005 -282.275299) (xy 127.604715 -282.326229) (xy 127.612658 -282.378933)
			(xy 127.613156 -282.405582) (xy 127.612658 -282.432231) (xy 127.841238 -282.432231) (xy 127.841238 -282.378933)
			(xy 127.849181 -282.326229) (xy 127.864891 -282.275299) (xy 127.888017 -282.227278) (xy 127.918041 -282.183241)
			(xy 127.954293 -282.14417) (xy 127.995964 -282.110939) (xy 128.042122 -282.08429) (xy 128.091736 -282.064818)
			(xy 128.143698 -282.052958) (xy 128.196848 -282.048975) (xy 128.249998 -282.052958) (xy 128.30196 -282.064818)
			(xy 128.351574 -282.08429) (xy 128.397732 -282.110939) (xy 128.439403 -282.14417) (xy 128.475655 -282.183241)
			(xy 128.505679 -282.227278) (xy 128.528805 -282.275299) (xy 128.544515 -282.326229) (xy 128.552458 -282.378933)
			(xy 128.552956 -282.405582) (xy 128.552458 -282.432231) (xy 128.781038 -282.432231) (xy 128.781038 -282.378933)
			(xy 128.788981 -282.326229) (xy 128.804691 -282.275299) (xy 128.827817 -282.227278) (xy 128.857841 -282.183241)
			(xy 128.894093 -282.14417) (xy 128.935764 -282.110939) (xy 128.981922 -282.08429) (xy 129.031536 -282.064818)
			(xy 129.083498 -282.052958) (xy 129.136648 -282.048975) (xy 129.189798 -282.052958) (xy 129.24176 -282.064818)
			(xy 129.291374 -282.08429) (xy 129.337532 -282.110939) (xy 129.379203 -282.14417) (xy 129.415455 -282.183241)
			(xy 129.445479 -282.227278) (xy 129.468605 -282.275299) (xy 129.484315 -282.326229) (xy 129.492258 -282.378933)
			(xy 129.492756 -282.405582) (xy 129.492258 -282.432231) (xy 129.720838 -282.432231) (xy 129.720838 -282.378933)
			(xy 129.728781 -282.326229) (xy 129.744491 -282.275299) (xy 129.767617 -282.227278) (xy 129.797641 -282.183241)
			(xy 129.833893 -282.14417) (xy 129.875564 -282.110939) (xy 129.921722 -282.08429) (xy 129.971336 -282.064818)
			(xy 130.023298 -282.052958) (xy 130.076448 -282.048975) (xy 130.129598 -282.052958) (xy 130.18156 -282.064818)
			(xy 130.231174 -282.08429) (xy 130.277332 -282.110939) (xy 130.319003 -282.14417) (xy 130.355255 -282.183241)
			(xy 130.385279 -282.227278) (xy 130.408405 -282.275299) (xy 130.424115 -282.326229) (xy 130.432058 -282.378933)
			(xy 130.432556 -282.405582) (xy 130.432058 -282.432231) (xy 130.43202 -282.432485) (xy 130.660384 -282.432485)
			(xy 130.660384 -282.379187) (xy 130.668327 -282.326483) (xy 130.684037 -282.275553) (xy 130.707163 -282.227532)
			(xy 130.737187 -282.183495) (xy 130.773439 -282.144424) (xy 130.81511 -282.111193) (xy 130.861268 -282.084544)
			(xy 130.910882 -282.065072) (xy 130.962844 -282.053212) (xy 131.015994 -282.049229) (xy 131.069144 -282.053212)
			(xy 131.121106 -282.065072) (xy 131.17072 -282.084544) (xy 131.216878 -282.111193) (xy 131.258549 -282.144424)
			(xy 131.294801 -282.183495) (xy 131.324825 -282.227532) (xy 131.347951 -282.275553) (xy 131.363661 -282.326483)
			(xy 131.371604 -282.379187) (xy 131.372102 -282.405836) (xy 131.371604 -282.432485) (xy 131.600184 -282.432485)
			(xy 131.600184 -282.379187) (xy 131.608127 -282.326483) (xy 131.623837 -282.275553) (xy 131.646963 -282.227532)
			(xy 131.676987 -282.183495) (xy 131.713239 -282.144424) (xy 131.75491 -282.111193) (xy 131.801068 -282.084544)
			(xy 131.850682 -282.065072) (xy 131.902644 -282.053212) (xy 131.955794 -282.049229) (xy 132.008944 -282.053212)
			(xy 132.060906 -282.065072) (xy 132.11052 -282.084544) (xy 132.156678 -282.111193) (xy 132.198349 -282.144424)
			(xy 132.234601 -282.183495) (xy 132.264625 -282.227532) (xy 132.287751 -282.275553) (xy 132.303461 -282.326483)
			(xy 132.311404 -282.379187) (xy 132.311902 -282.405836) (xy 132.311404 -282.432485) (xy 132.539984 -282.432485)
			(xy 132.539984 -282.379187) (xy 132.547927 -282.326483) (xy 132.563637 -282.275553) (xy 132.586763 -282.227532)
			(xy 132.616787 -282.183495) (xy 132.653039 -282.144424) (xy 132.69471 -282.111193) (xy 132.740868 -282.084544)
			(xy 132.790482 -282.065072) (xy 132.842444 -282.053212) (xy 132.895594 -282.049229) (xy 132.948744 -282.053212)
			(xy 133.000706 -282.065072) (xy 133.05032 -282.084544) (xy 133.096478 -282.111193) (xy 133.138149 -282.144424)
			(xy 133.174401 -282.183495) (xy 133.204425 -282.227532) (xy 133.227551 -282.275553) (xy 133.243261 -282.326483)
			(xy 133.251204 -282.379187) (xy 133.251702 -282.405836) (xy 133.251204 -282.432485) (xy 133.479784 -282.432485)
			(xy 133.479784 -282.379187) (xy 133.487727 -282.326483) (xy 133.503437 -282.275553) (xy 133.526563 -282.227532)
			(xy 133.556587 -282.183495) (xy 133.592839 -282.144424) (xy 133.63451 -282.111193) (xy 133.680668 -282.084544)
			(xy 133.730282 -282.065072) (xy 133.782244 -282.053212) (xy 133.835394 -282.049229) (xy 133.888544 -282.053212)
			(xy 133.940506 -282.065072) (xy 133.99012 -282.084544) (xy 134.036278 -282.111193) (xy 134.077949 -282.144424)
			(xy 134.114201 -282.183495) (xy 134.144225 -282.227532) (xy 134.167351 -282.275553) (xy 134.183061 -282.326483)
			(xy 134.191004 -282.379187) (xy 134.191502 -282.405836) (xy 134.191004 -282.432485) (xy 134.419838 -282.432485)
			(xy 134.419838 -282.379187) (xy 134.427781 -282.326483) (xy 134.443491 -282.275553) (xy 134.466617 -282.227532)
			(xy 134.496641 -282.183495) (xy 134.532893 -282.144424) (xy 134.574564 -282.111193) (xy 134.620722 -282.084544)
			(xy 134.670336 -282.065072) (xy 134.722298 -282.053212) (xy 134.775448 -282.049229) (xy 134.828598 -282.053212)
			(xy 134.88056 -282.065072) (xy 134.930174 -282.084544) (xy 134.976332 -282.111193) (xy 135.018003 -282.144424)
			(xy 135.054255 -282.183495) (xy 135.084279 -282.227532) (xy 135.107405 -282.275553) (xy 135.123115 -282.326483)
			(xy 135.131058 -282.379187) (xy 135.131556 -282.405836) (xy 135.131058 -282.432485) (xy 135.359384 -282.432485)
			(xy 135.359384 -282.379187) (xy 135.367327 -282.326483) (xy 135.383037 -282.275553) (xy 135.406163 -282.227532)
			(xy 135.436187 -282.183495) (xy 135.472439 -282.144424) (xy 135.51411 -282.111193) (xy 135.560268 -282.084544)
			(xy 135.609882 -282.065072) (xy 135.661844 -282.053212) (xy 135.714994 -282.049229) (xy 135.768144 -282.053212)
			(xy 135.820106 -282.065072) (xy 135.86972 -282.084544) (xy 135.915878 -282.111193) (xy 135.957549 -282.144424)
			(xy 135.993801 -282.183495) (xy 136.023825 -282.227532) (xy 136.046951 -282.275553) (xy 136.062661 -282.326483)
			(xy 136.070604 -282.379187) (xy 136.071102 -282.405836) (xy 136.070604 -282.432485) (xy 136.299184 -282.432485)
			(xy 136.299184 -282.379187) (xy 136.307127 -282.326483) (xy 136.322837 -282.275553) (xy 136.345963 -282.227532)
			(xy 136.375987 -282.183495) (xy 136.412239 -282.144424) (xy 136.45391 -282.111193) (xy 136.500068 -282.084544)
			(xy 136.549682 -282.065072) (xy 136.601644 -282.053212) (xy 136.654794 -282.049229) (xy 136.707944 -282.053212)
			(xy 136.759906 -282.065072) (xy 136.80952 -282.084544) (xy 136.855678 -282.111193) (xy 136.897349 -282.144424)
			(xy 136.933601 -282.183495) (xy 136.963625 -282.227532) (xy 136.986751 -282.275553) (xy 137.002461 -282.326483)
			(xy 137.010404 -282.379187) (xy 137.010902 -282.405836) (xy 137.010404 -282.432485) (xy 137.238984 -282.432485)
			(xy 137.238984 -282.379187) (xy 137.246927 -282.326483) (xy 137.262637 -282.275553) (xy 137.285763 -282.227532)
			(xy 137.315787 -282.183495) (xy 137.352039 -282.144424) (xy 137.39371 -282.111193) (xy 137.439868 -282.084544)
			(xy 137.489482 -282.065072) (xy 137.541444 -282.053212) (xy 137.594594 -282.049229) (xy 137.647744 -282.053212)
			(xy 137.699706 -282.065072) (xy 137.74932 -282.084544) (xy 137.795478 -282.111193) (xy 137.837149 -282.144424)
			(xy 137.873401 -282.183495) (xy 137.903425 -282.227532) (xy 137.926551 -282.275553) (xy 137.942261 -282.326483)
			(xy 137.950204 -282.379187) (xy 137.950702 -282.405836) (xy 137.950204 -282.432485) (xy 137.942261 -282.485189)
			(xy 137.926551 -282.536119) (xy 137.903425 -282.58414) (xy 137.873401 -282.628177) (xy 137.837149 -282.667248)
			(xy 137.795478 -282.700479) (xy 137.74932 -282.727128) (xy 137.699706 -282.7466) (xy 137.647744 -282.75846)
			(xy 137.594594 -282.762444) (xy 137.541444 -282.75846) (xy 137.489482 -282.7466) (xy 137.439868 -282.727128)
			(xy 137.39371 -282.700479) (xy 137.352039 -282.667248) (xy 137.315787 -282.628177) (xy 137.285763 -282.58414)
			(xy 137.262637 -282.536119) (xy 137.246927 -282.485189) (xy 137.238984 -282.432485) (xy 137.010404 -282.432485)
			(xy 137.002461 -282.485189) (xy 136.986751 -282.536119) (xy 136.963625 -282.58414) (xy 136.933601 -282.628177)
			(xy 136.897349 -282.667248) (xy 136.855678 -282.700479) (xy 136.80952 -282.727128) (xy 136.759906 -282.7466)
			(xy 136.707944 -282.75846) (xy 136.654794 -282.762444) (xy 136.601644 -282.75846) (xy 136.549682 -282.7466)
			(xy 136.500068 -282.727128) (xy 136.45391 -282.700479) (xy 136.412239 -282.667248) (xy 136.375987 -282.628177)
			(xy 136.345963 -282.58414) (xy 136.322837 -282.536119) (xy 136.307127 -282.485189) (xy 136.299184 -282.432485)
			(xy 136.070604 -282.432485) (xy 136.062661 -282.485189) (xy 136.046951 -282.536119) (xy 136.023825 -282.58414)
			(xy 135.993801 -282.628177) (xy 135.957549 -282.667248) (xy 135.915878 -282.700479) (xy 135.86972 -282.727128)
			(xy 135.820106 -282.7466) (xy 135.768144 -282.75846) (xy 135.714994 -282.762444) (xy 135.661844 -282.75846)
			(xy 135.609882 -282.7466) (xy 135.560268 -282.727128) (xy 135.51411 -282.700479) (xy 135.472439 -282.667248)
			(xy 135.436187 -282.628177) (xy 135.406163 -282.58414) (xy 135.383037 -282.536119) (xy 135.367327 -282.485189)
			(xy 135.359384 -282.432485) (xy 135.131058 -282.432485) (xy 135.123115 -282.485189) (xy 135.107405 -282.536119)
			(xy 135.084279 -282.58414) (xy 135.054255 -282.628177) (xy 135.018003 -282.667248) (xy 134.976332 -282.700479)
			(xy 134.930174 -282.727128) (xy 134.88056 -282.7466) (xy 134.828598 -282.75846) (xy 134.775448 -282.762444)
			(xy 134.722298 -282.75846) (xy 134.670336 -282.7466) (xy 134.620722 -282.727128) (xy 134.574564 -282.700479)
			(xy 134.532893 -282.667248) (xy 134.496641 -282.628177) (xy 134.466617 -282.58414) (xy 134.443491 -282.536119)
			(xy 134.427781 -282.485189) (xy 134.419838 -282.432485) (xy 134.191004 -282.432485) (xy 134.183061 -282.485189)
			(xy 134.167351 -282.536119) (xy 134.144225 -282.58414) (xy 134.114201 -282.628177) (xy 134.077949 -282.667248)
			(xy 134.036278 -282.700479) (xy 133.99012 -282.727128) (xy 133.940506 -282.7466) (xy 133.888544 -282.75846)
			(xy 133.835394 -282.762444) (xy 133.782244 -282.75846) (xy 133.730282 -282.7466) (xy 133.680668 -282.727128)
			(xy 133.63451 -282.700479) (xy 133.592839 -282.667248) (xy 133.556587 -282.628177) (xy 133.526563 -282.58414)
			(xy 133.503437 -282.536119) (xy 133.487727 -282.485189) (xy 133.479784 -282.432485) (xy 133.251204 -282.432485)
			(xy 133.243261 -282.485189) (xy 133.227551 -282.536119) (xy 133.204425 -282.58414) (xy 133.174401 -282.628177)
			(xy 133.138149 -282.667248) (xy 133.096478 -282.700479) (xy 133.05032 -282.727128) (xy 133.000706 -282.7466)
			(xy 132.948744 -282.75846) (xy 132.895594 -282.762444) (xy 132.842444 -282.75846) (xy 132.790482 -282.7466)
			(xy 132.740868 -282.727128) (xy 132.69471 -282.700479) (xy 132.653039 -282.667248) (xy 132.616787 -282.628177)
			(xy 132.586763 -282.58414) (xy 132.563637 -282.536119) (xy 132.547927 -282.485189) (xy 132.539984 -282.432485)
			(xy 132.311404 -282.432485) (xy 132.303461 -282.485189) (xy 132.287751 -282.536119) (xy 132.264625 -282.58414)
			(xy 132.234601 -282.628177) (xy 132.198349 -282.667248) (xy 132.156678 -282.700479) (xy 132.11052 -282.727128)
			(xy 132.060906 -282.7466) (xy 132.008944 -282.75846) (xy 131.955794 -282.762444) (xy 131.902644 -282.75846)
			(xy 131.850682 -282.7466) (xy 131.801068 -282.727128) (xy 131.75491 -282.700479) (xy 131.713239 -282.667248)
			(xy 131.676987 -282.628177) (xy 131.646963 -282.58414) (xy 131.623837 -282.536119) (xy 131.608127 -282.485189)
			(xy 131.600184 -282.432485) (xy 131.371604 -282.432485) (xy 131.363661 -282.485189) (xy 131.347951 -282.536119)
			(xy 131.324825 -282.58414) (xy 131.294801 -282.628177) (xy 131.258549 -282.667248) (xy 131.216878 -282.700479)
			(xy 131.17072 -282.727128) (xy 131.121106 -282.7466) (xy 131.069144 -282.75846) (xy 131.015994 -282.762444)
			(xy 130.962844 -282.75846) (xy 130.910882 -282.7466) (xy 130.861268 -282.727128) (xy 130.81511 -282.700479)
			(xy 130.773439 -282.667248) (xy 130.737187 -282.628177) (xy 130.707163 -282.58414) (xy 130.684037 -282.536119)
			(xy 130.668327 -282.485189) (xy 130.660384 -282.432485) (xy 130.43202 -282.432485) (xy 130.424115 -282.484935)
			(xy 130.408405 -282.535865) (xy 130.385279 -282.583886) (xy 130.355255 -282.627923) (xy 130.319003 -282.666994)
			(xy 130.277332 -282.700225) (xy 130.231174 -282.726874) (xy 130.18156 -282.746346) (xy 130.129598 -282.758206)
			(xy 130.076448 -282.76219) (xy 130.023298 -282.758206) (xy 129.971336 -282.746346) (xy 129.921722 -282.726874)
			(xy 129.875564 -282.700225) (xy 129.833893 -282.666994) (xy 129.797641 -282.627923) (xy 129.767617 -282.583886)
			(xy 129.744491 -282.535865) (xy 129.728781 -282.484935) (xy 129.720838 -282.432231) (xy 129.492258 -282.432231)
			(xy 129.484315 -282.484935) (xy 129.468605 -282.535865) (xy 129.445479 -282.583886) (xy 129.415455 -282.627923)
			(xy 129.379203 -282.666994) (xy 129.337532 -282.700225) (xy 129.291374 -282.726874) (xy 129.24176 -282.746346)
			(xy 129.189798 -282.758206) (xy 129.136648 -282.76219) (xy 129.083498 -282.758206) (xy 129.031536 -282.746346)
			(xy 128.981922 -282.726874) (xy 128.935764 -282.700225) (xy 128.894093 -282.666994) (xy 128.857841 -282.627923)
			(xy 128.827817 -282.583886) (xy 128.804691 -282.535865) (xy 128.788981 -282.484935) (xy 128.781038 -282.432231)
			(xy 128.552458 -282.432231) (xy 128.544515 -282.484935) (xy 128.528805 -282.535865) (xy 128.505679 -282.583886)
			(xy 128.475655 -282.627923) (xy 128.439403 -282.666994) (xy 128.397732 -282.700225) (xy 128.351574 -282.726874)
			(xy 128.30196 -282.746346) (xy 128.249998 -282.758206) (xy 128.196848 -282.76219) (xy 128.143698 -282.758206)
			(xy 128.091736 -282.746346) (xy 128.042122 -282.726874) (xy 127.995964 -282.700225) (xy 127.954293 -282.666994)
			(xy 127.918041 -282.627923) (xy 127.888017 -282.583886) (xy 127.864891 -282.535865) (xy 127.849181 -282.484935)
			(xy 127.841238 -282.432231) (xy 127.612658 -282.432231) (xy 127.604715 -282.484935) (xy 127.589005 -282.535865)
			(xy 127.565879 -282.583886) (xy 127.535855 -282.627923) (xy 127.499603 -282.666994) (xy 127.457932 -282.700225)
			(xy 127.411774 -282.726874) (xy 127.36216 -282.746346) (xy 127.310198 -282.758206) (xy 127.257048 -282.76219)
			(xy 127.203898 -282.758206) (xy 127.151936 -282.746346) (xy 127.102322 -282.726874) (xy 127.056164 -282.700225)
			(xy 127.014493 -282.666994) (xy 126.978241 -282.627923) (xy 126.948217 -282.583886) (xy 126.925091 -282.535865)
			(xy 126.909381 -282.484935) (xy 126.901438 -282.432231) (xy 126.672863 -282.432231) (xy 126.672858 -282.432485)
			(xy 126.664915 -282.485189) (xy 126.649205 -282.536119) (xy 126.626079 -282.58414) (xy 126.596055 -282.628177)
			(xy 126.559803 -282.667248) (xy 126.518132 -282.700479) (xy 126.471974 -282.727128) (xy 126.42236 -282.7466)
			(xy 126.370398 -282.75846) (xy 126.317248 -282.762444) (xy 126.264098 -282.75846) (xy 126.212136 -282.7466)
			(xy 126.162522 -282.727128) (xy 126.116364 -282.700479) (xy 126.074693 -282.667248) (xy 126.038441 -282.628177)
			(xy 126.008417 -282.58414) (xy 125.985291 -282.536119) (xy 125.969581 -282.485189) (xy 125.961638 -282.432485)
			(xy 125.732804 -282.432485) (xy 125.724861 -282.485189) (xy 125.709151 -282.536119) (xy 125.686025 -282.58414)
			(xy 125.656001 -282.628177) (xy 125.619749 -282.667248) (xy 125.578078 -282.700479) (xy 125.53192 -282.727128)
			(xy 125.482306 -282.7466) (xy 125.430344 -282.75846) (xy 125.377194 -282.762444) (xy 125.324044 -282.75846)
			(xy 125.272082 -282.7466) (xy 125.222468 -282.727128) (xy 125.17631 -282.700479) (xy 125.134639 -282.667248)
			(xy 125.098387 -282.628177) (xy 125.068363 -282.58414) (xy 125.045237 -282.536119) (xy 125.029527 -282.485189)
			(xy 125.021584 -282.432485) (xy 124.793004 -282.432485) (xy 124.785061 -282.485189) (xy 124.769351 -282.536119)
			(xy 124.746225 -282.58414) (xy 124.716201 -282.628177) (xy 124.679949 -282.667248) (xy 124.638278 -282.700479)
			(xy 124.59212 -282.727128) (xy 124.542506 -282.7466) (xy 124.490544 -282.75846) (xy 124.437394 -282.762444)
			(xy 124.384244 -282.75846) (xy 124.332282 -282.7466) (xy 124.282668 -282.727128) (xy 124.23651 -282.700479)
			(xy 124.194839 -282.667248) (xy 124.158587 -282.628177) (xy 124.128563 -282.58414) (xy 124.105437 -282.536119)
			(xy 124.089727 -282.485189) (xy 124.081784 -282.432485) (xy 123.853204 -282.432485) (xy 123.845261 -282.485189)
			(xy 123.829551 -282.536119) (xy 123.806425 -282.58414) (xy 123.776401 -282.628177) (xy 123.740149 -282.667248)
			(xy 123.698478 -282.700479) (xy 123.65232 -282.727128) (xy 123.602706 -282.7466) (xy 123.550744 -282.75846)
			(xy 123.497594 -282.762444) (xy 123.444444 -282.75846) (xy 123.392482 -282.7466) (xy 123.342868 -282.727128)
			(xy 123.29671 -282.700479) (xy 123.255039 -282.667248) (xy 123.218787 -282.628177) (xy 123.188763 -282.58414)
			(xy 123.165637 -282.536119) (xy 123.149927 -282.485189) (xy 123.141984 -282.432485) (xy 122.913404 -282.432485)
			(xy 122.905461 -282.485189) (xy 122.889751 -282.536119) (xy 122.866625 -282.58414) (xy 122.836601 -282.628177)
			(xy 122.800349 -282.667248) (xy 122.758678 -282.700479) (xy 122.71252 -282.727128) (xy 122.662906 -282.7466)
			(xy 122.610944 -282.75846) (xy 122.557794 -282.762444) (xy 122.504644 -282.75846) (xy 122.452682 -282.7466)
			(xy 122.403068 -282.727128) (xy 122.35691 -282.700479) (xy 122.315239 -282.667248) (xy 122.278987 -282.628177)
			(xy 122.248963 -282.58414) (xy 122.225837 -282.536119) (xy 122.210127 -282.485189) (xy 122.202184 -282.432485)
			(xy 121.973604 -282.432485) (xy 121.965661 -282.485189) (xy 121.949951 -282.536119) (xy 121.926825 -282.58414)
			(xy 121.896801 -282.628177) (xy 121.860549 -282.667248) (xy 121.818878 -282.700479) (xy 121.77272 -282.727128)
			(xy 121.723106 -282.7466) (xy 121.671144 -282.75846) (xy 121.617994 -282.762444) (xy 121.564844 -282.75846)
			(xy 121.512882 -282.7466) (xy 121.463268 -282.727128) (xy 121.41711 -282.700479) (xy 121.375439 -282.667248)
			(xy 121.339187 -282.628177) (xy 121.309163 -282.58414) (xy 121.286037 -282.536119) (xy 121.270327 -282.485189)
			(xy 121.262384 -282.432485) (xy 121.033804 -282.432485) (xy 121.025861 -282.485189) (xy 121.010151 -282.536119)
			(xy 120.987025 -282.58414) (xy 120.957001 -282.628177) (xy 120.920749 -282.667248) (xy 120.879078 -282.700479)
			(xy 120.83292 -282.727128) (xy 120.783306 -282.7466) (xy 120.731344 -282.75846) (xy 120.678194 -282.762444)
			(xy 120.625044 -282.75846) (xy 120.573082 -282.7466) (xy 120.523468 -282.727128) (xy 120.47731 -282.700479)
			(xy 120.435639 -282.667248) (xy 120.399387 -282.628177) (xy 120.369363 -282.58414) (xy 120.346237 -282.536119)
			(xy 120.330527 -282.485189) (xy 120.322584 -282.432485) (xy 120.094004 -282.432485) (xy 120.086061 -282.485189)
			(xy 120.070351 -282.536119) (xy 120.047225 -282.58414) (xy 120.017201 -282.628177) (xy 119.980949 -282.667248)
			(xy 119.939278 -282.700479) (xy 119.89312 -282.727128) (xy 119.843506 -282.7466) (xy 119.791544 -282.75846)
			(xy 119.738394 -282.762444) (xy 119.685244 -282.75846) (xy 119.633282 -282.7466) (xy 119.583668 -282.727128)
			(xy 119.53751 -282.700479) (xy 119.495839 -282.667248) (xy 119.459587 -282.628177) (xy 119.429563 -282.58414)
			(xy 119.406437 -282.536119) (xy 119.390727 -282.485189) (xy 119.382784 -282.432485) (xy 119.154198 -282.432485)
			(xy 119.146285 -282.485044) (xy 119.130627 -282.535888) (xy 119.107578 -282.583837) (xy 119.077653 -282.627823)
			(xy 119.041517 -282.666867) (xy 118.999974 -282.700101) (xy 118.953949 -282.726785) (xy 118.929404 -282.737052)
			(xy 118.916191 -282.7428) (xy 118.893421 -282.760436) (xy 118.876493 -282.783736) (xy 118.866758 -282.810842)
			(xy 118.864993 -282.839589) (xy 118.871339 -282.867682) (xy 118.885289 -282.892879) (xy 118.895114 -282.903422)
			(xy 118.987316 -282.995624) (xy 119.023384 -282.961588) (xy 119.043353 -282.94334) (xy 119.087777 -282.912475)
			(xy 119.136357 -282.888684) (xy 119.187976 -282.872512) (xy 119.241447 -282.864331) (xy 119.268494 -282.863798)
			(xy 119.296479 -282.864318) (xy 119.351761 -282.873073) (xy 119.404993 -282.890369) (xy 119.454864 -282.915779)
			(xy 119.500145 -282.948677) (xy 119.539723 -282.988255) (xy 119.572621 -283.033536) (xy 119.598031 -283.083407)
			(xy 119.615327 -283.136639) (xy 119.624082 -283.191921) (xy 119.624602 -283.219906) (xy 119.624105 -283.246555)
			(xy 119.852938 -283.246555) (xy 119.852938 -283.193257) (xy 119.860881 -283.140553) (xy 119.876591 -283.089623)
			(xy 119.899717 -283.041602) (xy 119.929741 -282.997565) (xy 119.965993 -282.958494) (xy 120.007664 -282.925263)
			(xy 120.053822 -282.898614) (xy 120.103436 -282.879142) (xy 120.155398 -282.867282) (xy 120.208548 -282.863299)
			(xy 120.261698 -282.867282) (xy 120.31366 -282.879142) (xy 120.363274 -282.898614) (xy 120.409432 -282.925263)
			(xy 120.451103 -282.958494) (xy 120.487355 -282.997565) (xy 120.517379 -283.041602) (xy 120.540505 -283.089623)
			(xy 120.556215 -283.140553) (xy 120.564158 -283.193257) (xy 120.564656 -283.219906) (xy 120.564158 -283.246555)
			(xy 120.792484 -283.246555) (xy 120.792484 -283.193257) (xy 120.800427 -283.140553) (xy 120.816137 -283.089623)
			(xy 120.839263 -283.041602) (xy 120.869287 -282.997565) (xy 120.905539 -282.958494) (xy 120.94721 -282.925263)
			(xy 120.993368 -282.898614) (xy 121.042982 -282.879142) (xy 121.094944 -282.867282) (xy 121.148094 -282.863299)
			(xy 121.201244 -282.867282) (xy 121.253206 -282.879142) (xy 121.30282 -282.898614) (xy 121.348978 -282.925263)
			(xy 121.390649 -282.958494) (xy 121.426901 -282.997565) (xy 121.456925 -283.041602) (xy 121.480051 -283.089623)
			(xy 121.495761 -283.140553) (xy 121.503704 -283.193257) (xy 121.504202 -283.219906) (xy 121.503704 -283.246555)
			(xy 121.732284 -283.246555) (xy 121.732284 -283.193257) (xy 121.740227 -283.140553) (xy 121.755937 -283.089623)
			(xy 121.779063 -283.041602) (xy 121.809087 -282.997565) (xy 121.845339 -282.958494) (xy 121.88701 -282.925263)
			(xy 121.933168 -282.898614) (xy 121.982782 -282.879142) (xy 122.034744 -282.867282) (xy 122.087894 -282.863299)
			(xy 122.141044 -282.867282) (xy 122.193006 -282.879142) (xy 122.24262 -282.898614) (xy 122.288778 -282.925263)
			(xy 122.330449 -282.958494) (xy 122.366701 -282.997565) (xy 122.396725 -283.041602) (xy 122.419851 -283.089623)
			(xy 122.435561 -283.140553) (xy 122.443504 -283.193257) (xy 122.444002 -283.219906) (xy 122.443504 -283.246555)
			(xy 122.672338 -283.246555) (xy 122.672338 -283.193257) (xy 122.680281 -283.140553) (xy 122.695991 -283.089623)
			(xy 122.719117 -283.041602) (xy 122.749141 -282.997565) (xy 122.785393 -282.958494) (xy 122.827064 -282.925263)
			(xy 122.873222 -282.898614) (xy 122.922836 -282.879142) (xy 122.974798 -282.867282) (xy 123.027948 -282.863299)
			(xy 123.081098 -282.867282) (xy 123.13306 -282.879142) (xy 123.182674 -282.898614) (xy 123.228832 -282.925263)
			(xy 123.270503 -282.958494) (xy 123.306755 -282.997565) (xy 123.336779 -283.041602) (xy 123.359905 -283.089623)
			(xy 123.375615 -283.140553) (xy 123.383558 -283.193257) (xy 123.384056 -283.219906) (xy 123.383558 -283.246555)
			(xy 124.551938 -283.246555) (xy 124.551938 -283.193257) (xy 124.559881 -283.140553) (xy 124.575591 -283.089623)
			(xy 124.598717 -283.041602) (xy 124.628741 -282.997565) (xy 124.664993 -282.958494) (xy 124.706664 -282.925263)
			(xy 124.752822 -282.898614) (xy 124.802436 -282.879142) (xy 124.854398 -282.867282) (xy 124.907548 -282.863299)
			(xy 124.960698 -282.867282) (xy 125.01266 -282.879142) (xy 125.062274 -282.898614) (xy 125.108432 -282.925263)
			(xy 125.150103 -282.958494) (xy 125.186355 -282.997565) (xy 125.216379 -283.041602) (xy 125.239505 -283.089623)
			(xy 125.255215 -283.140553) (xy 125.263158 -283.193257) (xy 125.263656 -283.219906) (xy 125.263158 -283.246555)
			(xy 125.491738 -283.246555) (xy 125.491738 -283.193257) (xy 125.499681 -283.140553) (xy 125.515391 -283.089623)
			(xy 125.538517 -283.041602) (xy 125.568541 -282.997565) (xy 125.604793 -282.958494) (xy 125.646464 -282.925263)
			(xy 125.692622 -282.898614) (xy 125.742236 -282.879142) (xy 125.794198 -282.867282) (xy 125.847348 -282.863299)
			(xy 125.900498 -282.867282) (xy 125.95246 -282.879142) (xy 126.002074 -282.898614) (xy 126.048232 -282.925263)
			(xy 126.089903 -282.958494) (xy 126.126155 -282.997565) (xy 126.156179 -283.041602) (xy 126.179305 -283.089623)
			(xy 126.195015 -283.140553) (xy 126.202958 -283.193257) (xy 126.203456 -283.219906) (xy 126.202958 -283.246555)
			(xy 126.431284 -283.246555) (xy 126.431284 -283.193257) (xy 126.439227 -283.140553) (xy 126.454937 -283.089623)
			(xy 126.478063 -283.041602) (xy 126.508087 -282.997565) (xy 126.544339 -282.958494) (xy 126.58601 -282.925263)
			(xy 126.632168 -282.898614) (xy 126.681782 -282.879142) (xy 126.733744 -282.867282) (xy 126.786894 -282.863299)
			(xy 126.840044 -282.867282) (xy 126.892006 -282.879142) (xy 126.94162 -282.898614) (xy 126.987778 -282.925263)
			(xy 127.029449 -282.958494) (xy 127.065701 -282.997565) (xy 127.095725 -283.041602) (xy 127.118851 -283.089623)
			(xy 127.134561 -283.140553) (xy 127.142504 -283.193257) (xy 127.143002 -283.219906) (xy 127.142509 -283.246301)
			(xy 128.310884 -283.246301) (xy 128.310884 -283.193003) (xy 128.318827 -283.140299) (xy 128.334537 -283.089369)
			(xy 128.357663 -283.041348) (xy 128.387687 -282.997311) (xy 128.423939 -282.95824) (xy 128.46561 -282.925009)
			(xy 128.511768 -282.89836) (xy 128.561382 -282.878888) (xy 128.613344 -282.867028) (xy 128.666494 -282.863045)
			(xy 128.719644 -282.867028) (xy 128.771606 -282.878888) (xy 128.82122 -282.89836) (xy 128.867378 -282.925009)
			(xy 128.909049 -282.95824) (xy 128.945301 -282.997311) (xy 128.975325 -283.041348) (xy 128.998451 -283.089369)
			(xy 129.014161 -283.140299) (xy 129.022104 -283.193003) (xy 129.022602 -283.219652) (xy 129.022104 -283.246301)
			(xy 129.022066 -283.246555) (xy 129.250684 -283.246555) (xy 129.250684 -283.193257) (xy 129.258627 -283.140553)
			(xy 129.274337 -283.089623) (xy 129.297463 -283.041602) (xy 129.327487 -282.997565) (xy 129.363739 -282.958494)
			(xy 129.40541 -282.925263) (xy 129.451568 -282.898614) (xy 129.501182 -282.879142) (xy 129.553144 -282.867282)
			(xy 129.606294 -282.863299) (xy 129.659444 -282.867282) (xy 129.711406 -282.879142) (xy 129.76102 -282.898614)
			(xy 129.807178 -282.925263) (xy 129.848849 -282.958494) (xy 129.885101 -282.997565) (xy 129.915125 -283.041602)
			(xy 129.938251 -283.089623) (xy 129.953961 -283.140553) (xy 129.961904 -283.193257) (xy 129.962402 -283.219906)
			(xy 129.961904 -283.246555) (xy 130.190484 -283.246555) (xy 130.190484 -283.193257) (xy 130.198427 -283.140553)
			(xy 130.214137 -283.089623) (xy 130.237263 -283.041602) (xy 130.267287 -282.997565) (xy 130.303539 -282.958494)
			(xy 130.34521 -282.925263) (xy 130.391368 -282.898614) (xy 130.440982 -282.879142) (xy 130.492944 -282.867282)
			(xy 130.546094 -282.863299) (xy 130.599244 -282.867282) (xy 130.651206 -282.879142) (xy 130.70082 -282.898614)
			(xy 130.746978 -282.925263) (xy 130.788649 -282.958494) (xy 130.824901 -282.997565) (xy 130.854925 -283.041602)
			(xy 130.878051 -283.089623) (xy 130.893761 -283.140553) (xy 130.901704 -283.193257) (xy 130.902202 -283.219906)
			(xy 130.901704 -283.246555) (xy 131.130538 -283.246555) (xy 131.130538 -283.193257) (xy 131.138481 -283.140553)
			(xy 131.154191 -283.089623) (xy 131.177317 -283.041602) (xy 131.207341 -282.997565) (xy 131.243593 -282.958494)
			(xy 131.285264 -282.925263) (xy 131.331422 -282.898614) (xy 131.381036 -282.879142) (xy 131.432998 -282.867282)
			(xy 131.486148 -282.863299) (xy 131.539298 -282.867282) (xy 131.59126 -282.879142) (xy 131.640874 -282.898614)
			(xy 131.687032 -282.925263) (xy 131.728703 -282.958494) (xy 131.764955 -282.997565) (xy 131.794979 -283.041602)
			(xy 131.818105 -283.089623) (xy 131.833815 -283.140553) (xy 131.841758 -283.193257) (xy 131.842256 -283.219906)
			(xy 131.841758 -283.246555) (xy 132.070084 -283.246555) (xy 132.070084 -283.193257) (xy 132.078027 -283.140553)
			(xy 132.093737 -283.089623) (xy 132.116863 -283.041602) (xy 132.146887 -282.997565) (xy 132.183139 -282.958494)
			(xy 132.22481 -282.925263) (xy 132.270968 -282.898614) (xy 132.320582 -282.879142) (xy 132.372544 -282.867282)
			(xy 132.425694 -282.863299) (xy 132.478844 -282.867282) (xy 132.530806 -282.879142) (xy 132.58042 -282.898614)
			(xy 132.626578 -282.925263) (xy 132.668249 -282.958494) (xy 132.704501 -282.997565) (xy 132.734525 -283.041602)
			(xy 132.757651 -283.089623) (xy 132.773361 -283.140553) (xy 132.781304 -283.193257) (xy 132.781802 -283.219906)
			(xy 132.781304 -283.246555) (xy 133.010138 -283.246555) (xy 133.010138 -283.193257) (xy 133.018081 -283.140553)
			(xy 133.033791 -283.089623) (xy 133.056917 -283.041602) (xy 133.086941 -282.997565) (xy 133.123193 -282.958494)
			(xy 133.164864 -282.925263) (xy 133.211022 -282.898614) (xy 133.260636 -282.879142) (xy 133.312598 -282.867282)
			(xy 133.365748 -282.863299) (xy 133.418898 -282.867282) (xy 133.47086 -282.879142) (xy 133.520474 -282.898614)
			(xy 133.566632 -282.925263) (xy 133.608303 -282.958494) (xy 133.644555 -282.997565) (xy 133.674579 -283.041602)
			(xy 133.697705 -283.089623) (xy 133.713415 -283.140553) (xy 133.721358 -283.193257) (xy 133.721856 -283.219906)
			(xy 133.721358 -283.246555) (xy 133.949938 -283.246555) (xy 133.949938 -283.193257) (xy 133.957881 -283.140553)
			(xy 133.973591 -283.089623) (xy 133.996717 -283.041602) (xy 134.026741 -282.997565) (xy 134.062993 -282.958494)
			(xy 134.104664 -282.925263) (xy 134.150822 -282.898614) (xy 134.200436 -282.879142) (xy 134.252398 -282.867282)
			(xy 134.305548 -282.863299) (xy 134.358698 -282.867282) (xy 134.41066 -282.879142) (xy 134.460274 -282.898614)
			(xy 134.506432 -282.925263) (xy 134.548103 -282.958494) (xy 134.584355 -282.997565) (xy 134.614379 -283.041602)
			(xy 134.637505 -283.089623) (xy 134.653215 -283.140553) (xy 134.661158 -283.193257) (xy 134.661656 -283.219906)
			(xy 134.661158 -283.246555) (xy 134.889484 -283.246555) (xy 134.889484 -283.193257) (xy 134.897427 -283.140553)
			(xy 134.913137 -283.089623) (xy 134.936263 -283.041602) (xy 134.966287 -282.997565) (xy 135.002539 -282.958494)
			(xy 135.04421 -282.925263) (xy 135.090368 -282.898614) (xy 135.139982 -282.879142) (xy 135.191944 -282.867282)
			(xy 135.245094 -282.863299) (xy 135.298244 -282.867282) (xy 135.350206 -282.879142) (xy 135.39982 -282.898614)
			(xy 135.445978 -282.925263) (xy 135.487649 -282.958494) (xy 135.523901 -282.997565) (xy 135.553925 -283.041602)
			(xy 135.577051 -283.089623) (xy 135.592761 -283.140553) (xy 135.600704 -283.193257) (xy 135.601202 -283.219906)
			(xy 135.600704 -283.246555) (xy 135.829284 -283.246555) (xy 135.829284 -283.193257) (xy 135.837227 -283.140553)
			(xy 135.852937 -283.089623) (xy 135.876063 -283.041602) (xy 135.906087 -282.997565) (xy 135.942339 -282.958494)
			(xy 135.98401 -282.925263) (xy 136.030168 -282.898614) (xy 136.079782 -282.879142) (xy 136.131744 -282.867282)
			(xy 136.184894 -282.863299) (xy 136.238044 -282.867282) (xy 136.290006 -282.879142) (xy 136.33962 -282.898614)
			(xy 136.385778 -282.925263) (xy 136.427449 -282.958494) (xy 136.463701 -282.997565) (xy 136.493725 -283.041602)
			(xy 136.516851 -283.089623) (xy 136.532561 -283.140553) (xy 136.540504 -283.193257) (xy 136.541002 -283.219906)
			(xy 136.540504 -283.246555) (xy 136.769338 -283.246555) (xy 136.769338 -283.193257) (xy 136.777281 -283.140553)
			(xy 136.792991 -283.089623) (xy 136.816117 -283.041602) (xy 136.846141 -282.997565) (xy 136.882393 -282.958494)
			(xy 136.924064 -282.925263) (xy 136.970222 -282.898614) (xy 137.019836 -282.879142) (xy 137.071798 -282.867282)
			(xy 137.124948 -282.863299) (xy 137.178098 -282.867282) (xy 137.23006 -282.879142) (xy 137.279674 -282.898614)
			(xy 137.325832 -282.925263) (xy 137.367503 -282.958494) (xy 137.403755 -282.997565) (xy 137.433779 -283.041602)
			(xy 137.456905 -283.089623) (xy 137.472615 -283.140553) (xy 137.480558 -283.193257) (xy 137.481056 -283.219906)
			(xy 137.480558 -283.246555) (xy 137.472615 -283.299259) (xy 137.456905 -283.350189) (xy 137.433779 -283.39821)
			(xy 137.403755 -283.442247) (xy 137.367503 -283.481318) (xy 137.325832 -283.514549) (xy 137.279674 -283.541198)
			(xy 137.23006 -283.56067) (xy 137.178098 -283.57253) (xy 137.124948 -283.576514) (xy 137.071798 -283.57253)
			(xy 137.019836 -283.56067) (xy 136.970222 -283.541198) (xy 136.924064 -283.514549) (xy 136.882393 -283.481318)
			(xy 136.846141 -283.442247) (xy 136.816117 -283.39821) (xy 136.792991 -283.350189) (xy 136.777281 -283.299259)
			(xy 136.769338 -283.246555) (xy 136.540504 -283.246555) (xy 136.532561 -283.299259) (xy 136.516851 -283.350189)
			(xy 136.493725 -283.39821) (xy 136.463701 -283.442247) (xy 136.427449 -283.481318) (xy 136.385778 -283.514549)
			(xy 136.33962 -283.541198) (xy 136.290006 -283.56067) (xy 136.238044 -283.57253) (xy 136.184894 -283.576514)
			(xy 136.131744 -283.57253) (xy 136.079782 -283.56067) (xy 136.030168 -283.541198) (xy 135.98401 -283.514549)
			(xy 135.942339 -283.481318) (xy 135.906087 -283.442247) (xy 135.876063 -283.39821) (xy 135.852937 -283.350189)
			(xy 135.837227 -283.299259) (xy 135.829284 -283.246555) (xy 135.600704 -283.246555) (xy 135.592761 -283.299259)
			(xy 135.577051 -283.350189) (xy 135.553925 -283.39821) (xy 135.523901 -283.442247) (xy 135.487649 -283.481318)
			(xy 135.445978 -283.514549) (xy 135.39982 -283.541198) (xy 135.350206 -283.56067) (xy 135.298244 -283.57253)
			(xy 135.245094 -283.576514) (xy 135.191944 -283.57253) (xy 135.139982 -283.56067) (xy 135.090368 -283.541198)
			(xy 135.04421 -283.514549) (xy 135.002539 -283.481318) (xy 134.966287 -283.442247) (xy 134.936263 -283.39821)
			(xy 134.913137 -283.350189) (xy 134.897427 -283.299259) (xy 134.889484 -283.246555) (xy 134.661158 -283.246555)
			(xy 134.653215 -283.299259) (xy 134.637505 -283.350189) (xy 134.614379 -283.39821) (xy 134.584355 -283.442247)
			(xy 134.548103 -283.481318) (xy 134.506432 -283.514549) (xy 134.460274 -283.541198) (xy 134.41066 -283.56067)
			(xy 134.358698 -283.57253) (xy 134.305548 -283.576514) (xy 134.252398 -283.57253) (xy 134.200436 -283.56067)
			(xy 134.150822 -283.541198) (xy 134.104664 -283.514549) (xy 134.062993 -283.481318) (xy 134.026741 -283.442247)
			(xy 133.996717 -283.39821) (xy 133.973591 -283.350189) (xy 133.957881 -283.299259) (xy 133.949938 -283.246555)
			(xy 133.721358 -283.246555) (xy 133.713415 -283.299259) (xy 133.697705 -283.350189) (xy 133.674579 -283.39821)
			(xy 133.644555 -283.442247) (xy 133.608303 -283.481318) (xy 133.566632 -283.514549) (xy 133.520474 -283.541198)
			(xy 133.47086 -283.56067) (xy 133.418898 -283.57253) (xy 133.365748 -283.576514) (xy 133.312598 -283.57253)
			(xy 133.260636 -283.56067) (xy 133.211022 -283.541198) (xy 133.164864 -283.514549) (xy 133.123193 -283.481318)
			(xy 133.086941 -283.442247) (xy 133.056917 -283.39821) (xy 133.033791 -283.350189) (xy 133.018081 -283.299259)
			(xy 133.010138 -283.246555) (xy 132.781304 -283.246555) (xy 132.773361 -283.299259) (xy 132.757651 -283.350189)
			(xy 132.734525 -283.39821) (xy 132.704501 -283.442247) (xy 132.668249 -283.481318) (xy 132.626578 -283.514549)
			(xy 132.58042 -283.541198) (xy 132.530806 -283.56067) (xy 132.478844 -283.57253) (xy 132.425694 -283.576514)
			(xy 132.372544 -283.57253) (xy 132.320582 -283.56067) (xy 132.270968 -283.541198) (xy 132.22481 -283.514549)
			(xy 132.183139 -283.481318) (xy 132.146887 -283.442247) (xy 132.116863 -283.39821) (xy 132.093737 -283.350189)
			(xy 132.078027 -283.299259) (xy 132.070084 -283.246555) (xy 131.841758 -283.246555) (xy 131.833815 -283.299259)
			(xy 131.818105 -283.350189) (xy 131.794979 -283.39821) (xy 131.764955 -283.442247) (xy 131.728703 -283.481318)
			(xy 131.687032 -283.514549) (xy 131.640874 -283.541198) (xy 131.59126 -283.56067) (xy 131.539298 -283.57253)
			(xy 131.486148 -283.576514) (xy 131.432998 -283.57253) (xy 131.381036 -283.56067) (xy 131.331422 -283.541198)
			(xy 131.285264 -283.514549) (xy 131.243593 -283.481318) (xy 131.207341 -283.442247) (xy 131.177317 -283.39821)
			(xy 131.154191 -283.350189) (xy 131.138481 -283.299259) (xy 131.130538 -283.246555) (xy 130.901704 -283.246555)
			(xy 130.893761 -283.299259) (xy 130.878051 -283.350189) (xy 130.854925 -283.39821) (xy 130.824901 -283.442247)
			(xy 130.788649 -283.481318) (xy 130.746978 -283.514549) (xy 130.70082 -283.541198) (xy 130.651206 -283.56067)
			(xy 130.599244 -283.57253) (xy 130.546094 -283.576514) (xy 130.492944 -283.57253) (xy 130.440982 -283.56067)
			(xy 130.391368 -283.541198) (xy 130.34521 -283.514549) (xy 130.303539 -283.481318) (xy 130.267287 -283.442247)
			(xy 130.237263 -283.39821) (xy 130.214137 -283.350189) (xy 130.198427 -283.299259) (xy 130.190484 -283.246555)
			(xy 129.961904 -283.246555) (xy 129.953961 -283.299259) (xy 129.938251 -283.350189) (xy 129.915125 -283.39821)
			(xy 129.885101 -283.442247) (xy 129.848849 -283.481318) (xy 129.807178 -283.514549) (xy 129.76102 -283.541198)
			(xy 129.711406 -283.56067) (xy 129.659444 -283.57253) (xy 129.606294 -283.576514) (xy 129.553144 -283.57253)
			(xy 129.501182 -283.56067) (xy 129.451568 -283.541198) (xy 129.40541 -283.514549) (xy 129.363739 -283.481318)
			(xy 129.327487 -283.442247) (xy 129.297463 -283.39821) (xy 129.274337 -283.350189) (xy 129.258627 -283.299259)
			(xy 129.250684 -283.246555) (xy 129.022066 -283.246555) (xy 129.014161 -283.299005) (xy 128.998451 -283.349935)
			(xy 128.975325 -283.397956) (xy 128.945301 -283.441993) (xy 128.909049 -283.481064) (xy 128.867378 -283.514295)
			(xy 128.82122 -283.540944) (xy 128.771606 -283.560416) (xy 128.719644 -283.572276) (xy 128.666494 -283.57626)
			(xy 128.613344 -283.572276) (xy 128.561382 -283.560416) (xy 128.511768 -283.540944) (xy 128.46561 -283.514295)
			(xy 128.423939 -283.481064) (xy 128.387687 -283.441993) (xy 128.357663 -283.397956) (xy 128.334537 -283.349935)
			(xy 128.318827 -283.299005) (xy 128.310884 -283.246301) (xy 127.142509 -283.246301) (xy 127.142504 -283.246555)
			(xy 127.134561 -283.299259) (xy 127.118851 -283.350189) (xy 127.095725 -283.39821) (xy 127.065701 -283.442247)
			(xy 127.029449 -283.481318) (xy 126.987778 -283.514549) (xy 126.94162 -283.541198) (xy 126.892006 -283.56067)
			(xy 126.840044 -283.57253) (xy 126.786894 -283.576514) (xy 126.733744 -283.57253) (xy 126.681782 -283.56067)
			(xy 126.632168 -283.541198) (xy 126.58601 -283.514549) (xy 126.544339 -283.481318) (xy 126.508087 -283.442247)
			(xy 126.478063 -283.39821) (xy 126.454937 -283.350189) (xy 126.439227 -283.299259) (xy 126.431284 -283.246555)
			(xy 126.202958 -283.246555) (xy 126.195015 -283.299259) (xy 126.179305 -283.350189) (xy 126.156179 -283.39821)
			(xy 126.126155 -283.442247) (xy 126.089903 -283.481318) (xy 126.048232 -283.514549) (xy 126.002074 -283.541198)
			(xy 125.95246 -283.56067) (xy 125.900498 -283.57253) (xy 125.847348 -283.576514) (xy 125.794198 -283.57253)
			(xy 125.742236 -283.56067) (xy 125.692622 -283.541198) (xy 125.646464 -283.514549) (xy 125.604793 -283.481318)
			(xy 125.568541 -283.442247) (xy 125.538517 -283.39821) (xy 125.515391 -283.350189) (xy 125.499681 -283.299259)
			(xy 125.491738 -283.246555) (xy 125.263158 -283.246555) (xy 125.255215 -283.299259) (xy 125.239505 -283.350189)
			(xy 125.216379 -283.39821) (xy 125.186355 -283.442247) (xy 125.150103 -283.481318) (xy 125.108432 -283.514549)
			(xy 125.062274 -283.541198) (xy 125.01266 -283.56067) (xy 124.960698 -283.57253) (xy 124.907548 -283.576514)
			(xy 124.854398 -283.57253) (xy 124.802436 -283.56067) (xy 124.752822 -283.541198) (xy 124.706664 -283.514549)
			(xy 124.664993 -283.481318) (xy 124.628741 -283.442247) (xy 124.598717 -283.39821) (xy 124.575591 -283.350189)
			(xy 124.559881 -283.299259) (xy 124.551938 -283.246555) (xy 123.383558 -283.246555) (xy 123.375615 -283.299259)
			(xy 123.359905 -283.350189) (xy 123.336779 -283.39821) (xy 123.306755 -283.442247) (xy 123.270503 -283.481318)
			(xy 123.228832 -283.514549) (xy 123.182674 -283.541198) (xy 123.13306 -283.56067) (xy 123.081098 -283.57253)
			(xy 123.027948 -283.576514) (xy 122.974798 -283.57253) (xy 122.922836 -283.56067) (xy 122.873222 -283.541198)
			(xy 122.827064 -283.514549) (xy 122.785393 -283.481318) (xy 122.749141 -283.442247) (xy 122.719117 -283.39821)
			(xy 122.695991 -283.350189) (xy 122.680281 -283.299259) (xy 122.672338 -283.246555) (xy 122.443504 -283.246555)
			(xy 122.435561 -283.299259) (xy 122.419851 -283.350189) (xy 122.396725 -283.39821) (xy 122.366701 -283.442247)
			(xy 122.330449 -283.481318) (xy 122.288778 -283.514549) (xy 122.24262 -283.541198) (xy 122.193006 -283.56067)
			(xy 122.141044 -283.57253) (xy 122.087894 -283.576514) (xy 122.034744 -283.57253) (xy 121.982782 -283.56067)
			(xy 121.933168 -283.541198) (xy 121.88701 -283.514549) (xy 121.845339 -283.481318) (xy 121.809087 -283.442247)
			(xy 121.779063 -283.39821) (xy 121.755937 -283.350189) (xy 121.740227 -283.299259) (xy 121.732284 -283.246555)
			(xy 121.503704 -283.246555) (xy 121.495761 -283.299259) (xy 121.480051 -283.350189) (xy 121.456925 -283.39821)
			(xy 121.426901 -283.442247) (xy 121.390649 -283.481318) (xy 121.348978 -283.514549) (xy 121.30282 -283.541198)
			(xy 121.253206 -283.56067) (xy 121.201244 -283.57253) (xy 121.148094 -283.576514) (xy 121.094944 -283.57253)
			(xy 121.042982 -283.56067) (xy 120.993368 -283.541198) (xy 120.94721 -283.514549) (xy 120.905539 -283.481318)
			(xy 120.869287 -283.442247) (xy 120.839263 -283.39821) (xy 120.816137 -283.350189) (xy 120.800427 -283.299259)
			(xy 120.792484 -283.246555) (xy 120.564158 -283.246555) (xy 120.556215 -283.299259) (xy 120.540505 -283.350189)
			(xy 120.517379 -283.39821) (xy 120.487355 -283.442247) (xy 120.451103 -283.481318) (xy 120.409432 -283.514549)
			(xy 120.363274 -283.541198) (xy 120.31366 -283.56067) (xy 120.261698 -283.57253) (xy 120.208548 -283.576514)
			(xy 120.155398 -283.57253) (xy 120.103436 -283.56067) (xy 120.053822 -283.541198) (xy 120.007664 -283.514549)
			(xy 119.965993 -283.481318) (xy 119.929741 -283.442247) (xy 119.899717 -283.39821) (xy 119.876591 -283.350189)
			(xy 119.860881 -283.299259) (xy 119.852938 -283.246555) (xy 119.624105 -283.246555) (xy 119.624098 -283.246953)
			(xy 119.615913 -283.300426) (xy 119.599733 -283.352044) (xy 119.575929 -283.40062) (xy 119.54505 -283.445036)
			(xy 119.526812 -283.465016) (xy 119.492776 -283.501084) (xy 119.674386 -283.682694) (xy 119.698516 -283.6799)
			(xy 119.708451 -283.678833) (xy 119.728402 -283.67769) (xy 119.738394 -283.677614) (xy 119.766379 -283.678134)
			(xy 119.82166 -283.686889) (xy 119.874891 -283.704185) (xy 119.92476 -283.729595) (xy 119.97004 -283.762494)
			(xy 120.009616 -283.802072) (xy 120.042513 -283.847353) (xy 120.067921 -283.897224) (xy 120.085214 -283.950456)
			(xy 120.093967 -284.005737) (xy 120.094502 -284.033722) (xy 120.094064 -284.058917) (xy 120.093857 -284.060371)
			(xy 120.322584 -284.060371) (xy 120.322584 -284.007073) (xy 120.330527 -283.954369) (xy 120.346237 -283.903439)
			(xy 120.369363 -283.855418) (xy 120.399387 -283.811381) (xy 120.435639 -283.77231) (xy 120.47731 -283.739079)
			(xy 120.523468 -283.71243) (xy 120.573082 -283.692958) (xy 120.625044 -283.681098) (xy 120.678194 -283.677115)
			(xy 120.731344 -283.681098) (xy 120.783306 -283.692958) (xy 120.83292 -283.71243) (xy 120.879078 -283.739079)
			(xy 120.920749 -283.77231) (xy 120.957001 -283.811381) (xy 120.987025 -283.855418) (xy 121.010151 -283.903439)
			(xy 121.025861 -283.954369) (xy 121.033804 -284.007073) (xy 121.034302 -284.033722) (xy 121.033804 -284.060371)
			(xy 121.262384 -284.060371) (xy 121.262384 -284.007073) (xy 121.270327 -283.954369) (xy 121.286037 -283.903439)
			(xy 121.309163 -283.855418) (xy 121.339187 -283.811381) (xy 121.375439 -283.77231) (xy 121.41711 -283.739079)
			(xy 121.463268 -283.71243) (xy 121.512882 -283.692958) (xy 121.564844 -283.681098) (xy 121.617994 -283.677115)
			(xy 121.671144 -283.681098) (xy 121.723106 -283.692958) (xy 121.77272 -283.71243) (xy 121.818878 -283.739079)
			(xy 121.860549 -283.77231) (xy 121.896801 -283.811381) (xy 121.926825 -283.855418) (xy 121.949951 -283.903439)
			(xy 121.965661 -283.954369) (xy 121.973604 -284.007073) (xy 121.974102 -284.033722) (xy 121.973604 -284.060371)
			(xy 122.202184 -284.060371) (xy 122.202184 -284.007073) (xy 122.210127 -283.954369) (xy 122.225837 -283.903439)
			(xy 122.248963 -283.855418) (xy 122.278987 -283.811381) (xy 122.315239 -283.77231) (xy 122.35691 -283.739079)
			(xy 122.403068 -283.71243) (xy 122.452682 -283.692958) (xy 122.504644 -283.681098) (xy 122.557794 -283.677115)
			(xy 122.610944 -283.681098) (xy 122.662906 -283.692958) (xy 122.71252 -283.71243) (xy 122.758678 -283.739079)
			(xy 122.800349 -283.77231) (xy 122.836601 -283.811381) (xy 122.866625 -283.855418) (xy 122.889751 -283.903439)
			(xy 122.905461 -283.954369) (xy 122.913404 -284.007073) (xy 122.913902 -284.033722) (xy 122.913404 -284.060371)
			(xy 123.141984 -284.060371) (xy 123.141984 -284.007073) (xy 123.149927 -283.954369) (xy 123.165637 -283.903439)
			(xy 123.188763 -283.855418) (xy 123.218787 -283.811381) (xy 123.255039 -283.77231) (xy 123.29671 -283.739079)
			(xy 123.342868 -283.71243) (xy 123.392482 -283.692958) (xy 123.444444 -283.681098) (xy 123.497594 -283.677115)
			(xy 123.550744 -283.681098) (xy 123.602706 -283.692958) (xy 123.65232 -283.71243) (xy 123.698478 -283.739079)
			(xy 123.740149 -283.77231) (xy 123.776401 -283.811381) (xy 123.806425 -283.855418) (xy 123.829551 -283.903439)
			(xy 123.845261 -283.954369) (xy 123.853204 -284.007073) (xy 123.853702 -284.033722) (xy 123.853204 -284.060371)
			(xy 124.081784 -284.060371) (xy 124.081784 -284.007073) (xy 124.089727 -283.954369) (xy 124.105437 -283.903439)
			(xy 124.128563 -283.855418) (xy 124.158587 -283.811381) (xy 124.194839 -283.77231) (xy 124.23651 -283.739079)
			(xy 124.282668 -283.71243) (xy 124.332282 -283.692958) (xy 124.384244 -283.681098) (xy 124.437394 -283.677115)
			(xy 124.490544 -283.681098) (xy 124.542506 -283.692958) (xy 124.59212 -283.71243) (xy 124.638278 -283.739079)
			(xy 124.679949 -283.77231) (xy 124.716201 -283.811381) (xy 124.746225 -283.855418) (xy 124.769351 -283.903439)
			(xy 124.785061 -283.954369) (xy 124.793004 -284.007073) (xy 124.793502 -284.033722) (xy 124.793004 -284.060371)
			(xy 125.021838 -284.060371) (xy 125.021838 -284.007073) (xy 125.029781 -283.954369) (xy 125.045491 -283.903439)
			(xy 125.068617 -283.855418) (xy 125.098641 -283.811381) (xy 125.134893 -283.77231) (xy 125.176564 -283.739079)
			(xy 125.222722 -283.71243) (xy 125.272336 -283.692958) (xy 125.324298 -283.681098) (xy 125.377448 -283.677115)
			(xy 125.430598 -283.681098) (xy 125.48256 -283.692958) (xy 125.532174 -283.71243) (xy 125.578332 -283.739079)
			(xy 125.620003 -283.77231) (xy 125.656255 -283.811381) (xy 125.686279 -283.855418) (xy 125.709405 -283.903439)
			(xy 125.725115 -283.954369) (xy 125.733058 -284.007073) (xy 125.733556 -284.033722) (xy 125.733058 -284.060371)
			(xy 125.961384 -284.060371) (xy 125.961384 -284.007073) (xy 125.969327 -283.954369) (xy 125.985037 -283.903439)
			(xy 126.008163 -283.855418) (xy 126.038187 -283.811381) (xy 126.074439 -283.77231) (xy 126.11611 -283.739079)
			(xy 126.162268 -283.71243) (xy 126.211882 -283.692958) (xy 126.263844 -283.681098) (xy 126.316994 -283.677115)
			(xy 126.370144 -283.681098) (xy 126.422106 -283.692958) (xy 126.47172 -283.71243) (xy 126.517878 -283.739079)
			(xy 126.559549 -283.77231) (xy 126.595801 -283.811381) (xy 126.625825 -283.855418) (xy 126.648951 -283.903439)
			(xy 126.664661 -283.954369) (xy 126.672604 -284.007073) (xy 126.673102 -284.033722) (xy 126.672604 -284.060371)
			(xy 126.901184 -284.060371) (xy 126.901184 -284.007073) (xy 126.909127 -283.954369) (xy 126.924837 -283.903439)
			(xy 126.947963 -283.855418) (xy 126.977987 -283.811381) (xy 127.014239 -283.77231) (xy 127.05591 -283.739079)
			(xy 127.102068 -283.71243) (xy 127.151682 -283.692958) (xy 127.203644 -283.681098) (xy 127.256794 -283.677115)
			(xy 127.309944 -283.681098) (xy 127.361906 -283.692958) (xy 127.41152 -283.71243) (xy 127.457678 -283.739079)
			(xy 127.499349 -283.77231) (xy 127.535601 -283.811381) (xy 127.565625 -283.855418) (xy 127.588751 -283.903439)
			(xy 127.604461 -283.954369) (xy 127.612404 -284.007073) (xy 127.612902 -284.033722) (xy 127.612404 -284.060371)
			(xy 127.840984 -284.060371) (xy 127.840984 -284.007073) (xy 127.848927 -283.954369) (xy 127.864637 -283.903439)
			(xy 127.887763 -283.855418) (xy 127.917787 -283.811381) (xy 127.954039 -283.77231) (xy 127.99571 -283.739079)
			(xy 128.041868 -283.71243) (xy 128.091482 -283.692958) (xy 128.143444 -283.681098) (xy 128.196594 -283.677115)
			(xy 128.249744 -283.681098) (xy 128.301706 -283.692958) (xy 128.35132 -283.71243) (xy 128.397478 -283.739079)
			(xy 128.439149 -283.77231) (xy 128.475401 -283.811381) (xy 128.505425 -283.855418) (xy 128.528551 -283.903439)
			(xy 128.544261 -283.954369) (xy 128.552204 -284.007073) (xy 128.552702 -284.033722) (xy 128.552204 -284.060371)
			(xy 128.780784 -284.060371) (xy 128.780784 -284.007073) (xy 128.788727 -283.954369) (xy 128.804437 -283.903439)
			(xy 128.827563 -283.855418) (xy 128.857587 -283.811381) (xy 128.893839 -283.77231) (xy 128.93551 -283.739079)
			(xy 128.981668 -283.71243) (xy 129.031282 -283.692958) (xy 129.083244 -283.681098) (xy 129.136394 -283.677115)
			(xy 129.189544 -283.681098) (xy 129.241506 -283.692958) (xy 129.29112 -283.71243) (xy 129.337278 -283.739079)
			(xy 129.378949 -283.77231) (xy 129.415201 -283.811381) (xy 129.445225 -283.855418) (xy 129.468351 -283.903439)
			(xy 129.484061 -283.954369) (xy 129.492004 -284.007073) (xy 129.492502 -284.033722) (xy 129.492004 -284.060371)
			(xy 129.720584 -284.060371) (xy 129.720584 -284.007073) (xy 129.728527 -283.954369) (xy 129.744237 -283.903439)
			(xy 129.767363 -283.855418) (xy 129.797387 -283.811381) (xy 129.833639 -283.77231) (xy 129.87531 -283.739079)
			(xy 129.921468 -283.71243) (xy 129.971082 -283.692958) (xy 130.023044 -283.681098) (xy 130.076194 -283.677115)
			(xy 130.129344 -283.681098) (xy 130.181306 -283.692958) (xy 130.23092 -283.71243) (xy 130.277078 -283.739079)
			(xy 130.318749 -283.77231) (xy 130.355001 -283.811381) (xy 130.385025 -283.855418) (xy 130.408151 -283.903439)
			(xy 130.423861 -283.954369) (xy 130.431804 -284.007073) (xy 130.432302 -284.033722) (xy 130.431804 -284.060371)
			(xy 130.660384 -284.060371) (xy 130.660384 -284.007073) (xy 130.668327 -283.954369) (xy 130.684037 -283.903439)
			(xy 130.707163 -283.855418) (xy 130.737187 -283.811381) (xy 130.773439 -283.77231) (xy 130.81511 -283.739079)
			(xy 130.861268 -283.71243) (xy 130.910882 -283.692958) (xy 130.962844 -283.681098) (xy 131.015994 -283.677115)
			(xy 131.069144 -283.681098) (xy 131.121106 -283.692958) (xy 131.17072 -283.71243) (xy 131.216878 -283.739079)
			(xy 131.258549 -283.77231) (xy 131.294801 -283.811381) (xy 131.324825 -283.855418) (xy 131.347951 -283.903439)
			(xy 131.363661 -283.954369) (xy 131.371604 -284.007073) (xy 131.372102 -284.033722) (xy 131.371604 -284.060371)
			(xy 131.600184 -284.060371) (xy 131.600184 -284.007073) (xy 131.608127 -283.954369) (xy 131.623837 -283.903439)
			(xy 131.646963 -283.855418) (xy 131.676987 -283.811381) (xy 131.713239 -283.77231) (xy 131.75491 -283.739079)
			(xy 131.801068 -283.71243) (xy 131.850682 -283.692958) (xy 131.902644 -283.681098) (xy 131.955794 -283.677115)
			(xy 132.008944 -283.681098) (xy 132.060906 -283.692958) (xy 132.11052 -283.71243) (xy 132.156678 -283.739079)
			(xy 132.198349 -283.77231) (xy 132.234601 -283.811381) (xy 132.264625 -283.855418) (xy 132.287751 -283.903439)
			(xy 132.303461 -283.954369) (xy 132.311404 -284.007073) (xy 132.311902 -284.033722) (xy 132.311404 -284.060371)
			(xy 132.539984 -284.060371) (xy 132.539984 -284.007073) (xy 132.547927 -283.954369) (xy 132.563637 -283.903439)
			(xy 132.586763 -283.855418) (xy 132.616787 -283.811381) (xy 132.653039 -283.77231) (xy 132.69471 -283.739079)
			(xy 132.740868 -283.71243) (xy 132.790482 -283.692958) (xy 132.842444 -283.681098) (xy 132.895594 -283.677115)
			(xy 132.948744 -283.681098) (xy 133.000706 -283.692958) (xy 133.05032 -283.71243) (xy 133.096478 -283.739079)
			(xy 133.138149 -283.77231) (xy 133.174401 -283.811381) (xy 133.204425 -283.855418) (xy 133.227551 -283.903439)
			(xy 133.243261 -283.954369) (xy 133.251204 -284.007073) (xy 133.251702 -284.033722) (xy 133.251204 -284.060371)
			(xy 134.419584 -284.060371) (xy 134.419584 -284.007073) (xy 134.427527 -283.954369) (xy 134.443237 -283.903439)
			(xy 134.466363 -283.855418) (xy 134.496387 -283.811381) (xy 134.532639 -283.77231) (xy 134.57431 -283.739079)
			(xy 134.620468 -283.71243) (xy 134.670082 -283.692958) (xy 134.722044 -283.681098) (xy 134.775194 -283.677115)
			(xy 134.828344 -283.681098) (xy 134.880306 -283.692958) (xy 134.92992 -283.71243) (xy 134.976078 -283.739079)
			(xy 135.017749 -283.77231) (xy 135.054001 -283.811381) (xy 135.084025 -283.855418) (xy 135.107151 -283.903439)
			(xy 135.122861 -283.954369) (xy 135.130804 -284.007073) (xy 135.131302 -284.033722) (xy 135.130809 -284.060117)
			(xy 136.29893 -284.060117) (xy 136.29893 -284.006819) (xy 136.306873 -283.954115) (xy 136.322583 -283.903185)
			(xy 136.345709 -283.855164) (xy 136.375733 -283.811127) (xy 136.411985 -283.772056) (xy 136.453656 -283.738825)
			(xy 136.499814 -283.712176) (xy 136.549428 -283.692704) (xy 136.60139 -283.680844) (xy 136.65454 -283.676861)
			(xy 136.70769 -283.680844) (xy 136.759652 -283.692704) (xy 136.809266 -283.712176) (xy 136.855424 -283.738825)
			(xy 136.897095 -283.772056) (xy 136.933347 -283.811127) (xy 136.963371 -283.855164) (xy 136.986497 -283.903185)
			(xy 137.002207 -283.954115) (xy 137.01015 -284.006819) (xy 137.010648 -284.033468) (xy 137.01015 -284.060117)
			(xy 137.002207 -284.112821) (xy 136.986497 -284.163751) (xy 136.963371 -284.211772) (xy 136.933347 -284.255809)
			(xy 136.897095 -284.29488) (xy 136.855424 -284.328111) (xy 136.809266 -284.35476) (xy 136.759652 -284.374232)
			(xy 136.70769 -284.386092) (xy 136.65454 -284.390076) (xy 136.60139 -284.386092) (xy 136.549428 -284.374232)
			(xy 136.499814 -284.35476) (xy 136.453656 -284.328111) (xy 136.411985 -284.29488) (xy 136.375733 -284.255809)
			(xy 136.345709 -284.211772) (xy 136.322583 -284.163751) (xy 136.306873 -284.112821) (xy 136.29893 -284.060117)
			(xy 135.130809 -284.060117) (xy 135.130804 -284.060371) (xy 135.122861 -284.113075) (xy 135.107151 -284.164005)
			(xy 135.084025 -284.212026) (xy 135.054001 -284.256063) (xy 135.017749 -284.295134) (xy 134.976078 -284.328365)
			(xy 134.92992 -284.355014) (xy 134.880306 -284.374486) (xy 134.828344 -284.386346) (xy 134.775194 -284.39033)
			(xy 134.722044 -284.386346) (xy 134.670082 -284.374486) (xy 134.620468 -284.355014) (xy 134.57431 -284.328365)
			(xy 134.532639 -284.295134) (xy 134.496387 -284.256063) (xy 134.466363 -284.212026) (xy 134.443237 -284.164005)
			(xy 134.427527 -284.113075) (xy 134.419584 -284.060371) (xy 133.251204 -284.060371) (xy 133.243261 -284.113075)
			(xy 133.227551 -284.164005) (xy 133.204425 -284.212026) (xy 133.174401 -284.256063) (xy 133.138149 -284.295134)
			(xy 133.096478 -284.328365) (xy 133.05032 -284.355014) (xy 133.000706 -284.374486) (xy 132.948744 -284.386346)
			(xy 132.895594 -284.39033) (xy 132.842444 -284.386346) (xy 132.790482 -284.374486) (xy 132.740868 -284.355014)
			(xy 132.69471 -284.328365) (xy 132.653039 -284.295134) (xy 132.616787 -284.256063) (xy 132.586763 -284.212026)
			(xy 132.563637 -284.164005) (xy 132.547927 -284.113075) (xy 132.539984 -284.060371) (xy 132.311404 -284.060371)
			(xy 132.303461 -284.113075) (xy 132.287751 -284.164005) (xy 132.264625 -284.212026) (xy 132.234601 -284.256063)
			(xy 132.198349 -284.295134) (xy 132.156678 -284.328365) (xy 132.11052 -284.355014) (xy 132.060906 -284.374486)
			(xy 132.008944 -284.386346) (xy 131.955794 -284.39033) (xy 131.902644 -284.386346) (xy 131.850682 -284.374486)
			(xy 131.801068 -284.355014) (xy 131.75491 -284.328365) (xy 131.713239 -284.295134) (xy 131.676987 -284.256063)
			(xy 131.646963 -284.212026) (xy 131.623837 -284.164005) (xy 131.608127 -284.113075) (xy 131.600184 -284.060371)
			(xy 131.371604 -284.060371) (xy 131.363661 -284.113075) (xy 131.347951 -284.164005) (xy 131.324825 -284.212026)
			(xy 131.294801 -284.256063) (xy 131.258549 -284.295134) (xy 131.216878 -284.328365) (xy 131.17072 -284.355014)
			(xy 131.121106 -284.374486) (xy 131.069144 -284.386346) (xy 131.015994 -284.39033) (xy 130.962844 -284.386346)
			(xy 130.910882 -284.374486) (xy 130.861268 -284.355014) (xy 130.81511 -284.328365) (xy 130.773439 -284.295134)
			(xy 130.737187 -284.256063) (xy 130.707163 -284.212026) (xy 130.684037 -284.164005) (xy 130.668327 -284.113075)
			(xy 130.660384 -284.060371) (xy 130.431804 -284.060371) (xy 130.423861 -284.113075) (xy 130.408151 -284.164005)
			(xy 130.385025 -284.212026) (xy 130.355001 -284.256063) (xy 130.318749 -284.295134) (xy 130.277078 -284.328365)
			(xy 130.23092 -284.355014) (xy 130.181306 -284.374486) (xy 130.129344 -284.386346) (xy 130.076194 -284.39033)
			(xy 130.023044 -284.386346) (xy 129.971082 -284.374486) (xy 129.921468 -284.355014) (xy 129.87531 -284.328365)
			(xy 129.833639 -284.295134) (xy 129.797387 -284.256063) (xy 129.767363 -284.212026) (xy 129.744237 -284.164005)
			(xy 129.728527 -284.113075) (xy 129.720584 -284.060371) (xy 129.492004 -284.060371) (xy 129.484061 -284.113075)
			(xy 129.468351 -284.164005) (xy 129.445225 -284.212026) (xy 129.415201 -284.256063) (xy 129.378949 -284.295134)
			(xy 129.337278 -284.328365) (xy 129.29112 -284.355014) (xy 129.241506 -284.374486) (xy 129.189544 -284.386346)
			(xy 129.136394 -284.39033) (xy 129.083244 -284.386346) (xy 129.031282 -284.374486) (xy 128.981668 -284.355014)
			(xy 128.93551 -284.328365) (xy 128.893839 -284.295134) (xy 128.857587 -284.256063) (xy 128.827563 -284.212026)
			(xy 128.804437 -284.164005) (xy 128.788727 -284.113075) (xy 128.780784 -284.060371) (xy 128.552204 -284.060371)
			(xy 128.544261 -284.113075) (xy 128.528551 -284.164005) (xy 128.505425 -284.212026) (xy 128.475401 -284.256063)
			(xy 128.439149 -284.295134) (xy 128.397478 -284.328365) (xy 128.35132 -284.355014) (xy 128.301706 -284.374486)
			(xy 128.249744 -284.386346) (xy 128.196594 -284.39033) (xy 128.143444 -284.386346) (xy 128.091482 -284.374486)
			(xy 128.041868 -284.355014) (xy 127.99571 -284.328365) (xy 127.954039 -284.295134) (xy 127.917787 -284.256063)
			(xy 127.887763 -284.212026) (xy 127.864637 -284.164005) (xy 127.848927 -284.113075) (xy 127.840984 -284.060371)
			(xy 127.612404 -284.060371) (xy 127.604461 -284.113075) (xy 127.588751 -284.164005) (xy 127.565625 -284.212026)
			(xy 127.535601 -284.256063) (xy 127.499349 -284.295134) (xy 127.457678 -284.328365) (xy 127.41152 -284.355014)
			(xy 127.361906 -284.374486) (xy 127.309944 -284.386346) (xy 127.256794 -284.39033) (xy 127.203644 -284.386346)
			(xy 127.151682 -284.374486) (xy 127.102068 -284.355014) (xy 127.05591 -284.328365) (xy 127.014239 -284.295134)
			(xy 126.977987 -284.256063) (xy 126.947963 -284.212026) (xy 126.924837 -284.164005) (xy 126.909127 -284.113075)
			(xy 126.901184 -284.060371) (xy 126.672604 -284.060371) (xy 126.664661 -284.113075) (xy 126.648951 -284.164005)
			(xy 126.625825 -284.212026) (xy 126.595801 -284.256063) (xy 126.559549 -284.295134) (xy 126.517878 -284.328365)
			(xy 126.47172 -284.355014) (xy 126.422106 -284.374486) (xy 126.370144 -284.386346) (xy 126.316994 -284.39033)
			(xy 126.263844 -284.386346) (xy 126.211882 -284.374486) (xy 126.162268 -284.355014) (xy 126.11611 -284.328365)
			(xy 126.074439 -284.295134) (xy 126.038187 -284.256063) (xy 126.008163 -284.212026) (xy 125.985037 -284.164005)
			(xy 125.969327 -284.113075) (xy 125.961384 -284.060371) (xy 125.733058 -284.060371) (xy 125.725115 -284.113075)
			(xy 125.709405 -284.164005) (xy 125.686279 -284.212026) (xy 125.656255 -284.256063) (xy 125.620003 -284.295134)
			(xy 125.578332 -284.328365) (xy 125.532174 -284.355014) (xy 125.48256 -284.374486) (xy 125.430598 -284.386346)
			(xy 125.377448 -284.39033) (xy 125.324298 -284.386346) (xy 125.272336 -284.374486) (xy 125.222722 -284.355014)
			(xy 125.176564 -284.328365) (xy 125.134893 -284.295134) (xy 125.098641 -284.256063) (xy 125.068617 -284.212026)
			(xy 125.045491 -284.164005) (xy 125.029781 -284.113075) (xy 125.021838 -284.060371) (xy 124.793004 -284.060371)
			(xy 124.785061 -284.113075) (xy 124.769351 -284.164005) (xy 124.746225 -284.212026) (xy 124.716201 -284.256063)
			(xy 124.679949 -284.295134) (xy 124.638278 -284.328365) (xy 124.59212 -284.355014) (xy 124.542506 -284.374486)
			(xy 124.490544 -284.386346) (xy 124.437394 -284.39033) (xy 124.384244 -284.386346) (xy 124.332282 -284.374486)
			(xy 124.282668 -284.355014) (xy 124.23651 -284.328365) (xy 124.194839 -284.295134) (xy 124.158587 -284.256063)
			(xy 124.128563 -284.212026) (xy 124.105437 -284.164005) (xy 124.089727 -284.113075) (xy 124.081784 -284.060371)
			(xy 123.853204 -284.060371) (xy 123.845261 -284.113075) (xy 123.829551 -284.164005) (xy 123.806425 -284.212026)
			(xy 123.776401 -284.256063) (xy 123.740149 -284.295134) (xy 123.698478 -284.328365) (xy 123.65232 -284.355014)
			(xy 123.602706 -284.374486) (xy 123.550744 -284.386346) (xy 123.497594 -284.39033) (xy 123.444444 -284.386346)
			(xy 123.392482 -284.374486) (xy 123.342868 -284.355014) (xy 123.29671 -284.328365) (xy 123.255039 -284.295134)
			(xy 123.218787 -284.256063) (xy 123.188763 -284.212026) (xy 123.165637 -284.164005) (xy 123.149927 -284.113075)
			(xy 123.141984 -284.060371) (xy 122.913404 -284.060371) (xy 122.905461 -284.113075) (xy 122.889751 -284.164005)
			(xy 122.866625 -284.212026) (xy 122.836601 -284.256063) (xy 122.800349 -284.295134) (xy 122.758678 -284.328365)
			(xy 122.71252 -284.355014) (xy 122.662906 -284.374486) (xy 122.610944 -284.386346) (xy 122.557794 -284.39033)
			(xy 122.504644 -284.386346) (xy 122.452682 -284.374486) (xy 122.403068 -284.355014) (xy 122.35691 -284.328365)
			(xy 122.315239 -284.295134) (xy 122.278987 -284.256063) (xy 122.248963 -284.212026) (xy 122.225837 -284.164005)
			(xy 122.210127 -284.113075) (xy 122.202184 -284.060371) (xy 121.973604 -284.060371) (xy 121.965661 -284.113075)
			(xy 121.949951 -284.164005) (xy 121.926825 -284.212026) (xy 121.896801 -284.256063) (xy 121.860549 -284.295134)
			(xy 121.818878 -284.328365) (xy 121.77272 -284.355014) (xy 121.723106 -284.374486) (xy 121.671144 -284.386346)
			(xy 121.617994 -284.39033) (xy 121.564844 -284.386346) (xy 121.512882 -284.374486) (xy 121.463268 -284.355014)
			(xy 121.41711 -284.328365) (xy 121.375439 -284.295134) (xy 121.339187 -284.256063) (xy 121.309163 -284.212026)
			(xy 121.286037 -284.164005) (xy 121.270327 -284.113075) (xy 121.262384 -284.060371) (xy 121.033804 -284.060371)
			(xy 121.025861 -284.113075) (xy 121.010151 -284.164005) (xy 120.987025 -284.212026) (xy 120.957001 -284.256063)
			(xy 120.920749 -284.295134) (xy 120.879078 -284.328365) (xy 120.83292 -284.355014) (xy 120.783306 -284.374486)
			(xy 120.731344 -284.386346) (xy 120.678194 -284.39033) (xy 120.625044 -284.386346) (xy 120.573082 -284.374486)
			(xy 120.523468 -284.355014) (xy 120.47731 -284.328365) (xy 120.435639 -284.295134) (xy 120.399387 -284.256063)
			(xy 120.369363 -284.212026) (xy 120.346237 -284.164005) (xy 120.330527 -284.113075) (xy 120.322584 -284.060371)
			(xy 120.093857 -284.060371) (xy 120.086957 -284.108804) (xy 120.072889 -284.157191) (xy 120.05214 -284.203111)
			(xy 120.025125 -284.245648) (xy 119.992383 -284.283951) (xy 119.954568 -284.317257) (xy 119.93372 -284.33141)
			(xy 119.93372 -284.847538) (xy 120.79224 -284.847538) (xy 120.792738 -284.820889) (xy 120.800681 -284.768185)
			(xy 120.816391 -284.717255) (xy 120.839517 -284.669234) (xy 120.869541 -284.625197) (xy 120.905793 -284.586126)
			(xy 120.947464 -284.552895) (xy 120.993622 -284.526246) (xy 121.043236 -284.506774) (xy 121.095198 -284.494914)
			(xy 121.148348 -284.490931) (xy 121.201498 -284.494914) (xy 121.25346 -284.506774) (xy 121.303074 -284.526246)
			(xy 121.349232 -284.552895) (xy 121.390903 -284.586126) (xy 121.427155 -284.625197) (xy 121.457179 -284.669234)
			(xy 121.480305 -284.717255) (xy 121.496015 -284.768185) (xy 121.503958 -284.820889) (xy 121.504456 -284.847538)
			(xy 122.67184 -284.847538) (xy 122.672338 -284.820889) (xy 122.680281 -284.768185) (xy 122.695991 -284.717255)
			(xy 122.719117 -284.669234) (xy 122.749141 -284.625197) (xy 122.785393 -284.586126) (xy 122.827064 -284.552895)
			(xy 122.873222 -284.526246) (xy 122.922836 -284.506774) (xy 122.974798 -284.494914) (xy 123.027948 -284.490931)
			(xy 123.081098 -284.494914) (xy 123.13306 -284.506774) (xy 123.182674 -284.526246) (xy 123.228832 -284.552895)
			(xy 123.270503 -284.586126) (xy 123.306755 -284.625197) (xy 123.336779 -284.669234) (xy 123.359905 -284.717255)
			(xy 123.375615 -284.768185) (xy 123.383558 -284.820889) (xy 123.384056 -284.847538) (xy 124.55144 -284.847538)
			(xy 124.551938 -284.820889) (xy 124.559881 -284.768185) (xy 124.575591 -284.717255) (xy 124.598717 -284.669234)
			(xy 124.628741 -284.625197) (xy 124.664993 -284.586126) (xy 124.706664 -284.552895) (xy 124.752822 -284.526246)
			(xy 124.802436 -284.506774) (xy 124.854398 -284.494914) (xy 124.907548 -284.490931) (xy 124.960698 -284.494914)
			(xy 125.01266 -284.506774) (xy 125.062274 -284.526246) (xy 125.108432 -284.552895) (xy 125.150103 -284.586126)
			(xy 125.186355 -284.625197) (xy 125.216379 -284.669234) (xy 125.239505 -284.717255) (xy 125.255215 -284.768185)
			(xy 125.263158 -284.820889) (xy 125.263656 -284.847538) (xy 125.26327 -284.870783) (xy 125.262824 -284.874187)
			(xy 125.491738 -284.874187) (xy 125.491738 -284.820889) (xy 125.499681 -284.768185) (xy 125.515391 -284.717255)
			(xy 125.538517 -284.669234) (xy 125.568541 -284.625197) (xy 125.604793 -284.586126) (xy 125.646464 -284.552895)
			(xy 125.692622 -284.526246) (xy 125.742236 -284.506774) (xy 125.794198 -284.494914) (xy 125.847348 -284.490931)
			(xy 125.900498 -284.494914) (xy 125.95246 -284.506774) (xy 126.002074 -284.526246) (xy 126.048232 -284.552895)
			(xy 126.089903 -284.586126) (xy 126.126155 -284.625197) (xy 126.156179 -284.669234) (xy 126.179305 -284.717255)
			(xy 126.195015 -284.768185) (xy 126.202958 -284.820889) (xy 126.203456 -284.847538) (xy 126.43104 -284.847538)
			(xy 126.431538 -284.820889) (xy 126.439481 -284.768185) (xy 126.455191 -284.717255) (xy 126.478317 -284.669234)
			(xy 126.508341 -284.625197) (xy 126.544593 -284.586126) (xy 126.586264 -284.552895) (xy 126.632422 -284.526246)
			(xy 126.682036 -284.506774) (xy 126.733998 -284.494914) (xy 126.787148 -284.490931) (xy 126.840298 -284.494914)
			(xy 126.89226 -284.506774) (xy 126.941874 -284.526246) (xy 126.988032 -284.552895) (xy 127.029703 -284.586126)
			(xy 127.065955 -284.625197) (xy 127.095979 -284.669234) (xy 127.119105 -284.717255) (xy 127.134815 -284.768185)
			(xy 127.142758 -284.820889) (xy 127.143256 -284.847538) (xy 128.31064 -284.847538) (xy 128.311138 -284.820889)
			(xy 128.319081 -284.768185) (xy 128.334791 -284.717255) (xy 128.357917 -284.669234) (xy 128.387941 -284.625197)
			(xy 128.424193 -284.586126) (xy 128.465864 -284.552895) (xy 128.512022 -284.526246) (xy 128.561636 -284.506774)
			(xy 128.613598 -284.494914) (xy 128.666748 -284.490931) (xy 128.719898 -284.494914) (xy 128.77186 -284.506774)
			(xy 128.821474 -284.526246) (xy 128.867632 -284.552895) (xy 128.909303 -284.586126) (xy 128.945555 -284.625197)
			(xy 128.975579 -284.669234) (xy 128.998705 -284.717255) (xy 129.014415 -284.768185) (xy 129.022358 -284.820889)
			(xy 129.022856 -284.847538) (xy 130.19024 -284.847538) (xy 130.190738 -284.820889) (xy 130.198681 -284.768185)
			(xy 130.214391 -284.717255) (xy 130.237517 -284.669234) (xy 130.267541 -284.625197) (xy 130.303793 -284.586126)
			(xy 130.345464 -284.552895) (xy 130.391622 -284.526246) (xy 130.441236 -284.506774) (xy 130.493198 -284.494914)
			(xy 130.546348 -284.490931) (xy 130.599498 -284.494914) (xy 130.65146 -284.506774) (xy 130.701074 -284.526246)
			(xy 130.747232 -284.552895) (xy 130.788903 -284.586126) (xy 130.825155 -284.625197) (xy 130.855179 -284.669234)
			(xy 130.878305 -284.717255) (xy 130.894015 -284.768185) (xy 130.901958 -284.820889) (xy 130.902456 -284.847538)
			(xy 132.06984 -284.847538) (xy 132.070338 -284.820889) (xy 132.078281 -284.768185) (xy 132.093991 -284.717255)
			(xy 132.117117 -284.669234) (xy 132.147141 -284.625197) (xy 132.183393 -284.586126) (xy 132.225064 -284.552895)
			(xy 132.271222 -284.526246) (xy 132.320836 -284.506774) (xy 132.372798 -284.494914) (xy 132.425948 -284.490931)
			(xy 132.479098 -284.494914) (xy 132.53106 -284.506774) (xy 132.580674 -284.526246) (xy 132.626832 -284.552895)
			(xy 132.668503 -284.586126) (xy 132.704755 -284.625197) (xy 132.734779 -284.669234) (xy 132.757905 -284.717255)
			(xy 132.773615 -284.768185) (xy 132.781558 -284.820889) (xy 132.782056 -284.847538) (xy 132.78167 -284.870783)
			(xy 132.781224 -284.874187) (xy 133.949938 -284.874187) (xy 133.949938 -284.820889) (xy 133.957881 -284.768185)
			(xy 133.973591 -284.717255) (xy 133.996717 -284.669234) (xy 134.026741 -284.625197) (xy 134.062993 -284.586126)
			(xy 134.104664 -284.552895) (xy 134.150822 -284.526246) (xy 134.200436 -284.506774) (xy 134.252398 -284.494914)
			(xy 134.305548 -284.490931) (xy 134.358698 -284.494914) (xy 134.41066 -284.506774) (xy 134.460274 -284.526246)
			(xy 134.506432 -284.552895) (xy 134.548103 -284.586126) (xy 134.584355 -284.625197) (xy 134.614379 -284.669234)
			(xy 134.637505 -284.717255) (xy 134.653215 -284.768185) (xy 134.661158 -284.820889) (xy 134.661656 -284.847538)
			(xy 134.661163 -284.873933) (xy 134.889484 -284.873933) (xy 134.889484 -284.820635) (xy 134.897427 -284.767931)
			(xy 134.913137 -284.717001) (xy 134.936263 -284.66898) (xy 134.966287 -284.624943) (xy 135.002539 -284.585872)
			(xy 135.04421 -284.552641) (xy 135.090368 -284.525992) (xy 135.139982 -284.50652) (xy 135.191944 -284.49466)
			(xy 135.245094 -284.490677) (xy 135.298244 -284.49466) (xy 135.350206 -284.50652) (xy 135.39982 -284.525992)
			(xy 135.445978 -284.552641) (xy 135.487649 -284.585872) (xy 135.523901 -284.624943) (xy 135.553925 -284.66898)
			(xy 135.577051 -284.717001) (xy 135.592761 -284.767931) (xy 135.600704 -284.820635) (xy 135.601202 -284.847284)
			(xy 135.600704 -284.873933) (xy 135.829284 -284.873933) (xy 135.829284 -284.820635) (xy 135.837227 -284.767931)
			(xy 135.852937 -284.717001) (xy 135.876063 -284.66898) (xy 135.906087 -284.624943) (xy 135.942339 -284.585872)
			(xy 135.98401 -284.552641) (xy 136.030168 -284.525992) (xy 136.079782 -284.50652) (xy 136.131744 -284.49466)
			(xy 136.184894 -284.490677) (xy 136.238044 -284.49466) (xy 136.290006 -284.50652) (xy 136.33962 -284.525992)
			(xy 136.385778 -284.552641) (xy 136.427449 -284.585872) (xy 136.463701 -284.624943) (xy 136.493725 -284.66898)
			(xy 136.516851 -284.717001) (xy 136.532561 -284.767931) (xy 136.540504 -284.820635) (xy 136.541002 -284.847284)
			(xy 136.540504 -284.873933) (xy 136.769084 -284.873933) (xy 136.769084 -284.820635) (xy 136.777027 -284.767931)
			(xy 136.792737 -284.717001) (xy 136.815863 -284.66898) (xy 136.845887 -284.624943) (xy 136.882139 -284.585872)
			(xy 136.92381 -284.552641) (xy 136.969968 -284.525992) (xy 137.019582 -284.50652) (xy 137.071544 -284.49466)
			(xy 137.124694 -284.490677) (xy 137.177844 -284.49466) (xy 137.229806 -284.50652) (xy 137.27942 -284.525992)
			(xy 137.325578 -284.552641) (xy 137.367249 -284.585872) (xy 137.403501 -284.624943) (xy 137.433525 -284.66898)
			(xy 137.456651 -284.717001) (xy 137.472361 -284.767931) (xy 137.480304 -284.820635) (xy 137.480802 -284.847284)
			(xy 137.480304 -284.873933) (xy 137.472361 -284.926637) (xy 137.456651 -284.977567) (xy 137.433525 -285.025588)
			(xy 137.403501 -285.069625) (xy 137.367249 -285.108696) (xy 137.325578 -285.141927) (xy 137.27942 -285.168576)
			(xy 137.229806 -285.188048) (xy 137.177844 -285.199908) (xy 137.124694 -285.203892) (xy 137.071544 -285.199908)
			(xy 137.019582 -285.188048) (xy 136.969968 -285.168576) (xy 136.92381 -285.141927) (xy 136.882139 -285.108696)
			(xy 136.845887 -285.069625) (xy 136.815863 -285.025588) (xy 136.792737 -284.977567) (xy 136.777027 -284.926637)
			(xy 136.769084 -284.873933) (xy 136.540504 -284.873933) (xy 136.532561 -284.926637) (xy 136.516851 -284.977567)
			(xy 136.493725 -285.025588) (xy 136.463701 -285.069625) (xy 136.427449 -285.108696) (xy 136.385778 -285.141927)
			(xy 136.33962 -285.168576) (xy 136.290006 -285.188048) (xy 136.238044 -285.199908) (xy 136.184894 -285.203892)
			(xy 136.131744 -285.199908) (xy 136.079782 -285.188048) (xy 136.030168 -285.168576) (xy 135.98401 -285.141927)
			(xy 135.942339 -285.108696) (xy 135.906087 -285.069625) (xy 135.876063 -285.025588) (xy 135.852937 -284.977567)
			(xy 135.837227 -284.926637) (xy 135.829284 -284.873933) (xy 135.600704 -284.873933) (xy 135.592761 -284.926637)
			(xy 135.577051 -284.977567) (xy 135.553925 -285.025588) (xy 135.523901 -285.069625) (xy 135.487649 -285.108696)
			(xy 135.445978 -285.141927) (xy 135.39982 -285.168576) (xy 135.350206 -285.188048) (xy 135.298244 -285.199908)
			(xy 135.245094 -285.203892) (xy 135.191944 -285.199908) (xy 135.139982 -285.188048) (xy 135.090368 -285.168576)
			(xy 135.04421 -285.141927) (xy 135.002539 -285.108696) (xy 134.966287 -285.069625) (xy 134.936263 -285.025588)
			(xy 134.913137 -284.977567) (xy 134.897427 -284.926637) (xy 134.889484 -284.873933) (xy 134.661163 -284.873933)
			(xy 134.661158 -284.874187) (xy 134.653215 -284.926891) (xy 134.637505 -284.977821) (xy 134.614379 -285.025842)
			(xy 134.584355 -285.069879) (xy 134.548103 -285.10895) (xy 134.506432 -285.142181) (xy 134.460274 -285.16883)
			(xy 134.41066 -285.188302) (xy 134.358698 -285.200162) (xy 134.305548 -285.204146) (xy 134.252398 -285.200162)
			(xy 134.200436 -285.188302) (xy 134.150822 -285.16883) (xy 134.104664 -285.142181) (xy 134.062993 -285.10895)
			(xy 134.026741 -285.069879) (xy 133.996717 -285.025842) (xy 133.973591 -284.977821) (xy 133.957881 -284.926891)
			(xy 133.949938 -284.874187) (xy 132.781224 -284.874187) (xy 132.775631 -284.916878) (xy 132.763647 -284.961796)
			(xy 132.755132 -284.983428) (xy 132.74548 -285.006542) (xy 132.917946 -285.304992) (xy 132.942584 -285.308294)
			(xy 132.967921 -285.312151) (xy 133.017227 -285.326136) (xy 133.064019 -285.347042) (xy 133.107331 -285.374438)
			(xy 133.146271 -285.407759) (xy 133.180033 -285.446317) (xy 133.20792 -285.489315) (xy 133.229358 -285.535866)
			(xy 133.243902 -285.585009) (xy 133.251254 -285.635729) (xy 133.251702 -285.661354) (xy 133.251204 -285.688003)
			(xy 133.243261 -285.740707) (xy 133.227551 -285.791637) (xy 133.204425 -285.839658) (xy 133.174401 -285.883695)
			(xy 133.138149 -285.922766) (xy 133.096478 -285.955997) (xy 133.05032 -285.982646) (xy 133.000706 -286.002118)
			(xy 132.948744 -286.013978) (xy 132.895594 -286.017962) (xy 132.842444 -286.013978) (xy 132.790482 -286.002118)
			(xy 132.740868 -285.982646) (xy 132.69471 -285.955997) (xy 132.653039 -285.922766) (xy 132.616787 -285.883695)
			(xy 132.586763 -285.839658) (xy 132.563637 -285.791637) (xy 132.547927 -285.740707) (xy 132.539984 -285.688003)
			(xy 132.539486 -285.661354) (xy 132.539873 -285.638109) (xy 132.545912 -285.592014) (xy 132.557896 -285.547096)
			(xy 132.56641 -285.525464) (xy 132.576062 -285.50235) (xy 132.403596 -285.2039) (xy 132.378958 -285.200598)
			(xy 132.353612 -285.196794) (xy 132.304306 -285.182801) (xy 132.257513 -285.161888) (xy 132.214201 -285.134484)
			(xy 132.175263 -285.101157) (xy 132.141502 -285.062593) (xy 132.113617 -285.01959) (xy 132.092181 -284.973035)
			(xy 132.077638 -284.923888) (xy 132.070288 -284.873165) (xy 132.06984 -284.847538) (xy 130.902456 -284.847538)
			(xy 130.90207 -284.870783) (xy 130.896031 -284.916878) (xy 130.884047 -284.961796) (xy 130.875532 -284.983428)
			(xy 130.86588 -285.006542) (xy 131.038346 -285.304992) (xy 131.062984 -285.308294) (xy 131.088321 -285.312151)
			(xy 131.137627 -285.326136) (xy 131.184419 -285.347042) (xy 131.227731 -285.374438) (xy 131.266671 -285.407759)
			(xy 131.300433 -285.446317) (xy 131.32832 -285.489315) (xy 131.349758 -285.535866) (xy 131.364302 -285.585009)
			(xy 131.371654 -285.635729) (xy 131.372102 -285.661354) (xy 131.371604 -285.688003) (xy 131.363661 -285.740707)
			(xy 131.347951 -285.791637) (xy 131.324825 -285.839658) (xy 131.294801 -285.883695) (xy 131.258549 -285.922766)
			(xy 131.216878 -285.955997) (xy 131.17072 -285.982646) (xy 131.121106 -286.002118) (xy 131.069144 -286.013978)
			(xy 131.015994 -286.017962) (xy 130.962844 -286.013978) (xy 130.910882 -286.002118) (xy 130.861268 -285.982646)
			(xy 130.81511 -285.955997) (xy 130.773439 -285.922766) (xy 130.737187 -285.883695) (xy 130.707163 -285.839658)
			(xy 130.684037 -285.791637) (xy 130.668327 -285.740707) (xy 130.660384 -285.688003) (xy 130.659886 -285.661354)
			(xy 130.660273 -285.638109) (xy 130.666312 -285.592014) (xy 130.678296 -285.547096) (xy 130.68681 -285.525464)
			(xy 130.696462 -285.50235) (xy 130.523996 -285.2039) (xy 130.499358 -285.200598) (xy 130.474012 -285.196794)
			(xy 130.424706 -285.182801) (xy 130.377913 -285.161888) (xy 130.334601 -285.134484) (xy 130.295663 -285.101157)
			(xy 130.261902 -285.062593) (xy 130.234017 -285.01959) (xy 130.212581 -284.973035) (xy 130.198038 -284.923888)
			(xy 130.190688 -284.873165) (xy 130.19024 -284.847538) (xy 129.022856 -284.847538) (xy 129.02247 -284.870783)
			(xy 129.016431 -284.916878) (xy 129.004447 -284.961796) (xy 128.995932 -284.983428) (xy 128.98628 -285.006542)
			(xy 129.158746 -285.304992) (xy 129.183384 -285.308294) (xy 129.208721 -285.312151) (xy 129.258027 -285.326136)
			(xy 129.304819 -285.347042) (xy 129.348131 -285.374438) (xy 129.387071 -285.407759) (xy 129.420833 -285.446317)
			(xy 129.44872 -285.489315) (xy 129.470158 -285.535866) (xy 129.484702 -285.585009) (xy 129.492054 -285.635729)
			(xy 129.492502 -285.661354) (xy 129.492004 -285.688003) (xy 129.484061 -285.740707) (xy 129.468351 -285.791637)
			(xy 129.445225 -285.839658) (xy 129.415201 -285.883695) (xy 129.378949 -285.922766) (xy 129.337278 -285.955997)
			(xy 129.29112 -285.982646) (xy 129.241506 -286.002118) (xy 129.189544 -286.013978) (xy 129.136394 -286.017962)
			(xy 129.083244 -286.013978) (xy 129.031282 -286.002118) (xy 128.981668 -285.982646) (xy 128.93551 -285.955997)
			(xy 128.893839 -285.922766) (xy 128.857587 -285.883695) (xy 128.827563 -285.839658) (xy 128.804437 -285.791637)
			(xy 128.788727 -285.740707) (xy 128.780784 -285.688003) (xy 128.780286 -285.661354) (xy 128.780673 -285.638109)
			(xy 128.786712 -285.592014) (xy 128.798696 -285.547096) (xy 128.80721 -285.525464) (xy 128.816862 -285.50235)
			(xy 128.644396 -285.2039) (xy 128.619758 -285.200598) (xy 128.594412 -285.196794) (xy 128.545106 -285.182801)
			(xy 128.498313 -285.161888) (xy 128.455001 -285.134484) (xy 128.416063 -285.101157) (xy 128.382302 -285.062593)
			(xy 128.354417 -285.01959) (xy 128.332981 -284.973035) (xy 128.318438 -284.923888) (xy 128.311088 -284.873165)
			(xy 128.31064 -284.847538) (xy 127.143256 -284.847538) (xy 127.14287 -284.870783) (xy 127.136831 -284.916878)
			(xy 127.124847 -284.961796) (xy 127.116332 -284.983428) (xy 127.10668 -285.006542) (xy 127.279146 -285.304992)
			(xy 127.303784 -285.308294) (xy 127.329121 -285.312151) (xy 127.378427 -285.326136) (xy 127.425219 -285.347042)
			(xy 127.468531 -285.374438) (xy 127.507471 -285.407759) (xy 127.541233 -285.446317) (xy 127.56912 -285.489315)
			(xy 127.590558 -285.535866) (xy 127.605102 -285.585009) (xy 127.612454 -285.635729) (xy 127.612902 -285.661354)
			(xy 127.612404 -285.688003) (xy 127.604461 -285.740707) (xy 127.588751 -285.791637) (xy 127.565625 -285.839658)
			(xy 127.535601 -285.883695) (xy 127.499349 -285.922766) (xy 127.457678 -285.955997) (xy 127.41152 -285.982646)
			(xy 127.361906 -286.002118) (xy 127.309944 -286.013978) (xy 127.256794 -286.017962) (xy 127.203644 -286.013978)
			(xy 127.151682 -286.002118) (xy 127.102068 -285.982646) (xy 127.05591 -285.955997) (xy 127.014239 -285.922766)
			(xy 126.977987 -285.883695) (xy 126.947963 -285.839658) (xy 126.924837 -285.791637) (xy 126.909127 -285.740707)
			(xy 126.901184 -285.688003) (xy 126.900686 -285.661354) (xy 126.901073 -285.638109) (xy 126.907112 -285.592014)
			(xy 126.919096 -285.547096) (xy 126.92761 -285.525464) (xy 126.937262 -285.50235) (xy 126.764796 -285.2039)
			(xy 126.740158 -285.200598) (xy 126.714812 -285.196794) (xy 126.665506 -285.182801) (xy 126.618713 -285.161888)
			(xy 126.575401 -285.134484) (xy 126.536463 -285.101157) (xy 126.502702 -285.062593) (xy 126.474817 -285.01959)
			(xy 126.453381 -284.973035) (xy 126.438838 -284.923888) (xy 126.431488 -284.873165) (xy 126.43104 -284.847538)
			(xy 126.203456 -284.847538) (xy 126.202958 -284.874187) (xy 126.195015 -284.926891) (xy 126.179305 -284.977821)
			(xy 126.156179 -285.025842) (xy 126.126155 -285.069879) (xy 126.089903 -285.10895) (xy 126.048232 -285.142181)
			(xy 126.002074 -285.16883) (xy 125.95246 -285.188302) (xy 125.900498 -285.200162) (xy 125.847348 -285.204146)
			(xy 125.794198 -285.200162) (xy 125.742236 -285.188302) (xy 125.692622 -285.16883) (xy 125.646464 -285.142181)
			(xy 125.604793 -285.10895) (xy 125.568541 -285.069879) (xy 125.538517 -285.025842) (xy 125.515391 -284.977821)
			(xy 125.499681 -284.926891) (xy 125.491738 -284.874187) (xy 125.262824 -284.874187) (xy 125.257231 -284.916878)
			(xy 125.245247 -284.961796) (xy 125.236732 -284.983428) (xy 125.22708 -285.006542) (xy 125.399546 -285.304992)
			(xy 125.424184 -285.308294) (xy 125.449521 -285.312151) (xy 125.498827 -285.326136) (xy 125.545619 -285.347042)
			(xy 125.588931 -285.374438) (xy 125.627871 -285.407759) (xy 125.661633 -285.446317) (xy 125.68952 -285.489315)
			(xy 125.710958 -285.535866) (xy 125.725502 -285.585009) (xy 125.732854 -285.635729) (xy 125.733302 -285.661354)
			(xy 125.732804 -285.688003) (xy 125.724861 -285.740707) (xy 125.709151 -285.791637) (xy 125.686025 -285.839658)
			(xy 125.656001 -285.883695) (xy 125.619749 -285.922766) (xy 125.578078 -285.955997) (xy 125.53192 -285.982646)
			(xy 125.482306 -286.002118) (xy 125.430344 -286.013978) (xy 125.377194 -286.017962) (xy 125.324044 -286.013978)
			(xy 125.272082 -286.002118) (xy 125.222468 -285.982646) (xy 125.17631 -285.955997) (xy 125.134639 -285.922766)
			(xy 125.098387 -285.883695) (xy 125.068363 -285.839658) (xy 125.045237 -285.791637) (xy 125.029527 -285.740707)
			(xy 125.021584 -285.688003) (xy 125.021086 -285.661354) (xy 125.021473 -285.638109) (xy 125.027512 -285.592014)
			(xy 125.039496 -285.547096) (xy 125.04801 -285.525464) (xy 125.057662 -285.50235) (xy 124.885196 -285.2039)
			(xy 124.860558 -285.200598) (xy 124.835212 -285.196794) (xy 124.785906 -285.182801) (xy 124.739113 -285.161888)
			(xy 124.695801 -285.134484) (xy 124.656863 -285.101157) (xy 124.623102 -285.062593) (xy 124.595217 -285.01959)
			(xy 124.573781 -284.973035) (xy 124.559238 -284.923888) (xy 124.551888 -284.873165) (xy 124.55144 -284.847538)
			(xy 123.384056 -284.847538) (xy 123.38367 -284.870783) (xy 123.377631 -284.916878) (xy 123.365647 -284.961796)
			(xy 123.357132 -284.983428) (xy 123.34748 -285.006542) (xy 123.519946 -285.304992) (xy 123.544584 -285.308294)
			(xy 123.569921 -285.312151) (xy 123.619227 -285.326136) (xy 123.666019 -285.347042) (xy 123.709331 -285.374438)
			(xy 123.748271 -285.407759) (xy 123.782033 -285.446317) (xy 123.80992 -285.489315) (xy 123.831358 -285.535866)
			(xy 123.845902 -285.585009) (xy 123.853254 -285.635729) (xy 123.853702 -285.661354) (xy 123.853204 -285.688003)
			(xy 123.845261 -285.740707) (xy 123.829551 -285.791637) (xy 123.806425 -285.839658) (xy 123.776401 -285.883695)
			(xy 123.740149 -285.922766) (xy 123.698478 -285.955997) (xy 123.65232 -285.982646) (xy 123.602706 -286.002118)
			(xy 123.550744 -286.013978) (xy 123.497594 -286.017962) (xy 123.444444 -286.013978) (xy 123.392482 -286.002118)
			(xy 123.342868 -285.982646) (xy 123.29671 -285.955997) (xy 123.255039 -285.922766) (xy 123.218787 -285.883695)
			(xy 123.188763 -285.839658) (xy 123.165637 -285.791637) (xy 123.149927 -285.740707) (xy 123.141984 -285.688003)
			(xy 123.141486 -285.661354) (xy 123.141873 -285.638109) (xy 123.147912 -285.592014) (xy 123.159896 -285.547096)
			(xy 123.16841 -285.525464) (xy 123.178062 -285.50235) (xy 123.005596 -285.2039) (xy 122.980958 -285.200598)
			(xy 122.955612 -285.196794) (xy 122.906306 -285.182801) (xy 122.859513 -285.161888) (xy 122.816201 -285.134484)
			(xy 122.777263 -285.101157) (xy 122.743502 -285.062593) (xy 122.715617 -285.01959) (xy 122.694181 -284.973035)
			(xy 122.679638 -284.923888) (xy 122.672288 -284.873165) (xy 122.67184 -284.847538) (xy 121.504456 -284.847538)
			(xy 121.50407 -284.870783) (xy 121.498031 -284.916878) (xy 121.486047 -284.961796) (xy 121.477532 -284.983428)
			(xy 121.46788 -285.006542) (xy 121.640346 -285.304992) (xy 121.664984 -285.308294) (xy 121.690321 -285.312151)
			(xy 121.739627 -285.326136) (xy 121.786419 -285.347042) (xy 121.829731 -285.374438) (xy 121.868671 -285.407759)
			(xy 121.902433 -285.446317) (xy 121.93032 -285.489315) (xy 121.951758 -285.535866) (xy 121.966302 -285.585009)
			(xy 121.973654 -285.635729) (xy 121.974102 -285.661354) (xy 121.973604 -285.688003) (xy 121.965661 -285.740707)
			(xy 121.949951 -285.791637) (xy 121.926825 -285.839658) (xy 121.896801 -285.883695) (xy 121.860549 -285.922766)
			(xy 121.818878 -285.955997) (xy 121.77272 -285.982646) (xy 121.723106 -286.002118) (xy 121.671144 -286.013978)
			(xy 121.617994 -286.017962) (xy 121.564844 -286.013978) (xy 121.512882 -286.002118) (xy 121.463268 -285.982646)
			(xy 121.41711 -285.955997) (xy 121.375439 -285.922766) (xy 121.339187 -285.883695) (xy 121.309163 -285.839658)
			(xy 121.286037 -285.791637) (xy 121.270327 -285.740707) (xy 121.262384 -285.688003) (xy 121.261886 -285.661354)
			(xy 121.262273 -285.638109) (xy 121.268312 -285.592014) (xy 121.280296 -285.547096) (xy 121.28881 -285.525464)
			(xy 121.298462 -285.50235) (xy 121.125996 -285.2039) (xy 121.101358 -285.200598) (xy 121.076012 -285.196794)
			(xy 121.026706 -285.182801) (xy 120.979913 -285.161888) (xy 120.936601 -285.134484) (xy 120.897663 -285.101157)
			(xy 120.863902 -285.062593) (xy 120.836017 -285.01959) (xy 120.814581 -284.973035) (xy 120.800038 -284.923888)
			(xy 120.792688 -284.873165) (xy 120.79224 -284.847538) (xy 119.93372 -284.847538) (xy 119.93372 -284.963108)
			(xy 119.83466 -284.963108) (xy 119.83466 -285.316676) (xy 119.867172 -285.329376) (xy 119.891922 -285.339497)
			(xy 119.938318 -285.366079) (xy 119.980218 -285.399299) (xy 120.016681 -285.438408) (xy 120.046888 -285.482529)
			(xy 120.07016 -285.53067) (xy 120.085974 -285.581749) (xy 120.093974 -285.634619) (xy 120.094502 -285.661354)
			(xy 120.094062 -285.686548) (xy 120.086951 -285.736432) (xy 120.07288 -285.784816) (xy 120.052128 -285.830733)
			(xy 120.025111 -285.873266) (xy 119.992368 -285.911566) (xy 119.954553 -285.944868) (xy 119.93372 -285.959042)
			(xy 119.93372 -286.051752) (xy 119.934191 -286.06601) (xy 119.942064 -286.093418) (xy 119.95721 -286.117579)
			(xy 119.978447 -286.136609) (xy 120.004118 -286.149025) (xy 120.032222 -286.153856) (xy 120.060566 -286.150727)
			(xy 120.073928 -286.145732) (xy 120.095113 -286.137453) (xy 120.139063 -286.125731) (xy 120.161558 -286.122364)
			(xy 120.186196 -286.119062) (xy 120.358662 -285.820358) (xy 120.34901 -285.797244) (xy 120.340495 -285.775612)
			(xy 120.328511 -285.730694) (xy 120.32247 -285.684599) (xy 120.322086 -285.661354) (xy 120.322584 -285.634705)
			(xy 120.330527 -285.582001) (xy 120.346237 -285.531071) (xy 120.369363 -285.48305) (xy 120.399387 -285.439013)
			(xy 120.435639 -285.399942) (xy 120.47731 -285.366711) (xy 120.523468 -285.340062) (xy 120.573082 -285.32059)
			(xy 120.625044 -285.30873) (xy 120.678194 -285.304747) (xy 120.731344 -285.30873) (xy 120.783306 -285.32059)
			(xy 120.83292 -285.340062) (xy 120.879078 -285.366711) (xy 120.920749 -285.399942) (xy 120.957001 -285.439013)
			(xy 120.987025 -285.48305) (xy 121.010151 -285.531071) (xy 121.025861 -285.582001) (xy 121.033804 -285.634705)
			(xy 121.034302 -285.661354) (xy 121.033853 -285.686979) (xy 121.026501 -285.737698) (xy 121.011955 -285.78684)
			(xy 120.990517 -285.83339) (xy 120.96263 -285.876387) (xy 120.928868 -285.914944) (xy 120.889929 -285.948264)
			(xy 120.846616 -285.975659) (xy 120.799825 -285.996565) (xy 120.75052 -286.010549) (xy 120.725184 -286.014414)
			(xy 120.700546 -286.017716) (xy 120.52808 -286.31642) (xy 120.537732 -286.339534) (xy 120.546249 -286.361166)
			(xy 120.558238 -286.406083) (xy 120.564282 -286.452179) (xy 120.564656 -286.475424) (xy 120.564158 -286.502073)
			(xy 120.792484 -286.502073) (xy 120.792484 -286.448775) (xy 120.800427 -286.396071) (xy 120.816137 -286.345141)
			(xy 120.839263 -286.29712) (xy 120.869287 -286.253083) (xy 120.905539 -286.214012) (xy 120.94721 -286.180781)
			(xy 120.993368 -286.154132) (xy 121.042982 -286.13466) (xy 121.094944 -286.1228) (xy 121.148094 -286.118817)
			(xy 121.201244 -286.1228) (xy 121.253206 -286.13466) (xy 121.30282 -286.154132) (xy 121.348978 -286.180781)
			(xy 121.390649 -286.214012) (xy 121.426901 -286.253083) (xy 121.456925 -286.29712) (xy 121.480051 -286.345141)
			(xy 121.495761 -286.396071) (xy 121.503704 -286.448775) (xy 121.504202 -286.475424) (xy 121.73204 -286.475424)
			(xy 121.732493 -286.449796) (xy 121.739826 -286.399067) (xy 121.754356 -286.349914) (xy 121.775785 -286.303352)
			(xy 121.803669 -286.260345) (xy 121.837433 -286.22178) (xy 121.876377 -286.188455) (xy 121.919697 -286.16106)
			(xy 121.966498 -286.140159) (xy 122.015813 -286.126185) (xy 122.041158 -286.122364) (xy 122.065796 -286.119062)
			(xy 122.238262 -285.820358) (xy 122.22861 -285.797244) (xy 122.220079 -285.775617) (xy 122.208098 -285.730697)
			(xy 122.202059 -285.6846) (xy 122.201686 -285.661354) (xy 122.202184 -285.634705) (xy 122.210127 -285.582001)
			(xy 122.225837 -285.531071) (xy 122.248963 -285.48305) (xy 122.278987 -285.439013) (xy 122.315239 -285.399942)
			(xy 122.35691 -285.366711) (xy 122.403068 -285.340062) (xy 122.452682 -285.32059) (xy 122.504644 -285.30873)
			(xy 122.557794 -285.304747) (xy 122.610944 -285.30873) (xy 122.662906 -285.32059) (xy 122.71252 -285.340062)
			(xy 122.758678 -285.366711) (xy 122.800349 -285.399942) (xy 122.836601 -285.439013) (xy 122.866625 -285.48305)
			(xy 122.889751 -285.531071) (xy 122.905461 -285.582001) (xy 122.913404 -285.634705) (xy 122.913902 -285.661354)
			(xy 122.913479 -285.686984) (xy 122.906148 -285.737716) (xy 122.891617 -285.786873) (xy 122.870187 -285.833438)
			(xy 122.8423 -285.876448) (xy 122.808532 -285.915013) (xy 122.769583 -285.948337) (xy 122.726258 -285.975731)
			(xy 122.679451 -285.996628) (xy 122.630132 -286.010596) (xy 122.604784 -286.014414) (xy 122.580146 -286.017716)
			(xy 122.40768 -286.31642) (xy 122.417332 -286.339534) (xy 122.425853 -286.361164) (xy 122.437839 -286.406083)
			(xy 122.443882 -286.452179) (xy 122.444256 -286.475424) (xy 122.443758 -286.502073) (xy 122.672084 -286.502073)
			(xy 122.672084 -286.448775) (xy 122.680027 -286.396071) (xy 122.695737 -286.345141) (xy 122.718863 -286.29712)
			(xy 122.748887 -286.253083) (xy 122.785139 -286.214012) (xy 122.82681 -286.180781) (xy 122.872968 -286.154132)
			(xy 122.922582 -286.13466) (xy 122.974544 -286.1228) (xy 123.027694 -286.118817) (xy 123.080844 -286.1228)
			(xy 123.132806 -286.13466) (xy 123.18242 -286.154132) (xy 123.228578 -286.180781) (xy 123.270249 -286.214012)
			(xy 123.306501 -286.253083) (xy 123.336525 -286.29712) (xy 123.359651 -286.345141) (xy 123.375361 -286.396071)
			(xy 123.383304 -286.448775) (xy 123.383802 -286.475424) (xy 123.61164 -286.475424) (xy 123.612093 -286.449796)
			(xy 123.619426 -286.399067) (xy 123.633956 -286.349914) (xy 123.655385 -286.303352) (xy 123.683269 -286.260345)
			(xy 123.717033 -286.22178) (xy 123.755977 -286.188455) (xy 123.799297 -286.16106) (xy 123.846098 -286.140159)
			(xy 123.895413 -286.126185) (xy 123.920758 -286.122364) (xy 123.945396 -286.119062) (xy 124.117862 -285.820358)
			(xy 124.10821 -285.797244) (xy 124.099679 -285.775617) (xy 124.087698 -285.730697) (xy 124.081659 -285.6846)
			(xy 124.081286 -285.661354) (xy 124.081784 -285.634705) (xy 124.089727 -285.582001) (xy 124.105437 -285.531071)
			(xy 124.128563 -285.48305) (xy 124.158587 -285.439013) (xy 124.194839 -285.399942) (xy 124.23651 -285.366711)
			(xy 124.282668 -285.340062) (xy 124.332282 -285.32059) (xy 124.384244 -285.30873) (xy 124.437394 -285.304747)
			(xy 124.490544 -285.30873) (xy 124.542506 -285.32059) (xy 124.59212 -285.340062) (xy 124.638278 -285.366711)
			(xy 124.679949 -285.399942) (xy 124.716201 -285.439013) (xy 124.746225 -285.48305) (xy 124.769351 -285.531071)
			(xy 124.785061 -285.582001) (xy 124.793004 -285.634705) (xy 124.793502 -285.661354) (xy 124.793079 -285.686984)
			(xy 124.785748 -285.737716) (xy 124.771217 -285.786873) (xy 124.749787 -285.833438) (xy 124.7219 -285.876448)
			(xy 124.688132 -285.915013) (xy 124.649183 -285.948337) (xy 124.605858 -285.975731) (xy 124.559051 -285.996628)
			(xy 124.509732 -286.010596) (xy 124.484384 -286.014414) (xy 124.459746 -286.017716) (xy 124.28728 -286.31642)
			(xy 124.296932 -286.339534) (xy 124.305453 -286.361164) (xy 124.317439 -286.406083) (xy 124.323482 -286.452179)
			(xy 124.323856 -286.475424) (xy 124.323358 -286.502073) (xy 124.551684 -286.502073) (xy 124.551684 -286.448775)
			(xy 124.559627 -286.396071) (xy 124.575337 -286.345141) (xy 124.598463 -286.29712) (xy 124.628487 -286.253083)
			(xy 124.664739 -286.214012) (xy 124.70641 -286.180781) (xy 124.752568 -286.154132) (xy 124.802182 -286.13466)
			(xy 124.854144 -286.1228) (xy 124.907294 -286.118817) (xy 124.960444 -286.1228) (xy 125.012406 -286.13466)
			(xy 125.06202 -286.154132) (xy 125.108178 -286.180781) (xy 125.149849 -286.214012) (xy 125.186101 -286.253083)
			(xy 125.216125 -286.29712) (xy 125.239251 -286.345141) (xy 125.254961 -286.396071) (xy 125.262904 -286.448775)
			(xy 125.263402 -286.475424) (xy 125.49124 -286.475424) (xy 125.491693 -286.449796) (xy 125.499026 -286.399067)
			(xy 125.513556 -286.349914) (xy 125.534985 -286.303352) (xy 125.562869 -286.260345) (xy 125.596633 -286.22178)
			(xy 125.635577 -286.188455) (xy 125.678897 -286.16106) (xy 125.725698 -286.140159) (xy 125.775013 -286.126185)
			(xy 125.800358 -286.122364) (xy 125.824996 -286.119062) (xy 125.997462 -285.820358) (xy 125.98781 -285.797244)
			(xy 125.979279 -285.775617) (xy 125.967298 -285.730697) (xy 125.961259 -285.6846) (xy 125.960886 -285.661354)
			(xy 125.961384 -285.634705) (xy 125.969327 -285.582001) (xy 125.985037 -285.531071) (xy 126.008163 -285.48305)
			(xy 126.038187 -285.439013) (xy 126.074439 -285.399942) (xy 126.11611 -285.366711) (xy 126.162268 -285.340062)
			(xy 126.211882 -285.32059) (xy 126.263844 -285.30873) (xy 126.316994 -285.304747) (xy 126.370144 -285.30873)
			(xy 126.422106 -285.32059) (xy 126.47172 -285.340062) (xy 126.517878 -285.366711) (xy 126.559549 -285.399942)
			(xy 126.595801 -285.439013) (xy 126.625825 -285.48305) (xy 126.648951 -285.531071) (xy 126.664661 -285.582001)
			(xy 126.672604 -285.634705) (xy 126.673102 -285.661354) (xy 126.672679 -285.686984) (xy 126.665348 -285.737716)
			(xy 126.650817 -285.786873) (xy 126.629387 -285.833438) (xy 126.6015 -285.876448) (xy 126.567732 -285.915013)
			(xy 126.528783 -285.948337) (xy 126.485458 -285.975731) (xy 126.438651 -285.996628) (xy 126.389332 -286.010596)
			(xy 126.363984 -286.014414) (xy 126.339346 -286.017716) (xy 126.16688 -286.31642) (xy 126.176532 -286.339534)
			(xy 126.185053 -286.361164) (xy 126.197039 -286.406083) (xy 126.203082 -286.452179) (xy 126.203456 -286.475424)
			(xy 126.202958 -286.502073) (xy 126.431284 -286.502073) (xy 126.431284 -286.448775) (xy 126.439227 -286.396071)
			(xy 126.454937 -286.345141) (xy 126.478063 -286.29712) (xy 126.508087 -286.253083) (xy 126.544339 -286.214012)
			(xy 126.58601 -286.180781) (xy 126.632168 -286.154132) (xy 126.681782 -286.13466) (xy 126.733744 -286.1228)
			(xy 126.786894 -286.118817) (xy 126.840044 -286.1228) (xy 126.892006 -286.13466) (xy 126.94162 -286.154132)
			(xy 126.987778 -286.180781) (xy 127.029449 -286.214012) (xy 127.065701 -286.253083) (xy 127.095725 -286.29712)
			(xy 127.118851 -286.345141) (xy 127.134561 -286.396071) (xy 127.142504 -286.448775) (xy 127.143002 -286.475424)
			(xy 127.37084 -286.475424) (xy 127.371293 -286.449796) (xy 127.378626 -286.399067) (xy 127.393156 -286.349914)
			(xy 127.414585 -286.303352) (xy 127.442469 -286.260345) (xy 127.476233 -286.22178) (xy 127.515177 -286.188455)
			(xy 127.558497 -286.16106) (xy 127.605298 -286.140159) (xy 127.654613 -286.126185) (xy 127.679958 -286.122364)
			(xy 127.704596 -286.119062) (xy 127.877062 -285.820358) (xy 127.86741 -285.797244) (xy 127.858879 -285.775617)
			(xy 127.846898 -285.730697) (xy 127.840859 -285.6846) (xy 127.840486 -285.661354) (xy 127.840984 -285.634705)
			(xy 127.848927 -285.582001) (xy 127.864637 -285.531071) (xy 127.887763 -285.48305) (xy 127.917787 -285.439013)
			(xy 127.954039 -285.399942) (xy 127.99571 -285.366711) (xy 128.041868 -285.340062) (xy 128.091482 -285.32059)
			(xy 128.143444 -285.30873) (xy 128.196594 -285.304747) (xy 128.249744 -285.30873) (xy 128.301706 -285.32059)
			(xy 128.35132 -285.340062) (xy 128.397478 -285.366711) (xy 128.439149 -285.399942) (xy 128.475401 -285.439013)
			(xy 128.505425 -285.48305) (xy 128.528551 -285.531071) (xy 128.544261 -285.582001) (xy 128.552204 -285.634705)
			(xy 128.552702 -285.661354) (xy 128.552279 -285.686984) (xy 128.544948 -285.737716) (xy 128.530417 -285.786873)
			(xy 128.508987 -285.833438) (xy 128.4811 -285.876448) (xy 128.447332 -285.915013) (xy 128.408383 -285.948337)
			(xy 128.365058 -285.975731) (xy 128.318251 -285.996628) (xy 128.268932 -286.010596) (xy 128.243584 -286.014414)
			(xy 128.218946 -286.017716) (xy 128.04648 -286.31642) (xy 128.056132 -286.339534) (xy 128.064653 -286.361164)
			(xy 128.076639 -286.406083) (xy 128.082682 -286.452179) (xy 128.083056 -286.475424) (xy 128.082558 -286.502073)
			(xy 128.310884 -286.502073) (xy 128.310884 -286.448775) (xy 128.318827 -286.396071) (xy 128.334537 -286.345141)
			(xy 128.357663 -286.29712) (xy 128.387687 -286.253083) (xy 128.423939 -286.214012) (xy 128.46561 -286.180781)
			(xy 128.511768 -286.154132) (xy 128.561382 -286.13466) (xy 128.613344 -286.1228) (xy 128.666494 -286.118817)
			(xy 128.719644 -286.1228) (xy 128.771606 -286.13466) (xy 128.82122 -286.154132) (xy 128.867378 -286.180781)
			(xy 128.909049 -286.214012) (xy 128.945301 -286.253083) (xy 128.975325 -286.29712) (xy 128.998451 -286.345141)
			(xy 129.014161 -286.396071) (xy 129.022104 -286.448775) (xy 129.022602 -286.475424) (xy 129.25044 -286.475424)
			(xy 129.250893 -286.449796) (xy 129.258226 -286.399067) (xy 129.272756 -286.349914) (xy 129.294185 -286.303352)
			(xy 129.322069 -286.260345) (xy 129.355833 -286.22178) (xy 129.394777 -286.188455) (xy 129.438097 -286.16106)
			(xy 129.484898 -286.140159) (xy 129.534213 -286.126185) (xy 129.559558 -286.122364) (xy 129.584196 -286.119062)
			(xy 129.756662 -285.820358) (xy 129.74701 -285.797244) (xy 129.738479 -285.775617) (xy 129.726498 -285.730697)
			(xy 129.720459 -285.6846) (xy 129.720086 -285.661354) (xy 129.720584 -285.634705) (xy 129.728527 -285.582001)
			(xy 129.744237 -285.531071) (xy 129.767363 -285.48305) (xy 129.797387 -285.439013) (xy 129.833639 -285.399942)
			(xy 129.87531 -285.366711) (xy 129.921468 -285.340062) (xy 129.971082 -285.32059) (xy 130.023044 -285.30873)
			(xy 130.076194 -285.304747) (xy 130.129344 -285.30873) (xy 130.181306 -285.32059) (xy 130.23092 -285.340062)
			(xy 130.277078 -285.366711) (xy 130.318749 -285.399942) (xy 130.355001 -285.439013) (xy 130.385025 -285.48305)
			(xy 130.408151 -285.531071) (xy 130.423861 -285.582001) (xy 130.431804 -285.634705) (xy 130.432302 -285.661354)
			(xy 130.431879 -285.686984) (xy 130.424548 -285.737716) (xy 130.410017 -285.786873) (xy 130.388587 -285.833438)
			(xy 130.3607 -285.876448) (xy 130.326932 -285.915013) (xy 130.287983 -285.948337) (xy 130.244658 -285.975731)
			(xy 130.197851 -285.996628) (xy 130.148532 -286.010596) (xy 130.123184 -286.014414) (xy 130.098546 -286.017716)
			(xy 129.92608 -286.31642) (xy 129.935732 -286.339534) (xy 129.944253 -286.361164) (xy 129.956239 -286.406083)
			(xy 129.962282 -286.452179) (xy 129.962656 -286.475424) (xy 129.962158 -286.502073) (xy 130.190484 -286.502073)
			(xy 130.190484 -286.448775) (xy 130.198427 -286.396071) (xy 130.214137 -286.345141) (xy 130.237263 -286.29712)
			(xy 130.267287 -286.253083) (xy 130.303539 -286.214012) (xy 130.34521 -286.180781) (xy 130.391368 -286.154132)
			(xy 130.440982 -286.13466) (xy 130.492944 -286.1228) (xy 130.546094 -286.118817) (xy 130.599244 -286.1228)
			(xy 130.651206 -286.13466) (xy 130.70082 -286.154132) (xy 130.746978 -286.180781) (xy 130.788649 -286.214012)
			(xy 130.824901 -286.253083) (xy 130.854925 -286.29712) (xy 130.878051 -286.345141) (xy 130.893761 -286.396071)
			(xy 130.901704 -286.448775) (xy 130.902202 -286.475424) (xy 131.13004 -286.475424) (xy 131.130493 -286.449796)
			(xy 131.137826 -286.399067) (xy 131.152356 -286.349914) (xy 131.173785 -286.303352) (xy 131.201669 -286.260345)
			(xy 131.235433 -286.22178) (xy 131.274377 -286.188455) (xy 131.317697 -286.16106) (xy 131.364498 -286.140159)
			(xy 131.413813 -286.126185) (xy 131.439158 -286.122364) (xy 131.463796 -286.119062) (xy 131.636262 -285.820358)
			(xy 131.62661 -285.797244) (xy 131.618079 -285.775617) (xy 131.606098 -285.730697) (xy 131.600059 -285.6846)
			(xy 131.599686 -285.661354) (xy 131.600184 -285.634705) (xy 131.608127 -285.582001) (xy 131.623837 -285.531071)
			(xy 131.646963 -285.48305) (xy 131.676987 -285.439013) (xy 131.713239 -285.399942) (xy 131.75491 -285.366711)
			(xy 131.801068 -285.340062) (xy 131.850682 -285.32059) (xy 131.902644 -285.30873) (xy 131.955794 -285.304747)
			(xy 132.008944 -285.30873) (xy 132.060906 -285.32059) (xy 132.11052 -285.340062) (xy 132.156678 -285.366711)
			(xy 132.198349 -285.399942) (xy 132.234601 -285.439013) (xy 132.264625 -285.48305) (xy 132.287751 -285.531071)
			(xy 132.303461 -285.582001) (xy 132.311404 -285.634705) (xy 132.311902 -285.661354) (xy 132.311479 -285.686984)
			(xy 132.304148 -285.737716) (xy 132.289617 -285.786873) (xy 132.268187 -285.833438) (xy 132.2403 -285.876448)
			(xy 132.206532 -285.915013) (xy 132.167583 -285.948337) (xy 132.124258 -285.975731) (xy 132.077451 -285.996628)
			(xy 132.028132 -286.010596) (xy 132.002784 -286.014414) (xy 131.978146 -286.017716) (xy 131.80568 -286.31642)
			(xy 131.815332 -286.339534) (xy 131.823853 -286.361164) (xy 131.835839 -286.406083) (xy 131.841882 -286.452179)
			(xy 131.842256 -286.475424) (xy 131.841758 -286.502073) (xy 132.070084 -286.502073) (xy 132.070084 -286.448775)
			(xy 132.078027 -286.396071) (xy 132.093737 -286.345141) (xy 132.116863 -286.29712) (xy 132.146887 -286.253083)
			(xy 132.183139 -286.214012) (xy 132.22481 -286.180781) (xy 132.270968 -286.154132) (xy 132.320582 -286.13466)
			(xy 132.372544 -286.1228) (xy 132.425694 -286.118817) (xy 132.478844 -286.1228) (xy 132.530806 -286.13466)
			(xy 132.58042 -286.154132) (xy 132.626578 -286.180781) (xy 132.668249 -286.214012) (xy 132.704501 -286.253083)
			(xy 132.734525 -286.29712) (xy 132.757651 -286.345141) (xy 132.773361 -286.396071) (xy 132.781304 -286.448775)
			(xy 132.781802 -286.475424) (xy 133.00964 -286.475424) (xy 133.010093 -286.449796) (xy 133.017426 -286.399067)
			(xy 133.031956 -286.349914) (xy 133.053385 -286.303352) (xy 133.081269 -286.260345) (xy 133.115033 -286.22178)
			(xy 133.153977 -286.188455) (xy 133.197297 -286.16106) (xy 133.244098 -286.140159) (xy 133.293413 -286.126185)
			(xy 133.318758 -286.122364) (xy 133.343396 -286.119062) (xy 133.515862 -285.820358) (xy 133.50621 -285.797244)
			(xy 133.497679 -285.775617) (xy 133.485698 -285.730697) (xy 133.479659 -285.6846) (xy 133.479286 -285.661354)
			(xy 133.479784 -285.634705) (xy 133.487727 -285.582001) (xy 133.503437 -285.531071) (xy 133.526563 -285.48305)
			(xy 133.556587 -285.439013) (xy 133.592839 -285.399942) (xy 133.63451 -285.366711) (xy 133.680668 -285.340062)
			(xy 133.730282 -285.32059) (xy 133.782244 -285.30873) (xy 133.835394 -285.304747) (xy 133.888544 -285.30873)
			(xy 133.940506 -285.32059) (xy 133.99012 -285.340062) (xy 134.036278 -285.366711) (xy 134.077949 -285.399942)
			(xy 134.114201 -285.439013) (xy 134.144225 -285.48305) (xy 134.167351 -285.531071) (xy 134.183061 -285.582001)
			(xy 134.191004 -285.634705) (xy 134.191502 -285.661354) (xy 134.191079 -285.686984) (xy 134.190932 -285.688003)
			(xy 134.419584 -285.688003) (xy 134.419584 -285.634705) (xy 134.427527 -285.582001) (xy 134.443237 -285.531071)
			(xy 134.466363 -285.48305) (xy 134.496387 -285.439013) (xy 134.532639 -285.399942) (xy 134.57431 -285.366711)
			(xy 134.620468 -285.340062) (xy 134.670082 -285.32059) (xy 134.722044 -285.30873) (xy 134.775194 -285.304747)
			(xy 134.828344 -285.30873) (xy 134.880306 -285.32059) (xy 134.92992 -285.340062) (xy 134.976078 -285.366711)
			(xy 135.017749 -285.399942) (xy 135.054001 -285.439013) (xy 135.084025 -285.48305) (xy 135.107151 -285.531071)
			(xy 135.122861 -285.582001) (xy 135.130804 -285.634705) (xy 135.131302 -285.661354) (xy 135.130809 -285.687749)
			(xy 135.359384 -285.687749) (xy 135.359384 -285.634451) (xy 135.367327 -285.581747) (xy 135.383037 -285.530817)
			(xy 135.406163 -285.482796) (xy 135.436187 -285.438759) (xy 135.472439 -285.399688) (xy 135.51411 -285.366457)
			(xy 135.560268 -285.339808) (xy 135.609882 -285.320336) (xy 135.661844 -285.308476) (xy 135.714994 -285.304493)
			(xy 135.768144 -285.308476) (xy 135.820106 -285.320336) (xy 135.86972 -285.339808) (xy 135.915878 -285.366457)
			(xy 135.957549 -285.399688) (xy 135.993801 -285.438759) (xy 136.023825 -285.482796) (xy 136.046951 -285.530817)
			(xy 136.062661 -285.581747) (xy 136.070604 -285.634451) (xy 136.071102 -285.6611) (xy 136.070604 -285.687749)
			(xy 136.070566 -285.688003) (xy 136.299184 -285.688003) (xy 136.299184 -285.634705) (xy 136.307127 -285.582001)
			(xy 136.322837 -285.531071) (xy 136.345963 -285.48305) (xy 136.375987 -285.439013) (xy 136.412239 -285.399942)
			(xy 136.45391 -285.366711) (xy 136.500068 -285.340062) (xy 136.549682 -285.32059) (xy 136.601644 -285.30873)
			(xy 136.654794 -285.304747) (xy 136.707944 -285.30873) (xy 136.759906 -285.32059) (xy 136.80952 -285.340062)
			(xy 136.855678 -285.366711) (xy 136.897349 -285.399942) (xy 136.933601 -285.439013) (xy 136.963625 -285.48305)
			(xy 136.986751 -285.531071) (xy 137.002461 -285.582001) (xy 137.010404 -285.634705) (xy 137.010902 -285.661354)
			(xy 137.010404 -285.688003) (xy 137.002461 -285.740707) (xy 136.986751 -285.791637) (xy 136.963625 -285.839658)
			(xy 136.933601 -285.883695) (xy 136.897349 -285.922766) (xy 136.855678 -285.955997) (xy 136.80952 -285.982646)
			(xy 136.759906 -286.002118) (xy 136.707944 -286.013978) (xy 136.654794 -286.017962) (xy 136.601644 -286.013978)
			(xy 136.549682 -286.002118) (xy 136.500068 -285.982646) (xy 136.45391 -285.955997) (xy 136.412239 -285.922766)
			(xy 136.375987 -285.883695) (xy 136.345963 -285.839658) (xy 136.322837 -285.791637) (xy 136.307127 -285.740707)
			(xy 136.299184 -285.688003) (xy 136.070566 -285.688003) (xy 136.062661 -285.740453) (xy 136.046951 -285.791383)
			(xy 136.023825 -285.839404) (xy 135.993801 -285.883441) (xy 135.957549 -285.922512) (xy 135.915878 -285.955743)
			(xy 135.86972 -285.982392) (xy 135.820106 -286.001864) (xy 135.768144 -286.013724) (xy 135.714994 -286.017708)
			(xy 135.661844 -286.013724) (xy 135.609882 -286.001864) (xy 135.560268 -285.982392) (xy 135.51411 -285.955743)
			(xy 135.472439 -285.922512) (xy 135.436187 -285.883441) (xy 135.406163 -285.839404) (xy 135.383037 -285.791383)
			(xy 135.367327 -285.740453) (xy 135.359384 -285.687749) (xy 135.130809 -285.687749) (xy 135.130804 -285.688003)
			(xy 135.122861 -285.740707) (xy 135.107151 -285.791637) (xy 135.084025 -285.839658) (xy 135.054001 -285.883695)
			(xy 135.017749 -285.922766) (xy 134.976078 -285.955997) (xy 134.92992 -285.982646) (xy 134.880306 -286.002118)
			(xy 134.828344 -286.013978) (xy 134.775194 -286.017962) (xy 134.722044 -286.013978) (xy 134.670082 -286.002118)
			(xy 134.620468 -285.982646) (xy 134.57431 -285.955997) (xy 134.532639 -285.922766) (xy 134.496387 -285.883695)
			(xy 134.466363 -285.839658) (xy 134.443237 -285.791637) (xy 134.427527 -285.740707) (xy 134.419584 -285.688003)
			(xy 134.190932 -285.688003) (xy 134.183748 -285.737716) (xy 134.169217 -285.786873) (xy 134.147787 -285.833438)
			(xy 134.1199 -285.876448) (xy 134.086132 -285.915013) (xy 134.047183 -285.948337) (xy 134.003858 -285.975731)
			(xy 133.957051 -285.996628) (xy 133.907732 -286.010596) (xy 133.882384 -286.014414) (xy 133.857746 -286.017716)
			(xy 133.68528 -286.31642) (xy 133.694932 -286.339534) (xy 133.703453 -286.361164) (xy 133.715439 -286.406083)
			(xy 133.721482 -286.452179) (xy 133.721856 -286.475424) (xy 133.721358 -286.502073) (xy 133.949684 -286.502073)
			(xy 133.949684 -286.448775) (xy 133.957627 -286.396071) (xy 133.973337 -286.345141) (xy 133.996463 -286.29712)
			(xy 134.026487 -286.253083) (xy 134.062739 -286.214012) (xy 134.10441 -286.180781) (xy 134.150568 -286.154132)
			(xy 134.200182 -286.13466) (xy 134.252144 -286.1228) (xy 134.305294 -286.118817) (xy 134.358444 -286.1228)
			(xy 134.410406 -286.13466) (xy 134.46002 -286.154132) (xy 134.506178 -286.180781) (xy 134.547849 -286.214012)
			(xy 134.584101 -286.253083) (xy 134.614125 -286.29712) (xy 134.637251 -286.345141) (xy 134.652961 -286.396071)
			(xy 134.660904 -286.448775) (xy 134.661402 -286.475424) (xy 134.660909 -286.501819) (xy 134.889484 -286.501819)
			(xy 134.889484 -286.448521) (xy 134.897427 -286.395817) (xy 134.913137 -286.344887) (xy 134.936263 -286.296866)
			(xy 134.966287 -286.252829) (xy 135.002539 -286.213758) (xy 135.04421 -286.180527) (xy 135.090368 -286.153878)
			(xy 135.139982 -286.134406) (xy 135.191944 -286.122546) (xy 135.245094 -286.118563) (xy 135.298244 -286.122546)
			(xy 135.350206 -286.134406) (xy 135.39982 -286.153878) (xy 135.445978 -286.180527) (xy 135.487649 -286.213758)
			(xy 135.523901 -286.252829) (xy 135.553925 -286.296866) (xy 135.577051 -286.344887) (xy 135.592761 -286.395817)
			(xy 135.600704 -286.448521) (xy 135.601202 -286.47517) (xy 135.600704 -286.501819) (xy 135.829284 -286.501819)
			(xy 135.829284 -286.448521) (xy 135.837227 -286.395817) (xy 135.852937 -286.344887) (xy 135.876063 -286.296866)
			(xy 135.906087 -286.252829) (xy 135.942339 -286.213758) (xy 135.98401 -286.180527) (xy 136.030168 -286.153878)
			(xy 136.079782 -286.134406) (xy 136.131744 -286.122546) (xy 136.184894 -286.118563) (xy 136.238044 -286.122546)
			(xy 136.290006 -286.134406) (xy 136.33962 -286.153878) (xy 136.385778 -286.180527) (xy 136.427449 -286.213758)
			(xy 136.463701 -286.252829) (xy 136.493725 -286.296866) (xy 136.516851 -286.344887) (xy 136.532561 -286.395817)
			(xy 136.540504 -286.448521) (xy 136.541002 -286.47517) (xy 136.540504 -286.501819) (xy 136.532561 -286.554523)
			(xy 136.516851 -286.605453) (xy 136.493725 -286.653474) (xy 136.463701 -286.697511) (xy 136.427449 -286.736582)
			(xy 136.385778 -286.769813) (xy 136.33962 -286.796462) (xy 136.290006 -286.815934) (xy 136.238044 -286.827794)
			(xy 136.184894 -286.831778) (xy 136.131744 -286.827794) (xy 136.079782 -286.815934) (xy 136.030168 -286.796462)
			(xy 135.98401 -286.769813) (xy 135.942339 -286.736582) (xy 135.906087 -286.697511) (xy 135.876063 -286.653474)
			(xy 135.852937 -286.605453) (xy 135.837227 -286.554523) (xy 135.829284 -286.501819) (xy 135.600704 -286.501819)
			(xy 135.592761 -286.554523) (xy 135.577051 -286.605453) (xy 135.553925 -286.653474) (xy 135.523901 -286.697511)
			(xy 135.487649 -286.736582) (xy 135.445978 -286.769813) (xy 135.39982 -286.796462) (xy 135.350206 -286.815934)
			(xy 135.298244 -286.827794) (xy 135.245094 -286.831778) (xy 135.191944 -286.827794) (xy 135.139982 -286.815934)
			(xy 135.090368 -286.796462) (xy 135.04421 -286.769813) (xy 135.002539 -286.736582) (xy 134.966287 -286.697511)
			(xy 134.936263 -286.653474) (xy 134.913137 -286.605453) (xy 134.897427 -286.554523) (xy 134.889484 -286.501819)
			(xy 134.660909 -286.501819) (xy 134.660904 -286.502073) (xy 134.652961 -286.554777) (xy 134.637251 -286.605707)
			(xy 134.614125 -286.653728) (xy 134.584101 -286.697765) (xy 134.547849 -286.736836) (xy 134.506178 -286.770067)
			(xy 134.46002 -286.796716) (xy 134.410406 -286.816188) (xy 134.358444 -286.828048) (xy 134.305294 -286.832032)
			(xy 134.252144 -286.828048) (xy 134.200182 -286.816188) (xy 134.150568 -286.796716) (xy 134.10441 -286.770067)
			(xy 134.062739 -286.736836) (xy 134.026487 -286.697765) (xy 133.996463 -286.653728) (xy 133.973337 -286.605707)
			(xy 133.957627 -286.554777) (xy 133.949684 -286.502073) (xy 133.721358 -286.502073) (xy 133.713415 -286.554777)
			(xy 133.697705 -286.605707) (xy 133.674579 -286.653728) (xy 133.644555 -286.697765) (xy 133.608303 -286.736836)
			(xy 133.566632 -286.770067) (xy 133.520474 -286.796716) (xy 133.47086 -286.816188) (xy 133.418898 -286.828048)
			(xy 133.365748 -286.832032) (xy 133.312598 -286.828048) (xy 133.260636 -286.816188) (xy 133.211022 -286.796716)
			(xy 133.164864 -286.770067) (xy 133.123193 -286.736836) (xy 133.086941 -286.697765) (xy 133.056917 -286.653728)
			(xy 133.033791 -286.605707) (xy 133.018081 -286.554777) (xy 133.010138 -286.502073) (xy 133.00964 -286.475424)
			(xy 132.781802 -286.475424) (xy 132.781304 -286.502073) (xy 132.773361 -286.554777) (xy 132.757651 -286.605707)
			(xy 132.734525 -286.653728) (xy 132.704501 -286.697765) (xy 132.668249 -286.736836) (xy 132.626578 -286.770067)
			(xy 132.58042 -286.796716) (xy 132.530806 -286.816188) (xy 132.478844 -286.828048) (xy 132.425694 -286.832032)
			(xy 132.372544 -286.828048) (xy 132.320582 -286.816188) (xy 132.270968 -286.796716) (xy 132.22481 -286.770067)
			(xy 132.183139 -286.736836) (xy 132.146887 -286.697765) (xy 132.116863 -286.653728) (xy 132.093737 -286.605707)
			(xy 132.078027 -286.554777) (xy 132.070084 -286.502073) (xy 131.841758 -286.502073) (xy 131.833815 -286.554777)
			(xy 131.818105 -286.605707) (xy 131.794979 -286.653728) (xy 131.764955 -286.697765) (xy 131.728703 -286.736836)
			(xy 131.687032 -286.770067) (xy 131.640874 -286.796716) (xy 131.59126 -286.816188) (xy 131.539298 -286.828048)
			(xy 131.486148 -286.832032) (xy 131.432998 -286.828048) (xy 131.381036 -286.816188) (xy 131.331422 -286.796716)
			(xy 131.285264 -286.770067) (xy 131.243593 -286.736836) (xy 131.207341 -286.697765) (xy 131.177317 -286.653728)
			(xy 131.154191 -286.605707) (xy 131.138481 -286.554777) (xy 131.130538 -286.502073) (xy 131.13004 -286.475424)
			(xy 130.902202 -286.475424) (xy 130.901704 -286.502073) (xy 130.893761 -286.554777) (xy 130.878051 -286.605707)
			(xy 130.854925 -286.653728) (xy 130.824901 -286.697765) (xy 130.788649 -286.736836) (xy 130.746978 -286.770067)
			(xy 130.70082 -286.796716) (xy 130.651206 -286.816188) (xy 130.599244 -286.828048) (xy 130.546094 -286.832032)
			(xy 130.492944 -286.828048) (xy 130.440982 -286.816188) (xy 130.391368 -286.796716) (xy 130.34521 -286.770067)
			(xy 130.303539 -286.736836) (xy 130.267287 -286.697765) (xy 130.237263 -286.653728) (xy 130.214137 -286.605707)
			(xy 130.198427 -286.554777) (xy 130.190484 -286.502073) (xy 129.962158 -286.502073) (xy 129.954215 -286.554777)
			(xy 129.938505 -286.605707) (xy 129.915379 -286.653728) (xy 129.885355 -286.697765) (xy 129.849103 -286.736836)
			(xy 129.807432 -286.770067) (xy 129.761274 -286.796716) (xy 129.71166 -286.816188) (xy 129.659698 -286.828048)
			(xy 129.606548 -286.832032) (xy 129.553398 -286.828048) (xy 129.501436 -286.816188) (xy 129.451822 -286.796716)
			(xy 129.405664 -286.770067) (xy 129.363993 -286.736836) (xy 129.327741 -286.697765) (xy 129.297717 -286.653728)
			(xy 129.274591 -286.605707) (xy 129.258881 -286.554777) (xy 129.250938 -286.502073) (xy 129.25044 -286.475424)
			(xy 129.022602 -286.475424) (xy 129.022104 -286.502073) (xy 129.014161 -286.554777) (xy 128.998451 -286.605707)
			(xy 128.975325 -286.653728) (xy 128.945301 -286.697765) (xy 128.909049 -286.736836) (xy 128.867378 -286.770067)
			(xy 128.82122 -286.796716) (xy 128.771606 -286.816188) (xy 128.719644 -286.828048) (xy 128.666494 -286.832032)
			(xy 128.613344 -286.828048) (xy 128.561382 -286.816188) (xy 128.511768 -286.796716) (xy 128.46561 -286.770067)
			(xy 128.423939 -286.736836) (xy 128.387687 -286.697765) (xy 128.357663 -286.653728) (xy 128.334537 -286.605707)
			(xy 128.318827 -286.554777) (xy 128.310884 -286.502073) (xy 128.082558 -286.502073) (xy 128.074615 -286.554777)
			(xy 128.058905 -286.605707) (xy 128.035779 -286.653728) (xy 128.005755 -286.697765) (xy 127.969503 -286.736836)
			(xy 127.927832 -286.770067) (xy 127.881674 -286.796716) (xy 127.83206 -286.816188) (xy 127.780098 -286.828048)
			(xy 127.726948 -286.832032) (xy 127.673798 -286.828048) (xy 127.621836 -286.816188) (xy 127.572222 -286.796716)
			(xy 127.526064 -286.770067) (xy 127.484393 -286.736836) (xy 127.448141 -286.697765) (xy 127.418117 -286.653728)
			(xy 127.394991 -286.605707) (xy 127.379281 -286.554777) (xy 127.371338 -286.502073) (xy 127.37084 -286.475424)
			(xy 127.143002 -286.475424) (xy 127.142504 -286.502073) (xy 127.134561 -286.554777) (xy 127.118851 -286.605707)
			(xy 127.095725 -286.653728) (xy 127.065701 -286.697765) (xy 127.029449 -286.736836) (xy 126.987778 -286.770067)
			(xy 126.94162 -286.796716) (xy 126.892006 -286.816188) (xy 126.840044 -286.828048) (xy 126.786894 -286.832032)
			(xy 126.733744 -286.828048) (xy 126.681782 -286.816188) (xy 126.632168 -286.796716) (xy 126.58601 -286.770067)
			(xy 126.544339 -286.736836) (xy 126.508087 -286.697765) (xy 126.478063 -286.653728) (xy 126.454937 -286.605707)
			(xy 126.439227 -286.554777) (xy 126.431284 -286.502073) (xy 126.202958 -286.502073) (xy 126.195015 -286.554777)
			(xy 126.179305 -286.605707) (xy 126.156179 -286.653728) (xy 126.126155 -286.697765) (xy 126.089903 -286.736836)
			(xy 126.048232 -286.770067) (xy 126.002074 -286.796716) (xy 125.95246 -286.816188) (xy 125.900498 -286.828048)
			(xy 125.847348 -286.832032) (xy 125.794198 -286.828048) (xy 125.742236 -286.816188) (xy 125.692622 -286.796716)
			(xy 125.646464 -286.770067) (xy 125.604793 -286.736836) (xy 125.568541 -286.697765) (xy 125.538517 -286.653728)
			(xy 125.515391 -286.605707) (xy 125.499681 -286.554777) (xy 125.491738 -286.502073) (xy 125.49124 -286.475424)
			(xy 125.263402 -286.475424) (xy 125.262904 -286.502073) (xy 125.254961 -286.554777) (xy 125.239251 -286.605707)
			(xy 125.216125 -286.653728) (xy 125.186101 -286.697765) (xy 125.149849 -286.736836) (xy 125.108178 -286.770067)
			(xy 125.06202 -286.796716) (xy 125.012406 -286.816188) (xy 124.960444 -286.828048) (xy 124.907294 -286.832032)
			(xy 124.854144 -286.828048) (xy 124.802182 -286.816188) (xy 124.752568 -286.796716) (xy 124.70641 -286.770067)
			(xy 124.664739 -286.736836) (xy 124.628487 -286.697765) (xy 124.598463 -286.653728) (xy 124.575337 -286.605707)
			(xy 124.559627 -286.554777) (xy 124.551684 -286.502073) (xy 124.323358 -286.502073) (xy 124.315415 -286.554777)
			(xy 124.299705 -286.605707) (xy 124.276579 -286.653728) (xy 124.246555 -286.697765) (xy 124.210303 -286.736836)
			(xy 124.168632 -286.770067) (xy 124.122474 -286.796716) (xy 124.07286 -286.816188) (xy 124.020898 -286.828048)
			(xy 123.967748 -286.832032) (xy 123.914598 -286.828048) (xy 123.862636 -286.816188) (xy 123.813022 -286.796716)
			(xy 123.766864 -286.770067) (xy 123.725193 -286.736836) (xy 123.688941 -286.697765) (xy 123.658917 -286.653728)
			(xy 123.635791 -286.605707) (xy 123.620081 -286.554777) (xy 123.612138 -286.502073) (xy 123.61164 -286.475424)
			(xy 123.383802 -286.475424) (xy 123.383304 -286.502073) (xy 123.375361 -286.554777) (xy 123.359651 -286.605707)
			(xy 123.336525 -286.653728) (xy 123.306501 -286.697765) (xy 123.270249 -286.736836) (xy 123.228578 -286.770067)
			(xy 123.18242 -286.796716) (xy 123.132806 -286.816188) (xy 123.080844 -286.828048) (xy 123.027694 -286.832032)
			(xy 122.974544 -286.828048) (xy 122.922582 -286.816188) (xy 122.872968 -286.796716) (xy 122.82681 -286.770067)
			(xy 122.785139 -286.736836) (xy 122.748887 -286.697765) (xy 122.718863 -286.653728) (xy 122.695737 -286.605707)
			(xy 122.680027 -286.554777) (xy 122.672084 -286.502073) (xy 122.443758 -286.502073) (xy 122.435815 -286.554777)
			(xy 122.420105 -286.605707) (xy 122.396979 -286.653728) (xy 122.366955 -286.697765) (xy 122.330703 -286.736836)
			(xy 122.289032 -286.770067) (xy 122.242874 -286.796716) (xy 122.19326 -286.816188) (xy 122.141298 -286.828048)
			(xy 122.088148 -286.832032) (xy 122.034998 -286.828048) (xy 121.983036 -286.816188) (xy 121.933422 -286.796716)
			(xy 121.887264 -286.770067) (xy 121.845593 -286.736836) (xy 121.809341 -286.697765) (xy 121.779317 -286.653728)
			(xy 121.756191 -286.605707) (xy 121.740481 -286.554777) (xy 121.732538 -286.502073) (xy 121.73204 -286.475424)
			(xy 121.504202 -286.475424) (xy 121.503704 -286.502073) (xy 121.495761 -286.554777) (xy 121.480051 -286.605707)
			(xy 121.456925 -286.653728) (xy 121.426901 -286.697765) (xy 121.390649 -286.736836) (xy 121.348978 -286.770067)
			(xy 121.30282 -286.796716) (xy 121.253206 -286.816188) (xy 121.201244 -286.828048) (xy 121.148094 -286.832032)
			(xy 121.094944 -286.828048) (xy 121.042982 -286.816188) (xy 120.993368 -286.796716) (xy 120.94721 -286.770067)
			(xy 120.905539 -286.736836) (xy 120.869287 -286.697765) (xy 120.839263 -286.653728) (xy 120.816137 -286.605707)
			(xy 120.800427 -286.554777) (xy 120.792484 -286.502073) (xy 120.564158 -286.502073) (xy 120.564131 -286.503544)
			(xy 120.555301 -286.559087) (xy 120.53785 -286.612552) (xy 120.51221 -286.662608) (xy 120.479021 -286.708011)
			(xy 120.439106 -286.747631) (xy 120.393459 -286.780485) (xy 120.343215 -286.805753) (xy 120.289623 -286.822809)
			(xy 120.261888 -286.827468) (xy 120.248031 -286.82997) (xy 120.222367 -286.841528) (xy 120.200836 -286.859658)
			(xy 120.185078 -286.882981) (xy 120.176292 -286.909722) (xy 120.175145 -286.937846) (xy 120.181726 -286.965213)
			(xy 120.195534 -286.989741) (xy 120.205246 -286.999934) (xy 120.263412 -287.0581) (xy 120.273514 -287.067567)
			(xy 120.297609 -287.081178) (xy 120.324478 -287.087801) (xy 120.352138 -287.086949) (xy 120.378548 -287.078684)
			(xy 120.401759 -287.063616) (xy 120.41124 -287.053528) (xy 120.42822 -287.034957) (xy 120.466508 -287.002306)
			(xy 120.509012 -286.975371) (xy 120.554885 -286.954689) (xy 120.603214 -286.940672) (xy 120.653034 -286.9336)
			(xy 120.678194 -286.933132) (xy 120.706179 -286.933652) (xy 120.761458 -286.942407) (xy 120.814688 -286.959703)
			(xy 120.864556 -286.985114) (xy 120.909835 -287.018013) (xy 120.949409 -287.057591) (xy 120.982304 -287.102873)
			(xy 121.00771 -287.152743) (xy 121.025001 -287.205975) (xy 121.033751 -287.261255) (xy 121.034302 -287.28924)
			(xy 121.033866 -287.3144) (xy 121.033654 -287.315889) (xy 121.262384 -287.315889) (xy 121.262384 -287.262591)
			(xy 121.270327 -287.209887) (xy 121.286037 -287.158957) (xy 121.309163 -287.110936) (xy 121.339187 -287.066899)
			(xy 121.375439 -287.027828) (xy 121.41711 -286.994597) (xy 121.463268 -286.967948) (xy 121.512882 -286.948476)
			(xy 121.564844 -286.936616) (xy 121.617994 -286.932633) (xy 121.671144 -286.936616) (xy 121.723106 -286.948476)
			(xy 121.77272 -286.967948) (xy 121.818878 -286.994597) (xy 121.860549 -287.027828) (xy 121.896801 -287.066899)
			(xy 121.926825 -287.110936) (xy 121.949951 -287.158957) (xy 121.965661 -287.209887) (xy 121.973604 -287.262591)
			(xy 121.974102 -287.28924) (xy 121.973604 -287.315889) (xy 122.202184 -287.315889) (xy 122.202184 -287.262591)
			(xy 122.210127 -287.209887) (xy 122.225837 -287.158957) (xy 122.248963 -287.110936) (xy 122.278987 -287.066899)
			(xy 122.315239 -287.027828) (xy 122.35691 -286.994597) (xy 122.403068 -286.967948) (xy 122.452682 -286.948476)
			(xy 122.504644 -286.936616) (xy 122.557794 -286.932633) (xy 122.610944 -286.936616) (xy 122.662906 -286.948476)
			(xy 122.71252 -286.967948) (xy 122.758678 -286.994597) (xy 122.800349 -287.027828) (xy 122.836601 -287.066899)
			(xy 122.866625 -287.110936) (xy 122.889751 -287.158957) (xy 122.905461 -287.209887) (xy 122.913404 -287.262591)
			(xy 122.913902 -287.28924) (xy 122.913404 -287.315889) (xy 123.141984 -287.315889) (xy 123.141984 -287.262591)
			(xy 123.149927 -287.209887) (xy 123.165637 -287.158957) (xy 123.188763 -287.110936) (xy 123.218787 -287.066899)
			(xy 123.255039 -287.027828) (xy 123.29671 -286.994597) (xy 123.342868 -286.967948) (xy 123.392482 -286.948476)
			(xy 123.444444 -286.936616) (xy 123.497594 -286.932633) (xy 123.550744 -286.936616) (xy 123.602706 -286.948476)
			(xy 123.65232 -286.967948) (xy 123.698478 -286.994597) (xy 123.740149 -287.027828) (xy 123.776401 -287.066899)
			(xy 123.806425 -287.110936) (xy 123.829551 -287.158957) (xy 123.845261 -287.209887) (xy 123.853204 -287.262591)
			(xy 123.853702 -287.28924) (xy 123.853204 -287.315889) (xy 124.081784 -287.315889) (xy 124.081784 -287.262591)
			(xy 124.089727 -287.209887) (xy 124.105437 -287.158957) (xy 124.128563 -287.110936) (xy 124.158587 -287.066899)
			(xy 124.194839 -287.027828) (xy 124.23651 -286.994597) (xy 124.282668 -286.967948) (xy 124.332282 -286.948476)
			(xy 124.384244 -286.936616) (xy 124.437394 -286.932633) (xy 124.490544 -286.936616) (xy 124.542506 -286.948476)
			(xy 124.59212 -286.967948) (xy 124.638278 -286.994597) (xy 124.679949 -287.027828) (xy 124.716201 -287.066899)
			(xy 124.746225 -287.110936) (xy 124.769351 -287.158957) (xy 124.785061 -287.209887) (xy 124.793004 -287.262591)
			(xy 124.793502 -287.28924) (xy 124.793004 -287.315889) (xy 125.021584 -287.315889) (xy 125.021584 -287.262591)
			(xy 125.029527 -287.209887) (xy 125.045237 -287.158957) (xy 125.068363 -287.110936) (xy 125.098387 -287.066899)
			(xy 125.134639 -287.027828) (xy 125.17631 -286.994597) (xy 125.222468 -286.967948) (xy 125.272082 -286.948476)
			(xy 125.324044 -286.936616) (xy 125.377194 -286.932633) (xy 125.430344 -286.936616) (xy 125.482306 -286.948476)
			(xy 125.53192 -286.967948) (xy 125.578078 -286.994597) (xy 125.619749 -287.027828) (xy 125.656001 -287.066899)
			(xy 125.686025 -287.110936) (xy 125.709151 -287.158957) (xy 125.724861 -287.209887) (xy 125.732804 -287.262591)
			(xy 125.733302 -287.28924) (xy 125.732804 -287.315889) (xy 125.961384 -287.315889) (xy 125.961384 -287.262591)
			(xy 125.969327 -287.209887) (xy 125.985037 -287.158957) (xy 126.008163 -287.110936) (xy 126.038187 -287.066899)
			(xy 126.074439 -287.027828) (xy 126.11611 -286.994597) (xy 126.162268 -286.967948) (xy 126.211882 -286.948476)
			(xy 126.263844 -286.936616) (xy 126.316994 -286.932633) (xy 126.370144 -286.936616) (xy 126.422106 -286.948476)
			(xy 126.47172 -286.967948) (xy 126.517878 -286.994597) (xy 126.559549 -287.027828) (xy 126.595801 -287.066899)
			(xy 126.625825 -287.110936) (xy 126.648951 -287.158957) (xy 126.664661 -287.209887) (xy 126.672604 -287.262591)
			(xy 126.673102 -287.28924) (xy 126.672604 -287.315889) (xy 126.901184 -287.315889) (xy 126.901184 -287.262591)
			(xy 126.909127 -287.209887) (xy 126.924837 -287.158957) (xy 126.947963 -287.110936) (xy 126.977987 -287.066899)
			(xy 127.014239 -287.027828) (xy 127.05591 -286.994597) (xy 127.102068 -286.967948) (xy 127.151682 -286.948476)
			(xy 127.203644 -286.936616) (xy 127.256794 -286.932633) (xy 127.309944 -286.936616) (xy 127.361906 -286.948476)
			(xy 127.41152 -286.967948) (xy 127.457678 -286.994597) (xy 127.499349 -287.027828) (xy 127.535601 -287.066899)
			(xy 127.565625 -287.110936) (xy 127.588751 -287.158957) (xy 127.604461 -287.209887) (xy 127.612404 -287.262591)
			(xy 127.612902 -287.28924) (xy 127.612404 -287.315889) (xy 127.840984 -287.315889) (xy 127.840984 -287.262591)
			(xy 127.848927 -287.209887) (xy 127.864637 -287.158957) (xy 127.887763 -287.110936) (xy 127.917787 -287.066899)
			(xy 127.954039 -287.027828) (xy 127.99571 -286.994597) (xy 128.041868 -286.967948) (xy 128.091482 -286.948476)
			(xy 128.143444 -286.936616) (xy 128.196594 -286.932633) (xy 128.249744 -286.936616) (xy 128.301706 -286.948476)
			(xy 128.35132 -286.967948) (xy 128.397478 -286.994597) (xy 128.439149 -287.027828) (xy 128.475401 -287.066899)
			(xy 128.505425 -287.110936) (xy 128.528551 -287.158957) (xy 128.544261 -287.209887) (xy 128.552204 -287.262591)
			(xy 128.552702 -287.28924) (xy 128.552204 -287.315889) (xy 128.780784 -287.315889) (xy 128.780784 -287.262591)
			(xy 128.788727 -287.209887) (xy 128.804437 -287.158957) (xy 128.827563 -287.110936) (xy 128.857587 -287.066899)
			(xy 128.893839 -287.027828) (xy 128.93551 -286.994597) (xy 128.981668 -286.967948) (xy 129.031282 -286.948476)
			(xy 129.083244 -286.936616) (xy 129.136394 -286.932633) (xy 129.189544 -286.936616) (xy 129.241506 -286.948476)
			(xy 129.29112 -286.967948) (xy 129.337278 -286.994597) (xy 129.378949 -287.027828) (xy 129.415201 -287.066899)
			(xy 129.445225 -287.110936) (xy 129.468351 -287.158957) (xy 129.484061 -287.209887) (xy 129.492004 -287.262591)
			(xy 129.492502 -287.28924) (xy 129.492004 -287.315889) (xy 129.720584 -287.315889) (xy 129.720584 -287.262591)
			(xy 129.728527 -287.209887) (xy 129.744237 -287.158957) (xy 129.767363 -287.110936) (xy 129.797387 -287.066899)
			(xy 129.833639 -287.027828) (xy 129.87531 -286.994597) (xy 129.921468 -286.967948) (xy 129.971082 -286.948476)
			(xy 130.023044 -286.936616) (xy 130.076194 -286.932633) (xy 130.129344 -286.936616) (xy 130.181306 -286.948476)
			(xy 130.23092 -286.967948) (xy 130.277078 -286.994597) (xy 130.318749 -287.027828) (xy 130.355001 -287.066899)
			(xy 130.385025 -287.110936) (xy 130.408151 -287.158957) (xy 130.423861 -287.209887) (xy 130.431804 -287.262591)
			(xy 130.432302 -287.28924) (xy 130.431804 -287.315889) (xy 130.660384 -287.315889) (xy 130.660384 -287.262591)
			(xy 130.668327 -287.209887) (xy 130.684037 -287.158957) (xy 130.707163 -287.110936) (xy 130.737187 -287.066899)
			(xy 130.773439 -287.027828) (xy 130.81511 -286.994597) (xy 130.861268 -286.967948) (xy 130.910882 -286.948476)
			(xy 130.962844 -286.936616) (xy 131.015994 -286.932633) (xy 131.069144 -286.936616) (xy 131.121106 -286.948476)
			(xy 131.17072 -286.967948) (xy 131.216878 -286.994597) (xy 131.258549 -287.027828) (xy 131.294801 -287.066899)
			(xy 131.324825 -287.110936) (xy 131.347951 -287.158957) (xy 131.363661 -287.209887) (xy 131.371604 -287.262591)
			(xy 131.372102 -287.28924) (xy 131.371604 -287.315889) (xy 131.600184 -287.315889) (xy 131.600184 -287.262591)
			(xy 131.608127 -287.209887) (xy 131.623837 -287.158957) (xy 131.646963 -287.110936) (xy 131.676987 -287.066899)
			(xy 131.713239 -287.027828) (xy 131.75491 -286.994597) (xy 131.801068 -286.967948) (xy 131.850682 -286.948476)
			(xy 131.902644 -286.936616) (xy 131.955794 -286.932633) (xy 132.008944 -286.936616) (xy 132.060906 -286.948476)
			(xy 132.11052 -286.967948) (xy 132.156678 -286.994597) (xy 132.198349 -287.027828) (xy 132.234601 -287.066899)
			(xy 132.264625 -287.110936) (xy 132.287751 -287.158957) (xy 132.303461 -287.209887) (xy 132.311404 -287.262591)
			(xy 132.311902 -287.28924) (xy 132.311404 -287.315889) (xy 132.539984 -287.315889) (xy 132.539984 -287.262591)
			(xy 132.547927 -287.209887) (xy 132.563637 -287.158957) (xy 132.586763 -287.110936) (xy 132.616787 -287.066899)
			(xy 132.653039 -287.027828) (xy 132.69471 -286.994597) (xy 132.740868 -286.967948) (xy 132.790482 -286.948476)
			(xy 132.842444 -286.936616) (xy 132.895594 -286.932633) (xy 132.948744 -286.936616) (xy 133.000706 -286.948476)
			(xy 133.05032 -286.967948) (xy 133.096478 -286.994597) (xy 133.138149 -287.027828) (xy 133.174401 -287.066899)
			(xy 133.204425 -287.110936) (xy 133.227551 -287.158957) (xy 133.243261 -287.209887) (xy 133.251204 -287.262591)
			(xy 133.251702 -287.28924) (xy 133.251204 -287.315889) (xy 133.480038 -287.315889) (xy 133.480038 -287.262591)
			(xy 133.487981 -287.209887) (xy 133.503691 -287.158957) (xy 133.526817 -287.110936) (xy 133.556841 -287.066899)
			(xy 133.593093 -287.027828) (xy 133.634764 -286.994597) (xy 133.680922 -286.967948) (xy 133.730536 -286.948476)
			(xy 133.782498 -286.936616) (xy 133.835648 -286.932633) (xy 133.888798 -286.936616) (xy 133.94076 -286.948476)
			(xy 133.990374 -286.967948) (xy 134.036532 -286.994597) (xy 134.078203 -287.027828) (xy 134.114455 -287.066899)
			(xy 134.144479 -287.110936) (xy 134.167605 -287.158957) (xy 134.183315 -287.209887) (xy 134.191258 -287.262591)
			(xy 134.191756 -287.28924) (xy 134.191258 -287.315889) (xy 134.419838 -287.315889) (xy 134.419838 -287.262591)
			(xy 134.427781 -287.209887) (xy 134.443491 -287.158957) (xy 134.466617 -287.110936) (xy 134.496641 -287.066899)
			(xy 134.532893 -287.027828) (xy 134.574564 -286.994597) (xy 134.620722 -286.967948) (xy 134.670336 -286.948476)
			(xy 134.722298 -286.936616) (xy 134.775448 -286.932633) (xy 134.828598 -286.936616) (xy 134.88056 -286.948476)
			(xy 134.930174 -286.967948) (xy 134.976332 -286.994597) (xy 135.018003 -287.027828) (xy 135.054255 -287.066899)
			(xy 135.084279 -287.110936) (xy 135.107405 -287.158957) (xy 135.123115 -287.209887) (xy 135.131058 -287.262591)
			(xy 135.131556 -287.28924) (xy 135.131058 -287.315889) (xy 135.359384 -287.315889) (xy 135.359384 -287.262591)
			(xy 135.367327 -287.209887) (xy 135.383037 -287.158957) (xy 135.406163 -287.110936) (xy 135.436187 -287.066899)
			(xy 135.472439 -287.027828) (xy 135.51411 -286.994597) (xy 135.560268 -286.967948) (xy 135.609882 -286.948476)
			(xy 135.661844 -286.936616) (xy 135.714994 -286.932633) (xy 135.768144 -286.936616) (xy 135.820106 -286.948476)
			(xy 135.86972 -286.967948) (xy 135.915878 -286.994597) (xy 135.957549 -287.027828) (xy 135.993801 -287.066899)
			(xy 136.023825 -287.110936) (xy 136.046951 -287.158957) (xy 136.062661 -287.209887) (xy 136.070604 -287.262591)
			(xy 136.071102 -287.28924) (xy 136.070604 -287.315889) (xy 136.062661 -287.368593) (xy 136.046951 -287.419523)
			(xy 136.023825 -287.467544) (xy 135.993801 -287.511581) (xy 135.957549 -287.550652) (xy 135.915878 -287.583883)
			(xy 135.86972 -287.610532) (xy 135.820106 -287.630004) (xy 135.768144 -287.641864) (xy 135.714994 -287.645848)
			(xy 135.661844 -287.641864) (xy 135.609882 -287.630004) (xy 135.560268 -287.610532) (xy 135.51411 -287.583883)
			(xy 135.472439 -287.550652) (xy 135.436187 -287.511581) (xy 135.406163 -287.467544) (xy 135.383037 -287.419523)
			(xy 135.367327 -287.368593) (xy 135.359384 -287.315889) (xy 135.131058 -287.315889) (xy 135.123115 -287.368593)
			(xy 135.107405 -287.419523) (xy 135.084279 -287.467544) (xy 135.054255 -287.511581) (xy 135.018003 -287.550652)
			(xy 134.976332 -287.583883) (xy 134.930174 -287.610532) (xy 134.88056 -287.630004) (xy 134.828598 -287.641864)
			(xy 134.775448 -287.645848) (xy 134.722298 -287.641864) (xy 134.670336 -287.630004) (xy 134.620722 -287.610532)
			(xy 134.574564 -287.583883) (xy 134.532893 -287.550652) (xy 134.496641 -287.511581) (xy 134.466617 -287.467544)
			(xy 134.443491 -287.419523) (xy 134.427781 -287.368593) (xy 134.419838 -287.315889) (xy 134.191258 -287.315889)
			(xy 134.183315 -287.368593) (xy 134.167605 -287.419523) (xy 134.144479 -287.467544) (xy 134.114455 -287.511581)
			(xy 134.078203 -287.550652) (xy 134.036532 -287.583883) (xy 133.990374 -287.610532) (xy 133.94076 -287.630004)
			(xy 133.888798 -287.641864) (xy 133.835648 -287.645848) (xy 133.782498 -287.641864) (xy 133.730536 -287.630004)
			(xy 133.680922 -287.610532) (xy 133.634764 -287.583883) (xy 133.593093 -287.550652) (xy 133.556841 -287.511581)
			(xy 133.526817 -287.467544) (xy 133.503691 -287.419523) (xy 133.487981 -287.368593) (xy 133.480038 -287.315889)
			(xy 133.251204 -287.315889) (xy 133.243261 -287.368593) (xy 133.227551 -287.419523) (xy 133.204425 -287.467544)
			(xy 133.174401 -287.511581) (xy 133.138149 -287.550652) (xy 133.096478 -287.583883) (xy 133.05032 -287.610532)
			(xy 133.000706 -287.630004) (xy 132.948744 -287.641864) (xy 132.895594 -287.645848) (xy 132.842444 -287.641864)
			(xy 132.790482 -287.630004) (xy 132.740868 -287.610532) (xy 132.69471 -287.583883) (xy 132.653039 -287.550652)
			(xy 132.616787 -287.511581) (xy 132.586763 -287.467544) (xy 132.563637 -287.419523) (xy 132.547927 -287.368593)
			(xy 132.539984 -287.315889) (xy 132.311404 -287.315889) (xy 132.303461 -287.368593) (xy 132.287751 -287.419523)
			(xy 132.264625 -287.467544) (xy 132.234601 -287.511581) (xy 132.198349 -287.550652) (xy 132.156678 -287.583883)
			(xy 132.11052 -287.610532) (xy 132.060906 -287.630004) (xy 132.008944 -287.641864) (xy 131.955794 -287.645848)
			(xy 131.902644 -287.641864) (xy 131.850682 -287.630004) (xy 131.801068 -287.610532) (xy 131.75491 -287.583883)
			(xy 131.713239 -287.550652) (xy 131.676987 -287.511581) (xy 131.646963 -287.467544) (xy 131.623837 -287.419523)
			(xy 131.608127 -287.368593) (xy 131.600184 -287.315889) (xy 131.371604 -287.315889) (xy 131.363661 -287.368593)
			(xy 131.347951 -287.419523) (xy 131.324825 -287.467544) (xy 131.294801 -287.511581) (xy 131.258549 -287.550652)
			(xy 131.216878 -287.583883) (xy 131.17072 -287.610532) (xy 131.121106 -287.630004) (xy 131.069144 -287.641864)
			(xy 131.015994 -287.645848) (xy 130.962844 -287.641864) (xy 130.910882 -287.630004) (xy 130.861268 -287.610532)
			(xy 130.81511 -287.583883) (xy 130.773439 -287.550652) (xy 130.737187 -287.511581) (xy 130.707163 -287.467544)
			(xy 130.684037 -287.419523) (xy 130.668327 -287.368593) (xy 130.660384 -287.315889) (xy 130.431804 -287.315889)
			(xy 130.423861 -287.368593) (xy 130.408151 -287.419523) (xy 130.385025 -287.467544) (xy 130.355001 -287.511581)
			(xy 130.318749 -287.550652) (xy 130.277078 -287.583883) (xy 130.23092 -287.610532) (xy 130.181306 -287.630004)
			(xy 130.129344 -287.641864) (xy 130.076194 -287.645848) (xy 130.023044 -287.641864) (xy 129.971082 -287.630004)
			(xy 129.921468 -287.610532) (xy 129.87531 -287.583883) (xy 129.833639 -287.550652) (xy 129.797387 -287.511581)
			(xy 129.767363 -287.467544) (xy 129.744237 -287.419523) (xy 129.728527 -287.368593) (xy 129.720584 -287.315889)
			(xy 129.492004 -287.315889) (xy 129.484061 -287.368593) (xy 129.468351 -287.419523) (xy 129.445225 -287.467544)
			(xy 129.415201 -287.511581) (xy 129.378949 -287.550652) (xy 129.337278 -287.583883) (xy 129.29112 -287.610532)
			(xy 129.241506 -287.630004) (xy 129.189544 -287.641864) (xy 129.136394 -287.645848) (xy 129.083244 -287.641864)
			(xy 129.031282 -287.630004) (xy 128.981668 -287.610532) (xy 128.93551 -287.583883) (xy 128.893839 -287.550652)
			(xy 128.857587 -287.511581) (xy 128.827563 -287.467544) (xy 128.804437 -287.419523) (xy 128.788727 -287.368593)
			(xy 128.780784 -287.315889) (xy 128.552204 -287.315889) (xy 128.544261 -287.368593) (xy 128.528551 -287.419523)
			(xy 128.505425 -287.467544) (xy 128.475401 -287.511581) (xy 128.439149 -287.550652) (xy 128.397478 -287.583883)
			(xy 128.35132 -287.610532) (xy 128.301706 -287.630004) (xy 128.249744 -287.641864) (xy 128.196594 -287.645848)
			(xy 128.143444 -287.641864) (xy 128.091482 -287.630004) (xy 128.041868 -287.610532) (xy 127.99571 -287.583883)
			(xy 127.954039 -287.550652) (xy 127.917787 -287.511581) (xy 127.887763 -287.467544) (xy 127.864637 -287.419523)
			(xy 127.848927 -287.368593) (xy 127.840984 -287.315889) (xy 127.612404 -287.315889) (xy 127.604461 -287.368593)
			(xy 127.588751 -287.419523) (xy 127.565625 -287.467544) (xy 127.535601 -287.511581) (xy 127.499349 -287.550652)
			(xy 127.457678 -287.583883) (xy 127.41152 -287.610532) (xy 127.361906 -287.630004) (xy 127.309944 -287.641864)
			(xy 127.256794 -287.645848) (xy 127.203644 -287.641864) (xy 127.151682 -287.630004) (xy 127.102068 -287.610532)
			(xy 127.05591 -287.583883) (xy 127.014239 -287.550652) (xy 126.977987 -287.511581) (xy 126.947963 -287.467544)
			(xy 126.924837 -287.419523) (xy 126.909127 -287.368593) (xy 126.901184 -287.315889) (xy 126.672604 -287.315889)
			(xy 126.664661 -287.368593) (xy 126.648951 -287.419523) (xy 126.625825 -287.467544) (xy 126.595801 -287.511581)
			(xy 126.559549 -287.550652) (xy 126.517878 -287.583883) (xy 126.47172 -287.610532) (xy 126.422106 -287.630004)
			(xy 126.370144 -287.641864) (xy 126.316994 -287.645848) (xy 126.263844 -287.641864) (xy 126.211882 -287.630004)
			(xy 126.162268 -287.610532) (xy 126.11611 -287.583883) (xy 126.074439 -287.550652) (xy 126.038187 -287.511581)
			(xy 126.008163 -287.467544) (xy 125.985037 -287.419523) (xy 125.969327 -287.368593) (xy 125.961384 -287.315889)
			(xy 125.732804 -287.315889) (xy 125.724861 -287.368593) (xy 125.709151 -287.419523) (xy 125.686025 -287.467544)
			(xy 125.656001 -287.511581) (xy 125.619749 -287.550652) (xy 125.578078 -287.583883) (xy 125.53192 -287.610532)
			(xy 125.482306 -287.630004) (xy 125.430344 -287.641864) (xy 125.377194 -287.645848) (xy 125.324044 -287.641864)
			(xy 125.272082 -287.630004) (xy 125.222468 -287.610532) (xy 125.17631 -287.583883) (xy 125.134639 -287.550652)
			(xy 125.098387 -287.511581) (xy 125.068363 -287.467544) (xy 125.045237 -287.419523) (xy 125.029527 -287.368593)
			(xy 125.021584 -287.315889) (xy 124.793004 -287.315889) (xy 124.785061 -287.368593) (xy 124.769351 -287.419523)
			(xy 124.746225 -287.467544) (xy 124.716201 -287.511581) (xy 124.679949 -287.550652) (xy 124.638278 -287.583883)
			(xy 124.59212 -287.610532) (xy 124.542506 -287.630004) (xy 124.490544 -287.641864) (xy 124.437394 -287.645848)
			(xy 124.384244 -287.641864) (xy 124.332282 -287.630004) (xy 124.282668 -287.610532) (xy 124.23651 -287.583883)
			(xy 124.194839 -287.550652) (xy 124.158587 -287.511581) (xy 124.128563 -287.467544) (xy 124.105437 -287.419523)
			(xy 124.089727 -287.368593) (xy 124.081784 -287.315889) (xy 123.853204 -287.315889) (xy 123.845261 -287.368593)
			(xy 123.829551 -287.419523) (xy 123.806425 -287.467544) (xy 123.776401 -287.511581) (xy 123.740149 -287.550652)
			(xy 123.698478 -287.583883) (xy 123.65232 -287.610532) (xy 123.602706 -287.630004) (xy 123.550744 -287.641864)
			(xy 123.497594 -287.645848) (xy 123.444444 -287.641864) (xy 123.392482 -287.630004) (xy 123.342868 -287.610532)
			(xy 123.29671 -287.583883) (xy 123.255039 -287.550652) (xy 123.218787 -287.511581) (xy 123.188763 -287.467544)
			(xy 123.165637 -287.419523) (xy 123.149927 -287.368593) (xy 123.141984 -287.315889) (xy 122.913404 -287.315889)
			(xy 122.905461 -287.368593) (xy 122.889751 -287.419523) (xy 122.866625 -287.467544) (xy 122.836601 -287.511581)
			(xy 122.800349 -287.550652) (xy 122.758678 -287.583883) (xy 122.71252 -287.610532) (xy 122.662906 -287.630004)
			(xy 122.610944 -287.641864) (xy 122.557794 -287.645848) (xy 122.504644 -287.641864) (xy 122.452682 -287.630004)
			(xy 122.403068 -287.610532) (xy 122.35691 -287.583883) (xy 122.315239 -287.550652) (xy 122.278987 -287.511581)
			(xy 122.248963 -287.467544) (xy 122.225837 -287.419523) (xy 122.210127 -287.368593) (xy 122.202184 -287.315889)
			(xy 121.973604 -287.315889) (xy 121.965661 -287.368593) (xy 121.949951 -287.419523) (xy 121.926825 -287.467544)
			(xy 121.896801 -287.511581) (xy 121.860549 -287.550652) (xy 121.818878 -287.583883) (xy 121.77272 -287.610532)
			(xy 121.723106 -287.630004) (xy 121.671144 -287.641864) (xy 121.617994 -287.645848) (xy 121.564844 -287.641864)
			(xy 121.512882 -287.630004) (xy 121.463268 -287.610532) (xy 121.41711 -287.583883) (xy 121.375439 -287.550652)
			(xy 121.339187 -287.511581) (xy 121.309163 -287.467544) (xy 121.286037 -287.419523) (xy 121.270327 -287.368593)
			(xy 121.262384 -287.315889) (xy 121.033654 -287.315889) (xy 121.026778 -287.364219) (xy 121.01275 -287.412544)
			(xy 120.99206 -287.458414) (xy 120.96512 -287.500916) (xy 120.932468 -287.539203) (xy 120.913906 -287.556194)
			(xy 120.903877 -287.565717) (xy 120.888879 -287.58894) (xy 120.88065 -287.615331) (xy 120.879789 -287.642962)
			(xy 120.886361 -287.669814) (xy 120.899885 -287.693925) (xy 120.909334 -287.704022) (xy 120.988328 -287.783016)
			(xy 121.019316 -287.771078) (xy 121.050375 -287.759809) (xy 121.115315 -287.74767) (xy 121.148348 -287.746948)
			(xy 121.17633 -287.747501) (xy 121.231604 -287.756261) (xy 121.284827 -287.773559) (xy 121.33469 -287.798969)
			(xy 121.379965 -287.831866) (xy 121.419537 -287.871438) (xy 121.452433 -287.916713) (xy 121.477842 -287.966576)
			(xy 121.49514 -288.0198) (xy 121.5039 -288.075074) (xy 121.504456 -288.103056) (xy 121.50376 -288.136091)
			(xy 121.491617 -288.201034) (xy 121.480326 -288.232088) (xy 121.468388 -288.263076) (xy 121.96318 -288.757868)
		)
		(stroke
			(width 0)
			(type solid)
		)
		(fill yes)
		(layer "In13.Cu")
		(net "PVCCFA_EHV_FIVRA_CPU1")
	)
	(gr_poly
		(pts
			(xy 87.448136 -288.802318) (xy 87.45696 -288.777816) (xy 87.480752 -288.731493) (xy 87.511038 -288.689129)
			(xy 87.547171 -288.651628) (xy 87.588381 -288.619789) (xy 87.63379 -288.594293) (xy 87.682427 -288.575683)
			(xy 87.733257 -288.564356) (xy 87.785194 -288.560553) (xy 87.837131 -288.564356) (xy 87.887961 -288.575683)
			(xy 87.936598 -288.594293) (xy 87.982007 -288.619789) (xy 88.023217 -288.651628) (xy 88.05935 -288.689129)
			(xy 88.089636 -288.731493) (xy 88.113428 -288.777816) (xy 88.122252 -288.802318) (xy 88.133936 -288.836608)
			(xy 88.376506 -288.836608) (xy 88.38819 -288.802318) (xy 88.397818 -288.77575) (xy 88.424262 -288.725811)
			(xy 88.458256 -288.680672) (xy 88.498947 -288.641463) (xy 88.545316 -288.609167) (xy 88.596201 -288.584593)
			(xy 88.650326 -288.568357) (xy 88.678258 -288.564066) (xy 88.702896 -288.560764) (xy 88.875362 -288.26206)
			(xy 88.86571 -288.238946) (xy 88.857195 -288.217314) (xy 88.84521 -288.172396) (xy 88.83917 -288.126301)
			(xy 88.838786 -288.103056) (xy 88.839284 -288.076407) (xy 88.847227 -288.023703) (xy 88.862937 -287.972773)
			(xy 88.886063 -287.924752) (xy 88.916087 -287.880715) (xy 88.952339 -287.841644) (xy 88.99401 -287.808413)
			(xy 89.040168 -287.781764) (xy 89.089782 -287.762292) (xy 89.141744 -287.750432) (xy 89.194894 -287.746449)
			(xy 89.248044 -287.750432) (xy 89.300006 -287.762292) (xy 89.34962 -287.781764) (xy 89.395778 -287.808413)
			(xy 89.437449 -287.841644) (xy 89.473701 -287.880715) (xy 89.503725 -287.924752) (xy 89.526851 -287.972773)
			(xy 89.542561 -288.023703) (xy 89.550504 -288.076407) (xy 89.551002 -288.103056) (xy 89.550553 -288.12868)
			(xy 89.5432 -288.179399) (xy 89.528655 -288.228541) (xy 89.507217 -288.275091) (xy 89.479329 -288.318088)
			(xy 89.445567 -288.356644) (xy 89.406628 -288.389964) (xy 89.363316 -288.41736) (xy 89.316524 -288.438265)
			(xy 89.26722 -288.452249) (xy 89.241884 -288.456116) (xy 89.217246 -288.459418) (xy 89.04478 -288.758122)
			(xy 89.054432 -288.781236) (xy 89.062306 -288.802318) (xy 89.07399 -288.836608) (xy 89.316052 -288.836608)
			(xy 89.327736 -288.802318) (xy 89.33656 -288.777816) (xy 89.360352 -288.731493) (xy 89.390638 -288.689129)
			(xy 89.426771 -288.651628) (xy 89.467981 -288.619789) (xy 89.51339 -288.594293) (xy 89.562027 -288.575683)
			(xy 89.612857 -288.564356) (xy 89.664794 -288.560553) (xy 89.716731 -288.564356) (xy 89.767561 -288.575683)
			(xy 89.816198 -288.594293) (xy 89.861607 -288.619789) (xy 89.902817 -288.651628) (xy 89.93895 -288.689129)
			(xy 89.969236 -288.731493) (xy 89.993028 -288.777816) (xy 90.001852 -288.802318) (xy 90.013536 -288.836608)
			(xy 90.256106 -288.836608) (xy 90.26779 -288.802318) (xy 90.277418 -288.77575) (xy 90.303862 -288.725811)
			(xy 90.337856 -288.680672) (xy 90.378547 -288.641463) (xy 90.424916 -288.609167) (xy 90.475801 -288.584593)
			(xy 90.529926 -288.568357) (xy 90.557858 -288.564066) (xy 90.582496 -288.560764) (xy 90.754962 -288.26206)
			(xy 90.74531 -288.238946) (xy 90.736795 -288.217314) (xy 90.72481 -288.172396) (xy 90.71877 -288.126301)
			(xy 90.718386 -288.103056) (xy 90.718884 -288.076407) (xy 90.726827 -288.023703) (xy 90.742537 -287.972773)
			(xy 90.765663 -287.924752) (xy 90.795687 -287.880715) (xy 90.831939 -287.841644) (xy 90.87361 -287.808413)
			(xy 90.919768 -287.781764) (xy 90.969382 -287.762292) (xy 91.021344 -287.750432) (xy 91.074494 -287.746449)
			(xy 91.127644 -287.750432) (xy 91.179606 -287.762292) (xy 91.22922 -287.781764) (xy 91.275378 -287.808413)
			(xy 91.317049 -287.841644) (xy 91.353301 -287.880715) (xy 91.383325 -287.924752) (xy 91.406451 -287.972773)
			(xy 91.422161 -288.023703) (xy 91.430104 -288.076407) (xy 91.430602 -288.103056) (xy 91.430153 -288.12868)
			(xy 91.4228 -288.179399) (xy 91.408255 -288.228541) (xy 91.386817 -288.275091) (xy 91.358929 -288.318088)
			(xy 91.325167 -288.356644) (xy 91.286228 -288.389964) (xy 91.242916 -288.41736) (xy 91.196124 -288.438265)
			(xy 91.14682 -288.452249) (xy 91.121484 -288.456116) (xy 91.096846 -288.459418) (xy 90.92438 -288.758122)
			(xy 90.934032 -288.781236) (xy 90.941906 -288.802318) (xy 90.95359 -288.836608) (xy 91.195906 -288.836608)
			(xy 91.20759 -288.802318) (xy 91.216414 -288.777816) (xy 91.240206 -288.731493) (xy 91.270492 -288.689129)
			(xy 91.306625 -288.651628) (xy 91.347835 -288.619789) (xy 91.393244 -288.594293) (xy 91.441881 -288.575683)
			(xy 91.492711 -288.564356) (xy 91.544648 -288.560553) (xy 91.596585 -288.564356) (xy 91.647415 -288.575683)
			(xy 91.696052 -288.594293) (xy 91.741461 -288.619789) (xy 91.782671 -288.651628) (xy 91.818804 -288.689129)
			(xy 91.84909 -288.731493) (xy 91.872882 -288.777816) (xy 91.881706 -288.802318) (xy 91.89339 -288.836608)
			(xy 92.135706 -288.836608) (xy 92.14739 -288.802318) (xy 92.157018 -288.77575) (xy 92.183462 -288.725811)
			(xy 92.217456 -288.680672) (xy 92.258147 -288.641463) (xy 92.304516 -288.609167) (xy 92.355401 -288.584593)
			(xy 92.409526 -288.568357) (xy 92.437458 -288.564066) (xy 92.462096 -288.560764) (xy 92.634816 -288.26206)
			(xy 92.625164 -288.238946) (xy 92.616648 -288.217314) (xy 92.604662 -288.172396) (xy 92.59862 -288.126301)
			(xy 92.59824 -288.103056) (xy 92.598738 -288.076407) (xy 92.606681 -288.023703) (xy 92.622391 -287.972773)
			(xy 92.645517 -287.924752) (xy 92.675541 -287.880715) (xy 92.711793 -287.841644) (xy 92.753464 -287.808413)
			(xy 92.799622 -287.781764) (xy 92.849236 -287.762292) (xy 92.901198 -287.750432) (xy 92.954348 -287.746449)
			(xy 93.007498 -287.750432) (xy 93.05946 -287.762292) (xy 93.109074 -287.781764) (xy 93.155232 -287.808413)
			(xy 93.196903 -287.841644) (xy 93.233155 -287.880715) (xy 93.263179 -287.924752) (xy 93.286305 -287.972773)
			(xy 93.302015 -288.023703) (xy 93.309958 -288.076407) (xy 93.310456 -288.103056) (xy 93.310007 -288.128682)
			(xy 93.302655 -288.179403) (xy 93.28811 -288.228548) (xy 93.266673 -288.275101) (xy 93.238787 -288.318101)
			(xy 93.205026 -288.356662) (xy 93.166088 -288.389987) (xy 93.122776 -288.417388) (xy 93.075985 -288.4383)
			(xy 93.026681 -288.452292) (xy 93.001338 -288.456116) (xy 92.9767 -288.459418) (xy 92.80398 -288.758122)
			(xy 92.813632 -288.781236) (xy 92.821506 -288.802318) (xy 92.83319 -288.836608) (xy 93.075506 -288.836608)
			(xy 93.08719 -288.802318) (xy 93.096014 -288.777816) (xy 93.119806 -288.731493) (xy 93.150092 -288.689129)
			(xy 93.186225 -288.651628) (xy 93.227435 -288.619789) (xy 93.272844 -288.594293) (xy 93.321481 -288.575683)
			(xy 93.372311 -288.564356) (xy 93.424248 -288.560553) (xy 93.476185 -288.564356) (xy 93.527015 -288.575683)
			(xy 93.575652 -288.594293) (xy 93.621061 -288.619789) (xy 93.662271 -288.651628) (xy 93.698404 -288.689129)
			(xy 93.72869 -288.731493) (xy 93.752482 -288.777816) (xy 93.761306 -288.802318) (xy 93.77299 -288.836608)
			(xy 94.015306 -288.836608) (xy 94.02699 -288.802318) (xy 94.036618 -288.77575) (xy 94.063062 -288.725811)
			(xy 94.097056 -288.680672) (xy 94.137747 -288.641463) (xy 94.184116 -288.609167) (xy 94.235001 -288.584593)
			(xy 94.289126 -288.568357) (xy 94.317058 -288.564066) (xy 94.341696 -288.560764) (xy 94.514416 -288.26206)
			(xy 94.504764 -288.238946) (xy 94.496248 -288.217314) (xy 94.484262 -288.172396) (xy 94.47822 -288.126301)
			(xy 94.47784 -288.103056) (xy 94.478338 -288.076407) (xy 94.486281 -288.023703) (xy 94.501991 -287.972773)
			(xy 94.525117 -287.924752) (xy 94.555141 -287.880715) (xy 94.591393 -287.841644) (xy 94.633064 -287.808413)
			(xy 94.679222 -287.781764) (xy 94.728836 -287.762292) (xy 94.780798 -287.750432) (xy 94.833948 -287.746449)
			(xy 94.887098 -287.750432) (xy 94.93906 -287.762292) (xy 94.988674 -287.781764) (xy 95.034832 -287.808413)
			(xy 95.076503 -287.841644) (xy 95.112755 -287.880715) (xy 95.142779 -287.924752) (xy 95.165905 -287.972773)
			(xy 95.181615 -288.023703) (xy 95.189558 -288.076407) (xy 95.190056 -288.103056) (xy 95.189607 -288.128682)
			(xy 95.182255 -288.179403) (xy 95.16771 -288.228548) (xy 95.146273 -288.275101) (xy 95.118387 -288.318101)
			(xy 95.084626 -288.356662) (xy 95.045688 -288.389987) (xy 95.002376 -288.417388) (xy 94.955585 -288.4383)
			(xy 94.906281 -288.452292) (xy 94.880938 -288.456116) (xy 94.8563 -288.459418) (xy 94.68358 -288.758122)
			(xy 94.693232 -288.781236) (xy 94.701106 -288.802318) (xy 94.71279 -288.836608) (xy 94.955106 -288.836608)
			(xy 94.96679 -288.802318) (xy 94.975614 -288.777816) (xy 94.999406 -288.731493) (xy 95.029692 -288.689129)
			(xy 95.065825 -288.651628) (xy 95.107035 -288.619789) (xy 95.152444 -288.594293) (xy 95.201081 -288.575683)
			(xy 95.251911 -288.564356) (xy 95.303848 -288.560553) (xy 95.355785 -288.564356) (xy 95.406615 -288.575683)
			(xy 95.455252 -288.594293) (xy 95.500661 -288.619789) (xy 95.541871 -288.651628) (xy 95.578004 -288.689129)
			(xy 95.60829 -288.731493) (xy 95.632082 -288.777816) (xy 95.640906 -288.802318) (xy 95.65259 -288.836608)
			(xy 95.894906 -288.836608) (xy 95.90659 -288.802318) (xy 95.916218 -288.77575) (xy 95.942662 -288.725811)
			(xy 95.976656 -288.680672) (xy 96.017347 -288.641463) (xy 96.063716 -288.609167) (xy 96.114601 -288.584593)
			(xy 96.168726 -288.568357) (xy 96.196658 -288.564066) (xy 96.221296 -288.560764) (xy 96.394016 -288.26206)
			(xy 96.384364 -288.238946) (xy 96.375848 -288.217314) (xy 96.363862 -288.172396) (xy 96.35782 -288.126301)
			(xy 96.35744 -288.103056) (xy 96.357938 -288.076407) (xy 96.365881 -288.023703) (xy 96.381591 -287.972773)
			(xy 96.404717 -287.924752) (xy 96.434741 -287.880715) (xy 96.470993 -287.841644) (xy 96.512664 -287.808413)
			(xy 96.558822 -287.781764) (xy 96.608436 -287.762292) (xy 96.660398 -287.750432) (xy 96.713548 -287.746449)
			(xy 96.766698 -287.750432) (xy 96.81866 -287.762292) (xy 96.868274 -287.781764) (xy 96.914432 -287.808413)
			(xy 96.956103 -287.841644) (xy 96.992355 -287.880715) (xy 97.022379 -287.924752) (xy 97.045505 -287.972773)
			(xy 97.061215 -288.023703) (xy 97.069158 -288.076407) (xy 97.069656 -288.103056) (xy 97.069207 -288.128682)
			(xy 97.061855 -288.179403) (xy 97.04731 -288.228548) (xy 97.025873 -288.275101) (xy 96.997987 -288.318101)
			(xy 96.964226 -288.356662) (xy 96.925288 -288.389987) (xy 96.881976 -288.417388) (xy 96.835185 -288.4383)
			(xy 96.785881 -288.452292) (xy 96.760538 -288.456116) (xy 96.7359 -288.459418) (xy 96.56318 -288.758122)
			(xy 96.572832 -288.781236) (xy 96.580706 -288.802318) (xy 96.59239 -288.836608) (xy 96.834706 -288.836608)
			(xy 96.84639 -288.802318) (xy 96.855214 -288.777816) (xy 96.879006 -288.731493) (xy 96.909292 -288.689129)
			(xy 96.945425 -288.651628) (xy 96.986635 -288.619789) (xy 97.032044 -288.594293) (xy 97.080681 -288.575683)
			(xy 97.131511 -288.564356) (xy 97.183448 -288.560553) (xy 97.235385 -288.564356) (xy 97.286215 -288.575683)
			(xy 97.334852 -288.594293) (xy 97.380261 -288.619789) (xy 97.421471 -288.651628) (xy 97.457604 -288.689129)
			(xy 97.48789 -288.731493) (xy 97.511682 -288.777816) (xy 97.520506 -288.802318) (xy 97.53219 -288.836608)
			(xy 97.774506 -288.836608) (xy 97.78619 -288.802318) (xy 97.795818 -288.77575) (xy 97.822262 -288.725811)
			(xy 97.856256 -288.680672) (xy 97.896947 -288.641463) (xy 97.943316 -288.609167) (xy 97.994201 -288.584593)
			(xy 98.048326 -288.568357) (xy 98.076258 -288.564066) (xy 98.100896 -288.560764) (xy 98.273616 -288.26206)
			(xy 98.263964 -288.238946) (xy 98.255448 -288.217314) (xy 98.243462 -288.172396) (xy 98.23742 -288.126301)
			(xy 98.23704 -288.103056) (xy 98.237538 -288.076407) (xy 98.245481 -288.023703) (xy 98.261191 -287.972773)
			(xy 98.284317 -287.924752) (xy 98.314341 -287.880715) (xy 98.350593 -287.841644) (xy 98.392264 -287.808413)
			(xy 98.438422 -287.781764) (xy 98.488036 -287.762292) (xy 98.539998 -287.750432) (xy 98.593148 -287.746449)
			(xy 98.646298 -287.750432) (xy 98.69826 -287.762292) (xy 98.747874 -287.781764) (xy 98.794032 -287.808413)
			(xy 98.835703 -287.841644) (xy 98.871955 -287.880715) (xy 98.901979 -287.924752) (xy 98.925105 -287.972773)
			(xy 98.940815 -288.023703) (xy 98.948758 -288.076407) (xy 98.949256 -288.103056) (xy 98.948807 -288.128682)
			(xy 98.941455 -288.179403) (xy 98.92691 -288.228548) (xy 98.905473 -288.275101) (xy 98.877587 -288.318101)
			(xy 98.843826 -288.356662) (xy 98.804888 -288.389987) (xy 98.761576 -288.417388) (xy 98.714785 -288.4383)
			(xy 98.665481 -288.452292) (xy 98.640138 -288.456116) (xy 98.6155 -288.459418) (xy 98.44278 -288.758122)
			(xy 98.452432 -288.781236) (xy 98.460306 -288.802318) (xy 98.47199 -288.836608) (xy 98.714306 -288.836608)
			(xy 98.72599 -288.802318) (xy 98.734814 -288.777816) (xy 98.758606 -288.731493) (xy 98.788892 -288.689129)
			(xy 98.825025 -288.651628) (xy 98.866235 -288.619789) (xy 98.911644 -288.594293) (xy 98.960281 -288.575683)
			(xy 99.011111 -288.564356) (xy 99.063048 -288.560553) (xy 99.114985 -288.564356) (xy 99.165815 -288.575683)
			(xy 99.214452 -288.594293) (xy 99.259861 -288.619789) (xy 99.301071 -288.651628) (xy 99.337204 -288.689129)
			(xy 99.36749 -288.731493) (xy 99.391282 -288.777816) (xy 99.400106 -288.802318) (xy 99.41179 -288.836608)
			(xy 99.654106 -288.836608) (xy 99.66579 -288.802318) (xy 99.675418 -288.77575) (xy 99.701862 -288.725811)
			(xy 99.735856 -288.680672) (xy 99.776547 -288.641463) (xy 99.822916 -288.609167) (xy 99.873801 -288.584593)
			(xy 99.927926 -288.568357) (xy 99.955858 -288.564066) (xy 99.980496 -288.560764) (xy 100.153216 -288.26206)
			(xy 100.143564 -288.238946) (xy 100.135048 -288.217314) (xy 100.123062 -288.172396) (xy 100.11702 -288.126301)
			(xy 100.11664 -288.103056) (xy 100.117138 -288.076407) (xy 100.125081 -288.023703) (xy 100.140791 -287.972773)
			(xy 100.163917 -287.924752) (xy 100.193941 -287.880715) (xy 100.230193 -287.841644) (xy 100.271864 -287.808413)
			(xy 100.318022 -287.781764) (xy 100.367636 -287.762292) (xy 100.419598 -287.750432) (xy 100.472748 -287.746449)
			(xy 100.525898 -287.750432) (xy 100.57786 -287.762292) (xy 100.627474 -287.781764) (xy 100.673632 -287.808413)
			(xy 100.715303 -287.841644) (xy 100.751555 -287.880715) (xy 100.781579 -287.924752) (xy 100.804705 -287.972773)
			(xy 100.820415 -288.023703) (xy 100.828358 -288.076407) (xy 100.828856 -288.103056) (xy 100.828407 -288.128682)
			(xy 100.821055 -288.179403) (xy 100.80651 -288.228548) (xy 100.785073 -288.275101) (xy 100.757187 -288.318101)
			(xy 100.723426 -288.356662) (xy 100.684488 -288.389987) (xy 100.641176 -288.417388) (xy 100.594385 -288.4383)
			(xy 100.545081 -288.452292) (xy 100.519738 -288.456116) (xy 100.4951 -288.459418) (xy 100.32238 -288.758122)
			(xy 100.332032 -288.781236) (xy 100.339906 -288.802318) (xy 100.35159 -288.836608) (xy 100.593906 -288.836608)
			(xy 100.60559 -288.802318) (xy 100.614414 -288.777816) (xy 100.638206 -288.731493) (xy 100.668492 -288.689129)
			(xy 100.704625 -288.651628) (xy 100.745835 -288.619789) (xy 100.791244 -288.594293) (xy 100.839881 -288.575683)
			(xy 100.890711 -288.564356) (xy 100.942648 -288.560553) (xy 100.994585 -288.564356) (xy 101.045415 -288.575683)
			(xy 101.094052 -288.594293) (xy 101.139461 -288.619789) (xy 101.180671 -288.651628) (xy 101.216804 -288.689129)
			(xy 101.24709 -288.731493) (xy 101.270882 -288.777816) (xy 101.279706 -288.802318) (xy 101.29139 -288.836608)
			(xy 101.533706 -288.836608) (xy 101.54539 -288.802318) (xy 101.555018 -288.77575) (xy 101.581462 -288.725811)
			(xy 101.615456 -288.680672) (xy 101.656147 -288.641463) (xy 101.702516 -288.609167) (xy 101.753401 -288.584593)
			(xy 101.807526 -288.568357) (xy 101.835458 -288.564066) (xy 101.860096 -288.560764) (xy 102.032816 -288.26206)
			(xy 102.023164 -288.238946) (xy 102.014648 -288.217314) (xy 102.002662 -288.172396) (xy 101.99662 -288.126301)
			(xy 101.99624 -288.103056) (xy 101.996738 -288.076407) (xy 102.004681 -288.023703) (xy 102.020391 -287.972773)
			(xy 102.043517 -287.924752) (xy 102.073541 -287.880715) (xy 102.109793 -287.841644) (xy 102.151464 -287.808413)
			(xy 102.197622 -287.781764) (xy 102.247236 -287.762292) (xy 102.299198 -287.750432) (xy 102.352348 -287.746449)
			(xy 102.405498 -287.750432) (xy 102.45746 -287.762292) (xy 102.507074 -287.781764) (xy 102.553232 -287.808413)
			(xy 102.594903 -287.841644) (xy 102.631155 -287.880715) (xy 102.661179 -287.924752) (xy 102.684305 -287.972773)
			(xy 102.700015 -288.023703) (xy 102.707958 -288.076407) (xy 102.708456 -288.103056) (xy 102.708007 -288.128682)
			(xy 102.700655 -288.179403) (xy 102.68611 -288.228548) (xy 102.664673 -288.275101) (xy 102.636787 -288.318101)
			(xy 102.603026 -288.356662) (xy 102.564088 -288.389987) (xy 102.520776 -288.417388) (xy 102.473985 -288.4383)
			(xy 102.424681 -288.452292) (xy 102.399338 -288.456116) (xy 102.3747 -288.459418) (xy 102.20198 -288.758122)
			(xy 102.211632 -288.781236) (xy 102.219506 -288.802318) (xy 102.23119 -288.836608) (xy 102.473506 -288.836608)
			(xy 102.48519 -288.802318) (xy 102.494014 -288.777816) (xy 102.517806 -288.731493) (xy 102.548092 -288.689129)
			(xy 102.584225 -288.651628) (xy 102.625435 -288.619789) (xy 102.670844 -288.594293) (xy 102.719481 -288.575683)
			(xy 102.770311 -288.564356) (xy 102.822248 -288.560553) (xy 102.874185 -288.564356) (xy 102.925015 -288.575683)
			(xy 102.973652 -288.594293) (xy 103.019061 -288.619789) (xy 103.060271 -288.651628) (xy 103.096404 -288.689129)
			(xy 103.12669 -288.731493) (xy 103.150482 -288.777816) (xy 103.159306 -288.802318) (xy 103.17099 -288.836608)
			(xy 103.413306 -288.836608) (xy 103.42499 -288.802318) (xy 103.434318 -288.776504) (xy 103.459777 -288.72788)
			(xy 103.492397 -288.683739) (xy 103.531405 -288.645128) (xy 103.575877 -288.61296) (xy 103.624758 -288.587999)
			(xy 103.676892 -288.570835) (xy 103.703882 -288.565844) (xy 103.720138 -288.56305) (xy 103.763572 -288.519616)
			(xy 103.912416 -288.26206) (xy 103.902764 -288.238946) (xy 103.894248 -288.217314) (xy 103.882262 -288.172396)
			(xy 103.87622 -288.126301) (xy 103.87584 -288.103056) (xy 103.876427 -288.073886) (xy 103.885937 -288.016326)
			(xy 103.904695 -287.961084) (xy 103.932202 -287.909635) (xy 103.9495 -287.88614) (xy 103.9495 -287.73882)
			(xy 103.94898 -287.723891) (xy 103.940355 -287.695307) (xy 103.923835 -287.670437) (xy 103.90083 -287.651405)
			(xy 103.873306 -287.639835) (xy 103.843612 -287.636716) (xy 103.82885 -287.638998) (xy 103.812248 -287.641988)
			(xy 103.778662 -287.64517) (xy 103.761794 -287.645348) (xy 103.735142 -287.64485) (xy 103.682433 -287.636904)
			(xy 103.631498 -287.621192) (xy 103.583473 -287.598064) (xy 103.539431 -287.568036) (xy 103.500357 -287.53178)
			(xy 103.467123 -287.490105) (xy 103.440471 -287.443942) (xy 103.420997 -287.394323) (xy 103.409136 -287.342355)
			(xy 103.405152 -287.2892) (xy 103.409136 -287.236045) (xy 103.420997 -287.184077) (xy 103.440471 -287.134458)
			(xy 103.467123 -287.088295) (xy 103.500357 -287.04662) (xy 103.539431 -287.010364) (xy 103.583473 -286.980336)
			(xy 103.631498 -286.957208) (xy 103.682433 -286.941496) (xy 103.735142 -286.93355) (xy 103.761794 -286.933132)
			(xy 103.778661 -286.93333) (xy 103.812246 -286.936509) (xy 103.82885 -286.939482) (xy 103.843611 -286.941768)
			(xy 103.873304 -286.938649) (xy 103.900827 -286.927078) (xy 103.923829 -286.908044) (xy 103.940346 -286.883173)
			(xy 103.948967 -286.854588) (xy 103.9495 -286.83966) (xy 103.9495 -286.692594) (xy 103.934037 -286.671732)
			(xy 103.908678 -286.626417) (xy 103.890169 -286.5779) (xy 103.878903 -286.527209) (xy 103.875119 -286.475419)
			(xy 103.878898 -286.423629) (xy 103.890158 -286.372937) (xy 103.908661 -286.324417) (xy 103.934016 -286.2791)
			(xy 103.9495 -286.258254) (xy 103.9495 -286.110934) (xy 103.948982 -286.096004) (xy 103.940359 -286.067416)
			(xy 103.923839 -286.042543) (xy 103.900834 -286.023507) (xy 103.873308 -286.011935) (xy 103.843611 -286.008816)
			(xy 103.82885 -286.011112) (xy 103.812248 -286.014102) (xy 103.778662 -286.017284) (xy 103.761794 -286.017462)
			(xy 103.73381 -286.016941) (xy 103.678532 -286.008184) (xy 103.625305 -285.990887) (xy 103.575439 -285.965476)
			(xy 103.530162 -285.932576) (xy 103.49059 -285.892998) (xy 103.457697 -285.847717) (xy 103.432293 -285.797847)
			(xy 103.415004 -285.744617) (xy 103.406255 -285.689338) (xy 103.405686 -285.661354) (xy 103.406134 -285.635729)
			(xy 103.413486 -285.585008) (xy 103.42803 -285.535865) (xy 103.449467 -285.489313) (xy 103.477355 -285.446314)
			(xy 103.511116 -285.407755) (xy 103.550055 -285.374433) (xy 103.593368 -285.347036) (xy 103.64016 -285.326128)
			(xy 103.689465 -285.312142) (xy 103.714804 -285.308294) (xy 103.739442 -285.304992) (xy 103.912162 -285.006034)
			(xy 103.90251 -284.98292) (xy 103.894067 -284.961359) (xy 103.882189 -284.916605) (xy 103.876197 -284.87069)
			(xy 103.87584 -284.847538) (xy 103.876428 -284.818368) (xy 103.885941 -284.76081) (xy 103.904702 -284.705569)
			(xy 103.93221 -284.654122) (xy 103.9495 -284.630622) (xy 103.9495 -284.483302) (xy 103.948978 -284.468375)
			(xy 103.94035 -284.439796) (xy 103.923829 -284.414931) (xy 103.900826 -284.395902) (xy 103.873304 -284.384335)
			(xy 103.843614 -284.381216) (xy 103.82885 -284.38348) (xy 103.812248 -284.38647) (xy 103.778662 -284.389651)
			(xy 103.761794 -284.38983) (xy 103.735143 -284.389332) (xy 103.682437 -284.381387) (xy 103.631504 -284.365675)
			(xy 103.583482 -284.342548) (xy 103.539442 -284.312522) (xy 103.50037 -284.276268) (xy 103.467138 -284.234595)
			(xy 103.440487 -284.188434) (xy 103.421014 -284.138817) (xy 103.409154 -284.086852) (xy 103.40517 -284.0337)
			(xy 103.409154 -283.980548) (xy 103.421014 -283.928583) (xy 103.440487 -283.878966) (xy 103.467138 -283.832805)
			(xy 103.50037 -283.791132) (xy 103.539442 -283.754878) (xy 103.583482 -283.724852) (xy 103.631504 -283.701725)
			(xy 103.682437 -283.686013) (xy 103.735143 -283.678068) (xy 103.761794 -283.677614) (xy 103.778661 -283.677812)
			(xy 103.812246 -283.680991) (xy 103.82885 -283.683964) (xy 103.84361 -283.68625) (xy 103.873302 -283.683131)
			(xy 103.900823 -283.67156) (xy 103.923822 -283.652526) (xy 103.940336 -283.627654) (xy 103.948952 -283.59907)
			(xy 103.9495 -283.584142) (xy 103.9495 -283.494988) (xy 103.974392 -283.470096) (xy 103.947722 -283.43479)
			(xy 103.930757 -283.411445) (xy 103.903811 -283.360416) (xy 103.885445 -283.30571) (xy 103.87614 -283.248759)
			(xy 103.875586 -283.219906) (xy 103.876135 -283.191922) (xy 103.884889 -283.136644) (xy 103.902183 -283.083416)
			(xy 103.92759 -283.033548) (xy 103.960486 -282.98827) (xy 104.00006 -282.948694) (xy 104.045338 -282.915797)
			(xy 104.095205 -282.890387) (xy 104.148432 -282.873092) (xy 104.20371 -282.864335) (xy 104.231694 -282.863798)
			(xy 104.260547 -282.864356) (xy 104.317498 -282.87366) (xy 104.372204 -282.892025) (xy 104.423232 -282.91897)
			(xy 104.446578 -282.935934) (xy 104.481884 -282.962604) (xy 104.561386 -282.883102) (xy 104.570671 -282.873142)
			(xy 104.584076 -282.849453) (xy 104.590755 -282.823067) (xy 104.590234 -282.795853) (xy 104.582549 -282.769741)
			(xy 104.568246 -282.746583) (xy 104.548339 -282.72802) (xy 104.536494 -282.721304) (xy 104.510413 -282.707009)
			(xy 104.463 -282.671107) (xy 104.422205 -282.627833) (xy 104.405176 -282.603448) (xy 104.058212 -282.603448)
			(xy 104.043974 -282.62402) (xy 104.010654 -282.661338) (xy 103.972441 -282.693627) (xy 103.930085 -282.720252)
			(xy 103.884421 -282.740689) (xy 103.836347 -282.754537) (xy 103.786809 -282.761522) (xy 103.761794 -282.761944)
			(xy 103.735142 -282.761446) (xy 103.682434 -282.753501) (xy 103.631499 -282.737788) (xy 103.583475 -282.71466)
			(xy 103.539434 -282.684633) (xy 103.50036 -282.648377) (xy 103.467126 -282.606703) (xy 103.440475 -282.56054)
			(xy 103.421001 -282.510921) (xy 103.40914 -282.458954) (xy 103.405156 -282.4058) (xy 103.40914 -282.352646)
			(xy 103.421001 -282.300679) (xy 103.440475 -282.25106) (xy 103.467126 -282.204897) (xy 103.50036 -282.163223)
			(xy 103.539434 -282.126967) (xy 103.583475 -282.09694) (xy 103.631499 -282.073812) (xy 103.682434 -282.058099)
			(xy 103.735142 -282.050154) (xy 103.761794 -282.049728) (xy 103.786808 -282.05015) (xy 103.836345 -282.057144)
			(xy 103.884418 -282.070995) (xy 103.930081 -282.091432) (xy 103.972439 -282.118053) (xy 104.010658 -282.150335)
			(xy 104.043988 -282.187644) (xy 104.058212 -282.208224) (xy 104.405176 -282.208224) (xy 104.419414 -282.187653)
			(xy 104.452735 -282.150337) (xy 104.490949 -282.118048) (xy 104.533305 -282.091424) (xy 104.578968 -282.070987)
			(xy 104.627042 -282.05714) (xy 104.67658 -282.050154) (xy 104.701594 -282.049728) (xy 104.729298 -282.050255)
			(xy 104.784038 -282.058839) (xy 104.836786 -282.075801) (xy 104.886269 -282.100732) (xy 104.931292 -282.133028)
			(xy 104.970766 -282.17191) (xy 105.00374 -282.216439) (xy 105.017062 -282.240736) (xy 105.023733 -282.252634)
			(xy 105.042261 -282.272639) (xy 105.065431 -282.287015) (xy 105.091582 -282.294734) (xy 105.118845 -282.295243)
			(xy 105.145266 -282.288506) (xy 105.168956 -282.275006) (xy 105.17886 -282.265628) (xy 105.765346 -281.679142)
			(xy 105.760774 -281.653234) (xy 105.758276 -281.638054) (xy 105.755602 -281.607403) (xy 105.75544 -281.59202)
			(xy 105.755959 -281.564035) (xy 105.764713 -281.508754) (xy 105.782007 -281.455523) (xy 105.807417 -281.405653)
			(xy 105.840316 -281.360373) (xy 105.879895 -281.320798) (xy 105.925177 -281.287903) (xy 105.975049 -281.262497)
			(xy 106.028281 -281.245206) (xy 106.083563 -281.236457) (xy 106.111548 -281.235912) (xy 106.126931 -281.236092)
			(xy 106.15758 -281.238765) (xy 106.172762 -281.241246) (xy 106.19867 -281.245818) (xy 106.30154 -281.142948)
			(xy 106.311768 -281.131914) (xy 106.325861 -281.10535) (xy 106.331605 -281.075833) (xy 106.328502 -281.045923)
			(xy 106.316821 -281.018214) (xy 106.307636 -281.006296) (xy 106.301566 -280.998949) (xy 106.290128 -280.983702)
			(xy 106.284776 -280.975816) (xy 105.937812 -280.975816) (xy 105.923572 -280.996384) (xy 105.890249 -281.033696)
			(xy 105.852034 -281.065979) (xy 105.809678 -281.092599) (xy 105.764015 -281.113032) (xy 105.715943 -281.126876)
			(xy 105.666407 -281.13386) (xy 105.641394 -281.134312) (xy 105.614745 -281.133814) (xy 105.562041 -281.125869)
			(xy 105.511111 -281.110159) (xy 105.463091 -281.087033) (xy 105.419054 -281.057008) (xy 105.379983 -281.020755)
			(xy 105.346752 -280.979085) (xy 105.320103 -280.932926) (xy 105.300631 -280.883312) (xy 105.288771 -280.83135)
			(xy 105.284788 -280.7782) (xy 105.288771 -280.72505) (xy 105.300631 -280.673088) (xy 105.320103 -280.623474)
			(xy 105.346752 -280.577315) (xy 105.379983 -280.535645) (xy 105.419054 -280.499392) (xy 105.463091 -280.469367)
			(xy 105.511111 -280.446241) (xy 105.562041 -280.430531) (xy 105.614745 -280.422586) (xy 105.641394 -280.422096)
			(xy 105.666409 -280.422518) (xy 105.715946 -280.429511) (xy 105.76402 -280.443362) (xy 105.809685 -280.463798)
			(xy 105.852044 -280.490417) (xy 105.890265 -280.522698) (xy 105.923599 -280.560004) (xy 105.937812 -280.580592)
			(xy 106.284776 -280.580592) (xy 106.299015 -280.560023) (xy 106.332338 -280.522709) (xy 106.370553 -280.490424)
			(xy 106.412908 -280.463802) (xy 106.458571 -280.443367) (xy 106.506644 -280.429521) (xy 106.55618 -280.422536)
			(xy 106.581194 -280.422096) (xy 106.605956 -280.422521) (xy 106.655003 -280.429377) (xy 106.702629 -280.442957)
			(xy 106.747915 -280.463) (xy 106.789991 -280.489121) (xy 106.809286 -280.504646) (xy 106.821181 -280.513873)
			(xy 106.848899 -280.525583) (xy 106.878827 -280.528696) (xy 106.908361 -280.522942) (xy 106.934931 -280.50882)
			(xy 106.945938 -280.49855) (xy 107.93476 -279.509728) (xy 107.93476 -278.690324) (xy 107.897422 -278.67991)
			(xy 107.872632 -278.67269) (xy 107.825292 -278.652079) (xy 107.781428 -278.624842) (xy 107.741962 -278.591551)
			(xy 107.707723 -278.552904) (xy 107.67943 -278.509715) (xy 107.657676 -278.462889) (xy 107.64292 -278.41341)
			(xy 107.635471 -278.362318) (xy 107.63504 -278.336502) (xy 107.635415 -278.313257) (xy 107.641461 -278.267162)
			(xy 107.653449 -278.222244) (xy 107.661964 -278.200612) (xy 107.671616 -278.177498) (xy 107.498896 -277.878794)
			(xy 107.474258 -277.875492) (xy 107.448901 -277.871683) (xy 107.399561 -277.857731) (xy 107.352732 -277.836846)
			(xy 107.309383 -277.809459) (xy 107.270411 -277.776138) (xy 107.236621 -277.737571) (xy 107.208712 -277.694557)
			(xy 107.187262 -277.647984) (xy 107.172714 -277.598816) (xy 107.165369 -277.54807) (xy 107.164886 -277.522432)
			(xy 107.165404 -277.494445) (xy 107.174155 -277.439159) (xy 107.191448 -277.385923) (xy 107.216857 -277.336048)
			(xy 107.249755 -277.290762) (xy 107.289333 -277.25118) (xy 107.334615 -277.218277) (xy 107.384488 -277.192863)
			(xy 107.437722 -277.175564) (xy 107.493007 -277.166807) (xy 107.520994 -277.166324) (xy 107.547734 -277.166805)
			(xy 107.600612 -277.174811) (xy 107.651695 -277.190644) (xy 107.699832 -277.213946) (xy 107.743937 -277.244192)
			(xy 107.763818 -277.262082) (xy 107.774966 -277.271795) (xy 107.801446 -277.284922) (xy 107.830575 -277.289919)
			(xy 107.859915 -277.286368) (xy 107.887011 -277.274565) (xy 107.909594 -277.2555) (xy 107.925774 -277.230767)
			(xy 107.934196 -277.202438) (xy 107.93476 -277.18766) (xy 107.93476 -277.062438) (xy 107.897422 -277.052024)
			(xy 107.871175 -277.044362) (xy 107.821235 -277.022103) (xy 107.775287 -276.992468) (xy 107.734411 -276.956155)
			(xy 107.699569 -276.914018) (xy 107.671581 -276.867049) (xy 107.651106 -276.816351) (xy 107.638625 -276.763119)
			(xy 107.634431 -276.708604) (xy 107.638623 -276.654089) (xy 107.651103 -276.600857) (xy 107.671578 -276.550159)
			(xy 107.699564 -276.503188) (xy 107.734405 -276.461051) (xy 107.77528 -276.424737) (xy 107.821228 -276.395101)
			(xy 107.871167 -276.372841) (xy 107.897422 -276.365208) (xy 107.93476 -276.354794) (xy 107.93476 -276.229572)
			(xy 107.934257 -276.2148) (xy 107.925801 -276.186492) (xy 107.909604 -276.161784) (xy 107.887018 -276.14274)
			(xy 107.859929 -276.130949) (xy 107.830599 -276.127397) (xy 107.801479 -276.132379) (xy 107.774999 -276.145481)
			(xy 107.763818 -276.15515) (xy 107.743943 -276.173045) (xy 107.69983 -276.203278) (xy 107.651691 -276.226572)
			(xy 107.600609 -276.242404) (xy 107.547733 -276.250417) (xy 107.520994 -276.250908) (xy 107.49598 -276.250486)
			(xy 107.446443 -276.243491) (xy 107.398371 -276.229639) (xy 107.352707 -276.209202) (xy 107.310349 -276.182582)
			(xy 107.272128 -276.150302) (xy 107.238796 -276.112995) (xy 107.224576 -276.092412) (xy 106.877612 -276.092412)
			(xy 106.863372 -276.11298) (xy 106.830049 -276.150292) (xy 106.791834 -276.182576) (xy 106.749479 -276.209196)
			(xy 106.703816 -276.229629) (xy 106.655744 -276.243474) (xy 106.606207 -276.250457) (xy 106.581194 -276.250908)
			(xy 106.554545 -276.25041) (xy 106.501842 -276.242465) (xy 106.450912 -276.226755) (xy 106.402893 -276.203629)
			(xy 106.358856 -276.173605) (xy 106.319786 -276.137353) (xy 106.286556 -276.095682) (xy 106.259907 -276.049525)
			(xy 106.240435 -275.999911) (xy 106.228575 -275.947949) (xy 106.224592 -275.8948) (xy 106.228575 -275.841651)
			(xy 106.240435 -275.789689) (xy 106.259907 -275.740075) (xy 106.286556 -275.693918) (xy 106.319786 -275.652247)
			(xy 106.358856 -275.615995) (xy 106.402893 -275.585971) (xy 106.450912 -275.562845) (xy 106.501842 -275.547135)
			(xy 106.554545 -275.53919) (xy 106.581194 -275.538692) (xy 106.606209 -275.539114) (xy 106.655746 -275.546107)
			(xy 106.70382 -275.559958) (xy 106.749485 -275.580394) (xy 106.791844 -275.607013) (xy 106.830066 -275.639293)
			(xy 106.8634 -275.676599) (xy 106.877612 -275.697188) (xy 107.224576 -275.697188) (xy 107.238816 -275.676619)
			(xy 107.272138 -275.639306) (xy 107.310353 -275.607021) (xy 107.352708 -275.580399) (xy 107.398371 -275.559965)
			(xy 107.446444 -275.546119) (xy 107.49598 -275.539134) (xy 107.520994 -275.538692) (xy 107.547734 -275.539173)
			(xy 107.600613 -275.547179) (xy 107.651696 -275.56301) (xy 107.699835 -275.586311) (xy 107.743942 -275.616555)
			(xy 107.763818 -275.63445) (xy 107.77497 -275.644158) (xy 107.801454 -275.657277) (xy 107.830584 -275.662269)
			(xy 107.859925 -275.658717) (xy 107.887022 -275.646918) (xy 107.90961 -275.627858) (xy 107.9258 -275.603131)
			(xy 107.934237 -275.574806) (xy 107.93476 -275.560028) (xy 107.93476 -275.434552) (xy 107.897422 -275.424138)
			(xy 107.871174 -275.416476) (xy 107.821232 -275.394217) (xy 107.775281 -275.364581) (xy 107.734404 -275.328267)
			(xy 107.69956 -275.286129) (xy 107.671571 -275.239158) (xy 107.651094 -275.188459) (xy 107.638612 -275.135225)
			(xy 107.634417 -275.080708) (xy 107.638609 -275.026191) (xy 107.651089 -274.972956) (xy 107.671564 -274.922256)
			(xy 107.699551 -274.875284) (xy 107.734393 -274.833144) (xy 107.775269 -274.796828) (xy 107.821218 -274.767191)
			(xy 107.871159 -274.744929) (xy 107.897422 -274.737322) (xy 107.93476 -274.726908) (xy 107.93476 -274.013168)
			(xy 107.54868 -273.627088) (xy 107.36199 -273.627088) (xy 107.348372 -273.650382) (xy 107.315205 -273.692939)
			(xy 107.275996 -273.730005) (xy 107.231643 -273.760731) (xy 107.183163 -273.784412) (xy 107.131664 -273.800508)
			(xy 107.078326 -273.808649) (xy 107.02437 -273.808649) (xy 106.971032 -273.800508) (xy 106.919533 -273.784412)
			(xy 106.871053 -273.760731) (xy 106.8267 -273.730005) (xy 106.787491 -273.692939) (xy 106.754324 -273.650382)
			(xy 106.740706 -273.627088) (xy 106.42219 -273.627088) (xy 106.408572 -273.650382) (xy 106.375405 -273.692939)
			(xy 106.336196 -273.730005) (xy 106.291843 -273.760731) (xy 106.243363 -273.784412) (xy 106.191864 -273.800508)
			(xy 106.138526 -273.808649) (xy 106.08457 -273.808649) (xy 106.031232 -273.800508) (xy 105.979733 -273.784412)
			(xy 105.931253 -273.760731) (xy 105.8869 -273.730005) (xy 105.847691 -273.692939) (xy 105.814524 -273.650382)
			(xy 105.800906 -273.627088) (xy 104.54259 -273.627088) (xy 104.528972 -273.650382) (xy 104.495805 -273.692939)
			(xy 104.456596 -273.730005) (xy 104.412243 -273.760731) (xy 104.363763 -273.784412) (xy 104.312264 -273.800508)
			(xy 104.258926 -273.808649) (xy 104.20497 -273.808649) (xy 104.151632 -273.800508) (xy 104.100133 -273.784412)
			(xy 104.051653 -273.760731) (xy 104.0073 -273.730005) (xy 103.968091 -273.692939) (xy 103.934924 -273.650382)
			(xy 103.921306 -273.627088) (xy 103.602536 -273.627088) (xy 103.588918 -273.650382) (xy 103.555751 -273.692939)
			(xy 103.516542 -273.730005) (xy 103.472189 -273.760731) (xy 103.423709 -273.784412) (xy 103.37221 -273.800508)
			(xy 103.318872 -273.808649) (xy 103.264916 -273.808649) (xy 103.211578 -273.800508) (xy 103.160079 -273.784412)
			(xy 103.111599 -273.760731) (xy 103.067246 -273.730005) (xy 103.028037 -273.692939) (xy 102.99487 -273.650382)
			(xy 102.981252 -273.627088) (xy 102.66299 -273.627088) (xy 102.649372 -273.650382) (xy 102.616205 -273.692939)
			(xy 102.576996 -273.730005) (xy 102.532643 -273.760731) (xy 102.484163 -273.784412) (xy 102.432664 -273.800508)
			(xy 102.379326 -273.808649) (xy 102.32537 -273.808649) (xy 102.272032 -273.800508) (xy 102.220533 -273.784412)
			(xy 102.172053 -273.760731) (xy 102.1277 -273.730005) (xy 102.088491 -273.692939) (xy 102.055324 -273.650382)
			(xy 102.041706 -273.627088) (xy 101.722936 -273.627088) (xy 101.709318 -273.650382) (xy 101.676151 -273.692939)
			(xy 101.636942 -273.730005) (xy 101.592589 -273.760731) (xy 101.544109 -273.784412) (xy 101.49261 -273.800508)
			(xy 101.439272 -273.808649) (xy 101.385316 -273.808649) (xy 101.331978 -273.800508) (xy 101.280479 -273.784412)
			(xy 101.231999 -273.760731) (xy 101.187646 -273.730005) (xy 101.148437 -273.692939) (xy 101.11527 -273.650382)
			(xy 101.101652 -273.627088) (xy 100.78339 -273.627088) (xy 100.769772 -273.650382) (xy 100.736605 -273.692939)
			(xy 100.697396 -273.730005) (xy 100.653043 -273.760731) (xy 100.604563 -273.784412) (xy 100.553064 -273.800508)
			(xy 100.499726 -273.808649) (xy 100.44577 -273.808649) (xy 100.392432 -273.800508) (xy 100.340933 -273.784412)
			(xy 100.292453 -273.760731) (xy 100.2481 -273.730005) (xy 100.208891 -273.692939) (xy 100.175724 -273.650382)
			(xy 100.162106 -273.627088) (xy 99.84359 -273.627088) (xy 99.829972 -273.650382) (xy 99.796805 -273.692939)
			(xy 99.757596 -273.730005) (xy 99.713243 -273.760731) (xy 99.664763 -273.784412) (xy 99.613264 -273.800508)
			(xy 99.559926 -273.808649) (xy 99.50597 -273.808649) (xy 99.452632 -273.800508) (xy 99.401133 -273.784412)
			(xy 99.352653 -273.760731) (xy 99.3083 -273.730005) (xy 99.269091 -273.692939) (xy 99.235924 -273.650382)
			(xy 99.222306 -273.627088) (xy 98.90379 -273.627088) (xy 98.890172 -273.650382) (xy 98.857005 -273.692939)
			(xy 98.817796 -273.730005) (xy 98.773443 -273.760731) (xy 98.724963 -273.784412) (xy 98.673464 -273.800508)
			(xy 98.620126 -273.808649) (xy 98.56617 -273.808649) (xy 98.512832 -273.800508) (xy 98.461333 -273.784412)
			(xy 98.412853 -273.760731) (xy 98.3685 -273.730005) (xy 98.329291 -273.692939) (xy 98.296124 -273.650382)
			(xy 98.282506 -273.627088) (xy 97.96399 -273.627088) (xy 97.950372 -273.650382) (xy 97.917205 -273.692939)
			(xy 97.877996 -273.730005) (xy 97.833643 -273.760731) (xy 97.785163 -273.784412) (xy 97.733664 -273.800508)
			(xy 97.680326 -273.808649) (xy 97.62637 -273.808649) (xy 97.573032 -273.800508) (xy 97.521533 -273.784412)
			(xy 97.473053 -273.760731) (xy 97.4287 -273.730005) (xy 97.389491 -273.692939) (xy 97.356324 -273.650382)
			(xy 97.342706 -273.627088) (xy 97.02419 -273.627088) (xy 97.010572 -273.650382) (xy 96.977405 -273.692939)
			(xy 96.938196 -273.730005) (xy 96.893843 -273.760731) (xy 96.845363 -273.784412) (xy 96.793864 -273.800508)
			(xy 96.740526 -273.808649) (xy 96.68657 -273.808649) (xy 96.633232 -273.800508) (xy 96.581733 -273.784412)
			(xy 96.533253 -273.760731) (xy 96.4889 -273.730005) (xy 96.449691 -273.692939) (xy 96.416524 -273.650382)
			(xy 96.402906 -273.627088) (xy 96.08439 -273.627088) (xy 96.070772 -273.650382) (xy 96.037605 -273.692939)
			(xy 95.998396 -273.730005) (xy 95.954043 -273.760731) (xy 95.905563 -273.784412) (xy 95.854064 -273.800508)
			(xy 95.800726 -273.808649) (xy 95.74677 -273.808649) (xy 95.693432 -273.800508) (xy 95.641933 -273.784412)
			(xy 95.593453 -273.760731) (xy 95.5491 -273.730005) (xy 95.509891 -273.692939) (xy 95.476724 -273.650382)
			(xy 95.463106 -273.627088) (xy 95.144336 -273.627088) (xy 95.130718 -273.650382) (xy 95.097551 -273.692939)
			(xy 95.058342 -273.730005) (xy 95.013989 -273.760731) (xy 94.965509 -273.784412) (xy 94.91401 -273.800508)
			(xy 94.860672 -273.808649) (xy 94.806716 -273.808649) (xy 94.753378 -273.800508) (xy 94.701879 -273.784412)
			(xy 94.653399 -273.760731) (xy 94.609046 -273.730005) (xy 94.569837 -273.692939) (xy 94.53667 -273.650382)
			(xy 94.523052 -273.627088) (xy 94.20479 -273.627088) (xy 94.191172 -273.650382) (xy 94.158005 -273.692939)
			(xy 94.118796 -273.730005) (xy 94.074443 -273.760731) (xy 94.025963 -273.784412) (xy 93.974464 -273.800508)
			(xy 93.921126 -273.808649) (xy 93.86717 -273.808649) (xy 93.813832 -273.800508) (xy 93.762333 -273.784412)
			(xy 93.713853 -273.760731) (xy 93.6695 -273.730005) (xy 93.630291 -273.692939) (xy 93.597124 -273.650382)
			(xy 93.583506 -273.627088) (xy 93.26499 -273.627088) (xy 93.251372 -273.650382) (xy 93.218205 -273.692939)
			(xy 93.178996 -273.730005) (xy 93.134643 -273.760731) (xy 93.086163 -273.784412) (xy 93.034664 -273.800508)
			(xy 92.981326 -273.808649) (xy 92.92737 -273.808649) (xy 92.874032 -273.800508) (xy 92.822533 -273.784412)
			(xy 92.774053 -273.760731) (xy 92.7297 -273.730005) (xy 92.690491 -273.692939) (xy 92.657324 -273.650382)
			(xy 92.643706 -273.627088) (xy 92.32519 -273.627088) (xy 92.311572 -273.650382) (xy 92.278405 -273.692939)
			(xy 92.239196 -273.730005) (xy 92.194843 -273.760731) (xy 92.146363 -273.784412) (xy 92.094864 -273.800508)
			(xy 92.041526 -273.808649) (xy 91.98757 -273.808649) (xy 91.934232 -273.800508) (xy 91.882733 -273.784412)
			(xy 91.834253 -273.760731) (xy 91.7899 -273.730005) (xy 91.750691 -273.692939) (xy 91.717524 -273.650382)
			(xy 91.703906 -273.627088) (xy 91.38539 -273.627088) (xy 91.371772 -273.650382) (xy 91.338605 -273.692939)
			(xy 91.299396 -273.730005) (xy 91.255043 -273.760731) (xy 91.206563 -273.784412) (xy 91.155064 -273.800508)
			(xy 91.101726 -273.808649) (xy 91.04777 -273.808649) (xy 90.994432 -273.800508) (xy 90.942933 -273.784412)
			(xy 90.894453 -273.760731) (xy 90.8501 -273.730005) (xy 90.810891 -273.692939) (xy 90.777724 -273.650382)
			(xy 90.764106 -273.627088) (xy 90.445336 -273.627088) (xy 90.431718 -273.650382) (xy 90.398551 -273.692939)
			(xy 90.359342 -273.730005) (xy 90.314989 -273.760731) (xy 90.266509 -273.784412) (xy 90.21501 -273.800508)
			(xy 90.161672 -273.808649) (xy 90.107716 -273.808649) (xy 90.054378 -273.800508) (xy 90.002879 -273.784412)
			(xy 89.954399 -273.760731) (xy 89.910046 -273.730005) (xy 89.870837 -273.692939) (xy 89.83767 -273.650382)
			(xy 89.824052 -273.627088) (xy 89.505536 -273.627088) (xy 89.491918 -273.650382) (xy 89.458751 -273.692939)
			(xy 89.419542 -273.730005) (xy 89.375189 -273.760731) (xy 89.326709 -273.784412) (xy 89.27521 -273.800508)
			(xy 89.221872 -273.808649) (xy 89.167916 -273.808649) (xy 89.114578 -273.800508) (xy 89.063079 -273.784412)
			(xy 89.014599 -273.760731) (xy 88.970246 -273.730005) (xy 88.931037 -273.692939) (xy 88.89787 -273.650382)
			(xy 88.884252 -273.627088) (xy 88.565736 -273.627088) (xy 88.552114 -273.65038) (xy 88.518941 -273.692935)
			(xy 88.479731 -273.730002) (xy 88.43538 -273.760733) (xy 88.386903 -273.784426) (xy 88.335408 -273.800539)
			(xy 88.282072 -273.808704) (xy 88.255094 -273.809206) (xy 88.223992 -273.808565) (xy 88.162736 -273.797753)
			(xy 88.104291 -273.776458) (xy 88.07704 -273.761454) (xy 88.043258 -273.74215) (xy 87.969598 -273.81581)
			(xy 87.959397 -273.826744) (xy 87.945277 -273.853086) (xy 87.939396 -273.882391) (xy 87.942258 -273.912142)
			(xy 87.953618 -273.939787) (xy 87.972501 -273.962955) (xy 87.984584 -273.971766) (xy 88.004925 -273.986052)
			(xy 88.041822 -274.019357) (xy 88.073733 -274.057466) (xy 88.100041 -274.099638) (xy 88.120235 -274.145056)
			(xy 88.133924 -274.19284) (xy 88.140841 -274.242061) (xy 88.141302 -274.266914) (xy 88.140778 -274.293563)
			(xy 88.369384 -274.293563) (xy 88.369384 -274.240265) (xy 88.377327 -274.187561) (xy 88.393037 -274.136631)
			(xy 88.416163 -274.08861) (xy 88.446187 -274.044573) (xy 88.482439 -274.005502) (xy 88.52411 -273.972271)
			(xy 88.570268 -273.945622) (xy 88.619882 -273.92615) (xy 88.671844 -273.91429) (xy 88.724994 -273.910307)
			(xy 88.778144 -273.91429) (xy 88.830106 -273.92615) (xy 88.87972 -273.945622) (xy 88.925878 -273.972271)
			(xy 88.967549 -274.005502) (xy 89.003801 -274.044573) (xy 89.033825 -274.08861) (xy 89.056951 -274.136631)
			(xy 89.072661 -274.187561) (xy 89.080604 -274.240265) (xy 89.081102 -274.266914) (xy 89.080604 -274.293563)
			(xy 89.309184 -274.293563) (xy 89.309184 -274.240265) (xy 89.317127 -274.187561) (xy 89.332837 -274.136631)
			(xy 89.355963 -274.08861) (xy 89.385987 -274.044573) (xy 89.422239 -274.005502) (xy 89.46391 -273.972271)
			(xy 89.510068 -273.945622) (xy 89.559682 -273.92615) (xy 89.611644 -273.91429) (xy 89.664794 -273.910307)
			(xy 89.717944 -273.91429) (xy 89.769906 -273.92615) (xy 89.81952 -273.945622) (xy 89.865678 -273.972271)
			(xy 89.907349 -274.005502) (xy 89.943601 -274.044573) (xy 89.973625 -274.08861) (xy 89.996751 -274.136631)
			(xy 90.012461 -274.187561) (xy 90.020404 -274.240265) (xy 90.020902 -274.266914) (xy 90.020404 -274.293563)
			(xy 90.248984 -274.293563) (xy 90.248984 -274.240265) (xy 90.256927 -274.187561) (xy 90.272637 -274.136631)
			(xy 90.295763 -274.08861) (xy 90.325787 -274.044573) (xy 90.362039 -274.005502) (xy 90.40371 -273.972271)
			(xy 90.449868 -273.945622) (xy 90.499482 -273.92615) (xy 90.551444 -273.91429) (xy 90.604594 -273.910307)
			(xy 90.657744 -273.91429) (xy 90.709706 -273.92615) (xy 90.75932 -273.945622) (xy 90.805478 -273.972271)
			(xy 90.847149 -274.005502) (xy 90.883401 -274.044573) (xy 90.913425 -274.08861) (xy 90.936551 -274.136631)
			(xy 90.952261 -274.187561) (xy 90.960204 -274.240265) (xy 90.960702 -274.266914) (xy 90.960204 -274.293563)
			(xy 91.189038 -274.293563) (xy 91.189038 -274.240265) (xy 91.196981 -274.187561) (xy 91.212691 -274.136631)
			(xy 91.235817 -274.08861) (xy 91.265841 -274.044573) (xy 91.302093 -274.005502) (xy 91.343764 -273.972271)
			(xy 91.389922 -273.945622) (xy 91.439536 -273.92615) (xy 91.491498 -273.91429) (xy 91.544648 -273.910307)
			(xy 91.597798 -273.91429) (xy 91.64976 -273.92615) (xy 91.699374 -273.945622) (xy 91.745532 -273.972271)
			(xy 91.787203 -274.005502) (xy 91.823455 -274.044573) (xy 91.853479 -274.08861) (xy 91.876605 -274.136631)
			(xy 91.892315 -274.187561) (xy 91.900258 -274.240265) (xy 91.900756 -274.266914) (xy 91.900258 -274.293563)
			(xy 92.128584 -274.293563) (xy 92.128584 -274.240265) (xy 92.136527 -274.187561) (xy 92.152237 -274.136631)
			(xy 92.175363 -274.08861) (xy 92.205387 -274.044573) (xy 92.241639 -274.005502) (xy 92.28331 -273.972271)
			(xy 92.329468 -273.945622) (xy 92.379082 -273.92615) (xy 92.431044 -273.91429) (xy 92.484194 -273.910307)
			(xy 92.537344 -273.91429) (xy 92.589306 -273.92615) (xy 92.63892 -273.945622) (xy 92.685078 -273.972271)
			(xy 92.726749 -274.005502) (xy 92.763001 -274.044573) (xy 92.793025 -274.08861) (xy 92.816151 -274.136631)
			(xy 92.831861 -274.187561) (xy 92.839804 -274.240265) (xy 92.840302 -274.266914) (xy 92.839804 -274.293563)
			(xy 93.068384 -274.293563) (xy 93.068384 -274.240265) (xy 93.076327 -274.187561) (xy 93.092037 -274.136631)
			(xy 93.115163 -274.08861) (xy 93.145187 -274.044573) (xy 93.181439 -274.005502) (xy 93.22311 -273.972271)
			(xy 93.269268 -273.945622) (xy 93.318882 -273.92615) (xy 93.370844 -273.91429) (xy 93.423994 -273.910307)
			(xy 93.477144 -273.91429) (xy 93.529106 -273.92615) (xy 93.57872 -273.945622) (xy 93.624878 -273.972271)
			(xy 93.666549 -274.005502) (xy 93.702801 -274.044573) (xy 93.732825 -274.08861) (xy 93.755951 -274.136631)
			(xy 93.771661 -274.187561) (xy 93.779604 -274.240265) (xy 93.780102 -274.266914) (xy 93.779604 -274.293563)
			(xy 94.008184 -274.293563) (xy 94.008184 -274.240265) (xy 94.016127 -274.187561) (xy 94.031837 -274.136631)
			(xy 94.054963 -274.08861) (xy 94.084987 -274.044573) (xy 94.121239 -274.005502) (xy 94.16291 -273.972271)
			(xy 94.209068 -273.945622) (xy 94.258682 -273.92615) (xy 94.310644 -273.91429) (xy 94.363794 -273.910307)
			(xy 94.416944 -273.91429) (xy 94.468906 -273.92615) (xy 94.51852 -273.945622) (xy 94.564678 -273.972271)
			(xy 94.606349 -274.005502) (xy 94.642601 -274.044573) (xy 94.672625 -274.08861) (xy 94.695751 -274.136631)
			(xy 94.711461 -274.187561) (xy 94.719404 -274.240265) (xy 94.719902 -274.266914) (xy 94.719404 -274.293563)
			(xy 94.947984 -274.293563) (xy 94.947984 -274.240265) (xy 94.955927 -274.187561) (xy 94.971637 -274.136631)
			(xy 94.994763 -274.08861) (xy 95.024787 -274.044573) (xy 95.061039 -274.005502) (xy 95.10271 -273.972271)
			(xy 95.148868 -273.945622) (xy 95.198482 -273.92615) (xy 95.250444 -273.91429) (xy 95.303594 -273.910307)
			(xy 95.356744 -273.91429) (xy 95.408706 -273.92615) (xy 95.45832 -273.945622) (xy 95.504478 -273.972271)
			(xy 95.546149 -274.005502) (xy 95.582401 -274.044573) (xy 95.612425 -274.08861) (xy 95.635551 -274.136631)
			(xy 95.651261 -274.187561) (xy 95.659204 -274.240265) (xy 95.659702 -274.266914) (xy 95.659204 -274.293563)
			(xy 95.887784 -274.293563) (xy 95.887784 -274.240265) (xy 95.895727 -274.187561) (xy 95.911437 -274.136631)
			(xy 95.934563 -274.08861) (xy 95.964587 -274.044573) (xy 96.000839 -274.005502) (xy 96.04251 -273.972271)
			(xy 96.088668 -273.945622) (xy 96.138282 -273.92615) (xy 96.190244 -273.91429) (xy 96.243394 -273.910307)
			(xy 96.296544 -273.91429) (xy 96.348506 -273.92615) (xy 96.39812 -273.945622) (xy 96.444278 -273.972271)
			(xy 96.485949 -274.005502) (xy 96.522201 -274.044573) (xy 96.552225 -274.08861) (xy 96.575351 -274.136631)
			(xy 96.591061 -274.187561) (xy 96.599004 -274.240265) (xy 96.599502 -274.266914) (xy 96.599004 -274.293563)
			(xy 96.827584 -274.293563) (xy 96.827584 -274.240265) (xy 96.835527 -274.187561) (xy 96.851237 -274.136631)
			(xy 96.874363 -274.08861) (xy 96.904387 -274.044573) (xy 96.940639 -274.005502) (xy 96.98231 -273.972271)
			(xy 97.028468 -273.945622) (xy 97.078082 -273.92615) (xy 97.130044 -273.91429) (xy 97.183194 -273.910307)
			(xy 97.236344 -273.91429) (xy 97.288306 -273.92615) (xy 97.33792 -273.945622) (xy 97.384078 -273.972271)
			(xy 97.425749 -274.005502) (xy 97.462001 -274.044573) (xy 97.492025 -274.08861) (xy 97.515151 -274.136631)
			(xy 97.530861 -274.187561) (xy 97.538804 -274.240265) (xy 97.539302 -274.266914) (xy 97.538804 -274.293563)
			(xy 97.767384 -274.293563) (xy 97.767384 -274.240265) (xy 97.775327 -274.187561) (xy 97.791037 -274.136631)
			(xy 97.814163 -274.08861) (xy 97.844187 -274.044573) (xy 97.880439 -274.005502) (xy 97.92211 -273.972271)
			(xy 97.968268 -273.945622) (xy 98.017882 -273.92615) (xy 98.069844 -273.91429) (xy 98.122994 -273.910307)
			(xy 98.176144 -273.91429) (xy 98.228106 -273.92615) (xy 98.27772 -273.945622) (xy 98.323878 -273.972271)
			(xy 98.365549 -274.005502) (xy 98.401801 -274.044573) (xy 98.431825 -274.08861) (xy 98.454951 -274.136631)
			(xy 98.470661 -274.187561) (xy 98.478604 -274.240265) (xy 98.479102 -274.266914) (xy 98.478604 -274.293563)
			(xy 98.707184 -274.293563) (xy 98.707184 -274.240265) (xy 98.715127 -274.187561) (xy 98.730837 -274.136631)
			(xy 98.753963 -274.08861) (xy 98.783987 -274.044573) (xy 98.820239 -274.005502) (xy 98.86191 -273.972271)
			(xy 98.908068 -273.945622) (xy 98.957682 -273.92615) (xy 99.009644 -273.91429) (xy 99.062794 -273.910307)
			(xy 99.115944 -273.91429) (xy 99.167906 -273.92615) (xy 99.21752 -273.945622) (xy 99.263678 -273.972271)
			(xy 99.305349 -274.005502) (xy 99.341601 -274.044573) (xy 99.371625 -274.08861) (xy 99.394751 -274.136631)
			(xy 99.410461 -274.187561) (xy 99.418404 -274.240265) (xy 99.418902 -274.266914) (xy 99.418404 -274.293563)
			(xy 99.646984 -274.293563) (xy 99.646984 -274.240265) (xy 99.654927 -274.187561) (xy 99.670637 -274.136631)
			(xy 99.693763 -274.08861) (xy 99.723787 -274.044573) (xy 99.760039 -274.005502) (xy 99.80171 -273.972271)
			(xy 99.847868 -273.945622) (xy 99.897482 -273.92615) (xy 99.949444 -273.91429) (xy 100.002594 -273.910307)
			(xy 100.055744 -273.91429) (xy 100.107706 -273.92615) (xy 100.15732 -273.945622) (xy 100.203478 -273.972271)
			(xy 100.245149 -274.005502) (xy 100.281401 -274.044573) (xy 100.311425 -274.08861) (xy 100.334551 -274.136631)
			(xy 100.350261 -274.187561) (xy 100.358204 -274.240265) (xy 100.358702 -274.266914) (xy 100.358204 -274.293563)
			(xy 100.586784 -274.293563) (xy 100.586784 -274.240265) (xy 100.594727 -274.187561) (xy 100.610437 -274.136631)
			(xy 100.633563 -274.08861) (xy 100.663587 -274.044573) (xy 100.699839 -274.005502) (xy 100.74151 -273.972271)
			(xy 100.787668 -273.945622) (xy 100.837282 -273.92615) (xy 100.889244 -273.91429) (xy 100.942394 -273.910307)
			(xy 100.995544 -273.91429) (xy 101.047506 -273.92615) (xy 101.09712 -273.945622) (xy 101.143278 -273.972271)
			(xy 101.184949 -274.005502) (xy 101.221201 -274.044573) (xy 101.251225 -274.08861) (xy 101.274351 -274.136631)
			(xy 101.290061 -274.187561) (xy 101.298004 -274.240265) (xy 101.298502 -274.266914) (xy 101.298004 -274.293563)
			(xy 101.526584 -274.293563) (xy 101.526584 -274.240265) (xy 101.534527 -274.187561) (xy 101.550237 -274.136631)
			(xy 101.573363 -274.08861) (xy 101.603387 -274.044573) (xy 101.639639 -274.005502) (xy 101.68131 -273.972271)
			(xy 101.727468 -273.945622) (xy 101.777082 -273.92615) (xy 101.829044 -273.91429) (xy 101.882194 -273.910307)
			(xy 101.935344 -273.91429) (xy 101.987306 -273.92615) (xy 102.03692 -273.945622) (xy 102.083078 -273.972271)
			(xy 102.124749 -274.005502) (xy 102.161001 -274.044573) (xy 102.191025 -274.08861) (xy 102.214151 -274.136631)
			(xy 102.229861 -274.187561) (xy 102.237804 -274.240265) (xy 102.238302 -274.266914) (xy 102.237804 -274.293563)
			(xy 102.466384 -274.293563) (xy 102.466384 -274.240265) (xy 102.474327 -274.187561) (xy 102.490037 -274.136631)
			(xy 102.513163 -274.08861) (xy 102.543187 -274.044573) (xy 102.579439 -274.005502) (xy 102.62111 -273.972271)
			(xy 102.667268 -273.945622) (xy 102.716882 -273.92615) (xy 102.768844 -273.91429) (xy 102.821994 -273.910307)
			(xy 102.875144 -273.91429) (xy 102.927106 -273.92615) (xy 102.97672 -273.945622) (xy 103.022878 -273.972271)
			(xy 103.064549 -274.005502) (xy 103.100801 -274.044573) (xy 103.130825 -274.08861) (xy 103.153951 -274.136631)
			(xy 103.169661 -274.187561) (xy 103.177604 -274.240265) (xy 103.178102 -274.266914) (xy 103.405686 -274.266914)
			(xy 103.406184 -274.240265) (xy 103.414127 -274.187561) (xy 103.429837 -274.136631) (xy 103.452963 -274.08861)
			(xy 103.482987 -274.044573) (xy 103.519239 -274.005502) (xy 103.56091 -273.972271) (xy 103.607068 -273.945622)
			(xy 103.656682 -273.92615) (xy 103.708644 -273.91429) (xy 103.761794 -273.910307) (xy 103.814944 -273.91429)
			(xy 103.866906 -273.92615) (xy 103.91652 -273.945622) (xy 103.962678 -273.972271) (xy 104.004349 -274.005502)
			(xy 104.040601 -274.044573) (xy 104.070625 -274.08861) (xy 104.093751 -274.136631) (xy 104.109461 -274.187561)
			(xy 104.117404 -274.240265) (xy 104.117902 -274.266914) (xy 104.117535 -274.290066) (xy 104.117079 -274.293563)
			(xy 104.345984 -274.293563) (xy 104.345984 -274.240265) (xy 104.353927 -274.187561) (xy 104.369637 -274.136631)
			(xy 104.392763 -274.08861) (xy 104.422787 -274.044573) (xy 104.459039 -274.005502) (xy 104.50071 -273.972271)
			(xy 104.546868 -273.945622) (xy 104.596482 -273.92615) (xy 104.648444 -273.91429) (xy 104.701594 -273.910307)
			(xy 104.754744 -273.91429) (xy 104.806706 -273.92615) (xy 104.85632 -273.945622) (xy 104.902478 -273.972271)
			(xy 104.944149 -274.005502) (xy 104.980401 -274.044573) (xy 105.010425 -274.08861) (xy 105.033551 -274.136631)
			(xy 105.049261 -274.187561) (xy 105.057204 -274.240265) (xy 105.057702 -274.266914) (xy 105.057204 -274.293563)
			(xy 106.225584 -274.293563) (xy 106.225584 -274.240265) (xy 106.233527 -274.187561) (xy 106.249237 -274.136631)
			(xy 106.272363 -274.08861) (xy 106.302387 -274.044573) (xy 106.338639 -274.005502) (xy 106.38031 -273.972271)
			(xy 106.426468 -273.945622) (xy 106.476082 -273.92615) (xy 106.528044 -273.91429) (xy 106.581194 -273.910307)
			(xy 106.634344 -273.91429) (xy 106.686306 -273.92615) (xy 106.73592 -273.945622) (xy 106.782078 -273.972271)
			(xy 106.823749 -274.005502) (xy 106.860001 -274.044573) (xy 106.890025 -274.08861) (xy 106.913151 -274.136631)
			(xy 106.928861 -274.187561) (xy 106.936804 -274.240265) (xy 106.937302 -274.266914) (xy 106.936804 -274.293563)
			(xy 106.928861 -274.346267) (xy 106.913151 -274.397197) (xy 106.890025 -274.445218) (xy 106.860001 -274.489255)
			(xy 106.823749 -274.528326) (xy 106.782078 -274.561557) (xy 106.73592 -274.588206) (xy 106.686306 -274.607678)
			(xy 106.634344 -274.619538) (xy 106.581194 -274.623522) (xy 106.528044 -274.619538) (xy 106.476082 -274.607678)
			(xy 106.426468 -274.588206) (xy 106.38031 -274.561557) (xy 106.338639 -274.528326) (xy 106.302387 -274.489255)
			(xy 106.272363 -274.445218) (xy 106.249237 -274.397197) (xy 106.233527 -274.346267) (xy 106.225584 -274.293563)
			(xy 105.057204 -274.293563) (xy 105.049261 -274.346267) (xy 105.033551 -274.397197) (xy 105.010425 -274.445218)
			(xy 104.980401 -274.489255) (xy 104.944149 -274.528326) (xy 104.902478 -274.561557) (xy 104.85632 -274.588206)
			(xy 104.806706 -274.607678) (xy 104.754744 -274.619538) (xy 104.701594 -274.623522) (xy 104.648444 -274.619538)
			(xy 104.596482 -274.607678) (xy 104.546868 -274.588206) (xy 104.50071 -274.561557) (xy 104.459039 -274.528326)
			(xy 104.422787 -274.489255) (xy 104.392763 -274.445218) (xy 104.369637 -274.397197) (xy 104.353927 -274.346267)
			(xy 104.345984 -274.293563) (xy 104.117079 -274.293563) (xy 104.111546 -274.33598) (xy 104.099672 -274.380735)
			(xy 104.091232 -274.402296) (xy 104.08158 -274.42541) (xy 104.2543 -274.724368) (xy 104.278938 -274.72767)
			(xy 104.304278 -274.731508) (xy 104.353582 -274.745498) (xy 104.400372 -274.766409) (xy 104.443683 -274.793809)
			(xy 104.482621 -274.827133) (xy 104.516381 -274.865692) (xy 104.544268 -274.908691) (xy 104.565706 -274.955242)
			(xy 104.580252 -275.004385) (xy 104.587606 -275.055105) (xy 104.588056 -275.08073) (xy 104.587558 -275.107379)
			(xy 104.579615 -275.160083) (xy 104.563905 -275.211013) (xy 104.540779 -275.259034) (xy 104.510755 -275.303071)
			(xy 104.474503 -275.342142) (xy 104.432832 -275.375373) (xy 104.386674 -275.402022) (xy 104.33706 -275.421494)
			(xy 104.285098 -275.433354) (xy 104.231948 -275.437338) (xy 104.178798 -275.433354) (xy 104.126836 -275.421494)
			(xy 104.077222 -275.402022) (xy 104.031064 -275.375373) (xy 103.989393 -275.342142) (xy 103.953141 -275.303071)
			(xy 103.923117 -275.259034) (xy 103.899991 -275.211013) (xy 103.884281 -275.160083) (xy 103.876338 -275.107379)
			(xy 103.87584 -275.08073) (xy 103.876216 -275.057485) (xy 103.882259 -275.01139) (xy 103.894247 -274.966472)
			(xy 103.902764 -274.94484) (xy 103.912416 -274.921726) (xy 103.73995 -274.623276) (xy 103.715058 -274.619974)
			(xy 103.689694 -274.616206) (xy 103.640353 -274.602242) (xy 103.593525 -274.581349) (xy 103.550176 -274.553956)
			(xy 103.511203 -274.52063) (xy 103.477411 -274.482061) (xy 103.449499 -274.439045) (xy 103.428044 -274.392471)
			(xy 103.413488 -274.343301) (xy 103.406133 -274.292553) (xy 103.405686 -274.266914) (xy 103.178102 -274.266914)
			(xy 103.177604 -274.293563) (xy 103.169661 -274.346267) (xy 103.153951 -274.397197) (xy 103.130825 -274.445218)
			(xy 103.100801 -274.489255) (xy 103.064549 -274.528326) (xy 103.022878 -274.561557) (xy 102.97672 -274.588206)
			(xy 102.927106 -274.607678) (xy 102.875144 -274.619538) (xy 102.821994 -274.623522) (xy 102.768844 -274.619538)
			(xy 102.716882 -274.607678) (xy 102.667268 -274.588206) (xy 102.62111 -274.561557) (xy 102.579439 -274.528326)
			(xy 102.543187 -274.489255) (xy 102.513163 -274.445218) (xy 102.490037 -274.397197) (xy 102.474327 -274.346267)
			(xy 102.466384 -274.293563) (xy 102.237804 -274.293563) (xy 102.229861 -274.346267) (xy 102.214151 -274.397197)
			(xy 102.191025 -274.445218) (xy 102.161001 -274.489255) (xy 102.124749 -274.528326) (xy 102.083078 -274.561557)
			(xy 102.03692 -274.588206) (xy 101.987306 -274.607678) (xy 101.935344 -274.619538) (xy 101.882194 -274.623522)
			(xy 101.829044 -274.619538) (xy 101.777082 -274.607678) (xy 101.727468 -274.588206) (xy 101.68131 -274.561557)
			(xy 101.639639 -274.528326) (xy 101.603387 -274.489255) (xy 101.573363 -274.445218) (xy 101.550237 -274.397197)
			(xy 101.534527 -274.346267) (xy 101.526584 -274.293563) (xy 101.298004 -274.293563) (xy 101.290061 -274.346267)
			(xy 101.274351 -274.397197) (xy 101.251225 -274.445218) (xy 101.221201 -274.489255) (xy 101.184949 -274.528326)
			(xy 101.143278 -274.561557) (xy 101.09712 -274.588206) (xy 101.047506 -274.607678) (xy 100.995544 -274.619538)
			(xy 100.942394 -274.623522) (xy 100.889244 -274.619538) (xy 100.837282 -274.607678) (xy 100.787668 -274.588206)
			(xy 100.74151 -274.561557) (xy 100.699839 -274.528326) (xy 100.663587 -274.489255) (xy 100.633563 -274.445218)
			(xy 100.610437 -274.397197) (xy 100.594727 -274.346267) (xy 100.586784 -274.293563) (xy 100.358204 -274.293563)
			(xy 100.350261 -274.346267) (xy 100.334551 -274.397197) (xy 100.311425 -274.445218) (xy 100.281401 -274.489255)
			(xy 100.245149 -274.528326) (xy 100.203478 -274.561557) (xy 100.15732 -274.588206) (xy 100.107706 -274.607678)
			(xy 100.055744 -274.619538) (xy 100.002594 -274.623522) (xy 99.949444 -274.619538) (xy 99.897482 -274.607678)
			(xy 99.847868 -274.588206) (xy 99.80171 -274.561557) (xy 99.760039 -274.528326) (xy 99.723787 -274.489255)
			(xy 99.693763 -274.445218) (xy 99.670637 -274.397197) (xy 99.654927 -274.346267) (xy 99.646984 -274.293563)
			(xy 99.418404 -274.293563) (xy 99.410461 -274.346267) (xy 99.394751 -274.397197) (xy 99.371625 -274.445218)
			(xy 99.341601 -274.489255) (xy 99.305349 -274.528326) (xy 99.263678 -274.561557) (xy 99.21752 -274.588206)
			(xy 99.167906 -274.607678) (xy 99.115944 -274.619538) (xy 99.062794 -274.623522) (xy 99.009644 -274.619538)
			(xy 98.957682 -274.607678) (xy 98.908068 -274.588206) (xy 98.86191 -274.561557) (xy 98.820239 -274.528326)
			(xy 98.783987 -274.489255) (xy 98.753963 -274.445218) (xy 98.730837 -274.397197) (xy 98.715127 -274.346267)
			(xy 98.707184 -274.293563) (xy 98.478604 -274.293563) (xy 98.470661 -274.346267) (xy 98.454951 -274.397197)
			(xy 98.431825 -274.445218) (xy 98.401801 -274.489255) (xy 98.365549 -274.528326) (xy 98.323878 -274.561557)
			(xy 98.27772 -274.588206) (xy 98.228106 -274.607678) (xy 98.176144 -274.619538) (xy 98.122994 -274.623522)
			(xy 98.069844 -274.619538) (xy 98.017882 -274.607678) (xy 97.968268 -274.588206) (xy 97.92211 -274.561557)
			(xy 97.880439 -274.528326) (xy 97.844187 -274.489255) (xy 97.814163 -274.445218) (xy 97.791037 -274.397197)
			(xy 97.775327 -274.346267) (xy 97.767384 -274.293563) (xy 97.538804 -274.293563) (xy 97.530861 -274.346267)
			(xy 97.515151 -274.397197) (xy 97.492025 -274.445218) (xy 97.462001 -274.489255) (xy 97.425749 -274.528326)
			(xy 97.384078 -274.561557) (xy 97.33792 -274.588206) (xy 97.288306 -274.607678) (xy 97.236344 -274.619538)
			(xy 97.183194 -274.623522) (xy 97.130044 -274.619538) (xy 97.078082 -274.607678) (xy 97.028468 -274.588206)
			(xy 96.98231 -274.561557) (xy 96.940639 -274.528326) (xy 96.904387 -274.489255) (xy 96.874363 -274.445218)
			(xy 96.851237 -274.397197) (xy 96.835527 -274.346267) (xy 96.827584 -274.293563) (xy 96.599004 -274.293563)
			(xy 96.591061 -274.346267) (xy 96.575351 -274.397197) (xy 96.552225 -274.445218) (xy 96.522201 -274.489255)
			(xy 96.485949 -274.528326) (xy 96.444278 -274.561557) (xy 96.39812 -274.588206) (xy 96.348506 -274.607678)
			(xy 96.296544 -274.619538) (xy 96.243394 -274.623522) (xy 96.190244 -274.619538) (xy 96.138282 -274.607678)
			(xy 96.088668 -274.588206) (xy 96.04251 -274.561557) (xy 96.000839 -274.528326) (xy 95.964587 -274.489255)
			(xy 95.934563 -274.445218) (xy 95.911437 -274.397197) (xy 95.895727 -274.346267) (xy 95.887784 -274.293563)
			(xy 95.659204 -274.293563) (xy 95.651261 -274.346267) (xy 95.635551 -274.397197) (xy 95.612425 -274.445218)
			(xy 95.582401 -274.489255) (xy 95.546149 -274.528326) (xy 95.504478 -274.561557) (xy 95.45832 -274.588206)
			(xy 95.408706 -274.607678) (xy 95.356744 -274.619538) (xy 95.303594 -274.623522) (xy 95.250444 -274.619538)
			(xy 95.198482 -274.607678) (xy 95.148868 -274.588206) (xy 95.10271 -274.561557) (xy 95.061039 -274.528326)
			(xy 95.024787 -274.489255) (xy 94.994763 -274.445218) (xy 94.971637 -274.397197) (xy 94.955927 -274.346267)
			(xy 94.947984 -274.293563) (xy 94.719404 -274.293563) (xy 94.711461 -274.346267) (xy 94.695751 -274.397197)
			(xy 94.672625 -274.445218) (xy 94.642601 -274.489255) (xy 94.606349 -274.528326) (xy 94.564678 -274.561557)
			(xy 94.51852 -274.588206) (xy 94.468906 -274.607678) (xy 94.416944 -274.619538) (xy 94.363794 -274.623522)
			(xy 94.310644 -274.619538) (xy 94.258682 -274.607678) (xy 94.209068 -274.588206) (xy 94.16291 -274.561557)
			(xy 94.121239 -274.528326) (xy 94.084987 -274.489255) (xy 94.054963 -274.445218) (xy 94.031837 -274.397197)
			(xy 94.016127 -274.346267) (xy 94.008184 -274.293563) (xy 93.779604 -274.293563) (xy 93.771661 -274.346267)
			(xy 93.755951 -274.397197) (xy 93.732825 -274.445218) (xy 93.702801 -274.489255) (xy 93.666549 -274.528326)
			(xy 93.624878 -274.561557) (xy 93.57872 -274.588206) (xy 93.529106 -274.607678) (xy 93.477144 -274.619538)
			(xy 93.423994 -274.623522) (xy 93.370844 -274.619538) (xy 93.318882 -274.607678) (xy 93.269268 -274.588206)
			(xy 93.22311 -274.561557) (xy 93.181439 -274.528326) (xy 93.145187 -274.489255) (xy 93.115163 -274.445218)
			(xy 93.092037 -274.397197) (xy 93.076327 -274.346267) (xy 93.068384 -274.293563) (xy 92.839804 -274.293563)
			(xy 92.831861 -274.346267) (xy 92.816151 -274.397197) (xy 92.793025 -274.445218) (xy 92.763001 -274.489255)
			(xy 92.726749 -274.528326) (xy 92.685078 -274.561557) (xy 92.63892 -274.588206) (xy 92.589306 -274.607678)
			(xy 92.537344 -274.619538) (xy 92.484194 -274.623522) (xy 92.431044 -274.619538) (xy 92.379082 -274.607678)
			(xy 92.329468 -274.588206) (xy 92.28331 -274.561557) (xy 92.241639 -274.528326) (xy 92.205387 -274.489255)
			(xy 92.175363 -274.445218) (xy 92.152237 -274.397197) (xy 92.136527 -274.346267) (xy 92.128584 -274.293563)
			(xy 91.900258 -274.293563) (xy 91.892315 -274.346267) (xy 91.876605 -274.397197) (xy 91.853479 -274.445218)
			(xy 91.823455 -274.489255) (xy 91.787203 -274.528326) (xy 91.745532 -274.561557) (xy 91.699374 -274.588206)
			(xy 91.64976 -274.607678) (xy 91.597798 -274.619538) (xy 91.544648 -274.623522) (xy 91.491498 -274.619538)
			(xy 91.439536 -274.607678) (xy 91.389922 -274.588206) (xy 91.343764 -274.561557) (xy 91.302093 -274.528326)
			(xy 91.265841 -274.489255) (xy 91.235817 -274.445218) (xy 91.212691 -274.397197) (xy 91.196981 -274.346267)
			(xy 91.189038 -274.293563) (xy 90.960204 -274.293563) (xy 90.952261 -274.346267) (xy 90.936551 -274.397197)
			(xy 90.913425 -274.445218) (xy 90.883401 -274.489255) (xy 90.847149 -274.528326) (xy 90.805478 -274.561557)
			(xy 90.75932 -274.588206) (xy 90.709706 -274.607678) (xy 90.657744 -274.619538) (xy 90.604594 -274.623522)
			(xy 90.551444 -274.619538) (xy 90.499482 -274.607678) (xy 90.449868 -274.588206) (xy 90.40371 -274.561557)
			(xy 90.362039 -274.528326) (xy 90.325787 -274.489255) (xy 90.295763 -274.445218) (xy 90.272637 -274.397197)
			(xy 90.256927 -274.346267) (xy 90.248984 -274.293563) (xy 90.020404 -274.293563) (xy 90.012461 -274.346267)
			(xy 89.996751 -274.397197) (xy 89.973625 -274.445218) (xy 89.943601 -274.489255) (xy 89.907349 -274.528326)
			(xy 89.865678 -274.561557) (xy 89.81952 -274.588206) (xy 89.769906 -274.607678) (xy 89.717944 -274.619538)
			(xy 89.664794 -274.623522) (xy 89.611644 -274.619538) (xy 89.559682 -274.607678) (xy 89.510068 -274.588206)
			(xy 89.46391 -274.561557) (xy 89.422239 -274.528326) (xy 89.385987 -274.489255) (xy 89.355963 -274.445218)
			(xy 89.332837 -274.397197) (xy 89.317127 -274.346267) (xy 89.309184 -274.293563) (xy 89.080604 -274.293563)
			(xy 89.072661 -274.346267) (xy 89.056951 -274.397197) (xy 89.033825 -274.445218) (xy 89.003801 -274.489255)
			(xy 88.967549 -274.528326) (xy 88.925878 -274.561557) (xy 88.87972 -274.588206) (xy 88.830106 -274.607678)
			(xy 88.778144 -274.619538) (xy 88.724994 -274.623522) (xy 88.671844 -274.619538) (xy 88.619882 -274.607678)
			(xy 88.570268 -274.588206) (xy 88.52411 -274.561557) (xy 88.482439 -274.528326) (xy 88.446187 -274.489255)
			(xy 88.416163 -274.445218) (xy 88.393037 -274.397197) (xy 88.377327 -274.346267) (xy 88.369384 -274.293563)
			(xy 88.140778 -274.293563) (xy 88.140752 -274.294896) (xy 88.131995 -274.350171) (xy 88.114699 -274.403396)
			(xy 88.08929 -274.45326) (xy 88.056394 -274.498535) (xy 88.01682 -274.538107) (xy 87.971543 -274.571001)
			(xy 87.921678 -274.596407) (xy 87.868452 -274.6137) (xy 87.813176 -274.622454) (xy 87.785194 -274.623022)
			(xy 87.76034 -274.62259) (xy 87.711115 -274.615678) (xy 87.66333 -274.601989) (xy 87.617911 -274.58179)
			(xy 87.575742 -274.555472) (xy 87.537641 -274.523547) (xy 87.50435 -274.486635) (xy 87.490046 -274.466304)
			(xy 87.481232 -274.454243) (xy 87.458046 -274.435431) (xy 87.430413 -274.424119) (xy 87.400692 -274.42127)
			(xy 87.371414 -274.427128) (xy 87.345076 -274.441192) (xy 87.33409 -274.451318) (xy 87.234014 -274.551394)
			(xy 87.223763 -274.562475) (xy 87.209665 -274.58915) (xy 87.203979 -274.61878) (xy 87.207199 -274.648779)
			(xy 87.219045 -274.676527) (xy 87.238484 -274.699601) (xy 87.263817 -274.715988) (xy 87.292833 -274.724256)
			(xy 87.307928 -274.724622) (xy 87.31504 -274.724622) (xy 87.342117 -274.72513) (xy 87.395645 -274.733337)
			(xy 87.447313 -274.749553) (xy 87.49593 -274.773407) (xy 87.540375 -274.804347) (xy 87.579622 -274.84166)
			(xy 87.612767 -274.884486) (xy 87.639044 -274.931836) (xy 87.657849 -274.98262) (xy 87.668747 -275.035666)
			(xy 87.671487 -275.08975) (xy 87.669694 -275.107379) (xy 87.899484 -275.107379) (xy 87.899484 -275.054081)
			(xy 87.907427 -275.001377) (xy 87.923137 -274.950447) (xy 87.946263 -274.902426) (xy 87.976287 -274.858389)
			(xy 88.012539 -274.819318) (xy 88.05421 -274.786087) (xy 88.100368 -274.759438) (xy 88.149982 -274.739966)
			(xy 88.201944 -274.728106) (xy 88.255094 -274.724123) (xy 88.308244 -274.728106) (xy 88.360206 -274.739966)
			(xy 88.40982 -274.759438) (xy 88.455978 -274.786087) (xy 88.497649 -274.819318) (xy 88.533901 -274.858389)
			(xy 88.563925 -274.902426) (xy 88.587051 -274.950447) (xy 88.602761 -275.001377) (xy 88.610704 -275.054081)
			(xy 88.611202 -275.08073) (xy 88.610704 -275.107379) (xy 88.839284 -275.107379) (xy 88.839284 -275.054081)
			(xy 88.847227 -275.001377) (xy 88.862937 -274.950447) (xy 88.886063 -274.902426) (xy 88.916087 -274.858389)
			(xy 88.952339 -274.819318) (xy 88.99401 -274.786087) (xy 89.040168 -274.759438) (xy 89.089782 -274.739966)
			(xy 89.141744 -274.728106) (xy 89.194894 -274.724123) (xy 89.248044 -274.728106) (xy 89.300006 -274.739966)
			(xy 89.34962 -274.759438) (xy 89.395778 -274.786087) (xy 89.437449 -274.819318) (xy 89.473701 -274.858389)
			(xy 89.503725 -274.902426) (xy 89.526851 -274.950447) (xy 89.542561 -275.001377) (xy 89.550504 -275.054081)
			(xy 89.551002 -275.08073) (xy 89.550504 -275.107379) (xy 89.779084 -275.107379) (xy 89.779084 -275.054081)
			(xy 89.787027 -275.001377) (xy 89.802737 -274.950447) (xy 89.825863 -274.902426) (xy 89.855887 -274.858389)
			(xy 89.892139 -274.819318) (xy 89.93381 -274.786087) (xy 89.979968 -274.759438) (xy 90.029582 -274.739966)
			(xy 90.081544 -274.728106) (xy 90.134694 -274.724123) (xy 90.187844 -274.728106) (xy 90.239806 -274.739966)
			(xy 90.28942 -274.759438) (xy 90.335578 -274.786087) (xy 90.377249 -274.819318) (xy 90.413501 -274.858389)
			(xy 90.443525 -274.902426) (xy 90.466651 -274.950447) (xy 90.482361 -275.001377) (xy 90.490304 -275.054081)
			(xy 90.490802 -275.08073) (xy 90.490304 -275.107379) (xy 90.719138 -275.107379) (xy 90.719138 -275.054081)
			(xy 90.727081 -275.001377) (xy 90.742791 -274.950447) (xy 90.765917 -274.902426) (xy 90.795941 -274.858389)
			(xy 90.832193 -274.819318) (xy 90.873864 -274.786087) (xy 90.920022 -274.759438) (xy 90.969636 -274.739966)
			(xy 91.021598 -274.728106) (xy 91.074748 -274.724123) (xy 91.127898 -274.728106) (xy 91.17986 -274.739966)
			(xy 91.229474 -274.759438) (xy 91.275632 -274.786087) (xy 91.317303 -274.819318) (xy 91.353555 -274.858389)
			(xy 91.383579 -274.902426) (xy 91.406705 -274.950447) (xy 91.422415 -275.001377) (xy 91.430358 -275.054081)
			(xy 91.430856 -275.08073) (xy 91.430358 -275.107379) (xy 91.658684 -275.107379) (xy 91.658684 -275.054081)
			(xy 91.666627 -275.001377) (xy 91.682337 -274.950447) (xy 91.705463 -274.902426) (xy 91.735487 -274.858389)
			(xy 91.771739 -274.819318) (xy 91.81341 -274.786087) (xy 91.859568 -274.759438) (xy 91.909182 -274.739966)
			(xy 91.961144 -274.728106) (xy 92.014294 -274.724123) (xy 92.067444 -274.728106) (xy 92.119406 -274.739966)
			(xy 92.16902 -274.759438) (xy 92.215178 -274.786087) (xy 92.256849 -274.819318) (xy 92.293101 -274.858389)
			(xy 92.323125 -274.902426) (xy 92.346251 -274.950447) (xy 92.361961 -275.001377) (xy 92.369904 -275.054081)
			(xy 92.370402 -275.08073) (xy 92.369904 -275.107379) (xy 92.598738 -275.107379) (xy 92.598738 -275.054081)
			(xy 92.606681 -275.001377) (xy 92.622391 -274.950447) (xy 92.645517 -274.902426) (xy 92.675541 -274.858389)
			(xy 92.711793 -274.819318) (xy 92.753464 -274.786087) (xy 92.799622 -274.759438) (xy 92.849236 -274.739966)
			(xy 92.901198 -274.728106) (xy 92.954348 -274.724123) (xy 93.007498 -274.728106) (xy 93.05946 -274.739966)
			(xy 93.109074 -274.759438) (xy 93.155232 -274.786087) (xy 93.196903 -274.819318) (xy 93.233155 -274.858389)
			(xy 93.263179 -274.902426) (xy 93.286305 -274.950447) (xy 93.302015 -275.001377) (xy 93.309958 -275.054081)
			(xy 93.310456 -275.08073) (xy 93.309958 -275.107379) (xy 93.538538 -275.107379) (xy 93.538538 -275.054081)
			(xy 93.546481 -275.001377) (xy 93.562191 -274.950447) (xy 93.585317 -274.902426) (xy 93.615341 -274.858389)
			(xy 93.651593 -274.819318) (xy 93.693264 -274.786087) (xy 93.739422 -274.759438) (xy 93.789036 -274.739966)
			(xy 93.840998 -274.728106) (xy 93.894148 -274.724123) (xy 93.947298 -274.728106) (xy 93.99926 -274.739966)
			(xy 94.048874 -274.759438) (xy 94.095032 -274.786087) (xy 94.136703 -274.819318) (xy 94.172955 -274.858389)
			(xy 94.202979 -274.902426) (xy 94.226105 -274.950447) (xy 94.241815 -275.001377) (xy 94.249758 -275.054081)
			(xy 94.250256 -275.08073) (xy 94.249758 -275.107379) (xy 94.478338 -275.107379) (xy 94.478338 -275.054081)
			(xy 94.486281 -275.001377) (xy 94.501991 -274.950447) (xy 94.525117 -274.902426) (xy 94.555141 -274.858389)
			(xy 94.591393 -274.819318) (xy 94.633064 -274.786087) (xy 94.679222 -274.759438) (xy 94.728836 -274.739966)
			(xy 94.780798 -274.728106) (xy 94.833948 -274.724123) (xy 94.887098 -274.728106) (xy 94.93906 -274.739966)
			(xy 94.988674 -274.759438) (xy 95.034832 -274.786087) (xy 95.076503 -274.819318) (xy 95.112755 -274.858389)
			(xy 95.142779 -274.902426) (xy 95.165905 -274.950447) (xy 95.181615 -275.001377) (xy 95.189558 -275.054081)
			(xy 95.190056 -275.08073) (xy 95.189558 -275.107379) (xy 95.418138 -275.107379) (xy 95.418138 -275.054081)
			(xy 95.426081 -275.001377) (xy 95.441791 -274.950447) (xy 95.464917 -274.902426) (xy 95.494941 -274.858389)
			(xy 95.531193 -274.819318) (xy 95.572864 -274.786087) (xy 95.619022 -274.759438) (xy 95.668636 -274.739966)
			(xy 95.720598 -274.728106) (xy 95.773748 -274.724123) (xy 95.826898 -274.728106) (xy 95.87886 -274.739966)
			(xy 95.928474 -274.759438) (xy 95.974632 -274.786087) (xy 96.016303 -274.819318) (xy 96.052555 -274.858389)
			(xy 96.082579 -274.902426) (xy 96.105705 -274.950447) (xy 96.121415 -275.001377) (xy 96.129358 -275.054081)
			(xy 96.129856 -275.08073) (xy 96.129358 -275.107379) (xy 96.357938 -275.107379) (xy 96.357938 -275.054081)
			(xy 96.365881 -275.001377) (xy 96.381591 -274.950447) (xy 96.404717 -274.902426) (xy 96.434741 -274.858389)
			(xy 96.470993 -274.819318) (xy 96.512664 -274.786087) (xy 96.558822 -274.759438) (xy 96.608436 -274.739966)
			(xy 96.660398 -274.728106) (xy 96.713548 -274.724123) (xy 96.766698 -274.728106) (xy 96.81866 -274.739966)
			(xy 96.868274 -274.759438) (xy 96.914432 -274.786087) (xy 96.956103 -274.819318) (xy 96.992355 -274.858389)
			(xy 97.022379 -274.902426) (xy 97.045505 -274.950447) (xy 97.061215 -275.001377) (xy 97.069158 -275.054081)
			(xy 97.069656 -275.08073) (xy 97.069158 -275.107379) (xy 97.297738 -275.107379) (xy 97.297738 -275.054081)
			(xy 97.305681 -275.001377) (xy 97.321391 -274.950447) (xy 97.344517 -274.902426) (xy 97.374541 -274.858389)
			(xy 97.410793 -274.819318) (xy 97.452464 -274.786087) (xy 97.498622 -274.759438) (xy 97.548236 -274.739966)
			(xy 97.600198 -274.728106) (xy 97.653348 -274.724123) (xy 97.706498 -274.728106) (xy 97.75846 -274.739966)
			(xy 97.808074 -274.759438) (xy 97.854232 -274.786087) (xy 97.895903 -274.819318) (xy 97.932155 -274.858389)
			(xy 97.962179 -274.902426) (xy 97.985305 -274.950447) (xy 98.001015 -275.001377) (xy 98.008958 -275.054081)
			(xy 98.009456 -275.08073) (xy 98.008958 -275.107379) (xy 98.237284 -275.107379) (xy 98.237284 -275.054081)
			(xy 98.245227 -275.001377) (xy 98.260937 -274.950447) (xy 98.284063 -274.902426) (xy 98.314087 -274.858389)
			(xy 98.350339 -274.819318) (xy 98.39201 -274.786087) (xy 98.438168 -274.759438) (xy 98.487782 -274.739966)
			(xy 98.539744 -274.728106) (xy 98.592894 -274.724123) (xy 98.646044 -274.728106) (xy 98.698006 -274.739966)
			(xy 98.74762 -274.759438) (xy 98.793778 -274.786087) (xy 98.835449 -274.819318) (xy 98.871701 -274.858389)
			(xy 98.901725 -274.902426) (xy 98.924851 -274.950447) (xy 98.940561 -275.001377) (xy 98.948504 -275.054081)
			(xy 98.949002 -275.08073) (xy 98.948504 -275.107379) (xy 99.177338 -275.107379) (xy 99.177338 -275.054081)
			(xy 99.185281 -275.001377) (xy 99.200991 -274.950447) (xy 99.224117 -274.902426) (xy 99.254141 -274.858389)
			(xy 99.290393 -274.819318) (xy 99.332064 -274.786087) (xy 99.378222 -274.759438) (xy 99.427836 -274.739966)
			(xy 99.479798 -274.728106) (xy 99.532948 -274.724123) (xy 99.586098 -274.728106) (xy 99.63806 -274.739966)
			(xy 99.687674 -274.759438) (xy 99.733832 -274.786087) (xy 99.775503 -274.819318) (xy 99.811755 -274.858389)
			(xy 99.841779 -274.902426) (xy 99.864905 -274.950447) (xy 99.880615 -275.001377) (xy 99.888558 -275.054081)
			(xy 99.889056 -275.08073) (xy 99.888558 -275.107379) (xy 100.117138 -275.107379) (xy 100.117138 -275.054081)
			(xy 100.125081 -275.001377) (xy 100.140791 -274.950447) (xy 100.163917 -274.902426) (xy 100.193941 -274.858389)
			(xy 100.230193 -274.819318) (xy 100.271864 -274.786087) (xy 100.318022 -274.759438) (xy 100.367636 -274.739966)
			(xy 100.419598 -274.728106) (xy 100.472748 -274.724123) (xy 100.525898 -274.728106) (xy 100.57786 -274.739966)
			(xy 100.627474 -274.759438) (xy 100.673632 -274.786087) (xy 100.715303 -274.819318) (xy 100.751555 -274.858389)
			(xy 100.781579 -274.902426) (xy 100.804705 -274.950447) (xy 100.820415 -275.001377) (xy 100.828358 -275.054081)
			(xy 100.828855 -275.0807) (xy 101.995698 -275.0807) (xy 101.999682 -275.027547) (xy 102.011544 -274.975581)
			(xy 102.031019 -274.925964) (xy 102.057672 -274.879804) (xy 102.090908 -274.838132) (xy 102.129984 -274.80188)
			(xy 102.174027 -274.771858) (xy 102.222053 -274.748735) (xy 102.272989 -274.73303) (xy 102.325697 -274.725092)
			(xy 102.352348 -274.724622) (xy 102.377372 -274.725072) (xy 102.426929 -274.732074) (xy 102.475017 -274.745946)
			(xy 102.520688 -274.766416) (xy 102.563042 -274.793081) (xy 102.601245 -274.825414) (xy 102.634543 -274.862778)
			(xy 102.648766 -274.883372) (xy 102.99573 -274.883372) (xy 103.009932 -274.862762) (xy 103.043233 -274.825395)
			(xy 103.081438 -274.793059) (xy 103.123796 -274.766392) (xy 103.16947 -274.74592) (xy 103.217561 -274.732046)
			(xy 103.267122 -274.725043) (xy 103.292148 -274.724622) (xy 103.318797 -274.725063) (xy 103.371499 -274.733013)
			(xy 103.422428 -274.748729) (xy 103.470447 -274.771859) (xy 103.514481 -274.801887) (xy 103.553549 -274.838142)
			(xy 103.586778 -274.879814) (xy 103.613425 -274.925973) (xy 103.632896 -274.975588) (xy 103.644755 -275.02755)
			(xy 103.648738 -275.0807) (xy 103.644755 -275.13385) (xy 103.632896 -275.185812) (xy 103.613425 -275.235427)
			(xy 103.586778 -275.281586) (xy 103.553549 -275.323258) (xy 103.514481 -275.359513) (xy 103.470447 -275.389541)
			(xy 103.422428 -275.412671) (xy 103.371499 -275.428387) (xy 103.318797 -275.436337) (xy 103.292148 -275.436838)
			(xy 103.267125 -275.436365) (xy 103.21757 -275.429364) (xy 103.169484 -275.415494) (xy 103.123814 -275.395027)
			(xy 103.08146 -275.368367) (xy 103.043255 -275.336039) (xy 103.009954 -275.29868) (xy 102.99573 -275.278088)
			(xy 102.648766 -275.278088) (xy 102.634522 -275.298667) (xy 102.601226 -275.336032) (xy 102.563027 -275.368368)
			(xy 102.520676 -275.395037) (xy 102.47501 -275.415515) (xy 102.426926 -275.429397) (xy 102.377372 -275.436411)
			(xy 102.352348 -275.436838) (xy 102.325697 -275.436308) (xy 102.272989 -275.42837) (xy 102.222053 -275.412665)
			(xy 102.174027 -275.389542) (xy 102.129984 -275.35952) (xy 102.090908 -275.323268) (xy 102.057672 -275.281596)
			(xy 102.031019 -275.235436) (xy 102.011544 -275.185819) (xy 101.999682 -275.133853) (xy 101.995698 -275.0807)
			(xy 100.828855 -275.0807) (xy 100.828856 -275.08073) (xy 100.828358 -275.107379) (xy 100.820415 -275.160083)
			(xy 100.804705 -275.211013) (xy 100.781579 -275.259034) (xy 100.751555 -275.303071) (xy 100.715303 -275.342142)
			(xy 100.673632 -275.375373) (xy 100.627474 -275.402022) (xy 100.57786 -275.421494) (xy 100.525898 -275.433354)
			(xy 100.472748 -275.437338) (xy 100.419598 -275.433354) (xy 100.367636 -275.421494) (xy 100.318022 -275.402022)
			(xy 100.271864 -275.375373) (xy 100.230193 -275.342142) (xy 100.193941 -275.303071) (xy 100.163917 -275.259034)
			(xy 100.140791 -275.211013) (xy 100.125081 -275.160083) (xy 100.117138 -275.107379) (xy 99.888558 -275.107379)
			(xy 99.880615 -275.160083) (xy 99.864905 -275.211013) (xy 99.841779 -275.259034) (xy 99.811755 -275.303071)
			(xy 99.775503 -275.342142) (xy 99.733832 -275.375373) (xy 99.687674 -275.402022) (xy 99.63806 -275.421494)
			(xy 99.586098 -275.433354) (xy 99.532948 -275.437338) (xy 99.479798 -275.433354) (xy 99.427836 -275.421494)
			(xy 99.378222 -275.402022) (xy 99.332064 -275.375373) (xy 99.290393 -275.342142) (xy 99.254141 -275.303071)
			(xy 99.224117 -275.259034) (xy 99.200991 -275.211013) (xy 99.185281 -275.160083) (xy 99.177338 -275.107379)
			(xy 98.948504 -275.107379) (xy 98.940561 -275.160083) (xy 98.924851 -275.211013) (xy 98.901725 -275.259034)
			(xy 98.871701 -275.303071) (xy 98.835449 -275.342142) (xy 98.793778 -275.375373) (xy 98.74762 -275.402022)
			(xy 98.698006 -275.421494) (xy 98.646044 -275.433354) (xy 98.592894 -275.437338) (xy 98.539744 -275.433354)
			(xy 98.487782 -275.421494) (xy 98.438168 -275.402022) (xy 98.39201 -275.375373) (xy 98.350339 -275.342142)
			(xy 98.314087 -275.303071) (xy 98.284063 -275.259034) (xy 98.260937 -275.211013) (xy 98.245227 -275.160083)
			(xy 98.237284 -275.107379) (xy 98.008958 -275.107379) (xy 98.001015 -275.160083) (xy 97.985305 -275.211013)
			(xy 97.962179 -275.259034) (xy 97.932155 -275.303071) (xy 97.895903 -275.342142) (xy 97.854232 -275.375373)
			(xy 97.808074 -275.402022) (xy 97.75846 -275.421494) (xy 97.706498 -275.433354) (xy 97.653348 -275.437338)
			(xy 97.600198 -275.433354) (xy 97.548236 -275.421494) (xy 97.498622 -275.402022) (xy 97.452464 -275.375373)
			(xy 97.410793 -275.342142) (xy 97.374541 -275.303071) (xy 97.344517 -275.259034) (xy 97.321391 -275.211013)
			(xy 97.305681 -275.160083) (xy 97.297738 -275.107379) (xy 97.069158 -275.107379) (xy 97.061215 -275.160083)
			(xy 97.045505 -275.211013) (xy 97.022379 -275.259034) (xy 96.992355 -275.303071) (xy 96.956103 -275.342142)
			(xy 96.914432 -275.375373) (xy 96.868274 -275.402022) (xy 96.81866 -275.421494) (xy 96.766698 -275.433354)
			(xy 96.713548 -275.437338) (xy 96.660398 -275.433354) (xy 96.608436 -275.421494) (xy 96.558822 -275.402022)
			(xy 96.512664 -275.375373) (xy 96.470993 -275.342142) (xy 96.434741 -275.303071) (xy 96.404717 -275.259034)
			(xy 96.381591 -275.211013) (xy 96.365881 -275.160083) (xy 96.357938 -275.107379) (xy 96.129358 -275.107379)
			(xy 96.121415 -275.160083) (xy 96.105705 -275.211013) (xy 96.082579 -275.259034) (xy 96.052555 -275.303071)
			(xy 96.016303 -275.342142) (xy 95.974632 -275.375373) (xy 95.928474 -275.402022) (xy 95.87886 -275.421494)
			(xy 95.826898 -275.433354) (xy 95.773748 -275.437338) (xy 95.720598 -275.433354) (xy 95.668636 -275.421494)
			(xy 95.619022 -275.402022) (xy 95.572864 -275.375373) (xy 95.531193 -275.342142) (xy 95.494941 -275.303071)
			(xy 95.464917 -275.259034) (xy 95.441791 -275.211013) (xy 95.426081 -275.160083) (xy 95.418138 -275.107379)
			(xy 95.189558 -275.107379) (xy 95.181615 -275.160083) (xy 95.165905 -275.211013) (xy 95.142779 -275.259034)
			(xy 95.112755 -275.303071) (xy 95.076503 -275.342142) (xy 95.034832 -275.375373) (xy 94.988674 -275.402022)
			(xy 94.93906 -275.421494) (xy 94.887098 -275.433354) (xy 94.833948 -275.437338) (xy 94.780798 -275.433354)
			(xy 94.728836 -275.421494) (xy 94.679222 -275.402022) (xy 94.633064 -275.375373) (xy 94.591393 -275.342142)
			(xy 94.555141 -275.303071) (xy 94.525117 -275.259034) (xy 94.501991 -275.211013) (xy 94.486281 -275.160083)
			(xy 94.478338 -275.107379) (xy 94.249758 -275.107379) (xy 94.241815 -275.160083) (xy 94.226105 -275.211013)
			(xy 94.202979 -275.259034) (xy 94.172955 -275.303071) (xy 94.136703 -275.342142) (xy 94.095032 -275.375373)
			(xy 94.048874 -275.402022) (xy 93.99926 -275.421494) (xy 93.947298 -275.433354) (xy 93.894148 -275.437338)
			(xy 93.840998 -275.433354) (xy 93.789036 -275.421494) (xy 93.739422 -275.402022) (xy 93.693264 -275.375373)
			(xy 93.651593 -275.342142) (xy 93.615341 -275.303071) (xy 93.585317 -275.259034) (xy 93.562191 -275.211013)
			(xy 93.546481 -275.160083) (xy 93.538538 -275.107379) (xy 93.309958 -275.107379) (xy 93.302015 -275.160083)
			(xy 93.286305 -275.211013) (xy 93.263179 -275.259034) (xy 93.233155 -275.303071) (xy 93.196903 -275.342142)
			(xy 93.155232 -275.375373) (xy 93.109074 -275.402022) (xy 93.05946 -275.421494) (xy 93.007498 -275.433354)
			(xy 92.954348 -275.437338) (xy 92.901198 -275.433354) (xy 92.849236 -275.421494) (xy 92.799622 -275.402022)
			(xy 92.753464 -275.375373) (xy 92.711793 -275.342142) (xy 92.675541 -275.303071) (xy 92.645517 -275.259034)
			(xy 92.622391 -275.211013) (xy 92.606681 -275.160083) (xy 92.598738 -275.107379) (xy 92.369904 -275.107379)
			(xy 92.361961 -275.160083) (xy 92.346251 -275.211013) (xy 92.323125 -275.259034) (xy 92.293101 -275.303071)
			(xy 92.256849 -275.342142) (xy 92.215178 -275.375373) (xy 92.16902 -275.402022) (xy 92.119406 -275.421494)
			(xy 92.067444 -275.433354) (xy 92.014294 -275.437338) (xy 91.961144 -275.433354) (xy 91.909182 -275.421494)
			(xy 91.859568 -275.402022) (xy 91.81341 -275.375373) (xy 91.771739 -275.342142) (xy 91.735487 -275.303071)
			(xy 91.705463 -275.259034) (xy 91.682337 -275.211013) (xy 91.666627 -275.160083) (xy 91.658684 -275.107379)
			(xy 91.430358 -275.107379) (xy 91.422415 -275.160083) (xy 91.406705 -275.211013) (xy 91.383579 -275.259034)
			(xy 91.353555 -275.303071) (xy 91.317303 -275.342142) (xy 91.275632 -275.375373) (xy 91.229474 -275.402022)
			(xy 91.17986 -275.421494) (xy 91.127898 -275.433354) (xy 91.074748 -275.437338) (xy 91.021598 -275.433354)
			(xy 90.969636 -275.421494) (xy 90.920022 -275.402022) (xy 90.873864 -275.375373) (xy 90.832193 -275.342142)
			(xy 90.795941 -275.303071) (xy 90.765917 -275.259034) (xy 90.742791 -275.211013) (xy 90.727081 -275.160083)
			(xy 90.719138 -275.107379) (xy 90.490304 -275.107379) (xy 90.482361 -275.160083) (xy 90.466651 -275.211013)
			(xy 90.443525 -275.259034) (xy 90.413501 -275.303071) (xy 90.377249 -275.342142) (xy 90.335578 -275.375373)
			(xy 90.28942 -275.402022) (xy 90.239806 -275.421494) (xy 90.187844 -275.433354) (xy 90.134694 -275.437338)
			(xy 90.081544 -275.433354) (xy 90.029582 -275.421494) (xy 89.979968 -275.402022) (xy 89.93381 -275.375373)
			(xy 89.892139 -275.342142) (xy 89.855887 -275.303071) (xy 89.825863 -275.259034) (xy 89.802737 -275.211013)
			(xy 89.787027 -275.160083) (xy 89.779084 -275.107379) (xy 89.550504 -275.107379) (xy 89.542561 -275.160083)
			(xy 89.526851 -275.211013) (xy 89.503725 -275.259034) (xy 89.473701 -275.303071) (xy 89.437449 -275.342142)
			(xy 89.395778 -275.375373) (xy 89.34962 -275.402022) (xy 89.300006 -275.421494) (xy 89.248044 -275.433354)
			(xy 89.194894 -275.437338) (xy 89.141744 -275.433354) (xy 89.089782 -275.421494) (xy 89.040168 -275.402022)
			(xy 88.99401 -275.375373) (xy 88.952339 -275.342142) (xy 88.916087 -275.303071) (xy 88.886063 -275.259034)
			(xy 88.862937 -275.211013) (xy 88.847227 -275.160083) (xy 88.839284 -275.107379) (xy 88.610704 -275.107379)
			(xy 88.602761 -275.160083) (xy 88.587051 -275.211013) (xy 88.563925 -275.259034) (xy 88.533901 -275.303071)
			(xy 88.497649 -275.342142) (xy 88.455978 -275.375373) (xy 88.40982 -275.402022) (xy 88.360206 -275.421494)
			(xy 88.308244 -275.433354) (xy 88.255094 -275.437338) (xy 88.201944 -275.433354) (xy 88.149982 -275.421494)
			(xy 88.100368 -275.402022) (xy 88.05421 -275.375373) (xy 88.012539 -275.342142) (xy 87.976287 -275.303071)
			(xy 87.946263 -275.259034) (xy 87.923137 -275.211013) (xy 87.907427 -275.160083) (xy 87.899484 -275.107379)
			(xy 87.669694 -275.107379) (xy 87.666006 -275.143625) (xy 87.652431 -275.19605) (xy 87.631073 -275.245814)
			(xy 87.602427 -275.29177) (xy 87.567152 -275.332859) (xy 87.526062 -275.368133) (xy 87.480105 -275.396778)
			(xy 87.43034 -275.418134) (xy 87.377916 -275.431708) (xy 87.32404 -275.437187) (xy 87.269956 -275.434446)
			(xy 87.216911 -275.423546) (xy 87.166127 -275.40474) (xy 87.118777 -275.378461) (xy 87.075952 -275.345315)
			(xy 87.03864 -275.306067) (xy 87.007702 -275.261622) (xy 86.98385 -275.213004) (xy 86.967634 -275.161335)
			(xy 86.95943 -275.107807) (xy 86.958932 -275.08073) (xy 86.958932 -275.073618) (xy 86.958696 -275.058497)
			(xy 86.950454 -275.029418) (xy 86.934062 -275.004024) (xy 86.910955 -274.984541) (xy 86.883157 -274.972674)
			(xy 86.853103 -274.969463) (xy 86.823425 -274.975189) (xy 86.796723 -274.989351) (xy 86.785704 -274.999704)
			(xy 86.718902 -275.066506) (xy 86.718648 -275.086826) (xy 86.717696 -275.113194) (xy 86.7087 -275.165182)
			(xy 86.69186 -275.215183) (xy 86.667573 -275.262021) (xy 86.636409 -275.304595) (xy 86.599102 -275.341903)
			(xy 86.55653 -275.373067) (xy 86.509692 -275.397356) (xy 86.459691 -275.414197) (xy 86.407704 -275.423195)
			(xy 86.381336 -275.424138) (xy 86.361016 -275.424392) (xy 85.863959 -275.921449) (xy 87.42933 -275.921449)
			(xy 87.42933 -275.868151) (xy 87.437273 -275.815447) (xy 87.452983 -275.764517) (xy 87.476109 -275.716496)
			(xy 87.506133 -275.672459) (xy 87.542385 -275.633388) (xy 87.584056 -275.600157) (xy 87.630214 -275.573508)
			(xy 87.679828 -275.554036) (xy 87.73179 -275.542176) (xy 87.78494 -275.538193) (xy 87.83809 -275.542176)
			(xy 87.890052 -275.554036) (xy 87.939666 -275.573508) (xy 87.985824 -275.600157) (xy 88.027495 -275.633388)
			(xy 88.063747 -275.672459) (xy 88.093771 -275.716496) (xy 88.116897 -275.764517) (xy 88.132607 -275.815447)
			(xy 88.14055 -275.868151) (xy 88.141048 -275.8948) (xy 88.14055 -275.921449) (xy 88.369384 -275.921449)
			(xy 88.369384 -275.868151) (xy 88.377327 -275.815447) (xy 88.393037 -275.764517) (xy 88.416163 -275.716496)
			(xy 88.446187 -275.672459) (xy 88.482439 -275.633388) (xy 88.52411 -275.600157) (xy 88.570268 -275.573508)
			(xy 88.619882 -275.554036) (xy 88.671844 -275.542176) (xy 88.724994 -275.538193) (xy 88.778144 -275.542176)
			(xy 88.830106 -275.554036) (xy 88.87972 -275.573508) (xy 88.925878 -275.600157) (xy 88.967549 -275.633388)
			(xy 89.003801 -275.672459) (xy 89.033825 -275.716496) (xy 89.056951 -275.764517) (xy 89.072661 -275.815447)
			(xy 89.080604 -275.868151) (xy 89.081102 -275.8948) (xy 89.080604 -275.921449) (xy 89.309184 -275.921449)
			(xy 89.309184 -275.868151) (xy 89.317127 -275.815447) (xy 89.332837 -275.764517) (xy 89.355963 -275.716496)
			(xy 89.385987 -275.672459) (xy 89.422239 -275.633388) (xy 89.46391 -275.600157) (xy 89.510068 -275.573508)
			(xy 89.559682 -275.554036) (xy 89.611644 -275.542176) (xy 89.664794 -275.538193) (xy 89.717944 -275.542176)
			(xy 89.769906 -275.554036) (xy 89.81952 -275.573508) (xy 89.865678 -275.600157) (xy 89.907349 -275.633388)
			(xy 89.943601 -275.672459) (xy 89.973625 -275.716496) (xy 89.996751 -275.764517) (xy 90.012461 -275.815447)
			(xy 90.020404 -275.868151) (xy 90.020902 -275.8948) (xy 90.020404 -275.921449) (xy 90.248984 -275.921449)
			(xy 90.248984 -275.868151) (xy 90.256927 -275.815447) (xy 90.272637 -275.764517) (xy 90.295763 -275.716496)
			(xy 90.325787 -275.672459) (xy 90.362039 -275.633388) (xy 90.40371 -275.600157) (xy 90.449868 -275.573508)
			(xy 90.499482 -275.554036) (xy 90.551444 -275.542176) (xy 90.604594 -275.538193) (xy 90.657744 -275.542176)
			(xy 90.709706 -275.554036) (xy 90.75932 -275.573508) (xy 90.805478 -275.600157) (xy 90.847149 -275.633388)
			(xy 90.883401 -275.672459) (xy 90.913425 -275.716496) (xy 90.936551 -275.764517) (xy 90.952261 -275.815447)
			(xy 90.960204 -275.868151) (xy 90.960702 -275.8948) (xy 90.960204 -275.921449) (xy 91.188784 -275.921449)
			(xy 91.188784 -275.868151) (xy 91.196727 -275.815447) (xy 91.212437 -275.764517) (xy 91.235563 -275.716496)
			(xy 91.265587 -275.672459) (xy 91.301839 -275.633388) (xy 91.34351 -275.600157) (xy 91.389668 -275.573508)
			(xy 91.439282 -275.554036) (xy 91.491244 -275.542176) (xy 91.544394 -275.538193) (xy 91.597544 -275.542176)
			(xy 91.649506 -275.554036) (xy 91.69912 -275.573508) (xy 91.745278 -275.600157) (xy 91.786949 -275.633388)
			(xy 91.823201 -275.672459) (xy 91.853225 -275.716496) (xy 91.876351 -275.764517) (xy 91.892061 -275.815447)
			(xy 91.900004 -275.868151) (xy 91.900502 -275.8948) (xy 91.900004 -275.921449) (xy 92.128584 -275.921449)
			(xy 92.128584 -275.868151) (xy 92.136527 -275.815447) (xy 92.152237 -275.764517) (xy 92.175363 -275.716496)
			(xy 92.205387 -275.672459) (xy 92.241639 -275.633388) (xy 92.28331 -275.600157) (xy 92.329468 -275.573508)
			(xy 92.379082 -275.554036) (xy 92.431044 -275.542176) (xy 92.484194 -275.538193) (xy 92.537344 -275.542176)
			(xy 92.589306 -275.554036) (xy 92.63892 -275.573508) (xy 92.685078 -275.600157) (xy 92.726749 -275.633388)
			(xy 92.763001 -275.672459) (xy 92.793025 -275.716496) (xy 92.816151 -275.764517) (xy 92.831861 -275.815447)
			(xy 92.839804 -275.868151) (xy 92.840302 -275.8948) (xy 92.839804 -275.921449) (xy 93.068384 -275.921449)
			(xy 93.068384 -275.868151) (xy 93.076327 -275.815447) (xy 93.092037 -275.764517) (xy 93.115163 -275.716496)
			(xy 93.145187 -275.672459) (xy 93.181439 -275.633388) (xy 93.22311 -275.600157) (xy 93.269268 -275.573508)
			(xy 93.318882 -275.554036) (xy 93.370844 -275.542176) (xy 93.423994 -275.538193) (xy 93.477144 -275.542176)
			(xy 93.529106 -275.554036) (xy 93.57872 -275.573508) (xy 93.624878 -275.600157) (xy 93.666549 -275.633388)
			(xy 93.702801 -275.672459) (xy 93.732825 -275.716496) (xy 93.755951 -275.764517) (xy 93.771661 -275.815447)
			(xy 93.779604 -275.868151) (xy 93.780102 -275.8948) (xy 93.779604 -275.921449) (xy 94.008438 -275.921449)
			(xy 94.008438 -275.868151) (xy 94.016381 -275.815447) (xy 94.032091 -275.764517) (xy 94.055217 -275.716496)
			(xy 94.085241 -275.672459) (xy 94.121493 -275.633388) (xy 94.163164 -275.600157) (xy 94.209322 -275.573508)
			(xy 94.258936 -275.554036) (xy 94.310898 -275.542176) (xy 94.364048 -275.538193) (xy 94.417198 -275.542176)
			(xy 94.46916 -275.554036) (xy 94.518774 -275.573508) (xy 94.564932 -275.600157) (xy 94.606603 -275.633388)
			(xy 94.642855 -275.672459) (xy 94.672879 -275.716496) (xy 94.696005 -275.764517) (xy 94.711715 -275.815447)
			(xy 94.719658 -275.868151) (xy 94.720156 -275.8948) (xy 94.719658 -275.921449) (xy 94.947984 -275.921449)
			(xy 94.947984 -275.868151) (xy 94.955927 -275.815447) (xy 94.971637 -275.764517) (xy 94.994763 -275.716496)
			(xy 95.024787 -275.672459) (xy 95.061039 -275.633388) (xy 95.10271 -275.600157) (xy 95.148868 -275.573508)
			(xy 95.198482 -275.554036) (xy 95.250444 -275.542176) (xy 95.303594 -275.538193) (xy 95.356744 -275.542176)
			(xy 95.408706 -275.554036) (xy 95.45832 -275.573508) (xy 95.504478 -275.600157) (xy 95.546149 -275.633388)
			(xy 95.582401 -275.672459) (xy 95.612425 -275.716496) (xy 95.635551 -275.764517) (xy 95.651261 -275.815447)
			(xy 95.659204 -275.868151) (xy 95.659702 -275.8948) (xy 95.659204 -275.921449) (xy 95.887784 -275.921449)
			(xy 95.887784 -275.868151) (xy 95.895727 -275.815447) (xy 95.911437 -275.764517) (xy 95.934563 -275.716496)
			(xy 95.964587 -275.672459) (xy 96.000839 -275.633388) (xy 96.04251 -275.600157) (xy 96.088668 -275.573508)
			(xy 96.138282 -275.554036) (xy 96.190244 -275.542176) (xy 96.243394 -275.538193) (xy 96.296544 -275.542176)
			(xy 96.348506 -275.554036) (xy 96.39812 -275.573508) (xy 96.444278 -275.600157) (xy 96.485949 -275.633388)
			(xy 96.522201 -275.672459) (xy 96.552225 -275.716496) (xy 96.575351 -275.764517) (xy 96.591061 -275.815447)
			(xy 96.599004 -275.868151) (xy 96.599502 -275.8948) (xy 96.599004 -275.921449) (xy 96.827584 -275.921449)
			(xy 96.827584 -275.868151) (xy 96.835527 -275.815447) (xy 96.851237 -275.764517) (xy 96.874363 -275.716496)
			(xy 96.904387 -275.672459) (xy 96.940639 -275.633388) (xy 96.98231 -275.600157) (xy 97.028468 -275.573508)
			(xy 97.078082 -275.554036) (xy 97.130044 -275.542176) (xy 97.183194 -275.538193) (xy 97.236344 -275.542176)
			(xy 97.288306 -275.554036) (xy 97.33792 -275.573508) (xy 97.384078 -275.600157) (xy 97.425749 -275.633388)
			(xy 97.462001 -275.672459) (xy 97.492025 -275.716496) (xy 97.515151 -275.764517) (xy 97.530861 -275.815447)
			(xy 97.538804 -275.868151) (xy 97.539302 -275.8948) (xy 97.538804 -275.921449) (xy 97.767384 -275.921449)
			(xy 97.767384 -275.868151) (xy 97.775327 -275.815447) (xy 97.791037 -275.764517) (xy 97.814163 -275.716496)
			(xy 97.844187 -275.672459) (xy 97.880439 -275.633388) (xy 97.92211 -275.600157) (xy 97.968268 -275.573508)
			(xy 98.017882 -275.554036) (xy 98.069844 -275.542176) (xy 98.122994 -275.538193) (xy 98.176144 -275.542176)
			(xy 98.228106 -275.554036) (xy 98.27772 -275.573508) (xy 98.323878 -275.600157) (xy 98.365549 -275.633388)
			(xy 98.401801 -275.672459) (xy 98.431825 -275.716496) (xy 98.454951 -275.764517) (xy 98.470661 -275.815447)
			(xy 98.478604 -275.868151) (xy 98.479102 -275.8948) (xy 98.478604 -275.921449) (xy 98.707184 -275.921449)
			(xy 98.707184 -275.868151) (xy 98.715127 -275.815447) (xy 98.730837 -275.764517) (xy 98.753963 -275.716496)
			(xy 98.783987 -275.672459) (xy 98.820239 -275.633388) (xy 98.86191 -275.600157) (xy 98.908068 -275.573508)
			(xy 98.957682 -275.554036) (xy 99.009644 -275.542176) (xy 99.062794 -275.538193) (xy 99.115944 -275.542176)
			(xy 99.167906 -275.554036) (xy 99.21752 -275.573508) (xy 99.263678 -275.600157) (xy 99.305349 -275.633388)
			(xy 99.341601 -275.672459) (xy 99.371625 -275.716496) (xy 99.394751 -275.764517) (xy 99.410461 -275.815447)
			(xy 99.418404 -275.868151) (xy 99.418902 -275.8948) (xy 99.418404 -275.921449) (xy 99.646984 -275.921449)
			(xy 99.646984 -275.868151) (xy 99.654927 -275.815447) (xy 99.670637 -275.764517) (xy 99.693763 -275.716496)
			(xy 99.723787 -275.672459) (xy 99.760039 -275.633388) (xy 99.80171 -275.600157) (xy 99.847868 -275.573508)
			(xy 99.897482 -275.554036) (xy 99.949444 -275.542176) (xy 100.002594 -275.538193) (xy 100.055744 -275.542176)
			(xy 100.107706 -275.554036) (xy 100.15732 -275.573508) (xy 100.203478 -275.600157) (xy 100.245149 -275.633388)
			(xy 100.281401 -275.672459) (xy 100.311425 -275.716496) (xy 100.334551 -275.764517) (xy 100.350261 -275.815447)
			(xy 100.358204 -275.868151) (xy 100.358702 -275.8948) (xy 100.358204 -275.921449) (xy 100.587038 -275.921449)
			(xy 100.587038 -275.868151) (xy 100.594981 -275.815447) (xy 100.610691 -275.764517) (xy 100.633817 -275.716496)
			(xy 100.663841 -275.672459) (xy 100.700093 -275.633388) (xy 100.741764 -275.600157) (xy 100.787922 -275.573508)
			(xy 100.837536 -275.554036) (xy 100.889498 -275.542176) (xy 100.942648 -275.538193) (xy 100.995798 -275.542176)
			(xy 101.04776 -275.554036) (xy 101.097374 -275.573508) (xy 101.143532 -275.600157) (xy 101.185203 -275.633388)
			(xy 101.221455 -275.672459) (xy 101.251479 -275.716496) (xy 101.274605 -275.764517) (xy 101.290315 -275.815447)
			(xy 101.298258 -275.868151) (xy 101.298756 -275.8948) (xy 101.298258 -275.921449) (xy 101.526584 -275.921449)
			(xy 101.526584 -275.868151) (xy 101.534527 -275.815447) (xy 101.550237 -275.764517) (xy 101.573363 -275.716496)
			(xy 101.603387 -275.672459) (xy 101.639639 -275.633388) (xy 101.68131 -275.600157) (xy 101.727468 -275.573508)
			(xy 101.777082 -275.554036) (xy 101.829044 -275.542176) (xy 101.882194 -275.538193) (xy 101.935344 -275.542176)
			(xy 101.987306 -275.554036) (xy 102.03692 -275.573508) (xy 102.083078 -275.600157) (xy 102.124749 -275.633388)
			(xy 102.161001 -275.672459) (xy 102.191025 -275.716496) (xy 102.214151 -275.764517) (xy 102.229861 -275.815447)
			(xy 102.237804 -275.868151) (xy 102.238302 -275.8948) (xy 102.237804 -275.921449) (xy 102.229861 -275.974153)
			(xy 102.214151 -276.025083) (xy 102.191025 -276.073104) (xy 102.161001 -276.117141) (xy 102.124749 -276.156212)
			(xy 102.083078 -276.189443) (xy 102.03692 -276.216092) (xy 101.987306 -276.235564) (xy 101.935344 -276.247424)
			(xy 101.882194 -276.251408) (xy 101.829044 -276.247424) (xy 101.777082 -276.235564) (xy 101.727468 -276.216092)
			(xy 101.68131 -276.189443) (xy 101.639639 -276.156212) (xy 101.603387 -276.117141) (xy 101.573363 -276.073104)
			(xy 101.550237 -276.025083) (xy 101.534527 -275.974153) (xy 101.526584 -275.921449) (xy 101.298258 -275.921449)
			(xy 101.290315 -275.974153) (xy 101.274605 -276.025083) (xy 101.251479 -276.073104) (xy 101.221455 -276.117141)
			(xy 101.185203 -276.156212) (xy 101.143532 -276.189443) (xy 101.097374 -276.216092) (xy 101.04776 -276.235564)
			(xy 100.995798 -276.247424) (xy 100.942648 -276.251408) (xy 100.889498 -276.247424) (xy 100.837536 -276.235564)
			(xy 100.787922 -276.216092) (xy 100.741764 -276.189443) (xy 100.700093 -276.156212) (xy 100.663841 -276.117141)
			(xy 100.633817 -276.073104) (xy 100.610691 -276.025083) (xy 100.594981 -275.974153) (xy 100.587038 -275.921449)
			(xy 100.358204 -275.921449) (xy 100.350261 -275.974153) (xy 100.334551 -276.025083) (xy 100.311425 -276.073104)
			(xy 100.281401 -276.117141) (xy 100.245149 -276.156212) (xy 100.203478 -276.189443) (xy 100.15732 -276.216092)
			(xy 100.107706 -276.235564) (xy 100.055744 -276.247424) (xy 100.002594 -276.251408) (xy 99.949444 -276.247424)
			(xy 99.897482 -276.235564) (xy 99.847868 -276.216092) (xy 99.80171 -276.189443) (xy 99.760039 -276.156212)
			(xy 99.723787 -276.117141) (xy 99.693763 -276.073104) (xy 99.670637 -276.025083) (xy 99.654927 -275.974153)
			(xy 99.646984 -275.921449) (xy 99.418404 -275.921449) (xy 99.410461 -275.974153) (xy 99.394751 -276.025083)
			(xy 99.371625 -276.073104) (xy 99.341601 -276.117141) (xy 99.305349 -276.156212) (xy 99.263678 -276.189443)
			(xy 99.21752 -276.216092) (xy 99.167906 -276.235564) (xy 99.115944 -276.247424) (xy 99.062794 -276.251408)
			(xy 99.009644 -276.247424) (xy 98.957682 -276.235564) (xy 98.908068 -276.216092) (xy 98.86191 -276.189443)
			(xy 98.820239 -276.156212) (xy 98.783987 -276.117141) (xy 98.753963 -276.073104) (xy 98.730837 -276.025083)
			(xy 98.715127 -275.974153) (xy 98.707184 -275.921449) (xy 98.478604 -275.921449) (xy 98.470661 -275.974153)
			(xy 98.454951 -276.025083) (xy 98.431825 -276.073104) (xy 98.401801 -276.117141) (xy 98.365549 -276.156212)
			(xy 98.323878 -276.189443) (xy 98.27772 -276.216092) (xy 98.228106 -276.235564) (xy 98.176144 -276.247424)
			(xy 98.122994 -276.251408) (xy 98.069844 -276.247424) (xy 98.017882 -276.235564) (xy 97.968268 -276.216092)
			(xy 97.92211 -276.189443) (xy 97.880439 -276.156212) (xy 97.844187 -276.117141) (xy 97.814163 -276.073104)
			(xy 97.791037 -276.025083) (xy 97.775327 -275.974153) (xy 97.767384 -275.921449) (xy 97.538804 -275.921449)
			(xy 97.530861 -275.974153) (xy 97.515151 -276.025083) (xy 97.492025 -276.073104) (xy 97.462001 -276.117141)
			(xy 97.425749 -276.156212) (xy 97.384078 -276.189443) (xy 97.33792 -276.216092) (xy 97.288306 -276.235564)
			(xy 97.236344 -276.247424) (xy 97.183194 -276.251408) (xy 97.130044 -276.247424) (xy 97.078082 -276.235564)
			(xy 97.028468 -276.216092) (xy 96.98231 -276.189443) (xy 96.940639 -276.156212) (xy 96.904387 -276.117141)
			(xy 96.874363 -276.073104) (xy 96.851237 -276.025083) (xy 96.835527 -275.974153) (xy 96.827584 -275.921449)
			(xy 96.599004 -275.921449) (xy 96.591061 -275.974153) (xy 96.575351 -276.025083) (xy 96.552225 -276.073104)
			(xy 96.522201 -276.117141) (xy 96.485949 -276.156212) (xy 96.444278 -276.189443) (xy 96.39812 -276.216092)
			(xy 96.348506 -276.235564) (xy 96.296544 -276.247424) (xy 96.243394 -276.251408) (xy 96.190244 -276.247424)
			(xy 96.138282 -276.235564) (xy 96.088668 -276.216092) (xy 96.04251 -276.189443) (xy 96.000839 -276.156212)
			(xy 95.964587 -276.117141) (xy 95.934563 -276.073104) (xy 95.911437 -276.025083) (xy 95.895727 -275.974153)
			(xy 95.887784 -275.921449) (xy 95.659204 -275.921449) (xy 95.651261 -275.974153) (xy 95.635551 -276.025083)
			(xy 95.612425 -276.073104) (xy 95.582401 -276.117141) (xy 95.546149 -276.156212) (xy 95.504478 -276.189443)
			(xy 95.45832 -276.216092) (xy 95.408706 -276.235564) (xy 95.356744 -276.247424) (xy 95.303594 -276.251408)
			(xy 95.250444 -276.247424) (xy 95.198482 -276.235564) (xy 95.148868 -276.216092) (xy 95.10271 -276.189443)
			(xy 95.061039 -276.156212) (xy 95.024787 -276.117141) (xy 94.994763 -276.073104) (xy 94.971637 -276.025083)
			(xy 94.955927 -275.974153) (xy 94.947984 -275.921449) (xy 94.719658 -275.921449) (xy 94.711715 -275.974153)
			(xy 94.696005 -276.025083) (xy 94.672879 -276.073104) (xy 94.642855 -276.117141) (xy 94.606603 -276.156212)
			(xy 94.564932 -276.189443) (xy 94.518774 -276.216092) (xy 94.46916 -276.235564) (xy 94.417198 -276.247424)
			(xy 94.364048 -276.251408) (xy 94.310898 -276.247424) (xy 94.258936 -276.235564) (xy 94.209322 -276.216092)
			(xy 94.163164 -276.189443) (xy 94.121493 -276.156212) (xy 94.085241 -276.117141) (xy 94.055217 -276.073104)
			(xy 94.032091 -276.025083) (xy 94.016381 -275.974153) (xy 94.008438 -275.921449) (xy 93.779604 -275.921449)
			(xy 93.771661 -275.974153) (xy 93.755951 -276.025083) (xy 93.732825 -276.073104) (xy 93.702801 -276.117141)
			(xy 93.666549 -276.156212) (xy 93.624878 -276.189443) (xy 93.57872 -276.216092) (xy 93.529106 -276.235564)
			(xy 93.477144 -276.247424) (xy 93.423994 -276.251408) (xy 93.370844 -276.247424) (xy 93.318882 -276.235564)
			(xy 93.269268 -276.216092) (xy 93.22311 -276.189443) (xy 93.181439 -276.156212) (xy 93.145187 -276.117141)
			(xy 93.115163 -276.073104) (xy 93.092037 -276.025083) (xy 93.076327 -275.974153) (xy 93.068384 -275.921449)
			(xy 92.839804 -275.921449) (xy 92.831861 -275.974153) (xy 92.816151 -276.025083) (xy 92.793025 -276.073104)
			(xy 92.763001 -276.117141) (xy 92.726749 -276.156212) (xy 92.685078 -276.189443) (xy 92.63892 -276.216092)
			(xy 92.589306 -276.235564) (xy 92.537344 -276.247424) (xy 92.484194 -276.251408) (xy 92.431044 -276.247424)
			(xy 92.379082 -276.235564) (xy 92.329468 -276.216092) (xy 92.28331 -276.189443) (xy 92.241639 -276.156212)
			(xy 92.205387 -276.117141) (xy 92.175363 -276.073104) (xy 92.152237 -276.025083) (xy 92.136527 -275.974153)
			(xy 92.128584 -275.921449) (xy 91.900004 -275.921449) (xy 91.892061 -275.974153) (xy 91.876351 -276.025083)
			(xy 91.853225 -276.073104) (xy 91.823201 -276.117141) (xy 91.786949 -276.156212) (xy 91.745278 -276.189443)
			(xy 91.69912 -276.216092) (xy 91.649506 -276.235564) (xy 91.597544 -276.247424) (xy 91.544394 -276.251408)
			(xy 91.491244 -276.247424) (xy 91.439282 -276.235564) (xy 91.389668 -276.216092) (xy 91.34351 -276.189443)
			(xy 91.301839 -276.156212) (xy 91.265587 -276.117141) (xy 91.235563 -276.073104) (xy 91.212437 -276.025083)
			(xy 91.196727 -275.974153) (xy 91.188784 -275.921449) (xy 90.960204 -275.921449) (xy 90.952261 -275.974153)
			(xy 90.936551 -276.025083) (xy 90.913425 -276.073104) (xy 90.883401 -276.117141) (xy 90.847149 -276.156212)
			(xy 90.805478 -276.189443) (xy 90.75932 -276.216092) (xy 90.709706 -276.235564) (xy 90.657744 -276.247424)
			(xy 90.604594 -276.251408) (xy 90.551444 -276.247424) (xy 90.499482 -276.235564) (xy 90.449868 -276.216092)
			(xy 90.40371 -276.189443) (xy 90.362039 -276.156212) (xy 90.325787 -276.117141) (xy 90.295763 -276.073104)
			(xy 90.272637 -276.025083) (xy 90.256927 -275.974153) (xy 90.248984 -275.921449) (xy 90.020404 -275.921449)
			(xy 90.012461 -275.974153) (xy 89.996751 -276.025083) (xy 89.973625 -276.073104) (xy 89.943601 -276.117141)
			(xy 89.907349 -276.156212) (xy 89.865678 -276.189443) (xy 89.81952 -276.216092) (xy 89.769906 -276.235564)
			(xy 89.717944 -276.247424) (xy 89.664794 -276.251408) (xy 89.611644 -276.247424) (xy 89.559682 -276.235564)
			(xy 89.510068 -276.216092) (xy 89.46391 -276.189443) (xy 89.422239 -276.156212) (xy 89.385987 -276.117141)
			(xy 89.355963 -276.073104) (xy 89.332837 -276.025083) (xy 89.317127 -275.974153) (xy 89.309184 -275.921449)
			(xy 89.080604 -275.921449) (xy 89.072661 -275.974153) (xy 89.056951 -276.025083) (xy 89.033825 -276.073104)
			(xy 89.003801 -276.117141) (xy 88.967549 -276.156212) (xy 88.925878 -276.189443) (xy 88.87972 -276.216092)
			(xy 88.830106 -276.235564) (xy 88.778144 -276.247424) (xy 88.724994 -276.251408) (xy 88.671844 -276.247424)
			(xy 88.619882 -276.235564) (xy 88.570268 -276.216092) (xy 88.52411 -276.189443) (xy 88.482439 -276.156212)
			(xy 88.446187 -276.117141) (xy 88.416163 -276.073104) (xy 88.393037 -276.025083) (xy 88.377327 -275.974153)
			(xy 88.369384 -275.921449) (xy 88.14055 -275.921449) (xy 88.132607 -275.974153) (xy 88.116897 -276.025083)
			(xy 88.093771 -276.073104) (xy 88.063747 -276.117141) (xy 88.027495 -276.156212) (xy 87.985824 -276.189443)
			(xy 87.939666 -276.216092) (xy 87.890052 -276.235564) (xy 87.83809 -276.247424) (xy 87.78494 -276.251408)
			(xy 87.73179 -276.247424) (xy 87.679828 -276.235564) (xy 87.630214 -276.216092) (xy 87.584056 -276.189443)
			(xy 87.542385 -276.156212) (xy 87.506133 -276.117141) (xy 87.476109 -276.073104) (xy 87.452983 -276.025083)
			(xy 87.437273 -275.974153) (xy 87.42933 -275.921449) (xy 85.863959 -275.921449) (xy 85.52688 -276.258528)
			(xy 85.52688 -276.735265) (xy 87.899484 -276.735265) (xy 87.899484 -276.681967) (xy 87.907427 -276.629263)
			(xy 87.923137 -276.578333) (xy 87.946263 -276.530312) (xy 87.976287 -276.486275) (xy 88.012539 -276.447204)
			(xy 88.05421 -276.413973) (xy 88.100368 -276.387324) (xy 88.149982 -276.367852) (xy 88.201944 -276.355992)
			(xy 88.255094 -276.352009) (xy 88.308244 -276.355992) (xy 88.360206 -276.367852) (xy 88.40982 -276.387324)
			(xy 88.455978 -276.413973) (xy 88.497649 -276.447204) (xy 88.533901 -276.486275) (xy 88.563925 -276.530312)
			(xy 88.587051 -276.578333) (xy 88.602761 -276.629263) (xy 88.610704 -276.681967) (xy 88.611202 -276.708616)
			(xy 88.610704 -276.735265) (xy 88.839284 -276.735265) (xy 88.839284 -276.681967) (xy 88.847227 -276.629263)
			(xy 88.862937 -276.578333) (xy 88.886063 -276.530312) (xy 88.916087 -276.486275) (xy 88.952339 -276.447204)
			(xy 88.99401 -276.413973) (xy 89.040168 -276.387324) (xy 89.089782 -276.367852) (xy 89.141744 -276.355992)
			(xy 89.194894 -276.352009) (xy 89.248044 -276.355992) (xy 89.300006 -276.367852) (xy 89.34962 -276.387324)
			(xy 89.395778 -276.413973) (xy 89.437449 -276.447204) (xy 89.473701 -276.486275) (xy 89.503725 -276.530312)
			(xy 89.526851 -276.578333) (xy 89.542561 -276.629263) (xy 89.550504 -276.681967) (xy 89.551002 -276.708616)
			(xy 89.550504 -276.735265) (xy 89.779084 -276.735265) (xy 89.779084 -276.681967) (xy 89.787027 -276.629263)
			(xy 89.802737 -276.578333) (xy 89.825863 -276.530312) (xy 89.855887 -276.486275) (xy 89.892139 -276.447204)
			(xy 89.93381 -276.413973) (xy 89.979968 -276.387324) (xy 90.029582 -276.367852) (xy 90.081544 -276.355992)
			(xy 90.134694 -276.352009) (xy 90.187844 -276.355992) (xy 90.239806 -276.367852) (xy 90.28942 -276.387324)
			(xy 90.335578 -276.413973) (xy 90.377249 -276.447204) (xy 90.413501 -276.486275) (xy 90.443525 -276.530312)
			(xy 90.466651 -276.578333) (xy 90.482361 -276.629263) (xy 90.490304 -276.681967) (xy 90.490802 -276.708616)
			(xy 90.490304 -276.735265) (xy 90.718884 -276.735265) (xy 90.718884 -276.681967) (xy 90.726827 -276.629263)
			(xy 90.742537 -276.578333) (xy 90.765663 -276.530312) (xy 90.795687 -276.486275) (xy 90.831939 -276.447204)
			(xy 90.87361 -276.413973) (xy 90.919768 -276.387324) (xy 90.969382 -276.367852) (xy 91.021344 -276.355992)
			(xy 91.074494 -276.352009) (xy 91.127644 -276.355992) (xy 91.179606 -276.367852) (xy 91.22922 -276.387324)
			(xy 91.275378 -276.413973) (xy 91.317049 -276.447204) (xy 91.353301 -276.486275) (xy 91.383325 -276.530312)
			(xy 91.406451 -276.578333) (xy 91.422161 -276.629263) (xy 91.430104 -276.681967) (xy 91.430602 -276.708616)
			(xy 91.430104 -276.735265) (xy 91.658938 -276.735265) (xy 91.658938 -276.681967) (xy 91.666881 -276.629263)
			(xy 91.682591 -276.578333) (xy 91.705717 -276.530312) (xy 91.735741 -276.486275) (xy 91.771993 -276.447204)
			(xy 91.813664 -276.413973) (xy 91.859822 -276.387324) (xy 91.909436 -276.367852) (xy 91.961398 -276.355992)
			(xy 92.014548 -276.352009) (xy 92.067698 -276.355992) (xy 92.11966 -276.367852) (xy 92.169274 -276.387324)
			(xy 92.215432 -276.413973) (xy 92.257103 -276.447204) (xy 92.293355 -276.486275) (xy 92.323379 -276.530312)
			(xy 92.346505 -276.578333) (xy 92.362215 -276.629263) (xy 92.370158 -276.681967) (xy 92.370656 -276.708616)
			(xy 92.370158 -276.735265) (xy 92.598738 -276.735265) (xy 92.598738 -276.681967) (xy 92.606681 -276.629263)
			(xy 92.622391 -276.578333) (xy 92.645517 -276.530312) (xy 92.675541 -276.486275) (xy 92.711793 -276.447204)
			(xy 92.753464 -276.413973) (xy 92.799622 -276.387324) (xy 92.849236 -276.367852) (xy 92.901198 -276.355992)
			(xy 92.954348 -276.352009) (xy 93.007498 -276.355992) (xy 93.05946 -276.367852) (xy 93.109074 -276.387324)
			(xy 93.155232 -276.413973) (xy 93.196903 -276.447204) (xy 93.233155 -276.486275) (xy 93.263179 -276.530312)
			(xy 93.286305 -276.578333) (xy 93.302015 -276.629263) (xy 93.309958 -276.681967) (xy 93.310456 -276.708616)
			(xy 93.309958 -276.735265) (xy 93.538538 -276.735265) (xy 93.538538 -276.681967) (xy 93.546481 -276.629263)
			(xy 93.562191 -276.578333) (xy 93.585317 -276.530312) (xy 93.615341 -276.486275) (xy 93.651593 -276.447204)
			(xy 93.693264 -276.413973) (xy 93.739422 -276.387324) (xy 93.789036 -276.367852) (xy 93.840998 -276.355992)
			(xy 93.894148 -276.352009) (xy 93.947298 -276.355992) (xy 93.99926 -276.367852) (xy 94.048874 -276.387324)
			(xy 94.095032 -276.413973) (xy 94.136703 -276.447204) (xy 94.172955 -276.486275) (xy 94.202979 -276.530312)
			(xy 94.226105 -276.578333) (xy 94.241815 -276.629263) (xy 94.249758 -276.681967) (xy 94.250256 -276.708616)
			(xy 94.249758 -276.735265) (xy 94.478338 -276.735265) (xy 94.478338 -276.681967) (xy 94.486281 -276.629263)
			(xy 94.501991 -276.578333) (xy 94.525117 -276.530312) (xy 94.555141 -276.486275) (xy 94.591393 -276.447204)
			(xy 94.633064 -276.413973) (xy 94.679222 -276.387324) (xy 94.728836 -276.367852) (xy 94.780798 -276.355992)
			(xy 94.833948 -276.352009) (xy 94.887098 -276.355992) (xy 94.93906 -276.367852) (xy 94.988674 -276.387324)
			(xy 95.034832 -276.413973) (xy 95.076503 -276.447204) (xy 95.112755 -276.486275) (xy 95.142779 -276.530312)
			(xy 95.165905 -276.578333) (xy 95.181615 -276.629263) (xy 95.189558 -276.681967) (xy 95.190056 -276.708616)
			(xy 95.189558 -276.735265) (xy 95.418138 -276.735265) (xy 95.418138 -276.681967) (xy 95.426081 -276.629263)
			(xy 95.441791 -276.578333) (xy 95.464917 -276.530312) (xy 95.494941 -276.486275) (xy 95.531193 -276.447204)
			(xy 95.572864 -276.413973) (xy 95.619022 -276.387324) (xy 95.668636 -276.367852) (xy 95.720598 -276.355992)
			(xy 95.773748 -276.352009) (xy 95.826898 -276.355992) (xy 95.87886 -276.367852) (xy 95.928474 -276.387324)
			(xy 95.974632 -276.413973) (xy 96.016303 -276.447204) (xy 96.052555 -276.486275) (xy 96.082579 -276.530312)
			(xy 96.105705 -276.578333) (xy 96.121415 -276.629263) (xy 96.129358 -276.681967) (xy 96.129856 -276.708616)
			(xy 96.129358 -276.735265) (xy 96.357938 -276.735265) (xy 96.357938 -276.681967) (xy 96.365881 -276.629263)
			(xy 96.381591 -276.578333) (xy 96.404717 -276.530312) (xy 96.434741 -276.486275) (xy 96.470993 -276.447204)
			(xy 96.512664 -276.413973) (xy 96.558822 -276.387324) (xy 96.608436 -276.367852) (xy 96.660398 -276.355992)
			(xy 96.713548 -276.352009) (xy 96.766698 -276.355992) (xy 96.81866 -276.367852) (xy 96.868274 -276.387324)
			(xy 96.914432 -276.413973) (xy 96.956103 -276.447204) (xy 96.992355 -276.486275) (xy 97.022379 -276.530312)
			(xy 97.045505 -276.578333) (xy 97.061215 -276.629263) (xy 97.069158 -276.681967) (xy 97.069656 -276.708616)
			(xy 97.069158 -276.735265) (xy 97.297484 -276.735265) (xy 97.297484 -276.681967) (xy 97.305427 -276.629263)
			(xy 97.321137 -276.578333) (xy 97.344263 -276.530312) (xy 97.374287 -276.486275) (xy 97.410539 -276.447204)
			(xy 97.45221 -276.413973) (xy 97.498368 -276.387324) (xy 97.547982 -276.367852) (xy 97.599944 -276.355992)
			(xy 97.653094 -276.352009) (xy 97.706244 -276.355992) (xy 97.758206 -276.367852) (xy 97.80782 -276.387324)
			(xy 97.853978 -276.413973) (xy 97.895649 -276.447204) (xy 97.931901 -276.486275) (xy 97.961925 -276.530312)
			(xy 97.985051 -276.578333) (xy 98.000761 -276.629263) (xy 98.008704 -276.681967) (xy 98.009202 -276.708616)
			(xy 98.008704 -276.735265) (xy 98.237538 -276.735265) (xy 98.237538 -276.681967) (xy 98.245481 -276.629263)
			(xy 98.261191 -276.578333) (xy 98.284317 -276.530312) (xy 98.314341 -276.486275) (xy 98.350593 -276.447204)
			(xy 98.392264 -276.413973) (xy 98.438422 -276.387324) (xy 98.488036 -276.367852) (xy 98.539998 -276.355992)
			(xy 98.593148 -276.352009) (xy 98.646298 -276.355992) (xy 98.69826 -276.367852) (xy 98.747874 -276.387324)
			(xy 98.794032 -276.413973) (xy 98.835703 -276.447204) (xy 98.871955 -276.486275) (xy 98.901979 -276.530312)
			(xy 98.925105 -276.578333) (xy 98.940815 -276.629263) (xy 98.948758 -276.681967) (xy 98.949256 -276.708616)
			(xy 98.948758 -276.735265) (xy 99.177338 -276.735265) (xy 99.177338 -276.681967) (xy 99.185281 -276.629263)
			(xy 99.200991 -276.578333) (xy 99.224117 -276.530312) (xy 99.254141 -276.486275) (xy 99.290393 -276.447204)
			(xy 99.332064 -276.413973) (xy 99.378222 -276.387324) (xy 99.427836 -276.367852) (xy 99.479798 -276.355992)
			(xy 99.532948 -276.352009) (xy 99.586098 -276.355992) (xy 99.63806 -276.367852) (xy 99.687674 -276.387324)
			(xy 99.733832 -276.413973) (xy 99.775503 -276.447204) (xy 99.811755 -276.486275) (xy 99.841779 -276.530312)
			(xy 99.864905 -276.578333) (xy 99.880615 -276.629263) (xy 99.888558 -276.681967) (xy 99.889056 -276.708616)
			(xy 99.888558 -276.735265) (xy 100.117138 -276.735265) (xy 100.117138 -276.681967) (xy 100.125081 -276.629263)
			(xy 100.140791 -276.578333) (xy 100.163917 -276.530312) (xy 100.193941 -276.486275) (xy 100.230193 -276.447204)
			(xy 100.271864 -276.413973) (xy 100.318022 -276.387324) (xy 100.367636 -276.367852) (xy 100.419598 -276.355992)
			(xy 100.472748 -276.352009) (xy 100.525898 -276.355992) (xy 100.57786 -276.367852) (xy 100.627474 -276.387324)
			(xy 100.673632 -276.413973) (xy 100.715303 -276.447204) (xy 100.751555 -276.486275) (xy 100.781579 -276.530312)
			(xy 100.804705 -276.578333) (xy 100.820415 -276.629263) (xy 100.828358 -276.681967) (xy 100.828856 -276.708616)
			(xy 100.828358 -276.735265) (xy 101.056938 -276.735265) (xy 101.056938 -276.681967) (xy 101.064881 -276.629263)
			(xy 101.080591 -276.578333) (xy 101.103717 -276.530312) (xy 101.133741 -276.486275) (xy 101.169993 -276.447204)
			(xy 101.211664 -276.413973) (xy 101.257822 -276.387324) (xy 101.307436 -276.367852) (xy 101.359398 -276.355992)
			(xy 101.412548 -276.352009) (xy 101.465698 -276.355992) (xy 101.51766 -276.367852) (xy 101.567274 -276.387324)
			(xy 101.613432 -276.413973) (xy 101.655103 -276.447204) (xy 101.691355 -276.486275) (xy 101.721379 -276.530312)
			(xy 101.744505 -276.578333) (xy 101.760215 -276.629263) (xy 101.768158 -276.681967) (xy 101.768656 -276.708616)
			(xy 101.995986 -276.708616) (xy 101.996392 -276.682986) (xy 102.003727 -276.632253) (xy 102.018261 -276.583097)
			(xy 102.039694 -276.536532) (xy 102.067583 -276.493523) (xy 102.101352 -276.454958) (xy 102.140302 -276.421634)
			(xy 102.183629 -276.394241) (xy 102.230436 -276.373343) (xy 102.279756 -276.359374) (xy 102.305104 -276.355556)
			(xy 102.329742 -276.352254) (xy 102.502208 -276.05355) (xy 102.49281 -276.030436) (xy 102.484305 -276.008845)
			(xy 102.472334 -275.964011) (xy 102.466278 -275.918002) (xy 102.465886 -275.8948) (xy 102.466384 -275.868151)
			(xy 102.474327 -275.815447) (xy 102.490037 -275.764517) (xy 102.513163 -275.716496) (xy 102.543187 -275.672459)
			(xy 102.579439 -275.633388) (xy 102.62111 -275.600157) (xy 102.667268 -275.573508) (xy 102.716882 -275.554036)
			(xy 102.768844 -275.542176) (xy 102.821994 -275.538193) (xy 102.875144 -275.542176) (xy 102.927106 -275.554036)
			(xy 102.97672 -275.573508) (xy 103.022878 -275.600157) (xy 103.064549 -275.633388) (xy 103.100801 -275.672459)
			(xy 103.130825 -275.716496) (xy 103.153951 -275.764517) (xy 103.169661 -275.815447) (xy 103.177604 -275.868151)
			(xy 103.178102 -275.8948) (xy 103.177721 -275.920431) (xy 103.177574 -275.921449) (xy 103.406184 -275.921449)
			(xy 103.406184 -275.868151) (xy 103.414127 -275.815447) (xy 103.429837 -275.764517) (xy 103.452963 -275.716496)
			(xy 103.482987 -275.672459) (xy 103.519239 -275.633388) (xy 103.56091 -275.600157) (xy 103.607068 -275.573508)
			(xy 103.656682 -275.554036) (xy 103.708644 -275.542176) (xy 103.761794 -275.538193) (xy 103.814944 -275.542176)
			(xy 103.866906 -275.554036) (xy 103.91652 -275.573508) (xy 103.962678 -275.600157) (xy 104.004349 -275.633388)
			(xy 104.040601 -275.672459) (xy 104.070625 -275.716496) (xy 104.093751 -275.764517) (xy 104.109461 -275.815447)
			(xy 104.117404 -275.868151) (xy 104.117902 -275.8948) (xy 104.345486 -275.8948) (xy 104.345877 -275.869169)
			(xy 104.353214 -275.818436) (xy 104.36775 -275.769279) (xy 104.389185 -275.722715) (xy 104.417076 -275.679706)
			(xy 104.450847 -275.641141) (xy 104.489798 -275.607817) (xy 104.533126 -275.580424) (xy 104.579934 -275.559527)
			(xy 104.629256 -275.545558) (xy 104.654604 -275.54174) (xy 104.679242 -275.538438) (xy 104.851962 -275.23948)
			(xy 104.842564 -275.216366) (xy 104.834071 -275.194771) (xy 104.822095 -275.149939) (xy 104.816034 -275.103932)
			(xy 104.81564 -275.08073) (xy 104.816138 -275.054081) (xy 104.824081 -275.001377) (xy 104.839791 -274.950447)
			(xy 104.862917 -274.902426) (xy 104.892941 -274.858389) (xy 104.929193 -274.819318) (xy 104.970864 -274.786087)
			(xy 105.017022 -274.759438) (xy 105.066636 -274.739966) (xy 105.118598 -274.728106) (xy 105.171748 -274.724123)
			(xy 105.224898 -274.728106) (xy 105.27686 -274.739966) (xy 105.326474 -274.759438) (xy 105.372632 -274.786087)
			(xy 105.414303 -274.819318) (xy 105.450555 -274.858389) (xy 105.480579 -274.902426) (xy 105.503705 -274.950447)
			(xy 105.519415 -275.001377) (xy 105.527358 -275.054081) (xy 105.527856 -275.08073) (xy 105.527422 -275.10637)
			(xy 105.527276 -275.107379) (xy 105.755684 -275.107379) (xy 105.755684 -275.054081) (xy 105.763627 -275.001377)
			(xy 105.779337 -274.950447) (xy 105.802463 -274.902426) (xy 105.832487 -274.858389) (xy 105.868739 -274.819318)
			(xy 105.91041 -274.786087) (xy 105.956568 -274.759438) (xy 106.006182 -274.739966) (xy 106.058144 -274.728106)
			(xy 106.111294 -274.724123) (xy 106.164444 -274.728106) (xy 106.216406 -274.739966) (xy 106.26602 -274.759438)
			(xy 106.312178 -274.786087) (xy 106.353849 -274.819318) (xy 106.390101 -274.858389) (xy 106.420125 -274.902426)
			(xy 106.443251 -274.950447) (xy 106.458961 -275.001377) (xy 106.466904 -275.054081) (xy 106.467402 -275.08073)
			(xy 106.466904 -275.107379) (xy 106.695738 -275.107379) (xy 106.695738 -275.054081) (xy 106.703681 -275.001377)
			(xy 106.719391 -274.950447) (xy 106.742517 -274.902426) (xy 106.772541 -274.858389) (xy 106.808793 -274.819318)
			(xy 106.850464 -274.786087) (xy 106.896622 -274.759438) (xy 106.946236 -274.739966) (xy 106.998198 -274.728106)
			(xy 107.051348 -274.724123) (xy 107.104498 -274.728106) (xy 107.15646 -274.739966) (xy 107.206074 -274.759438)
			(xy 107.252232 -274.786087) (xy 107.293903 -274.819318) (xy 107.330155 -274.858389) (xy 107.360179 -274.902426)
			(xy 107.383305 -274.950447) (xy 107.399015 -275.001377) (xy 107.406958 -275.054081) (xy 107.407456 -275.08073)
			(xy 107.406958 -275.107379) (xy 107.399015 -275.160083) (xy 107.383305 -275.211013) (xy 107.360179 -275.259034)
			(xy 107.330155 -275.303071) (xy 107.293903 -275.342142) (xy 107.252232 -275.375373) (xy 107.206074 -275.402022)
			(xy 107.15646 -275.421494) (xy 107.104498 -275.433354) (xy 107.051348 -275.437338) (xy 106.998198 -275.433354)
			(xy 106.946236 -275.421494) (xy 106.896622 -275.402022) (xy 106.850464 -275.375373) (xy 106.808793 -275.342142)
			(xy 106.772541 -275.303071) (xy 106.742517 -275.259034) (xy 106.719391 -275.211013) (xy 106.703681 -275.160083)
			(xy 106.695738 -275.107379) (xy 106.466904 -275.107379) (xy 106.458961 -275.160083) (xy 106.443251 -275.211013)
			(xy 106.420125 -275.259034) (xy 106.390101 -275.303071) (xy 106.353849 -275.342142) (xy 106.312178 -275.375373)
			(xy 106.26602 -275.402022) (xy 106.216406 -275.421494) (xy 106.164444 -275.433354) (xy 106.111294 -275.437338)
			(xy 106.058144 -275.433354) (xy 106.006182 -275.421494) (xy 105.956568 -275.402022) (xy 105.91041 -275.375373)
			(xy 105.868739 -275.342142) (xy 105.832487 -275.303071) (xy 105.802463 -275.259034) (xy 105.779337 -275.211013)
			(xy 105.763627 -275.160083) (xy 105.755684 -275.107379) (xy 105.527276 -275.107379) (xy 105.520075 -275.157121)
			(xy 105.505525 -275.206293) (xy 105.484071 -275.252869) (xy 105.456157 -275.295885) (xy 105.422361 -275.334453)
			(xy 105.383382 -275.367773) (xy 105.340026 -275.395157) (xy 105.293191 -275.416039) (xy 105.243844 -275.429985)
			(xy 105.218484 -275.43379) (xy 105.193846 -275.437092) (xy 105.021126 -275.735796) (xy 105.030778 -275.75891)
			(xy 105.039294 -275.780542) (xy 105.051282 -275.82546) (xy 105.057326 -275.871555) (xy 105.057702 -275.8948)
			(xy 105.057204 -275.921449) (xy 105.286038 -275.921449) (xy 105.286038 -275.868151) (xy 105.293981 -275.815447)
			(xy 105.309691 -275.764517) (xy 105.332817 -275.716496) (xy 105.362841 -275.672459) (xy 105.399093 -275.633388)
			(xy 105.440764 -275.600157) (xy 105.486922 -275.573508) (xy 105.536536 -275.554036) (xy 105.588498 -275.542176)
			(xy 105.641648 -275.538193) (xy 105.694798 -275.542176) (xy 105.74676 -275.554036) (xy 105.796374 -275.573508)
			(xy 105.842532 -275.600157) (xy 105.884203 -275.633388) (xy 105.920455 -275.672459) (xy 105.950479 -275.716496)
			(xy 105.973605 -275.764517) (xy 105.989315 -275.815447) (xy 105.997258 -275.868151) (xy 105.997756 -275.8948)
			(xy 105.997258 -275.921449) (xy 105.989315 -275.974153) (xy 105.973605 -276.025083) (xy 105.950479 -276.073104)
			(xy 105.920455 -276.117141) (xy 105.884203 -276.156212) (xy 105.842532 -276.189443) (xy 105.796374 -276.216092)
			(xy 105.74676 -276.235564) (xy 105.694798 -276.247424) (xy 105.641648 -276.251408) (xy 105.588498 -276.247424)
			(xy 105.536536 -276.235564) (xy 105.486922 -276.216092) (xy 105.440764 -276.189443) (xy 105.399093 -276.156212)
			(xy 105.362841 -276.117141) (xy 105.332817 -276.073104) (xy 105.309691 -276.025083) (xy 105.293981 -275.974153)
			(xy 105.286038 -275.921449) (xy 105.057204 -275.921449) (xy 105.049261 -275.974153) (xy 105.033551 -276.025083)
			(xy 105.010425 -276.073104) (xy 104.980401 -276.117141) (xy 104.944149 -276.156212) (xy 104.902478 -276.189443)
			(xy 104.85632 -276.216092) (xy 104.806706 -276.235564) (xy 104.754744 -276.247424) (xy 104.701594 -276.251408)
			(xy 104.648444 -276.247424) (xy 104.596482 -276.235564) (xy 104.546868 -276.216092) (xy 104.50071 -276.189443)
			(xy 104.459039 -276.156212) (xy 104.422787 -276.117141) (xy 104.392763 -276.073104) (xy 104.369637 -276.025083)
			(xy 104.353927 -275.974153) (xy 104.345984 -275.921449) (xy 104.345486 -275.8948) (xy 104.117902 -275.8948)
			(xy 104.117404 -275.921449) (xy 104.109461 -275.974153) (xy 104.093751 -276.025083) (xy 104.070625 -276.073104)
			(xy 104.040601 -276.117141) (xy 104.004349 -276.156212) (xy 103.962678 -276.189443) (xy 103.91652 -276.216092)
			(xy 103.866906 -276.235564) (xy 103.814944 -276.247424) (xy 103.761794 -276.251408) (xy 103.708644 -276.247424)
			(xy 103.656682 -276.235564) (xy 103.607068 -276.216092) (xy 103.56091 -276.189443) (xy 103.519239 -276.156212)
			(xy 103.482987 -276.117141) (xy 103.452963 -276.073104) (xy 103.429837 -276.025083) (xy 103.414127 -275.974153)
			(xy 103.406184 -275.921449) (xy 103.177574 -275.921449) (xy 103.170384 -275.971165) (xy 103.155847 -276.020323)
			(xy 103.134411 -276.066888) (xy 103.106519 -276.109897) (xy 103.072747 -276.148463) (xy 103.033794 -276.181786)
			(xy 102.990465 -276.209179) (xy 102.943655 -276.230075) (xy 102.894333 -276.244042) (xy 102.868984 -276.24786)
			(xy 102.844092 -276.251162) (xy 102.671626 -276.549612) (xy 102.681278 -276.572726) (xy 102.689799 -276.594356)
			(xy 102.701785 -276.639275) (xy 102.707828 -276.685371) (xy 102.708202 -276.708616) (xy 102.93604 -276.708616)
			(xy 102.936538 -276.681967) (xy 102.944481 -276.629263) (xy 102.960191 -276.578333) (xy 102.983317 -276.530312)
			(xy 103.013341 -276.486275) (xy 103.049593 -276.447204) (xy 103.091264 -276.413973) (xy 103.137422 -276.387324)
			(xy 103.187036 -276.367852) (xy 103.238998 -276.355992) (xy 103.292148 -276.352009) (xy 103.345298 -276.355992)
			(xy 103.39726 -276.367852) (xy 103.446874 -276.387324) (xy 103.493032 -276.413973) (xy 103.534703 -276.447204)
			(xy 103.570955 -276.486275) (xy 103.600979 -276.530312) (xy 103.624105 -276.578333) (xy 103.639815 -276.629263)
			(xy 103.647758 -276.681967) (xy 103.648256 -276.7086) (xy 103.875284 -276.7086) (xy 103.879268 -276.655445)
			(xy 103.89113 -276.603477) (xy 103.910606 -276.553858) (xy 103.93726 -276.507696) (xy 103.970498 -276.466023)
			(xy 104.009575 -276.429769) (xy 104.05362 -276.399745) (xy 104.101648 -276.376622) (xy 104.152586 -276.360916)
			(xy 104.205296 -276.352978) (xy 104.231948 -276.352508) (xy 104.256963 -276.35291) (xy 104.306502 -276.359902)
			(xy 104.354575 -276.373754) (xy 104.400239 -276.394195) (xy 104.442593 -276.420823) (xy 104.480807 -276.453114)
			(xy 104.514128 -276.490432) (xy 104.528366 -276.511004) (xy 104.87533 -276.511004) (xy 104.889584 -276.490446)
			(xy 104.92291 -276.453138) (xy 104.961125 -276.420855) (xy 105.003477 -276.394232) (xy 105.049135 -276.373791)
			(xy 105.097203 -276.359934) (xy 105.146736 -276.352934) (xy 105.171748 -276.352508) (xy 105.198396 -276.352977)
			(xy 105.251096 -276.360927) (xy 105.302023 -276.376642) (xy 105.35004 -276.399771) (xy 105.394073 -276.429798)
			(xy 105.433139 -276.466051) (xy 105.466366 -276.507722) (xy 105.493013 -276.553879) (xy 105.512482 -276.603492)
			(xy 105.524341 -276.655453) (xy 105.528324 -276.7086) (xy 105.526326 -276.735265) (xy 105.755684 -276.735265)
			(xy 105.755684 -276.681967) (xy 105.763627 -276.629263) (xy 105.779337 -276.578333) (xy 105.802463 -276.530312)
			(xy 105.832487 -276.486275) (xy 105.868739 -276.447204) (xy 105.91041 -276.413973) (xy 105.956568 -276.387324)
			(xy 106.006182 -276.367852) (xy 106.058144 -276.355992) (xy 106.111294 -276.352009) (xy 106.164444 -276.355992)
			(xy 106.216406 -276.367852) (xy 106.26602 -276.387324) (xy 106.312178 -276.413973) (xy 106.353849 -276.447204)
			(xy 106.390101 -276.486275) (xy 106.420125 -276.530312) (xy 106.443251 -276.578333) (xy 106.458961 -276.629263)
			(xy 106.466904 -276.681967) (xy 106.467402 -276.708616) (xy 106.466904 -276.735265) (xy 106.458961 -276.787969)
			(xy 106.443251 -276.838899) (xy 106.420125 -276.88692) (xy 106.390101 -276.930957) (xy 106.353849 -276.970028)
			(xy 106.312178 -277.003259) (xy 106.26602 -277.029908) (xy 106.216406 -277.04938) (xy 106.164444 -277.06124)
			(xy 106.111294 -277.065224) (xy 106.058144 -277.06124) (xy 106.006182 -277.04938) (xy 105.956568 -277.029908)
			(xy 105.91041 -277.003259) (xy 105.868739 -276.970028) (xy 105.832487 -276.930957) (xy 105.802463 -276.88692)
			(xy 105.779337 -276.838899) (xy 105.763627 -276.787969) (xy 105.755684 -276.735265) (xy 105.526326 -276.735265)
			(xy 105.524341 -276.761747) (xy 105.512482 -276.813708) (xy 105.493013 -276.863321) (xy 105.466366 -276.909478)
			(xy 105.433139 -276.951149) (xy 105.394073 -276.987402) (xy 105.35004 -277.017429) (xy 105.302023 -277.040558)
			(xy 105.251096 -277.056273) (xy 105.198396 -277.064223) (xy 105.171748 -277.064724) (xy 105.146732 -277.064355)
			(xy 105.09719 -277.057361) (xy 105.049114 -277.043506) (xy 105.00345 -277.02306) (xy 104.961095 -276.996426)
			(xy 104.922883 -276.964129) (xy 104.889566 -276.926803) (xy 104.87533 -276.906228) (xy 104.528366 -276.906228)
			(xy 104.514124 -276.926795) (xy 104.480795 -276.964101) (xy 104.442578 -276.996382) (xy 104.400224 -277.023004)
			(xy 104.354564 -277.043443) (xy 104.306495 -277.057299) (xy 104.256961 -277.064299) (xy 104.231948 -277.064724)
			(xy 104.205296 -277.064222) (xy 104.152586 -277.056284) (xy 104.101648 -277.040578) (xy 104.05362 -277.017455)
			(xy 104.009575 -276.987431) (xy 103.970498 -276.951177) (xy 103.93726 -276.909504) (xy 103.910606 -276.863342)
			(xy 103.89113 -276.813723) (xy 103.879268 -276.761755) (xy 103.875284 -276.7086) (xy 103.648256 -276.7086)
			(xy 103.648256 -276.708616) (xy 103.647895 -276.731862) (xy 103.641846 -276.777957) (xy 103.629852 -276.822875)
			(xy 103.621332 -276.844506) (xy 103.61168 -276.86762) (xy 103.784146 -277.16607) (xy 103.808784 -277.169372)
			(xy 103.834118 -277.17325) (xy 103.883421 -277.187234) (xy 103.930212 -277.208138) (xy 103.973524 -277.235533)
			(xy 104.012463 -277.268851) (xy 104.046225 -277.307406) (xy 104.074113 -277.350402) (xy 104.095551 -277.39695)
			(xy 104.110098 -277.44609) (xy 104.117452 -277.496808) (xy 104.117902 -277.522432) (xy 104.117404 -277.549081)
			(xy 104.345984 -277.549081) (xy 104.345984 -277.495783) (xy 104.353927 -277.443079) (xy 104.369637 -277.392149)
			(xy 104.392763 -277.344128) (xy 104.422787 -277.300091) (xy 104.459039 -277.26102) (xy 104.50071 -277.227789)
			(xy 104.546868 -277.20114) (xy 104.596482 -277.181668) (xy 104.648444 -277.169808) (xy 104.701594 -277.165825)
			(xy 104.754744 -277.169808) (xy 104.806706 -277.181668) (xy 104.85632 -277.20114) (xy 104.902478 -277.227789)
			(xy 104.944149 -277.26102) (xy 104.980401 -277.300091) (xy 105.010425 -277.344128) (xy 105.033551 -277.392149)
			(xy 105.049261 -277.443079) (xy 105.057204 -277.495783) (xy 105.057702 -277.522432) (xy 105.057204 -277.549081)
			(xy 105.285784 -277.549081) (xy 105.285784 -277.495783) (xy 105.293727 -277.443079) (xy 105.309437 -277.392149)
			(xy 105.332563 -277.344128) (xy 105.362587 -277.300091) (xy 105.398839 -277.26102) (xy 105.44051 -277.227789)
			(xy 105.486668 -277.20114) (xy 105.536282 -277.181668) (xy 105.588244 -277.169808) (xy 105.641394 -277.165825)
			(xy 105.694544 -277.169808) (xy 105.746506 -277.181668) (xy 105.79612 -277.20114) (xy 105.842278 -277.227789)
			(xy 105.883949 -277.26102) (xy 105.920201 -277.300091) (xy 105.950225 -277.344128) (xy 105.973351 -277.392149)
			(xy 105.989061 -277.443079) (xy 105.997004 -277.495783) (xy 105.997502 -277.522432) (xy 106.225086 -277.522432)
			(xy 106.225507 -277.496802) (xy 106.232839 -277.44607) (xy 106.247371 -277.396914) (xy 106.268803 -277.35035)
			(xy 106.29669 -277.307341) (xy 106.330457 -277.268775) (xy 106.369406 -277.235451) (xy 106.412731 -277.208057)
			(xy 106.459537 -277.18716) (xy 106.508856 -277.17319) (xy 106.534204 -277.169372) (xy 106.558842 -277.16607)
			(xy 106.731562 -276.867112) (xy 106.72191 -276.843998) (xy 106.713439 -276.822447) (xy 106.701556 -276.777691)
			(xy 106.695588 -276.73177) (xy 106.69524 -276.708616) (xy 106.695738 -276.681967) (xy 106.703681 -276.629263)
			(xy 106.719391 -276.578333) (xy 106.742517 -276.530312) (xy 106.772541 -276.486275) (xy 106.808793 -276.447204)
			(xy 106.850464 -276.413973) (xy 106.896622 -276.387324) (xy 106.946236 -276.367852) (xy 106.998198 -276.355992)
			(xy 107.051348 -276.352009) (xy 107.104498 -276.355992) (xy 107.15646 -276.367852) (xy 107.206074 -276.387324)
			(xy 107.252232 -276.413973) (xy 107.293903 -276.447204) (xy 107.330155 -276.486275) (xy 107.360179 -276.530312)
			(xy 107.383305 -276.578333) (xy 107.399015 -276.629263) (xy 107.406958 -276.681967) (xy 107.407456 -276.708616)
			(xy 107.407009 -276.734256) (xy 107.399664 -276.785006) (xy 107.385115 -276.834178) (xy 107.363663 -276.880753)
			(xy 107.335751 -276.92377) (xy 107.301956 -276.962338) (xy 107.262979 -276.995658) (xy 107.219624 -277.023043)
			(xy 107.172789 -277.043924) (xy 107.123443 -277.057871) (xy 107.098084 -277.061676) (xy 107.073192 -277.064978)
			(xy 106.900726 -277.363428) (xy 106.910378 -277.386542) (xy 106.918904 -277.40817) (xy 106.930888 -277.45309)
			(xy 106.936929 -277.499187) (xy 106.937302 -277.522432) (xy 106.936804 -277.549081) (xy 106.928861 -277.601785)
			(xy 106.913151 -277.652715) (xy 106.890025 -277.700736) (xy 106.860001 -277.744773) (xy 106.823749 -277.783844)
			(xy 106.782078 -277.817075) (xy 106.73592 -277.843724) (xy 106.686306 -277.863196) (xy 106.634344 -277.875056)
			(xy 106.581194 -277.87904) (xy 106.528044 -277.875056) (xy 106.476082 -277.863196) (xy 106.426468 -277.843724)
			(xy 106.38031 -277.817075) (xy 106.338639 -277.783844) (xy 106.302387 -277.744773) (xy 106.272363 -277.700736)
			(xy 106.249237 -277.652715) (xy 106.233527 -277.601785) (xy 106.225584 -277.549081) (xy 106.225086 -277.522432)
			(xy 105.997502 -277.522432) (xy 105.997004 -277.549081) (xy 105.989061 -277.601785) (xy 105.973351 -277.652715)
			(xy 105.950225 -277.700736) (xy 105.920201 -277.744773) (xy 105.883949 -277.783844) (xy 105.842278 -277.817075)
			(xy 105.79612 -277.843724) (xy 105.746506 -277.863196) (xy 105.694544 -277.875056) (xy 105.641394 -277.87904)
			(xy 105.588244 -277.875056) (xy 105.536282 -277.863196) (xy 105.486668 -277.843724) (xy 105.44051 -277.817075)
			(xy 105.398839 -277.783844) (xy 105.362587 -277.744773) (xy 105.332563 -277.700736) (xy 105.309437 -277.652715)
			(xy 105.293727 -277.601785) (xy 105.285784 -277.549081) (xy 105.057204 -277.549081) (xy 105.049261 -277.601785)
			(xy 105.033551 -277.652715) (xy 105.010425 -277.700736) (xy 104.980401 -277.744773) (xy 104.944149 -277.783844)
			(xy 104.902478 -277.817075) (xy 104.85632 -277.843724) (xy 104.806706 -277.863196) (xy 104.754744 -277.875056)
			(xy 104.701594 -277.87904) (xy 104.648444 -277.875056) (xy 104.596482 -277.863196) (xy 104.546868 -277.843724)
			(xy 104.50071 -277.817075) (xy 104.459039 -277.783844) (xy 104.422787 -277.744773) (xy 104.392763 -277.700736)
			(xy 104.369637 -277.652715) (xy 104.353927 -277.601785) (xy 104.345984 -277.549081) (xy 104.117404 -277.549081)
			(xy 104.109461 -277.601785) (xy 104.093751 -277.652715) (xy 104.070625 -277.700736) (xy 104.040601 -277.744773)
			(xy 104.004349 -277.783844) (xy 103.962678 -277.817075) (xy 103.91652 -277.843724) (xy 103.866906 -277.863196)
			(xy 103.814944 -277.875056) (xy 103.761794 -277.87904) (xy 103.708644 -277.875056) (xy 103.656682 -277.863196)
			(xy 103.607068 -277.843724) (xy 103.56091 -277.817075) (xy 103.519239 -277.783844) (xy 103.482987 -277.744773)
			(xy 103.452963 -277.700736) (xy 103.429837 -277.652715) (xy 103.414127 -277.601785) (xy 103.406184 -277.549081)
			(xy 103.405686 -277.522432) (xy 103.406066 -277.499187) (xy 103.412108 -277.453092) (xy 103.424094 -277.408174)
			(xy 103.43261 -277.386542) (xy 103.442262 -277.363428) (xy 103.269796 -277.064978) (xy 103.244904 -277.061676)
			(xy 103.219591 -277.057748) (xy 103.170324 -277.043735) (xy 103.123571 -277.022811) (xy 103.080297 -276.995407)
			(xy 103.041393 -276.962088) (xy 103.007663 -276.923541) (xy 102.9798 -276.880561) (xy 102.95838 -276.834033)
			(xy 102.943844 -276.784918) (xy 102.936492 -276.734227) (xy 102.93604 -276.708616) (xy 102.708202 -276.708616)
			(xy 102.707704 -276.735265) (xy 102.699761 -276.787969) (xy 102.684051 -276.838899) (xy 102.660925 -276.88692)
			(xy 102.630901 -276.930957) (xy 102.594649 -276.970028) (xy 102.552978 -277.003259) (xy 102.50682 -277.029908)
			(xy 102.457206 -277.04938) (xy 102.405244 -277.06124) (xy 102.352094 -277.065224) (xy 102.298944 -277.06124)
			(xy 102.246982 -277.04938) (xy 102.197368 -277.029908) (xy 102.15121 -277.003259) (xy 102.109539 -276.970028)
			(xy 102.073287 -276.930957) (xy 102.043263 -276.88692) (xy 102.020137 -276.838899) (xy 102.004427 -276.787969)
			(xy 101.996484 -276.735265) (xy 101.995986 -276.708616) (xy 101.768656 -276.708616) (xy 101.768158 -276.735265)
			(xy 101.760215 -276.787969) (xy 101.744505 -276.838899) (xy 101.721379 -276.88692) (xy 101.691355 -276.930957)
			(xy 101.655103 -276.970028) (xy 101.613432 -277.003259) (xy 101.567274 -277.029908) (xy 101.51766 -277.04938)
			(xy 101.465698 -277.06124) (xy 101.412548 -277.065224) (xy 101.359398 -277.06124) (xy 101.307436 -277.04938)
			(xy 101.257822 -277.029908) (xy 101.211664 -277.003259) (xy 101.169993 -276.970028) (xy 101.133741 -276.930957)
			(xy 101.103717 -276.88692) (xy 101.080591 -276.838899) (xy 101.064881 -276.787969) (xy 101.056938 -276.735265)
			(xy 100.828358 -276.735265) (xy 100.820415 -276.787969) (xy 100.804705 -276.838899) (xy 100.781579 -276.88692)
			(xy 100.751555 -276.930957) (xy 100.715303 -276.970028) (xy 100.673632 -277.003259) (xy 100.627474 -277.029908)
			(xy 100.57786 -277.04938) (xy 100.525898 -277.06124) (xy 100.472748 -277.065224) (xy 100.419598 -277.06124)
			(xy 100.367636 -277.04938) (xy 100.318022 -277.029908) (xy 100.271864 -277.003259) (xy 100.230193 -276.970028)
			(xy 100.193941 -276.930957) (xy 100.163917 -276.88692) (xy 100.140791 -276.838899) (xy 100.125081 -276.787969)
			(xy 100.117138 -276.735265) (xy 99.888558 -276.735265) (xy 99.880615 -276.787969) (xy 99.864905 -276.838899)
			(xy 99.841779 -276.88692) (xy 99.811755 -276.930957) (xy 99.775503 -276.970028) (xy 99.733832 -277.003259)
			(xy 99.687674 -277.029908) (xy 99.63806 -277.04938) (xy 99.586098 -277.06124) (xy 99.532948 -277.065224)
			(xy 99.479798 -277.06124) (xy 99.427836 -277.04938) (xy 99.378222 -277.029908) (xy 99.332064 -277.003259)
			(xy 99.290393 -276.970028) (xy 99.254141 -276.930957) (xy 99.224117 -276.88692) (xy 99.200991 -276.838899)
			(xy 99.185281 -276.787969) (xy 99.177338 -276.735265) (xy 98.948758 -276.735265) (xy 98.940815 -276.787969)
			(xy 98.925105 -276.838899) (xy 98.901979 -276.88692) (xy 98.871955 -276.930957) (xy 98.835703 -276.970028)
			(xy 98.794032 -277.003259) (xy 98.747874 -277.029908) (xy 98.69826 -277.04938) (xy 98.646298 -277.06124)
			(xy 98.593148 -277.065224) (xy 98.539998 -277.06124) (xy 98.488036 -277.04938) (xy 98.438422 -277.029908)
			(xy 98.392264 -277.003259) (xy 98.350593 -276.970028) (xy 98.314341 -276.930957) (xy 98.284317 -276.88692)
			(xy 98.261191 -276.838899) (xy 98.245481 -276.787969) (xy 98.237538 -276.735265) (xy 98.008704 -276.735265)
			(xy 98.000761 -276.787969) (xy 97.985051 -276.838899) (xy 97.961925 -276.88692) (xy 97.931901 -276.930957)
			(xy 97.895649 -276.970028) (xy 97.853978 -277.003259) (xy 97.80782 -277.029908) (xy 97.758206 -277.04938)
			(xy 97.706244 -277.06124) (xy 97.653094 -277.065224) (xy 97.599944 -277.06124) (xy 97.547982 -277.04938)
			(xy 97.498368 -277.029908) (xy 97.45221 -277.003259) (xy 97.410539 -276.970028) (xy 97.374287 -276.930957)
			(xy 97.344263 -276.88692) (xy 97.321137 -276.838899) (xy 97.305427 -276.787969) (xy 97.297484 -276.735265)
			(xy 97.069158 -276.735265) (xy 97.061215 -276.787969) (xy 97.045505 -276.838899) (xy 97.022379 -276.88692)
			(xy 96.992355 -276.930957) (xy 96.956103 -276.970028) (xy 96.914432 -277.003259) (xy 96.868274 -277.029908)
			(xy 96.81866 -277.04938) (xy 96.766698 -277.06124) (xy 96.713548 -277.065224) (xy 96.660398 -277.06124)
			(xy 96.608436 -277.04938) (xy 96.558822 -277.029908) (xy 96.512664 -277.003259) (xy 96.470993 -276.970028)
			(xy 96.434741 -276.930957) (xy 96.404717 -276.88692) (xy 96.381591 -276.838899) (xy 96.365881 -276.787969)
			(xy 96.357938 -276.735265) (xy 96.129358 -276.735265) (xy 96.121415 -276.787969) (xy 96.105705 -276.838899)
			(xy 96.082579 -276.88692) (xy 96.052555 -276.930957) (xy 96.016303 -276.970028) (xy 95.974632 -277.003259)
			(xy 95.928474 -277.029908) (xy 95.87886 -277.04938) (xy 95.826898 -277.06124) (xy 95.773748 -277.065224)
			(xy 95.720598 -277.06124) (xy 95.668636 -277.04938) (xy 95.619022 -277.029908) (xy 95.572864 -277.003259)
			(xy 95.531193 -276.970028) (xy 95.494941 -276.930957) (xy 95.464917 -276.88692) (xy 95.441791 -276.838899)
			(xy 95.426081 -276.787969) (xy 95.418138 -276.735265) (xy 95.189558 -276.735265) (xy 95.181615 -276.787969)
			(xy 95.165905 -276.838899) (xy 95.142779 -276.88692) (xy 95.112755 -276.930957) (xy 95.076503 -276.970028)
			(xy 95.034832 -277.003259) (xy 94.988674 -277.029908) (xy 94.93906 -277.04938) (xy 94.887098 -277.06124)
			(xy 94.833948 -277.065224) (xy 94.780798 -277.06124) (xy 94.728836 -277.04938) (xy 94.679222 -277.029908)
			(xy 94.633064 -277.003259) (xy 94.591393 -276.970028) (xy 94.555141 -276.930957) (xy 94.525117 -276.88692)
			(xy 94.501991 -276.838899) (xy 94.486281 -276.787969) (xy 94.478338 -276.735265) (xy 94.249758 -276.735265)
			(xy 94.241815 -276.787969) (xy 94.226105 -276.838899) (xy 94.202979 -276.88692) (xy 94.172955 -276.930957)
			(xy 94.136703 -276.970028) (xy 94.095032 -277.003259) (xy 94.048874 -277.029908) (xy 93.99926 -277.04938)
			(xy 93.947298 -277.06124) (xy 93.894148 -277.065224) (xy 93.840998 -277.06124) (xy 93.789036 -277.04938)
			(xy 93.739422 -277.029908) (xy 93.693264 -277.003259) (xy 93.651593 -276.970028) (xy 93.615341 -276.930957)
			(xy 93.585317 -276.88692) (xy 93.562191 -276.838899) (xy 93.546481 -276.787969) (xy 93.538538 -276.735265)
			(xy 93.309958 -276.735265) (xy 93.302015 -276.787969) (xy 93.286305 -276.838899) (xy 93.263179 -276.88692)
			(xy 93.233155 -276.930957) (xy 93.196903 -276.970028) (xy 93.155232 -277.003259) (xy 93.109074 -277.029908)
			(xy 93.05946 -277.04938) (xy 93.007498 -277.06124) (xy 92.954348 -277.065224) (xy 92.901198 -277.06124)
			(xy 92.849236 -277.04938) (xy 92.799622 -277.029908) (xy 92.753464 -277.003259) (xy 92.711793 -276.970028)
			(xy 92.675541 -276.930957) (xy 92.645517 -276.88692) (xy 92.622391 -276.838899) (xy 92.606681 -276.787969)
			(xy 92.598738 -276.735265) (xy 92.370158 -276.735265) (xy 92.362215 -276.787969) (xy 92.346505 -276.838899)
			(xy 92.323379 -276.88692) (xy 92.293355 -276.930957) (xy 92.257103 -276.970028) (xy 92.215432 -277.003259)
			(xy 92.169274 -277.029908) (xy 92.11966 -277.04938) (xy 92.067698 -277.06124) (xy 92.014548 -277.065224)
			(xy 91.961398 -277.06124) (xy 91.909436 -277.04938) (xy 91.859822 -277.029908) (xy 91.813664 -277.003259)
			(xy 91.771993 -276.970028) (xy 91.735741 -276.930957) (xy 91.705717 -276.88692) (xy 91.682591 -276.838899)
			(xy 91.666881 -276.787969) (xy 91.658938 -276.735265) (xy 91.430104 -276.735265) (xy 91.422161 -276.787969)
			(xy 91.406451 -276.838899) (xy 91.383325 -276.88692) (xy 91.353301 -276.930957) (xy 91.317049 -276.970028)
			(xy 91.275378 -277.003259) (xy 91.22922 -277.029908) (xy 91.179606 -277.04938) (xy 91.127644 -277.06124)
			(xy 91.074494 -277.065224) (xy 91.021344 -277.06124) (xy 90.969382 -277.04938) (xy 90.919768 -277.029908)
			(xy 90.87361 -277.003259) (xy 90.831939 -276.970028) (xy 90.795687 -276.930957) (xy 90.765663 -276.88692)
			(xy 90.742537 -276.838899) (xy 90.726827 -276.787969) (xy 90.718884 -276.735265) (xy 90.490304 -276.735265)
			(xy 90.482361 -276.787969) (xy 90.466651 -276.838899) (xy 90.443525 -276.88692) (xy 90.413501 -276.930957)
			(xy 90.377249 -276.970028) (xy 90.335578 -277.003259) (xy 90.28942 -277.029908) (xy 90.239806 -277.04938)
			(xy 90.187844 -277.06124) (xy 90.134694 -277.065224) (xy 90.081544 -277.06124) (xy 90.029582 -277.04938)
			(xy 89.979968 -277.029908) (xy 89.93381 -277.003259) (xy 89.892139 -276.970028) (xy 89.855887 -276.930957)
			(xy 89.825863 -276.88692) (xy 89.802737 -276.838899) (xy 89.787027 -276.787969) (xy 89.779084 -276.735265)
			(xy 89.550504 -276.735265) (xy 89.542561 -276.787969) (xy 89.526851 -276.838899) (xy 89.503725 -276.88692)
			(xy 89.473701 -276.930957) (xy 89.437449 -276.970028) (xy 89.395778 -277.003259) (xy 89.34962 -277.029908)
			(xy 89.300006 -277.04938) (xy 89.248044 -277.06124) (xy 89.194894 -277.065224) (xy 89.141744 -277.06124)
			(xy 89.089782 -277.04938) (xy 89.040168 -277.029908) (xy 88.99401 -277.003259) (xy 88.952339 -276.970028)
			(xy 88.916087 -276.930957) (xy 88.886063 -276.88692) (xy 88.862937 -276.838899) (xy 88.847227 -276.787969)
			(xy 88.839284 -276.735265) (xy 88.610704 -276.735265) (xy 88.602761 -276.787969) (xy 88.587051 -276.838899)
			(xy 88.563925 -276.88692) (xy 88.533901 -276.930957) (xy 88.497649 -276.970028) (xy 88.455978 -277.003259)
			(xy 88.40982 -277.029908) (xy 88.360206 -277.04938) (xy 88.308244 -277.06124) (xy 88.255094 -277.065224)
			(xy 88.201944 -277.06124) (xy 88.149982 -277.04938) (xy 88.100368 -277.029908) (xy 88.05421 -277.003259)
			(xy 88.012539 -276.970028) (xy 87.976287 -276.930957) (xy 87.946263 -276.88692) (xy 87.923137 -276.838899)
			(xy 87.907427 -276.787969) (xy 87.899484 -276.735265) (xy 85.52688 -276.735265) (xy 85.52688 -277.270951)
			(xy 86.945968 -277.270951) (xy 86.945968 -277.217653) (xy 86.953911 -277.164949) (xy 86.969621 -277.114019)
			(xy 86.992747 -277.065998) (xy 87.022771 -277.021961) (xy 87.059023 -276.98289) (xy 87.100694 -276.949659)
			(xy 87.146852 -276.92301) (xy 87.196466 -276.903538) (xy 87.248428 -276.891678) (xy 87.301578 -276.887695)
			(xy 87.354728 -276.891678) (xy 87.40669 -276.903538) (xy 87.456304 -276.92301) (xy 87.502462 -276.949659)
			(xy 87.544133 -276.98289) (xy 87.580385 -277.021961) (xy 87.610409 -277.065998) (xy 87.633535 -277.114019)
			(xy 87.649245 -277.164949) (xy 87.657188 -277.217653) (xy 87.657686 -277.244302) (xy 87.657188 -277.270951)
			(xy 87.649245 -277.323655) (xy 87.633535 -277.374585) (xy 87.610409 -277.422606) (xy 87.580385 -277.466643)
			(xy 87.544133 -277.505714) (xy 87.502462 -277.538945) (xy 87.484466 -277.549335) (xy 88.36913 -277.549335)
			(xy 88.36913 -277.496037) (xy 88.377073 -277.443333) (xy 88.392783 -277.392403) (xy 88.415909 -277.344382)
			(xy 88.445933 -277.300345) (xy 88.482185 -277.261274) (xy 88.523856 -277.228043) (xy 88.570014 -277.201394)
			(xy 88.619628 -277.181922) (xy 88.67159 -277.170062) (xy 88.72474 -277.166079) (xy 88.77789 -277.170062)
			(xy 88.829852 -277.181922) (xy 88.879466 -277.201394) (xy 88.925624 -277.228043) (xy 88.967295 -277.261274)
			(xy 89.003547 -277.300345) (xy 89.033571 -277.344382) (xy 89.056697 -277.392403) (xy 89.072407 -277.443333)
			(xy 89.08035 -277.496037) (xy 89.080848 -277.522686) (xy 89.080355 -277.549081) (xy 89.309184 -277.549081)
			(xy 89.309184 -277.495783) (xy 89.317127 -277.443079) (xy 89.332837 -277.392149) (xy 89.355963 -277.344128)
			(xy 89.385987 -277.300091) (xy 89.422239 -277.26102) (xy 89.46391 -277.227789) (xy 89.510068 -277.20114)
			(xy 89.559682 -277.181668) (xy 89.611644 -277.169808) (xy 89.664794 -277.165825) (xy 89.717944 -277.169808)
			(xy 89.769906 -277.181668) (xy 89.81952 -277.20114) (xy 89.865678 -277.227789) (xy 89.907349 -277.26102)
			(xy 89.943601 -277.300091) (xy 89.973625 -277.344128) (xy 89.996751 -277.392149) (xy 90.012461 -277.443079)
			(xy 90.020404 -277.495783) (xy 90.020902 -277.522432) (xy 90.020404 -277.549081) (xy 90.249238 -277.549081)
			(xy 90.249238 -277.495783) (xy 90.257181 -277.443079) (xy 90.272891 -277.392149) (xy 90.296017 -277.344128)
			(xy 90.326041 -277.300091) (xy 90.362293 -277.26102) (xy 90.403964 -277.227789) (xy 90.450122 -277.20114)
			(xy 90.499736 -277.181668) (xy 90.551698 -277.169808) (xy 90.604848 -277.165825) (xy 90.657998 -277.169808)
			(xy 90.70996 -277.181668) (xy 90.759574 -277.20114) (xy 90.805732 -277.227789) (xy 90.847403 -277.26102)
			(xy 90.883655 -277.300091) (xy 90.913679 -277.344128) (xy 90.936805 -277.392149) (xy 90.952515 -277.443079)
			(xy 90.960458 -277.495783) (xy 90.960956 -277.522432) (xy 90.960458 -277.549081) (xy 91.188784 -277.549081)
			(xy 91.188784 -277.495783) (xy 91.196727 -277.443079) (xy 91.212437 -277.392149) (xy 91.235563 -277.344128)
			(xy 91.265587 -277.300091) (xy 91.301839 -277.26102) (xy 91.34351 -277.227789) (xy 91.389668 -277.20114)
			(xy 91.439282 -277.181668) (xy 91.491244 -277.169808) (xy 91.544394 -277.165825) (xy 91.597544 -277.169808)
			(xy 91.649506 -277.181668) (xy 91.69912 -277.20114) (xy 91.745278 -277.227789) (xy 91.786949 -277.26102)
			(xy 91.823201 -277.300091) (xy 91.853225 -277.344128) (xy 91.876351 -277.392149) (xy 91.892061 -277.443079)
			(xy 91.900004 -277.495783) (xy 91.900502 -277.522432) (xy 91.900004 -277.549081) (xy 92.128584 -277.549081)
			(xy 92.128584 -277.495783) (xy 92.136527 -277.443079) (xy 92.152237 -277.392149) (xy 92.175363 -277.344128)
			(xy 92.205387 -277.300091) (xy 92.241639 -277.26102) (xy 92.28331 -277.227789) (xy 92.329468 -277.20114)
			(xy 92.379082 -277.181668) (xy 92.431044 -277.169808) (xy 92.484194 -277.165825) (xy 92.537344 -277.169808)
			(xy 92.589306 -277.181668) (xy 92.63892 -277.20114) (xy 92.685078 -277.227789) (xy 92.726749 -277.26102)
			(xy 92.763001 -277.300091) (xy 92.793025 -277.344128) (xy 92.816151 -277.392149) (xy 92.831861 -277.443079)
			(xy 92.839804 -277.495783) (xy 92.840302 -277.522432) (xy 92.839804 -277.549081) (xy 93.068384 -277.549081)
			(xy 93.068384 -277.495783) (xy 93.076327 -277.443079) (xy 93.092037 -277.392149) (xy 93.115163 -277.344128)
			(xy 93.145187 -277.300091) (xy 93.181439 -277.26102) (xy 93.22311 -277.227789) (xy 93.269268 -277.20114)
			(xy 93.318882 -277.181668) (xy 93.370844 -277.169808) (xy 93.423994 -277.165825) (xy 93.477144 -277.169808)
			(xy 93.529106 -277.181668) (xy 93.57872 -277.20114) (xy 93.624878 -277.227789) (xy 93.666549 -277.26102)
			(xy 93.702801 -277.300091) (xy 93.732825 -277.344128) (xy 93.755951 -277.392149) (xy 93.771661 -277.443079)
			(xy 93.779604 -277.495783) (xy 93.780102 -277.522432) (xy 93.779604 -277.549081) (xy 94.008184 -277.549081)
			(xy 94.008184 -277.495783) (xy 94.016127 -277.443079) (xy 94.031837 -277.392149) (xy 94.054963 -277.344128)
			(xy 94.084987 -277.300091) (xy 94.121239 -277.26102) (xy 94.16291 -277.227789) (xy 94.209068 -277.20114)
			(xy 94.258682 -277.181668) (xy 94.310644 -277.169808) (xy 94.363794 -277.165825) (xy 94.416944 -277.169808)
			(xy 94.468906 -277.181668) (xy 94.51852 -277.20114) (xy 94.564678 -277.227789) (xy 94.606349 -277.26102)
			(xy 94.642601 -277.300091) (xy 94.672625 -277.344128) (xy 94.695751 -277.392149) (xy 94.711461 -277.443079)
			(xy 94.719404 -277.495783) (xy 94.719902 -277.522432) (xy 94.719404 -277.549081) (xy 94.947984 -277.549081)
			(xy 94.947984 -277.495783) (xy 94.955927 -277.443079) (xy 94.971637 -277.392149) (xy 94.994763 -277.344128)
			(xy 95.024787 -277.300091) (xy 95.061039 -277.26102) (xy 95.10271 -277.227789) (xy 95.148868 -277.20114)
			(xy 95.198482 -277.181668) (xy 95.250444 -277.169808) (xy 95.303594 -277.165825) (xy 95.356744 -277.169808)
			(xy 95.408706 -277.181668) (xy 95.45832 -277.20114) (xy 95.504478 -277.227789) (xy 95.546149 -277.26102)
			(xy 95.582401 -277.300091) (xy 95.612425 -277.344128) (xy 95.635551 -277.392149) (xy 95.651261 -277.443079)
			(xy 95.659204 -277.495783) (xy 95.659702 -277.522432) (xy 95.659204 -277.549081) (xy 95.887784 -277.549081)
			(xy 95.887784 -277.495783) (xy 95.895727 -277.443079) (xy 95.911437 -277.392149) (xy 95.934563 -277.344128)
			(xy 95.964587 -277.300091) (xy 96.000839 -277.26102) (xy 96.04251 -277.227789) (xy 96.088668 -277.20114)
			(xy 96.138282 -277.181668) (xy 96.190244 -277.169808) (xy 96.243394 -277.165825) (xy 96.296544 -277.169808)
			(xy 96.348506 -277.181668) (xy 96.39812 -277.20114) (xy 96.444278 -277.227789) (xy 96.485949 -277.26102)
			(xy 96.522201 -277.300091) (xy 96.552225 -277.344128) (xy 96.575351 -277.392149) (xy 96.591061 -277.443079)
			(xy 96.599004 -277.495783) (xy 96.599502 -277.522432) (xy 96.599004 -277.549081) (xy 96.827584 -277.549081)
			(xy 96.827584 -277.495783) (xy 96.835527 -277.443079) (xy 96.851237 -277.392149) (xy 96.874363 -277.344128)
			(xy 96.904387 -277.300091) (xy 96.940639 -277.26102) (xy 96.98231 -277.227789) (xy 97.028468 -277.20114)
			(xy 97.078082 -277.181668) (xy 97.130044 -277.169808) (xy 97.183194 -277.165825) (xy 97.236344 -277.169808)
			(xy 97.288306 -277.181668) (xy 97.33792 -277.20114) (xy 97.384078 -277.227789) (xy 97.425749 -277.26102)
			(xy 97.462001 -277.300091) (xy 97.492025 -277.344128) (xy 97.515151 -277.392149) (xy 97.530861 -277.443079)
			(xy 97.538804 -277.495783) (xy 97.539302 -277.522432) (xy 97.538804 -277.549081) (xy 97.767384 -277.549081)
			(xy 97.767384 -277.495783) (xy 97.775327 -277.443079) (xy 97.791037 -277.392149) (xy 97.814163 -277.344128)
			(xy 97.844187 -277.300091) (xy 97.880439 -277.26102) (xy 97.92211 -277.227789) (xy 97.968268 -277.20114)
			(xy 98.017882 -277.181668) (xy 98.069844 -277.169808) (xy 98.122994 -277.165825) (xy 98.176144 -277.169808)
			(xy 98.228106 -277.181668) (xy 98.27772 -277.20114) (xy 98.323878 -277.227789) (xy 98.365549 -277.26102)
			(xy 98.401801 -277.300091) (xy 98.431825 -277.344128) (xy 98.454951 -277.392149) (xy 98.470661 -277.443079)
			(xy 98.478604 -277.495783) (xy 98.479102 -277.522432) (xy 98.478604 -277.549081) (xy 98.707184 -277.549081)
			(xy 98.707184 -277.495783) (xy 98.715127 -277.443079) (xy 98.730837 -277.392149) (xy 98.753963 -277.344128)
			(xy 98.783987 -277.300091) (xy 98.820239 -277.26102) (xy 98.86191 -277.227789) (xy 98.908068 -277.20114)
			(xy 98.957682 -277.181668) (xy 99.009644 -277.169808) (xy 99.062794 -277.165825) (xy 99.115944 -277.169808)
			(xy 99.167906 -277.181668) (xy 99.21752 -277.20114) (xy 99.263678 -277.227789) (xy 99.305349 -277.26102)
			(xy 99.341601 -277.300091) (xy 99.371625 -277.344128) (xy 99.394751 -277.392149) (xy 99.410461 -277.443079)
			(xy 99.418404 -277.495783) (xy 99.418902 -277.522432) (xy 99.418404 -277.549081) (xy 99.646984 -277.549081)
			(xy 99.646984 -277.495783) (xy 99.654927 -277.443079) (xy 99.670637 -277.392149) (xy 99.693763 -277.344128)
			(xy 99.723787 -277.300091) (xy 99.760039 -277.26102) (xy 99.80171 -277.227789) (xy 99.847868 -277.20114)
			(xy 99.897482 -277.181668) (xy 99.949444 -277.169808) (xy 100.002594 -277.165825) (xy 100.055744 -277.169808)
			(xy 100.107706 -277.181668) (xy 100.15732 -277.20114) (xy 100.203478 -277.227789) (xy 100.245149 -277.26102)
			(xy 100.281401 -277.300091) (xy 100.311425 -277.344128) (xy 100.334551 -277.392149) (xy 100.350261 -277.443079)
			(xy 100.358204 -277.495783) (xy 100.358702 -277.522432) (xy 100.358204 -277.549081) (xy 100.586784 -277.549081)
			(xy 100.586784 -277.495783) (xy 100.594727 -277.443079) (xy 100.610437 -277.392149) (xy 100.633563 -277.344128)
			(xy 100.663587 -277.300091) (xy 100.699839 -277.26102) (xy 100.74151 -277.227789) (xy 100.787668 -277.20114)
			(xy 100.837282 -277.181668) (xy 100.889244 -277.169808) (xy 100.942394 -277.165825) (xy 100.995544 -277.169808)
			(xy 101.047506 -277.181668) (xy 101.09712 -277.20114) (xy 101.143278 -277.227789) (xy 101.184949 -277.26102)
			(xy 101.221201 -277.300091) (xy 101.251225 -277.344128) (xy 101.274351 -277.392149) (xy 101.290061 -277.443079)
			(xy 101.298004 -277.495783) (xy 101.298502 -277.522432) (xy 101.298004 -277.549081) (xy 101.526838 -277.549081)
			(xy 101.526838 -277.495783) (xy 101.534781 -277.443079) (xy 101.550491 -277.392149) (xy 101.573617 -277.344128)
			(xy 101.603641 -277.300091) (xy 101.639893 -277.26102) (xy 101.681564 -277.227789) (xy 101.727722 -277.20114)
			(xy 101.777336 -277.181668) (xy 101.829298 -277.169808) (xy 101.882448 -277.165825) (xy 101.935598 -277.169808)
			(xy 101.98756 -277.181668) (xy 102.037174 -277.20114) (xy 102.083332 -277.227789) (xy 102.125003 -277.26102)
			(xy 102.161255 -277.300091) (xy 102.191279 -277.344128) (xy 102.214405 -277.392149) (xy 102.230115 -277.443079)
			(xy 102.238058 -277.495783) (xy 102.238556 -277.522432) (xy 102.238058 -277.549081) (xy 102.230115 -277.601785)
			(xy 102.214405 -277.652715) (xy 102.191279 -277.700736) (xy 102.161255 -277.744773) (xy 102.125003 -277.783844)
			(xy 102.083332 -277.817075) (xy 102.037174 -277.843724) (xy 101.98756 -277.863196) (xy 101.935598 -277.875056)
			(xy 101.882448 -277.87904) (xy 101.829298 -277.875056) (xy 101.777336 -277.863196) (xy 101.727722 -277.843724)
			(xy 101.681564 -277.817075) (xy 101.639893 -277.783844) (xy 101.603641 -277.744773) (xy 101.573617 -277.700736)
			(xy 101.550491 -277.652715) (xy 101.534781 -277.601785) (xy 101.526838 -277.549081) (xy 101.298004 -277.549081)
			(xy 101.290061 -277.601785) (xy 101.274351 -277.652715) (xy 101.251225 -277.700736) (xy 101.221201 -277.744773)
			(xy 101.184949 -277.783844) (xy 101.143278 -277.817075) (xy 101.09712 -277.843724) (xy 101.047506 -277.863196)
			(xy 100.995544 -277.875056) (xy 100.942394 -277.87904) (xy 100.889244 -277.875056) (xy 100.837282 -277.863196)
			(xy 100.787668 -277.843724) (xy 100.74151 -277.817075) (xy 100.699839 -277.783844) (xy 100.663587 -277.744773)
			(xy 100.633563 -277.700736) (xy 100.610437 -277.652715) (xy 100.594727 -277.601785) (xy 100.586784 -277.549081)
			(xy 100.358204 -277.549081) (xy 100.350261 -277.601785) (xy 100.334551 -277.652715) (xy 100.311425 -277.700736)
			(xy 100.281401 -277.744773) (xy 100.245149 -277.783844) (xy 100.203478 -277.817075) (xy 100.15732 -277.843724)
			(xy 100.107706 -277.863196) (xy 100.055744 -277.875056) (xy 100.002594 -277.87904) (xy 99.949444 -277.875056)
			(xy 99.897482 -277.863196) (xy 99.847868 -277.843724) (xy 99.80171 -277.817075) (xy 99.760039 -277.783844)
			(xy 99.723787 -277.744773) (xy 99.693763 -277.700736) (xy 99.670637 -277.652715) (xy 99.654927 -277.601785)
			(xy 99.646984 -277.549081) (xy 99.418404 -277.549081) (xy 99.410461 -277.601785) (xy 99.394751 -277.652715)
			(xy 99.371625 -277.700736) (xy 99.341601 -277.744773) (xy 99.305349 -277.783844) (xy 99.263678 -277.817075)
			(xy 99.21752 -277.843724) (xy 99.167906 -277.863196) (xy 99.115944 -277.875056) (xy 99.062794 -277.87904)
			(xy 99.009644 -277.875056) (xy 98.957682 -277.863196) (xy 98.908068 -277.843724) (xy 98.86191 -277.817075)
			(xy 98.820239 -277.783844) (xy 98.783987 -277.744773) (xy 98.753963 -277.700736) (xy 98.730837 -277.652715)
			(xy 98.715127 -277.601785) (xy 98.707184 -277.549081) (xy 98.478604 -277.549081) (xy 98.470661 -277.601785)
			(xy 98.454951 -277.652715) (xy 98.431825 -277.700736) (xy 98.401801 -277.744773) (xy 98.365549 -277.783844)
			(xy 98.323878 -277.817075) (xy 98.27772 -277.843724) (xy 98.228106 -277.863196) (xy 98.176144 -277.875056)
			(xy 98.122994 -277.87904) (xy 98.069844 -277.875056) (xy 98.017882 -277.863196) (xy 97.968268 -277.843724)
			(xy 97.92211 -277.817075) (xy 97.880439 -277.783844) (xy 97.844187 -277.744773) (xy 97.814163 -277.700736)
			(xy 97.791037 -277.652715) (xy 97.775327 -277.601785) (xy 97.767384 -277.549081) (xy 97.538804 -277.549081)
			(xy 97.530861 -277.601785) (xy 97.515151 -277.652715) (xy 97.492025 -277.700736) (xy 97.462001 -277.744773)
			(xy 97.425749 -277.783844) (xy 97.384078 -277.817075) (xy 97.33792 -277.843724) (xy 97.288306 -277.863196)
			(xy 97.236344 -277.875056) (xy 97.183194 -277.87904) (xy 97.130044 -277.875056) (xy 97.078082 -277.863196)
			(xy 97.028468 -277.843724) (xy 96.98231 -277.817075) (xy 96.940639 -277.783844) (xy 96.904387 -277.744773)
			(xy 96.874363 -277.700736) (xy 96.851237 -277.652715) (xy 96.835527 -277.601785) (xy 96.827584 -277.549081)
			(xy 96.599004 -277.549081) (xy 96.591061 -277.601785) (xy 96.575351 -277.652715) (xy 96.552225 -277.700736)
			(xy 96.522201 -277.744773) (xy 96.485949 -277.783844) (xy 96.444278 -277.817075) (xy 96.39812 -277.843724)
			(xy 96.348506 -277.863196) (xy 96.296544 -277.875056) (xy 96.243394 -277.87904) (xy 96.190244 -277.875056)
			(xy 96.138282 -277.863196) (xy 96.088668 -277.843724) (xy 96.04251 -277.817075) (xy 96.000839 -277.783844)
			(xy 95.964587 -277.744773) (xy 95.934563 -277.700736) (xy 95.911437 -277.652715) (xy 95.895727 -277.601785)
			(xy 95.887784 -277.549081) (xy 95.659204 -277.549081) (xy 95.651261 -277.601785) (xy 95.635551 -277.652715)
			(xy 95.612425 -277.700736) (xy 95.582401 -277.744773) (xy 95.546149 -277.783844) (xy 95.504478 -277.817075)
			(xy 95.45832 -277.843724) (xy 95.408706 -277.863196) (xy 95.356744 -277.875056) (xy 95.303594 -277.87904)
			(xy 95.250444 -277.875056) (xy 95.198482 -277.863196) (xy 95.148868 -277.843724) (xy 95.10271 -277.817075)
			(xy 95.061039 -277.783844) (xy 95.024787 -277.744773) (xy 94.994763 -277.700736) (xy 94.971637 -277.652715)
			(xy 94.955927 -277.601785) (xy 94.947984 -277.549081) (xy 94.719404 -277.549081) (xy 94.711461 -277.601785)
			(xy 94.695751 -277.652715) (xy 94.672625 -277.700736) (xy 94.642601 -277.744773) (xy 94.606349 -277.783844)
			(xy 94.564678 -277.817075) (xy 94.51852 -277.843724) (xy 94.468906 -277.863196) (xy 94.416944 -277.875056)
			(xy 94.363794 -277.87904) (xy 94.310644 -277.875056) (xy 94.258682 -277.863196) (xy 94.209068 -277.843724)
			(xy 94.16291 -277.817075) (xy 94.121239 -277.783844) (xy 94.084987 -277.744773) (xy 94.054963 -277.700736)
			(xy 94.031837 -277.652715) (xy 94.016127 -277.601785) (xy 94.008184 -277.549081) (xy 93.779604 -277.549081)
			(xy 93.771661 -277.601785) (xy 93.755951 -277.652715) (xy 93.732825 -277.700736) (xy 93.702801 -277.744773)
			(xy 93.666549 -277.783844) (xy 93.624878 -277.817075) (xy 93.57872 -277.843724) (xy 93.529106 -277.863196)
			(xy 93.477144 -277.875056) (xy 93.423994 -277.87904) (xy 93.370844 -277.875056) (xy 93.318882 -277.863196)
			(xy 93.269268 -277.843724) (xy 93.22311 -277.817075) (xy 93.181439 -277.783844) (xy 93.145187 -277.744773)
			(xy 93.115163 -277.700736) (xy 93.092037 -277.652715) (xy 93.076327 -277.601785) (xy 93.068384 -277.549081)
			(xy 92.839804 -277.549081) (xy 92.831861 -277.601785) (xy 92.816151 -277.652715) (xy 92.793025 -277.700736)
			(xy 92.763001 -277.744773) (xy 92.726749 -277.783844) (xy 92.685078 -277.817075) (xy 92.63892 -277.843724)
			(xy 92.589306 -277.863196) (xy 92.537344 -277.875056) (xy 92.484194 -277.87904) (xy 92.431044 -277.875056)
			(xy 92.379082 -277.863196) (xy 92.329468 -277.843724) (xy 92.28331 -277.817075) (xy 92.241639 -277.783844)
			(xy 92.205387 -277.744773) (xy 92.175363 -277.700736) (xy 92.152237 -277.652715) (xy 92.136527 -277.601785)
			(xy 92.128584 -277.549081) (xy 91.900004 -277.549081) (xy 91.892061 -277.601785) (xy 91.876351 -277.652715)
			(xy 91.853225 -277.700736) (xy 91.823201 -277.744773) (xy 91.786949 -277.783844) (xy 91.745278 -277.817075)
			(xy 91.69912 -277.843724) (xy 91.649506 -277.863196) (xy 91.597544 -277.875056) (xy 91.544394 -277.87904)
			(xy 91.491244 -277.875056) (xy 91.439282 -277.863196) (xy 91.389668 -277.843724) (xy 91.34351 -277.817075)
			(xy 91.301839 -277.783844) (xy 91.265587 -277.744773) (xy 91.235563 -277.700736) (xy 91.212437 -277.652715)
			(xy 91.196727 -277.601785) (xy 91.188784 -277.549081) (xy 90.960458 -277.549081) (xy 90.952515 -277.601785)
			(xy 90.936805 -277.652715) (xy 90.913679 -277.700736) (xy 90.883655 -277.744773) (xy 90.847403 -277.783844)
			(xy 90.805732 -277.817075) (xy 90.759574 -277.843724) (xy 90.70996 -277.863196) (xy 90.657998 -277.875056)
			(xy 90.604848 -277.87904) (xy 90.551698 -277.875056) (xy 90.499736 -277.863196) (xy 90.450122 -277.843724)
			(xy 90.403964 -277.817075) (xy 90.362293 -277.783844) (xy 90.326041 -277.744773) (xy 90.296017 -277.700736)
			(xy 90.272891 -277.652715) (xy 90.257181 -277.601785) (xy 90.249238 -277.549081) (xy 90.020404 -277.549081)
			(xy 90.012461 -277.601785) (xy 89.996751 -277.652715) (xy 89.973625 -277.700736) (xy 89.943601 -277.744773)
			(xy 89.907349 -277.783844) (xy 89.865678 -277.817075) (xy 89.81952 -277.843724) (xy 89.769906 -277.863196)
			(xy 89.717944 -277.875056) (xy 89.664794 -277.87904) (xy 89.611644 -277.875056) (xy 89.559682 -277.863196)
			(xy 89.510068 -277.843724) (xy 89.46391 -277.817075) (xy 89.422239 -277.783844) (xy 89.385987 -277.744773)
			(xy 89.355963 -277.700736) (xy 89.332837 -277.652715) (xy 89.317127 -277.601785) (xy 89.309184 -277.549081)
			(xy 89.080355 -277.549081) (xy 89.08035 -277.549335) (xy 89.072407 -277.602039) (xy 89.056697 -277.652969)
			(xy 89.033571 -277.70099) (xy 89.003547 -277.745027) (xy 88.967295 -277.784098) (xy 88.925624 -277.817329)
			(xy 88.879466 -277.843978) (xy 88.829852 -277.86345) (xy 88.77789 -277.87531) (xy 88.72474 -277.879294)
			(xy 88.67159 -277.87531) (xy 88.619628 -277.86345) (xy 88.570014 -277.843978) (xy 88.523856 -277.817329)
			(xy 88.482185 -277.784098) (xy 88.445933 -277.745027) (xy 88.415909 -277.70099) (xy 88.392783 -277.652969)
			(xy 88.377073 -277.602039) (xy 88.36913 -277.549335) (xy 87.484466 -277.549335) (xy 87.456304 -277.565594)
			(xy 87.40669 -277.585066) (xy 87.354728 -277.596926) (xy 87.301578 -277.60091) (xy 87.248428 -277.596926)
			(xy 87.196466 -277.585066) (xy 87.146852 -277.565594) (xy 87.100694 -277.538945) (xy 87.059023 -277.505714)
			(xy 87.022771 -277.466643) (xy 86.992747 -277.422606) (xy 86.969621 -277.374585) (xy 86.953911 -277.323655)
			(xy 86.945968 -277.270951) (xy 85.52688 -277.270951) (xy 85.52688 -278.336502) (xy 86.031581 -278.336502)
			(xy 86.035611 -278.284004) (xy 86.047608 -278.232736) (xy 86.067291 -278.183901) (xy 86.094197 -278.138642)
			(xy 86.127697 -278.098021) (xy 86.167005 -278.06299) (xy 86.2112 -278.03437) (xy 86.259245 -278.012831)
			(xy 86.310016 -277.998879) (xy 86.362321 -277.992841) (xy 86.414935 -277.994858) (xy 86.466625 -278.004882)
			(xy 86.516178 -278.02268) (xy 86.562434 -278.047833) (xy 86.604308 -278.079752) (xy 86.64082 -278.11769)
			(xy 86.671112 -278.160756) (xy 86.694475 -278.207941) (xy 86.710361 -278.25814) (xy 86.718398 -278.310176)
			(xy 86.718902 -278.336502) (xy 86.718398 -278.362828) (xy 86.718348 -278.363151) (xy 90.718884 -278.363151)
			(xy 90.718884 -278.309853) (xy 90.726827 -278.257149) (xy 90.742537 -278.206219) (xy 90.765663 -278.158198)
			(xy 90.795687 -278.114161) (xy 90.831939 -278.07509) (xy 90.87361 -278.041859) (xy 90.919768 -278.01521)
			(xy 90.969382 -277.995738) (xy 91.021344 -277.983878) (xy 91.074494 -277.979895) (xy 91.127644 -277.983878)
			(xy 91.179606 -277.995738) (xy 91.22922 -278.01521) (xy 91.275378 -278.041859) (xy 91.317049 -278.07509)
			(xy 91.353301 -278.114161) (xy 91.383325 -278.158198) (xy 91.406451 -278.206219) (xy 91.422161 -278.257149)
			(xy 91.430104 -278.309853) (xy 91.430602 -278.336502) (xy 91.430104 -278.363151) (xy 91.658938 -278.363151)
			(xy 91.658938 -278.309853) (xy 91.666881 -278.257149) (xy 91.682591 -278.206219) (xy 91.705717 -278.158198)
			(xy 91.735741 -278.114161) (xy 91.771993 -278.07509) (xy 91.813664 -278.041859) (xy 91.859822 -278.01521)
			(xy 91.909436 -277.995738) (xy 91.961398 -277.983878) (xy 92.014548 -277.979895) (xy 92.067698 -277.983878)
			(xy 92.11966 -277.995738) (xy 92.169274 -278.01521) (xy 92.215432 -278.041859) (xy 92.257103 -278.07509)
			(xy 92.293355 -278.114161) (xy 92.323379 -278.158198) (xy 92.346505 -278.206219) (xy 92.362215 -278.257149)
			(xy 92.370158 -278.309853) (xy 92.370656 -278.336502) (xy 92.370158 -278.363151) (xy 92.598738 -278.363151)
			(xy 92.598738 -278.309853) (xy 92.606681 -278.257149) (xy 92.622391 -278.206219) (xy 92.645517 -278.158198)
			(xy 92.675541 -278.114161) (xy 92.711793 -278.07509) (xy 92.753464 -278.041859) (xy 92.799622 -278.01521)
			(xy 92.849236 -277.995738) (xy 92.901198 -277.983878) (xy 92.954348 -277.979895) (xy 93.007498 -277.983878)
			(xy 93.05946 -277.995738) (xy 93.109074 -278.01521) (xy 93.155232 -278.041859) (xy 93.196903 -278.07509)
			(xy 93.233155 -278.114161) (xy 93.263179 -278.158198) (xy 93.286305 -278.206219) (xy 93.302015 -278.257149)
			(xy 93.309958 -278.309853) (xy 93.310456 -278.336502) (xy 93.309958 -278.363151) (xy 93.538538 -278.363151)
			(xy 93.538538 -278.309853) (xy 93.546481 -278.257149) (xy 93.562191 -278.206219) (xy 93.585317 -278.158198)
			(xy 93.615341 -278.114161) (xy 93.651593 -278.07509) (xy 93.693264 -278.041859) (xy 93.739422 -278.01521)
			(xy 93.789036 -277.995738) (xy 93.840998 -277.983878) (xy 93.894148 -277.979895) (xy 93.947298 -277.983878)
			(xy 93.99926 -277.995738) (xy 94.048874 -278.01521) (xy 94.095032 -278.041859) (xy 94.136703 -278.07509)
			(xy 94.172955 -278.114161) (xy 94.202979 -278.158198) (xy 94.226105 -278.206219) (xy 94.241815 -278.257149)
			(xy 94.249758 -278.309853) (xy 94.250256 -278.336502) (xy 94.249758 -278.363151) (xy 94.478338 -278.363151)
			(xy 94.478338 -278.309853) (xy 94.486281 -278.257149) (xy 94.501991 -278.206219) (xy 94.525117 -278.158198)
			(xy 94.555141 -278.114161) (xy 94.591393 -278.07509) (xy 94.633064 -278.041859) (xy 94.679222 -278.01521)
			(xy 94.728836 -277.995738) (xy 94.780798 -277.983878) (xy 94.833948 -277.979895) (xy 94.887098 -277.983878)
			(xy 94.93906 -277.995738) (xy 94.988674 -278.01521) (xy 95.034832 -278.041859) (xy 95.076503 -278.07509)
			(xy 95.112755 -278.114161) (xy 95.142779 -278.158198) (xy 95.165905 -278.206219) (xy 95.181615 -278.257149)
			(xy 95.189558 -278.309853) (xy 95.190056 -278.336502) (xy 95.189558 -278.363151) (xy 97.297738 -278.363151)
			(xy 97.297738 -278.309853) (xy 97.305681 -278.257149) (xy 97.321391 -278.206219) (xy 97.344517 -278.158198)
			(xy 97.374541 -278.114161) (xy 97.410793 -278.07509) (xy 97.452464 -278.041859) (xy 97.498622 -278.01521)
			(xy 97.548236 -277.995738) (xy 97.600198 -277.983878) (xy 97.653348 -277.979895) (xy 97.706498 -277.983878)
			(xy 97.75846 -277.995738) (xy 97.808074 -278.01521) (xy 97.854232 -278.041859) (xy 97.895903 -278.07509)
			(xy 97.932155 -278.114161) (xy 97.962179 -278.158198) (xy 97.985305 -278.206219) (xy 98.001015 -278.257149)
			(xy 98.008958 -278.309853) (xy 98.009456 -278.336502) (xy 98.008958 -278.363151) (xy 98.237538 -278.363151)
			(xy 98.237538 -278.309853) (xy 98.245481 -278.257149) (xy 98.261191 -278.206219) (xy 98.284317 -278.158198)
			(xy 98.314341 -278.114161) (xy 98.350593 -278.07509) (xy 98.392264 -278.041859) (xy 98.438422 -278.01521)
			(xy 98.488036 -277.995738) (xy 98.539998 -277.983878) (xy 98.593148 -277.979895) (xy 98.646298 -277.983878)
			(xy 98.69826 -277.995738) (xy 98.747874 -278.01521) (xy 98.794032 -278.041859) (xy 98.835703 -278.07509)
			(xy 98.871955 -278.114161) (xy 98.901979 -278.158198) (xy 98.925105 -278.206219) (xy 98.940815 -278.257149)
			(xy 98.948758 -278.309853) (xy 98.949256 -278.336502) (xy 98.948758 -278.363151) (xy 99.177338 -278.363151)
			(xy 99.177338 -278.309853) (xy 99.185281 -278.257149) (xy 99.200991 -278.206219) (xy 99.224117 -278.158198)
			(xy 99.254141 -278.114161) (xy 99.290393 -278.07509) (xy 99.332064 -278.041859) (xy 99.378222 -278.01521)
			(xy 99.427836 -277.995738) (xy 99.479798 -277.983878) (xy 99.532948 -277.979895) (xy 99.586098 -277.983878)
			(xy 99.63806 -277.995738) (xy 99.687674 -278.01521) (xy 99.733832 -278.041859) (xy 99.775503 -278.07509)
			(xy 99.811755 -278.114161) (xy 99.841779 -278.158198) (xy 99.864905 -278.206219) (xy 99.880615 -278.257149)
			(xy 99.888558 -278.309853) (xy 99.889056 -278.336502) (xy 99.888558 -278.363151) (xy 100.117138 -278.363151)
			(xy 100.117138 -278.309853) (xy 100.125081 -278.257149) (xy 100.140791 -278.206219) (xy 100.163917 -278.158198)
			(xy 100.193941 -278.114161) (xy 100.230193 -278.07509) (xy 100.271864 -278.041859) (xy 100.318022 -278.01521)
			(xy 100.367636 -277.995738) (xy 100.419598 -277.983878) (xy 100.472748 -277.979895) (xy 100.525898 -277.983878)
			(xy 100.57786 -277.995738) (xy 100.627474 -278.01521) (xy 100.673632 -278.041859) (xy 100.715303 -278.07509)
			(xy 100.751555 -278.114161) (xy 100.781579 -278.158198) (xy 100.804705 -278.206219) (xy 100.820415 -278.257149)
			(xy 100.828358 -278.309853) (xy 100.828856 -278.336502) (xy 100.828358 -278.363151) (xy 101.056684 -278.363151)
			(xy 101.056684 -278.309853) (xy 101.064627 -278.257149) (xy 101.080337 -278.206219) (xy 101.103463 -278.158198)
			(xy 101.133487 -278.114161) (xy 101.169739 -278.07509) (xy 101.21141 -278.041859) (xy 101.257568 -278.01521)
			(xy 101.307182 -277.995738) (xy 101.359144 -277.983878) (xy 101.412294 -277.979895) (xy 101.465444 -277.983878)
			(xy 101.517406 -277.995738) (xy 101.56702 -278.01521) (xy 101.613178 -278.041859) (xy 101.654849 -278.07509)
			(xy 101.691101 -278.114161) (xy 101.721125 -278.158198) (xy 101.744251 -278.206219) (xy 101.759961 -278.257149)
			(xy 101.767904 -278.309853) (xy 101.768402 -278.336502) (xy 101.767904 -278.363151) (xy 101.996738 -278.363151)
			(xy 101.996738 -278.309853) (xy 102.004681 -278.257149) (xy 102.020391 -278.206219) (xy 102.043517 -278.158198)
			(xy 102.073541 -278.114161) (xy 102.109793 -278.07509) (xy 102.151464 -278.041859) (xy 102.197622 -278.01521)
			(xy 102.247236 -277.995738) (xy 102.299198 -277.983878) (xy 102.352348 -277.979895) (xy 102.405498 -277.983878)
			(xy 102.45746 -277.995738) (xy 102.507074 -278.01521) (xy 102.553232 -278.041859) (xy 102.594903 -278.07509)
			(xy 102.631155 -278.114161) (xy 102.661179 -278.158198) (xy 102.684305 -278.206219) (xy 102.700015 -278.257149)
			(xy 102.707958 -278.309853) (xy 102.708456 -278.336502) (xy 102.707958 -278.363151) (xy 102.936538 -278.363151)
			(xy 102.936538 -278.309853) (xy 102.944481 -278.257149) (xy 102.960191 -278.206219) (xy 102.983317 -278.158198)
			(xy 103.013341 -278.114161) (xy 103.049593 -278.07509) (xy 103.091264 -278.041859) (xy 103.137422 -278.01521)
			(xy 103.187036 -277.995738) (xy 103.238998 -277.983878) (xy 103.292148 -277.979895) (xy 103.345298 -277.983878)
			(xy 103.39726 -277.995738) (xy 103.446874 -278.01521) (xy 103.493032 -278.041859) (xy 103.534703 -278.07509)
			(xy 103.570955 -278.114161) (xy 103.600979 -278.158198) (xy 103.624105 -278.206219) (xy 103.639815 -278.257149)
			(xy 103.647758 -278.309853) (xy 103.648256 -278.336502) (xy 103.647758 -278.363151) (xy 103.876338 -278.363151)
			(xy 103.876338 -278.309853) (xy 103.884281 -278.257149) (xy 103.899991 -278.206219) (xy 103.923117 -278.158198)
			(xy 103.953141 -278.114161) (xy 103.989393 -278.07509) (xy 104.031064 -278.041859) (xy 104.077222 -278.01521)
			(xy 104.126836 -277.995738) (xy 104.178798 -277.983878) (xy 104.231948 -277.979895) (xy 104.285098 -277.983878)
			(xy 104.33706 -277.995738) (xy 104.386674 -278.01521) (xy 104.432832 -278.041859) (xy 104.474503 -278.07509)
			(xy 104.510755 -278.114161) (xy 104.540779 -278.158198) (xy 104.563905 -278.206219) (xy 104.579615 -278.257149)
			(xy 104.587558 -278.309853) (xy 104.588056 -278.336502) (xy 104.587558 -278.363151) (xy 104.815884 -278.363151)
			(xy 104.815884 -278.309853) (xy 104.823827 -278.257149) (xy 104.839537 -278.206219) (xy 104.862663 -278.158198)
			(xy 104.892687 -278.114161) (xy 104.928939 -278.07509) (xy 104.97061 -278.041859) (xy 105.016768 -278.01521)
			(xy 105.066382 -277.995738) (xy 105.118344 -277.983878) (xy 105.171494 -277.979895) (xy 105.224644 -277.983878)
			(xy 105.276606 -277.995738) (xy 105.32622 -278.01521) (xy 105.372378 -278.041859) (xy 105.414049 -278.07509)
			(xy 105.450301 -278.114161) (xy 105.480325 -278.158198) (xy 105.503451 -278.206219) (xy 105.519161 -278.257149)
			(xy 105.527104 -278.309853) (xy 105.527602 -278.336502) (xy 105.527104 -278.363151) (xy 106.695738 -278.363151)
			(xy 106.695738 -278.309853) (xy 106.703681 -278.257149) (xy 106.719391 -278.206219) (xy 106.742517 -278.158198)
			(xy 106.772541 -278.114161) (xy 106.808793 -278.07509) (xy 106.850464 -278.041859) (xy 106.896622 -278.01521)
			(xy 106.946236 -277.995738) (xy 106.998198 -277.983878) (xy 107.051348 -277.979895) (xy 107.104498 -277.983878)
			(xy 107.15646 -277.995738) (xy 107.206074 -278.01521) (xy 107.252232 -278.041859) (xy 107.293903 -278.07509)
			(xy 107.330155 -278.114161) (xy 107.360179 -278.158198) (xy 107.383305 -278.206219) (xy 107.399015 -278.257149)
			(xy 107.406958 -278.309853) (xy 107.407456 -278.336502) (xy 107.406958 -278.363151) (xy 107.399015 -278.415855)
			(xy 107.383305 -278.466785) (xy 107.360179 -278.514806) (xy 107.330155 -278.558843) (xy 107.293903 -278.597914)
			(xy 107.252232 -278.631145) (xy 107.206074 -278.657794) (xy 107.15646 -278.677266) (xy 107.104498 -278.689126)
			(xy 107.051348 -278.69311) (xy 106.998198 -278.689126) (xy 106.946236 -278.677266) (xy 106.896622 -278.657794)
			(xy 106.850464 -278.631145) (xy 106.808793 -278.597914) (xy 106.772541 -278.558843) (xy 106.742517 -278.514806)
			(xy 106.719391 -278.466785) (xy 106.703681 -278.415855) (xy 106.695738 -278.363151) (xy 105.527104 -278.363151)
			(xy 105.519161 -278.415855) (xy 105.503451 -278.466785) (xy 105.480325 -278.514806) (xy 105.450301 -278.558843)
			(xy 105.414049 -278.597914) (xy 105.372378 -278.631145) (xy 105.32622 -278.657794) (xy 105.276606 -278.677266)
			(xy 105.224644 -278.689126) (xy 105.171494 -278.69311) (xy 105.118344 -278.689126) (xy 105.066382 -278.677266)
			(xy 105.016768 -278.657794) (xy 104.97061 -278.631145) (xy 104.928939 -278.597914) (xy 104.892687 -278.558843)
			(xy 104.862663 -278.514806) (xy 104.839537 -278.466785) (xy 104.823827 -278.415855) (xy 104.815884 -278.363151)
			(xy 104.587558 -278.363151) (xy 104.579615 -278.415855) (xy 104.563905 -278.466785) (xy 104.540779 -278.514806)
			(xy 104.510755 -278.558843) (xy 104.474503 -278.597914) (xy 104.432832 -278.631145) (xy 104.386674 -278.657794)
			(xy 104.33706 -278.677266) (xy 104.285098 -278.689126) (xy 104.231948 -278.69311) (xy 104.178798 -278.689126)
			(xy 104.126836 -278.677266) (xy 104.077222 -278.657794) (xy 104.031064 -278.631145) (xy 103.989393 -278.597914)
			(xy 103.953141 -278.558843) (xy 103.923117 -278.514806) (xy 103.899991 -278.466785) (xy 103.884281 -278.415855)
			(xy 103.876338 -278.363151) (xy 103.647758 -278.363151) (xy 103.639815 -278.415855) (xy 103.624105 -278.466785)
			(xy 103.600979 -278.514806) (xy 103.570955 -278.558843) (xy 103.534703 -278.597914) (xy 103.493032 -278.631145)
			(xy 103.446874 -278.657794) (xy 103.39726 -278.677266) (xy 103.345298 -278.689126) (xy 103.292148 -278.69311)
			(xy 103.238998 -278.689126) (xy 103.187036 -278.677266) (xy 103.137422 -278.657794) (xy 103.091264 -278.631145)
			(xy 103.049593 -278.597914) (xy 103.013341 -278.558843) (xy 102.983317 -278.514806) (xy 102.960191 -278.466785)
			(xy 102.944481 -278.415855) (xy 102.936538 -278.363151) (xy 102.707958 -278.363151) (xy 102.700015 -278.415855)
			(xy 102.684305 -278.466785) (xy 102.661179 -278.514806) (xy 102.631155 -278.558843) (xy 102.594903 -278.597914)
			(xy 102.553232 -278.631145) (xy 102.507074 -278.657794) (xy 102.45746 -278.677266) (xy 102.405498 -278.689126)
			(xy 102.352348 -278.69311) (xy 102.299198 -278.689126) (xy 102.247236 -278.677266) (xy 102.197622 -278.657794)
			(xy 102.151464 -278.631145) (xy 102.109793 -278.597914) (xy 102.073541 -278.558843) (xy 102.043517 -278.514806)
			(xy 102.020391 -278.466785) (xy 102.004681 -278.415855) (xy 101.996738 -278.363151) (xy 101.767904 -278.363151)
			(xy 101.759961 -278.415855) (xy 101.744251 -278.466785) (xy 101.721125 -278.514806) (xy 101.691101 -278.558843)
			(xy 101.654849 -278.597914) (xy 101.613178 -278.631145) (xy 101.56702 -278.657794) (xy 101.517406 -278.677266)
			(xy 101.465444 -278.689126) (xy 101.412294 -278.69311) (xy 101.359144 -278.689126) (xy 101.307182 -278.677266)
			(xy 101.257568 -278.657794) (xy 101.21141 -278.631145) (xy 101.169739 -278.597914) (xy 101.133487 -278.558843)
			(xy 101.103463 -278.514806) (xy 101.080337 -278.466785) (xy 101.064627 -278.415855) (xy 101.056684 -278.363151)
			(xy 100.828358 -278.363151) (xy 100.820415 -278.415855) (xy 100.804705 -278.466785) (xy 100.781579 -278.514806)
			(xy 100.751555 -278.558843) (xy 100.715303 -278.597914) (xy 100.673632 -278.631145) (xy 100.627474 -278.657794)
			(xy 100.57786 -278.677266) (xy 100.525898 -278.689126) (xy 100.472748 -278.69311) (xy 100.419598 -278.689126)
			(xy 100.367636 -278.677266) (xy 100.318022 -278.657794) (xy 100.271864 -278.631145) (xy 100.230193 -278.597914)
			(xy 100.193941 -278.558843) (xy 100.163917 -278.514806) (xy 100.140791 -278.466785) (xy 100.125081 -278.415855)
			(xy 100.117138 -278.363151) (xy 99.888558 -278.363151) (xy 99.880615 -278.415855) (xy 99.864905 -278.466785)
			(xy 99.841779 -278.514806) (xy 99.811755 -278.558843) (xy 99.775503 -278.597914) (xy 99.733832 -278.631145)
			(xy 99.687674 -278.657794) (xy 99.63806 -278.677266) (xy 99.586098 -278.689126) (xy 99.532948 -278.69311)
			(xy 99.479798 -278.689126) (xy 99.427836 -278.677266) (xy 99.378222 -278.657794) (xy 99.332064 -278.631145)
			(xy 99.290393 -278.597914) (xy 99.254141 -278.558843) (xy 99.224117 -278.514806) (xy 99.200991 -278.466785)
			(xy 99.185281 -278.415855) (xy 99.177338 -278.363151) (xy 98.948758 -278.363151) (xy 98.940815 -278.415855)
			(xy 98.925105 -278.466785) (xy 98.901979 -278.514806) (xy 98.871955 -278.558843) (xy 98.835703 -278.597914)
			(xy 98.794032 -278.631145) (xy 98.747874 -278.657794) (xy 98.69826 -278.677266) (xy 98.646298 -278.689126)
			(xy 98.593148 -278.69311) (xy 98.539998 -278.689126) (xy 98.488036 -278.677266) (xy 98.438422 -278.657794)
			(xy 98.392264 -278.631145) (xy 98.350593 -278.597914) (xy 98.314341 -278.558843) (xy 98.284317 -278.514806)
			(xy 98.261191 -278.466785) (xy 98.245481 -278.415855) (xy 98.237538 -278.363151) (xy 98.008958 -278.363151)
			(xy 98.001015 -278.415855) (xy 97.985305 -278.466785) (xy 97.962179 -278.514806) (xy 97.932155 -278.558843)
			(xy 97.895903 -278.597914) (xy 97.854232 -278.631145) (xy 97.808074 -278.657794) (xy 97.75846 -278.677266)
			(xy 97.706498 -278.689126) (xy 97.653348 -278.69311) (xy 97.600198 -278.689126) (xy 97.548236 -278.677266)
			(xy 97.498622 -278.657794) (xy 97.452464 -278.631145) (xy 97.410793 -278.597914) (xy 97.374541 -278.558843)
			(xy 97.344517 -278.514806) (xy 97.321391 -278.466785) (xy 97.305681 -278.415855) (xy 97.297738 -278.363151)
			(xy 95.189558 -278.363151) (xy 95.181615 -278.415855) (xy 95.165905 -278.466785) (xy 95.142779 -278.514806)
			(xy 95.112755 -278.558843) (xy 95.076503 -278.597914) (xy 95.034832 -278.631145) (xy 94.988674 -278.657794)
			(xy 94.93906 -278.677266) (xy 94.887098 -278.689126) (xy 94.833948 -278.69311) (xy 94.780798 -278.689126)
			(xy 94.728836 -278.677266) (xy 94.679222 -278.657794) (xy 94.633064 -278.631145) (xy 94.591393 -278.597914)
			(xy 94.555141 -278.558843) (xy 94.525117 -278.514806) (xy 94.501991 -278.466785) (xy 94.486281 -278.415855)
			(xy 94.478338 -278.363151) (xy 94.249758 -278.363151) (xy 94.241815 -278.415855) (xy 94.226105 -278.466785)
			(xy 94.202979 -278.514806) (xy 94.172955 -278.558843) (xy 94.136703 -278.597914) (xy 94.095032 -278.631145)
			(xy 94.048874 -278.657794) (xy 93.99926 -278.677266) (xy 93.947298 -278.689126) (xy 93.894148 -278.69311)
			(xy 93.840998 -278.689126) (xy 93.789036 -278.677266) (xy 93.739422 -278.657794) (xy 93.693264 -278.631145)
			(xy 93.651593 -278.597914) (xy 93.615341 -278.558843) (xy 93.585317 -278.514806) (xy 93.562191 -278.466785)
			(xy 93.546481 -278.415855) (xy 93.538538 -278.363151) (xy 93.309958 -278.363151) (xy 93.302015 -278.415855)
			(xy 93.286305 -278.466785) (xy 93.263179 -278.514806) (xy 93.233155 -278.558843) (xy 93.196903 -278.597914)
			(xy 93.155232 -278.631145) (xy 93.109074 -278.657794) (xy 93.05946 -278.677266) (xy 93.007498 -278.689126)
			(xy 92.954348 -278.69311) (xy 92.901198 -278.689126) (xy 92.849236 -278.677266) (xy 92.799622 -278.657794)
			(xy 92.753464 -278.631145) (xy 92.711793 -278.597914) (xy 92.675541 -278.558843) (xy 92.645517 -278.514806)
			(xy 92.622391 -278.466785) (xy 92.606681 -278.415855) (xy 92.598738 -278.363151) (xy 92.370158 -278.363151)
			(xy 92.362215 -278.415855) (xy 92.346505 -278.466785) (xy 92.323379 -278.514806) (xy 92.293355 -278.558843)
			(xy 92.257103 -278.597914) (xy 92.215432 -278.631145) (xy 92.169274 -278.657794) (xy 92.11966 -278.677266)
			(xy 92.067698 -278.689126) (xy 92.014548 -278.69311) (xy 91.961398 -278.689126) (xy 91.909436 -278.677266)
			(xy 91.859822 -278.657794) (xy 91.813664 -278.631145) (xy 91.771993 -278.597914) (xy 91.735741 -278.558843)
			(xy 91.705717 -278.514806) (xy 91.682591 -278.466785) (xy 91.666881 -278.415855) (xy 91.658938 -278.363151)
			(xy 91.430104 -278.363151) (xy 91.422161 -278.415855) (xy 91.406451 -278.466785) (xy 91.383325 -278.514806)
			(xy 91.353301 -278.558843) (xy 91.317049 -278.597914) (xy 91.275378 -278.631145) (xy 91.22922 -278.657794)
			(xy 91.179606 -278.677266) (xy 91.127644 -278.689126) (xy 91.074494 -278.69311) (xy 91.021344 -278.689126)
			(xy 90.969382 -278.677266) (xy 90.919768 -278.657794) (xy 90.87361 -278.631145) (xy 90.831939 -278.597914)
			(xy 90.795687 -278.558843) (xy 90.765663 -278.514806) (xy 90.742537 -278.466785) (xy 90.726827 -278.415855)
			(xy 90.718884 -278.363151) (xy 86.718348 -278.363151) (xy 86.710361 -278.414864) (xy 86.694475 -278.465063)
			(xy 86.671112 -278.512248) (xy 86.64082 -278.555314) (xy 86.604308 -278.593252) (xy 86.562434 -278.625171)
			(xy 86.516178 -278.650324) (xy 86.466625 -278.668122) (xy 86.414935 -278.678146) (xy 86.362321 -278.680163)
			(xy 86.310016 -278.674125) (xy 86.259245 -278.660173) (xy 86.2112 -278.638634) (xy 86.167005 -278.610014)
			(xy 86.127697 -278.574983) (xy 86.094197 -278.534362) (xy 86.067291 -278.489103) (xy 86.047608 -278.440268)
			(xy 86.035611 -278.389) (xy 86.031581 -278.336502) (xy 85.52688 -278.336502) (xy 85.52688 -278.64308)
			(xy 85.527642 -278.647398) (xy 85.53037 -278.663259) (xy 85.533296 -278.695313) (xy 85.533484 -278.711406)
			(xy 85.533292 -278.727499) (xy 85.530364 -278.759552) (xy 85.527642 -278.775414) (xy 85.52688 -278.779732)
			(xy 85.52688 -279.176967) (xy 88.369384 -279.176967) (xy 88.369384 -279.123669) (xy 88.377327 -279.070965)
			(xy 88.393037 -279.020035) (xy 88.416163 -278.972014) (xy 88.446187 -278.927977) (xy 88.482439 -278.888906)
			(xy 88.52411 -278.855675) (xy 88.570268 -278.829026) (xy 88.619882 -278.809554) (xy 88.671844 -278.797694)
			(xy 88.724994 -278.793711) (xy 88.778144 -278.797694) (xy 88.830106 -278.809554) (xy 88.87972 -278.829026)
			(xy 88.925878 -278.855675) (xy 88.967549 -278.888906) (xy 89.003801 -278.927977) (xy 89.033825 -278.972014)
			(xy 89.056951 -279.020035) (xy 89.072661 -279.070965) (xy 89.080604 -279.123669) (xy 89.081102 -279.150318)
			(xy 89.080604 -279.176967) (xy 89.309184 -279.176967) (xy 89.309184 -279.123669) (xy 89.317127 -279.070965)
			(xy 89.332837 -279.020035) (xy 89.355963 -278.972014) (xy 89.385987 -278.927977) (xy 89.422239 -278.888906)
			(xy 89.46391 -278.855675) (xy 89.510068 -278.829026) (xy 89.559682 -278.809554) (xy 89.611644 -278.797694)
			(xy 89.664794 -278.793711) (xy 89.717944 -278.797694) (xy 89.769906 -278.809554) (xy 89.81952 -278.829026)
			(xy 89.865678 -278.855675) (xy 89.907349 -278.888906) (xy 89.943601 -278.927977) (xy 89.973625 -278.972014)
			(xy 89.996751 -279.020035) (xy 90.012461 -279.070965) (xy 90.020404 -279.123669) (xy 90.020902 -279.150318)
			(xy 90.020404 -279.176967) (xy 90.248984 -279.176967) (xy 90.248984 -279.123669) (xy 90.256927 -279.070965)
			(xy 90.272637 -279.020035) (xy 90.295763 -278.972014) (xy 90.325787 -278.927977) (xy 90.362039 -278.888906)
			(xy 90.40371 -278.855675) (xy 90.449868 -278.829026) (xy 90.499482 -278.809554) (xy 90.551444 -278.797694)
			(xy 90.604594 -278.793711) (xy 90.657744 -278.797694) (xy 90.709706 -278.809554) (xy 90.75932 -278.829026)
			(xy 90.805478 -278.855675) (xy 90.847149 -278.888906) (xy 90.883401 -278.927977) (xy 90.913425 -278.972014)
			(xy 90.936551 -279.020035) (xy 90.952261 -279.070965) (xy 90.960204 -279.123669) (xy 90.960702 -279.150318)
			(xy 90.960204 -279.176967) (xy 91.188784 -279.176967) (xy 91.188784 -279.123669) (xy 91.196727 -279.070965)
			(xy 91.212437 -279.020035) (xy 91.235563 -278.972014) (xy 91.265587 -278.927977) (xy 91.301839 -278.888906)
			(xy 91.34351 -278.855675) (xy 91.389668 -278.829026) (xy 91.439282 -278.809554) (xy 91.491244 -278.797694)
			(xy 91.544394 -278.793711) (xy 91.597544 -278.797694) (xy 91.649506 -278.809554) (xy 91.69912 -278.829026)
			(xy 91.745278 -278.855675) (xy 91.786949 -278.888906) (xy 91.823201 -278.927977) (xy 91.853225 -278.972014)
			(xy 91.876351 -279.020035) (xy 91.892061 -279.070965) (xy 91.900004 -279.123669) (xy 91.900502 -279.150318)
			(xy 91.900004 -279.176967) (xy 92.128584 -279.176967) (xy 92.128584 -279.123669) (xy 92.136527 -279.070965)
			(xy 92.152237 -279.020035) (xy 92.175363 -278.972014) (xy 92.205387 -278.927977) (xy 92.241639 -278.888906)
			(xy 92.28331 -278.855675) (xy 92.329468 -278.829026) (xy 92.379082 -278.809554) (xy 92.431044 -278.797694)
			(xy 92.484194 -278.793711) (xy 92.537344 -278.797694) (xy 92.589306 -278.809554) (xy 92.63892 -278.829026)
			(xy 92.685078 -278.855675) (xy 92.726749 -278.888906) (xy 92.763001 -278.927977) (xy 92.793025 -278.972014)
			(xy 92.816151 -279.020035) (xy 92.831861 -279.070965) (xy 92.839804 -279.123669) (xy 92.840302 -279.150318)
			(xy 92.839804 -279.176967) (xy 93.068384 -279.176967) (xy 93.068384 -279.123669) (xy 93.076327 -279.070965)
			(xy 93.092037 -279.020035) (xy 93.115163 -278.972014) (xy 93.145187 -278.927977) (xy 93.181439 -278.888906)
			(xy 93.22311 -278.855675) (xy 93.269268 -278.829026) (xy 93.318882 -278.809554) (xy 93.370844 -278.797694)
			(xy 93.423994 -278.793711) (xy 93.477144 -278.797694) (xy 93.529106 -278.809554) (xy 93.57872 -278.829026)
			(xy 93.624878 -278.855675) (xy 93.666549 -278.888906) (xy 93.702801 -278.927977) (xy 93.732825 -278.972014)
			(xy 93.755951 -279.020035) (xy 93.771661 -279.070965) (xy 93.779604 -279.123669) (xy 93.780102 -279.150318)
			(xy 93.779604 -279.176967) (xy 94.008438 -279.176967) (xy 94.008438 -279.123669) (xy 94.016381 -279.070965)
			(xy 94.032091 -279.020035) (xy 94.055217 -278.972014) (xy 94.085241 -278.927977) (xy 94.121493 -278.888906)
			(xy 94.163164 -278.855675) (xy 94.209322 -278.829026) (xy 94.258936 -278.809554) (xy 94.310898 -278.797694)
			(xy 94.364048 -278.793711) (xy 94.417198 -278.797694) (xy 94.46916 -278.809554) (xy 94.518774 -278.829026)
			(xy 94.564932 -278.855675) (xy 94.606603 -278.888906) (xy 94.642855 -278.927977) (xy 94.672879 -278.972014)
			(xy 94.696005 -279.020035) (xy 94.711715 -279.070965) (xy 94.719658 -279.123669) (xy 94.720156 -279.150318)
			(xy 94.719658 -279.176967) (xy 94.947984 -279.176967) (xy 94.947984 -279.123669) (xy 94.955927 -279.070965)
			(xy 94.971637 -279.020035) (xy 94.994763 -278.972014) (xy 95.024787 -278.927977) (xy 95.061039 -278.888906)
			(xy 95.10271 -278.855675) (xy 95.148868 -278.829026) (xy 95.198482 -278.809554) (xy 95.250444 -278.797694)
			(xy 95.303594 -278.793711) (xy 95.356744 -278.797694) (xy 95.408706 -278.809554) (xy 95.45832 -278.829026)
			(xy 95.504478 -278.855675) (xy 95.546149 -278.888906) (xy 95.582401 -278.927977) (xy 95.612425 -278.972014)
			(xy 95.635551 -279.020035) (xy 95.651261 -279.070965) (xy 95.659204 -279.123669) (xy 95.659702 -279.150318)
			(xy 95.659204 -279.176967) (xy 95.887784 -279.176967) (xy 95.887784 -279.123669) (xy 95.895727 -279.070965)
			(xy 95.911437 -279.020035) (xy 95.934563 -278.972014) (xy 95.964587 -278.927977) (xy 96.000839 -278.888906)
			(xy 96.04251 -278.855675) (xy 96.088668 -278.829026) (xy 96.138282 -278.809554) (xy 96.190244 -278.797694)
			(xy 96.243394 -278.793711) (xy 96.296544 -278.797694) (xy 96.348506 -278.809554) (xy 96.39812 -278.829026)
			(xy 96.444278 -278.855675) (xy 96.485949 -278.888906) (xy 96.522201 -278.927977) (xy 96.552225 -278.972014)
			(xy 96.575351 -279.020035) (xy 96.591061 -279.070965) (xy 96.599004 -279.123669) (xy 96.599502 -279.150318)
			(xy 96.599004 -279.176967) (xy 97.767638 -279.176967) (xy 97.767638 -279.123669) (xy 97.775581 -279.070965)
			(xy 97.791291 -279.020035) (xy 97.814417 -278.972014) (xy 97.844441 -278.927977) (xy 97.880693 -278.888906)
			(xy 97.922364 -278.855675) (xy 97.968522 -278.829026) (xy 98.018136 -278.809554) (xy 98.070098 -278.797694)
			(xy 98.123248 -278.793711) (xy 98.176398 -278.797694) (xy 98.22836 -278.809554) (xy 98.277974 -278.829026)
			(xy 98.324132 -278.855675) (xy 98.365803 -278.888906) (xy 98.402055 -278.927977) (xy 98.432079 -278.972014)
			(xy 98.455205 -279.020035) (xy 98.470915 -279.070965) (xy 98.478858 -279.123669) (xy 98.479356 -279.150318)
			(xy 98.478858 -279.176967) (xy 98.707184 -279.176967) (xy 98.707184 -279.123669) (xy 98.715127 -279.070965)
			(xy 98.730837 -279.020035) (xy 98.753963 -278.972014) (xy 98.783987 -278.927977) (xy 98.820239 -278.888906)
			(xy 98.86191 -278.855675) (xy 98.908068 -278.829026) (xy 98.957682 -278.809554) (xy 99.009644 -278.797694)
			(xy 99.062794 -278.793711) (xy 99.115944 -278.797694) (xy 99.167906 -278.809554) (xy 99.21752 -278.829026)
			(xy 99.263678 -278.855675) (xy 99.305349 -278.888906) (xy 99.341601 -278.927977) (xy 99.371625 -278.972014)
			(xy 99.394751 -279.020035) (xy 99.410461 -279.070965) (xy 99.418404 -279.123669) (xy 99.418902 -279.150318)
			(xy 99.418404 -279.176967) (xy 99.646984 -279.176967) (xy 99.646984 -279.123669) (xy 99.654927 -279.070965)
			(xy 99.670637 -279.020035) (xy 99.693763 -278.972014) (xy 99.723787 -278.927977) (xy 99.760039 -278.888906)
			(xy 99.80171 -278.855675) (xy 99.847868 -278.829026) (xy 99.897482 -278.809554) (xy 99.949444 -278.797694)
			(xy 100.002594 -278.793711) (xy 100.055744 -278.797694) (xy 100.107706 -278.809554) (xy 100.15732 -278.829026)
			(xy 100.203478 -278.855675) (xy 100.245149 -278.888906) (xy 100.281401 -278.927977) (xy 100.311425 -278.972014)
			(xy 100.334551 -279.020035) (xy 100.350261 -279.070965) (xy 100.358204 -279.123669) (xy 100.358702 -279.150318)
			(xy 100.358204 -279.176967) (xy 100.587038 -279.176967) (xy 100.587038 -279.123669) (xy 100.594981 -279.070965)
			(xy 100.610691 -279.020035) (xy 100.633817 -278.972014) (xy 100.663841 -278.927977) (xy 100.700093 -278.888906)
			(xy 100.741764 -278.855675) (xy 100.787922 -278.829026) (xy 100.837536 -278.809554) (xy 100.889498 -278.797694)
			(xy 100.942648 -278.793711) (xy 100.995798 -278.797694) (xy 101.04776 -278.809554) (xy 101.097374 -278.829026)
			(xy 101.143532 -278.855675) (xy 101.185203 -278.888906) (xy 101.221455 -278.927977) (xy 101.251479 -278.972014)
			(xy 101.274605 -279.020035) (xy 101.290315 -279.070965) (xy 101.298258 -279.123669) (xy 101.298756 -279.150318)
			(xy 101.526086 -279.150318) (xy 101.526584 -279.123669) (xy 101.534527 -279.070965) (xy 101.550237 -279.020035)
			(xy 101.573363 -278.972014) (xy 101.603387 -278.927977) (xy 101.639639 -278.888906) (xy 101.68131 -278.855675)
			(xy 101.727468 -278.829026) (xy 101.777082 -278.809554) (xy 101.829044 -278.797694) (xy 101.882194 -278.793711)
			(xy 101.935344 -278.797694) (xy 101.987306 -278.809554) (xy 102.03692 -278.829026) (xy 102.083078 -278.855675)
			(xy 102.124749 -278.888906) (xy 102.161001 -278.927977) (xy 102.191025 -278.972014) (xy 102.214151 -279.020035)
			(xy 102.229861 -279.070965) (xy 102.237804 -279.123669) (xy 102.238302 -279.1503) (xy 102.465411 -279.1503)
			(xy 102.469394 -279.097154) (xy 102.481253 -279.045195) (xy 102.500724 -278.995583) (xy 102.527371 -278.949428)
			(xy 102.5606 -278.90776) (xy 102.599668 -278.87151) (xy 102.643702 -278.841487) (xy 102.691719 -278.818362)
			(xy 102.742646 -278.802653) (xy 102.795346 -278.794709) (xy 102.821994 -278.79421) (xy 102.847019 -278.79463)
			(xy 102.896577 -278.801637) (xy 102.944665 -278.815516) (xy 102.990336 -278.835991) (xy 103.03269 -278.86266)
			(xy 103.070893 -278.894996) (xy 103.10419 -278.932364) (xy 103.118412 -278.95296) (xy 103.465376 -278.95296)
			(xy 103.479609 -278.932372) (xy 103.512905 -278.895005) (xy 103.551105 -278.862668) (xy 103.593457 -278.835999)
			(xy 103.639127 -278.815523) (xy 103.687213 -278.801644) (xy 103.736769 -278.794635) (xy 103.761794 -278.79421)
			(xy 103.788447 -278.794647) (xy 103.841157 -278.802591) (xy 103.892095 -278.818302) (xy 103.940122 -278.84143)
			(xy 103.984165 -278.871458) (xy 104.023241 -278.907714) (xy 104.056477 -278.94939) (xy 104.08313 -278.995554)
			(xy 104.102605 -279.045174) (xy 104.114466 -279.097144) (xy 104.11845 -279.1503) (xy 104.116451 -279.176967)
			(xy 104.345984 -279.176967) (xy 104.345984 -279.123669) (xy 104.353927 -279.070965) (xy 104.369637 -279.020035)
			(xy 104.392763 -278.972014) (xy 104.422787 -278.927977) (xy 104.459039 -278.888906) (xy 104.50071 -278.855675)
			(xy 104.546868 -278.829026) (xy 104.596482 -278.809554) (xy 104.648444 -278.797694) (xy 104.701594 -278.793711)
			(xy 104.754744 -278.797694) (xy 104.806706 -278.809554) (xy 104.85632 -278.829026) (xy 104.902478 -278.855675)
			(xy 104.944149 -278.888906) (xy 104.980401 -278.927977) (xy 105.010425 -278.972014) (xy 105.033551 -279.020035)
			(xy 105.049261 -279.070965) (xy 105.057204 -279.123669) (xy 105.057702 -279.150318) (xy 105.057204 -279.176967)
			(xy 105.286038 -279.176967) (xy 105.286038 -279.123669) (xy 105.293981 -279.070965) (xy 105.309691 -279.020035)
			(xy 105.332817 -278.972014) (xy 105.362841 -278.927977) (xy 105.399093 -278.888906) (xy 105.440764 -278.855675)
			(xy 105.486922 -278.829026) (xy 105.536536 -278.809554) (xy 105.588498 -278.797694) (xy 105.641648 -278.793711)
			(xy 105.694798 -278.797694) (xy 105.74676 -278.809554) (xy 105.796374 -278.829026) (xy 105.842532 -278.855675)
			(xy 105.884203 -278.888906) (xy 105.920455 -278.927977) (xy 105.950479 -278.972014) (xy 105.973605 -279.020035)
			(xy 105.989315 -279.070965) (xy 105.997258 -279.123669) (xy 105.997756 -279.150318) (xy 105.997258 -279.176967)
			(xy 106.225838 -279.176967) (xy 106.225838 -279.123669) (xy 106.233781 -279.070965) (xy 106.249491 -279.020035)
			(xy 106.272617 -278.972014) (xy 106.302641 -278.927977) (xy 106.338893 -278.888906) (xy 106.380564 -278.855675)
			(xy 106.426722 -278.829026) (xy 106.476336 -278.809554) (xy 106.528298 -278.797694) (xy 106.581448 -278.793711)
			(xy 106.634598 -278.797694) (xy 106.68656 -278.809554) (xy 106.736174 -278.829026) (xy 106.782332 -278.855675)
			(xy 106.824003 -278.888906) (xy 106.860255 -278.927977) (xy 106.890279 -278.972014) (xy 106.913405 -279.020035)
			(xy 106.929115 -279.070965) (xy 106.937058 -279.123669) (xy 106.937556 -279.150318) (xy 106.937058 -279.176967)
			(xy 106.929115 -279.229671) (xy 106.913405 -279.280601) (xy 106.890279 -279.328622) (xy 106.860255 -279.372659)
			(xy 106.824003 -279.41173) (xy 106.782332 -279.444961) (xy 106.736174 -279.47161) (xy 106.68656 -279.491082)
			(xy 106.634598 -279.502942) (xy 106.581448 -279.506926) (xy 106.528298 -279.502942) (xy 106.476336 -279.491082)
			(xy 106.426722 -279.47161) (xy 106.380564 -279.444961) (xy 106.338893 -279.41173) (xy 106.302641 -279.372659)
			(xy 106.272617 -279.328622) (xy 106.249491 -279.280601) (xy 106.233781 -279.229671) (xy 106.225838 -279.176967)
			(xy 105.997258 -279.176967) (xy 105.989315 -279.229671) (xy 105.973605 -279.280601) (xy 105.950479 -279.328622)
			(xy 105.920455 -279.372659) (xy 105.884203 -279.41173) (xy 105.842532 -279.444961) (xy 105.796374 -279.47161)
			(xy 105.74676 -279.491082) (xy 105.694798 -279.502942) (xy 105.641648 -279.506926) (xy 105.588498 -279.502942)
			(xy 105.536536 -279.491082) (xy 105.486922 -279.47161) (xy 105.440764 -279.444961) (xy 105.399093 -279.41173)
			(xy 105.362841 -279.372659) (xy 105.332817 -279.328622) (xy 105.309691 -279.280601) (xy 105.293981 -279.229671)
			(xy 105.286038 -279.176967) (xy 105.057204 -279.176967) (xy 105.049261 -279.229671) (xy 105.033551 -279.280601)
			(xy 105.010425 -279.328622) (xy 104.980401 -279.372659) (xy 104.944149 -279.41173) (xy 104.902478 -279.444961)
			(xy 104.85632 -279.47161) (xy 104.806706 -279.491082) (xy 104.754744 -279.502942) (xy 104.701594 -279.506926)
			(xy 104.648444 -279.502942) (xy 104.596482 -279.491082) (xy 104.546868 -279.47161) (xy 104.50071 -279.444961)
			(xy 104.459039 -279.41173) (xy 104.422787 -279.372659) (xy 104.392763 -279.328622) (xy 104.369637 -279.280601)
			(xy 104.353927 -279.229671) (xy 104.345984 -279.176967) (xy 104.116451 -279.176967) (xy 104.114466 -279.203456)
			(xy 104.102605 -279.255426) (xy 104.08313 -279.305046) (xy 104.056477 -279.35121) (xy 104.023241 -279.392886)
			(xy 103.984165 -279.429142) (xy 103.940122 -279.45917) (xy 103.892095 -279.482298) (xy 103.841157 -279.498009)
			(xy 103.788447 -279.505953) (xy 103.761794 -279.506426) (xy 103.736769 -279.506) (xy 103.687212 -279.498991)
			(xy 103.639125 -279.485113) (xy 103.593454 -279.464638) (xy 103.551101 -279.437971) (xy 103.512898 -279.405636)
			(xy 103.479599 -279.368271) (xy 103.465376 -279.347676) (xy 103.118412 -279.347676) (xy 103.104198 -279.368277)
			(xy 103.070898 -279.405643) (xy 103.032693 -279.437977) (xy 102.990338 -279.464644) (xy 102.944666 -279.485118)
			(xy 102.896577 -279.498995) (xy 102.847019 -279.506002) (xy 102.821994 -279.506426) (xy 102.795346 -279.505891)
			(xy 102.742646 -279.497947) (xy 102.691719 -279.482238) (xy 102.643702 -279.459113) (xy 102.599668 -279.42909)
			(xy 102.5606 -279.39284) (xy 102.527371 -279.351172) (xy 102.500724 -279.305017) (xy 102.481253 -279.255405)
			(xy 102.469394 -279.203446) (xy 102.465411 -279.1503) (xy 102.238302 -279.1503) (xy 102.238302 -279.150318)
			(xy 102.237936 -279.17347) (xy 102.231947 -279.219384) (xy 102.220072 -279.264139) (xy 102.211632 -279.2857)
			(xy 102.20198 -279.308814) (xy 102.3747 -279.607772) (xy 102.399338 -279.611074) (xy 102.424679 -279.614908)
			(xy 102.473983 -279.628899) (xy 102.520773 -279.64981) (xy 102.564084 -279.67721) (xy 102.603022 -279.710534)
			(xy 102.636783 -279.749094) (xy 102.66467 -279.792093) (xy 102.686107 -279.838645) (xy 102.700653 -279.887788)
			(xy 102.708006 -279.938509) (xy 102.708456 -279.964134) (xy 102.707958 -279.990783) (xy 102.936284 -279.990783)
			(xy 102.936284 -279.937485) (xy 102.944227 -279.884781) (xy 102.959937 -279.833851) (xy 102.983063 -279.78583)
			(xy 103.013087 -279.741793) (xy 103.049339 -279.702722) (xy 103.09101 -279.669491) (xy 103.137168 -279.642842)
			(xy 103.186782 -279.62337) (xy 103.238744 -279.61151) (xy 103.291894 -279.607527) (xy 103.345044 -279.61151)
			(xy 103.397006 -279.62337) (xy 103.44662 -279.642842) (xy 103.492778 -279.669491) (xy 103.534449 -279.702722)
			(xy 103.570701 -279.741793) (xy 103.600725 -279.78583) (xy 103.623851 -279.833851) (xy 103.639561 -279.884781)
			(xy 103.647504 -279.937485) (xy 103.648002 -279.964134) (xy 103.647504 -279.990783) (xy 103.876338 -279.990783)
			(xy 103.876338 -279.937485) (xy 103.884281 -279.884781) (xy 103.899991 -279.833851) (xy 103.923117 -279.78583)
			(xy 103.953141 -279.741793) (xy 103.989393 -279.702722) (xy 104.031064 -279.669491) (xy 104.077222 -279.642842)
			(xy 104.126836 -279.62337) (xy 104.178798 -279.61151) (xy 104.231948 -279.607527) (xy 104.285098 -279.61151)
			(xy 104.33706 -279.62337) (xy 104.386674 -279.642842) (xy 104.432832 -279.669491) (xy 104.474503 -279.702722)
			(xy 104.510755 -279.741793) (xy 104.540779 -279.78583) (xy 104.563905 -279.833851) (xy 104.579615 -279.884781)
			(xy 104.587558 -279.937485) (xy 104.588056 -279.964134) (xy 104.587558 -279.990783) (xy 104.579615 -280.043487)
			(xy 104.563905 -280.094417) (xy 104.540779 -280.142438) (xy 104.510755 -280.186475) (xy 104.474503 -280.225546)
			(xy 104.432832 -280.258777) (xy 104.386674 -280.285426) (xy 104.33706 -280.304898) (xy 104.285098 -280.316758)
			(xy 104.231948 -280.320742) (xy 104.178798 -280.316758) (xy 104.126836 -280.304898) (xy 104.077222 -280.285426)
			(xy 104.031064 -280.258777) (xy 103.989393 -280.225546) (xy 103.953141 -280.186475) (xy 103.923117 -280.142438)
			(xy 103.899991 -280.094417) (xy 103.884281 -280.043487) (xy 103.876338 -279.990783) (xy 103.647504 -279.990783)
			(xy 103.639561 -280.043487) (xy 103.623851 -280.094417) (xy 103.600725 -280.142438) (xy 103.570701 -280.186475)
			(xy 103.534449 -280.225546) (xy 103.492778 -280.258777) (xy 103.44662 -280.285426) (xy 103.397006 -280.304898)
			(xy 103.345044 -280.316758) (xy 103.291894 -280.320742) (xy 103.238744 -280.316758) (xy 103.186782 -280.304898)
			(xy 103.137168 -280.285426) (xy 103.09101 -280.258777) (xy 103.049339 -280.225546) (xy 103.013087 -280.186475)
			(xy 102.983063 -280.142438) (xy 102.959937 -280.094417) (xy 102.944227 -280.043487) (xy 102.936284 -279.990783)
			(xy 102.707958 -279.990783) (xy 102.700015 -280.043487) (xy 102.684305 -280.094417) (xy 102.661179 -280.142438)
			(xy 102.631155 -280.186475) (xy 102.594903 -280.225546) (xy 102.553232 -280.258777) (xy 102.507074 -280.285426)
			(xy 102.45746 -280.304898) (xy 102.405498 -280.316758) (xy 102.352348 -280.320742) (xy 102.299198 -280.316758)
			(xy 102.247236 -280.304898) (xy 102.197622 -280.285426) (xy 102.151464 -280.258777) (xy 102.109793 -280.225546)
			(xy 102.073541 -280.186475) (xy 102.043517 -280.142438) (xy 102.020391 -280.094417) (xy 102.004681 -280.043487)
			(xy 101.996738 -279.990783) (xy 101.99624 -279.964134) (xy 101.996617 -279.940889) (xy 102.00266 -279.894794)
			(xy 102.014648 -279.849876) (xy 102.023164 -279.828244) (xy 102.032816 -279.80513) (xy 101.86035 -279.50668)
			(xy 101.835458 -279.503378) (xy 101.810095 -279.499606) (xy 101.760754 -279.485643) (xy 101.713926 -279.464749)
			(xy 101.670577 -279.437357) (xy 101.631604 -279.404032) (xy 101.597813 -279.365463) (xy 101.5699 -279.322447)
			(xy 101.548445 -279.275874) (xy 101.533889 -279.226705) (xy 101.526533 -279.175957) (xy 101.526086 -279.150318)
			(xy 101.298756 -279.150318) (xy 101.298258 -279.176967) (xy 101.290315 -279.229671) (xy 101.274605 -279.280601)
			(xy 101.251479 -279.328622) (xy 101.221455 -279.372659) (xy 101.185203 -279.41173) (xy 101.143532 -279.444961)
			(xy 101.097374 -279.47161) (xy 101.04776 -279.491082) (xy 100.995798 -279.502942) (xy 100.942648 -279.506926)
			(xy 100.889498 -279.502942) (xy 100.837536 -279.491082) (xy 100.787922 -279.47161) (xy 100.741764 -279.444961)
			(xy 100.700093 -279.41173) (xy 100.663841 -279.372659) (xy 100.633817 -279.328622) (xy 100.610691 -279.280601)
			(xy 100.594981 -279.229671) (xy 100.587038 -279.176967) (xy 100.358204 -279.176967) (xy 100.350261 -279.229671)
			(xy 100.334551 -279.280601) (xy 100.311425 -279.328622) (xy 100.281401 -279.372659) (xy 100.245149 -279.41173)
			(xy 100.203478 -279.444961) (xy 100.15732 -279.47161) (xy 100.107706 -279.491082) (xy 100.055744 -279.502942)
			(xy 100.002594 -279.506926) (xy 99.949444 -279.502942) (xy 99.897482 -279.491082) (xy 99.847868 -279.47161)
			(xy 99.80171 -279.444961) (xy 99.760039 -279.41173) (xy 99.723787 -279.372659) (xy 99.693763 -279.328622)
			(xy 99.670637 -279.280601) (xy 99.654927 -279.229671) (xy 99.646984 -279.176967) (xy 99.418404 -279.176967)
			(xy 99.410461 -279.229671) (xy 99.394751 -279.280601) (xy 99.371625 -279.328622) (xy 99.341601 -279.372659)
			(xy 99.305349 -279.41173) (xy 99.263678 -279.444961) (xy 99.21752 -279.47161) (xy 99.167906 -279.491082)
			(xy 99.115944 -279.502942) (xy 99.062794 -279.506926) (xy 99.009644 -279.502942) (xy 98.957682 -279.491082)
			(xy 98.908068 -279.47161) (xy 98.86191 -279.444961) (xy 98.820239 -279.41173) (xy 98.783987 -279.372659)
			(xy 98.753963 -279.328622) (xy 98.730837 -279.280601) (xy 98.715127 -279.229671) (xy 98.707184 -279.176967)
			(xy 98.478858 -279.176967) (xy 98.470915 -279.229671) (xy 98.455205 -279.280601) (xy 98.432079 -279.328622)
			(xy 98.402055 -279.372659) (xy 98.365803 -279.41173) (xy 98.324132 -279.444961) (xy 98.277974 -279.47161)
			(xy 98.22836 -279.491082) (xy 98.176398 -279.502942) (xy 98.123248 -279.506926) (xy 98.070098 -279.502942)
			(xy 98.018136 -279.491082) (xy 97.968522 -279.47161) (xy 97.922364 -279.444961) (xy 97.880693 -279.41173)
			(xy 97.844441 -279.372659) (xy 97.814417 -279.328622) (xy 97.791291 -279.280601) (xy 97.775581 -279.229671)
			(xy 97.767638 -279.176967) (xy 96.599004 -279.176967) (xy 96.591061 -279.229671) (xy 96.575351 -279.280601)
			(xy 96.552225 -279.328622) (xy 96.522201 -279.372659) (xy 96.485949 -279.41173) (xy 96.444278 -279.444961)
			(xy 96.39812 -279.47161) (xy 96.348506 -279.491082) (xy 96.296544 -279.502942) (xy 96.243394 -279.506926)
			(xy 96.190244 -279.502942) (xy 96.138282 -279.491082) (xy 96.088668 -279.47161) (xy 96.04251 -279.444961)
			(xy 96.000839 -279.41173) (xy 95.964587 -279.372659) (xy 95.934563 -279.328622) (xy 95.911437 -279.280601)
			(xy 95.895727 -279.229671) (xy 95.887784 -279.176967) (xy 95.659204 -279.176967) (xy 95.651261 -279.229671)
			(xy 95.635551 -279.280601) (xy 95.612425 -279.328622) (xy 95.582401 -279.372659) (xy 95.546149 -279.41173)
			(xy 95.504478 -279.444961) (xy 95.45832 -279.47161) (xy 95.408706 -279.491082) (xy 95.356744 -279.502942)
			(xy 95.303594 -279.506926) (xy 95.250444 -279.502942) (xy 95.198482 -279.491082) (xy 95.148868 -279.47161)
			(xy 95.10271 -279.444961) (xy 95.061039 -279.41173) (xy 95.024787 -279.372659) (xy 94.994763 -279.328622)
			(xy 94.971637 -279.280601) (xy 94.955927 -279.229671) (xy 94.947984 -279.176967) (xy 94.719658 -279.176967)
			(xy 94.711715 -279.229671) (xy 94.696005 -279.280601) (xy 94.672879 -279.328622) (xy 94.642855 -279.372659)
			(xy 94.606603 -279.41173) (xy 94.564932 -279.444961) (xy 94.518774 -279.47161) (xy 94.46916 -279.491082)
			(xy 94.417198 -279.502942) (xy 94.364048 -279.506926) (xy 94.310898 -279.502942) (xy 94.258936 -279.491082)
			(xy 94.209322 -279.47161) (xy 94.163164 -279.444961) (xy 94.121493 -279.41173) (xy 94.085241 -279.372659)
			(xy 94.055217 -279.328622) (xy 94.032091 -279.280601) (xy 94.016381 -279.229671) (xy 94.008438 -279.176967)
			(xy 93.779604 -279.176967) (xy 93.771661 -279.229671) (xy 93.755951 -279.280601) (xy 93.732825 -279.328622)
			(xy 93.702801 -279.372659) (xy 93.666549 -279.41173) (xy 93.624878 -279.444961) (xy 93.57872 -279.47161)
			(xy 93.529106 -279.491082) (xy 93.477144 -279.502942) (xy 93.423994 -279.506926) (xy 93.370844 -279.502942)
			(xy 93.318882 -279.491082) (xy 93.269268 -279.47161) (xy 93.22311 -279.444961) (xy 93.181439 -279.41173)
			(xy 93.145187 -279.372659) (xy 93.115163 -279.328622) (xy 93.092037 -279.280601) (xy 93.076327 -279.229671)
			(xy 93.068384 -279.176967) (xy 92.839804 -279.176967) (xy 92.831861 -279.229671) (xy 92.816151 -279.280601)
			(xy 92.793025 -279.328622) (xy 92.763001 -279.372659) (xy 92.726749 -279.41173) (xy 92.685078 -279.444961)
			(xy 92.63892 -279.47161) (xy 92.589306 -279.491082) (xy 92.537344 -279.502942) (xy 92.484194 -279.506926)
			(xy 92.431044 -279.502942) (xy 92.379082 -279.491082) (xy 92.329468 -279.47161) (xy 92.28331 -279.444961)
			(xy 92.241639 -279.41173) (xy 92.205387 -279.372659) (xy 92.175363 -279.328622) (xy 92.152237 -279.280601)
			(xy 92.136527 -279.229671) (xy 92.128584 -279.176967) (xy 91.900004 -279.176967) (xy 91.892061 -279.229671)
			(xy 91.876351 -279.280601) (xy 91.853225 -279.328622) (xy 91.823201 -279.372659) (xy 91.786949 -279.41173)
			(xy 91.745278 -279.444961) (xy 91.69912 -279.47161) (xy 91.649506 -279.491082) (xy 91.597544 -279.502942)
			(xy 91.544394 -279.506926) (xy 91.491244 -279.502942) (xy 91.439282 -279.491082) (xy 91.389668 -279.47161)
			(xy 91.34351 -279.444961) (xy 91.301839 -279.41173) (xy 91.265587 -279.372659) (xy 91.235563 -279.328622)
			(xy 91.212437 -279.280601) (xy 91.196727 -279.229671) (xy 91.188784 -279.176967) (xy 90.960204 -279.176967)
			(xy 90.952261 -279.229671) (xy 90.936551 -279.280601) (xy 90.913425 -279.328622) (xy 90.883401 -279.372659)
			(xy 90.847149 -279.41173) (xy 90.805478 -279.444961) (xy 90.75932 -279.47161) (xy 90.709706 -279.491082)
			(xy 90.657744 -279.502942) (xy 90.604594 -279.506926) (xy 90.551444 -279.502942) (xy 90.499482 -279.491082)
			(xy 90.449868 -279.47161) (xy 90.40371 -279.444961) (xy 90.362039 -279.41173) (xy 90.325787 -279.372659)
			(xy 90.295763 -279.328622) (xy 90.272637 -279.280601) (xy 90.256927 -279.229671) (xy 90.248984 -279.176967)
			(xy 90.020404 -279.176967) (xy 90.012461 -279.229671) (xy 89.996751 -279.280601) (xy 89.973625 -279.328622)
			(xy 89.943601 -279.372659) (xy 89.907349 -279.41173) (xy 89.865678 -279.444961) (xy 89.81952 -279.47161)
			(xy 89.769906 -279.491082) (xy 89.717944 -279.502942) (xy 89.664794 -279.506926) (xy 89.611644 -279.502942)
			(xy 89.559682 -279.491082) (xy 89.510068 -279.47161) (xy 89.46391 -279.444961) (xy 89.422239 -279.41173)
			(xy 89.385987 -279.372659) (xy 89.355963 -279.328622) (xy 89.332837 -279.280601) (xy 89.317127 -279.229671)
			(xy 89.309184 -279.176967) (xy 89.080604 -279.176967) (xy 89.072661 -279.229671) (xy 89.056951 -279.280601)
			(xy 89.033825 -279.328622) (xy 89.003801 -279.372659) (xy 88.967549 -279.41173) (xy 88.925878 -279.444961)
			(xy 88.87972 -279.47161) (xy 88.830106 -279.491082) (xy 88.778144 -279.502942) (xy 88.724994 -279.506926)
			(xy 88.671844 -279.502942) (xy 88.619882 -279.491082) (xy 88.570268 -279.47161) (xy 88.52411 -279.444961)
			(xy 88.482439 -279.41173) (xy 88.446187 -279.372659) (xy 88.416163 -279.328622) (xy 88.393037 -279.280601)
			(xy 88.377327 -279.229671) (xy 88.369384 -279.176967) (xy 85.52688 -279.176967) (xy 85.52688 -279.990783)
			(xy 86.019884 -279.990783) (xy 86.019884 -279.937485) (xy 86.027827 -279.884781) (xy 86.043537 -279.833851)
			(xy 86.066663 -279.78583) (xy 86.096687 -279.741793) (xy 86.132939 -279.702722) (xy 86.17461 -279.669491)
			(xy 86.220768 -279.642842) (xy 86.270382 -279.62337) (xy 86.322344 -279.61151) (xy 86.375494 -279.607527)
			(xy 86.428644 -279.61151) (xy 86.480606 -279.62337) (xy 86.53022 -279.642842) (xy 86.576378 -279.669491)
			(xy 86.618049 -279.702722) (xy 86.654301 -279.741793) (xy 86.684325 -279.78583) (xy 86.707451 -279.833851)
			(xy 86.723161 -279.884781) (xy 86.731104 -279.937485) (xy 86.731602 -279.964134) (xy 86.731104 -279.990783)
			(xy 86.959684 -279.990783) (xy 86.959684 -279.937485) (xy 86.967627 -279.884781) (xy 86.983337 -279.833851)
			(xy 87.006463 -279.78583) (xy 87.036487 -279.741793) (xy 87.072739 -279.702722) (xy 87.11441 -279.669491)
			(xy 87.160568 -279.642842) (xy 87.210182 -279.62337) (xy 87.262144 -279.61151) (xy 87.315294 -279.607527)
			(xy 87.368444 -279.61151) (xy 87.420406 -279.62337) (xy 87.47002 -279.642842) (xy 87.516178 -279.669491)
			(xy 87.557849 -279.702722) (xy 87.594101 -279.741793) (xy 87.624125 -279.78583) (xy 87.647251 -279.833851)
			(xy 87.662961 -279.884781) (xy 87.670904 -279.937485) (xy 87.671402 -279.964134) (xy 87.670904 -279.990783)
			(xy 87.899484 -279.990783) (xy 87.899484 -279.937485) (xy 87.907427 -279.884781) (xy 87.923137 -279.833851)
			(xy 87.946263 -279.78583) (xy 87.976287 -279.741793) (xy 88.012539 -279.702722) (xy 88.05421 -279.669491)
			(xy 88.100368 -279.642842) (xy 88.149982 -279.62337) (xy 88.201944 -279.61151) (xy 88.255094 -279.607527)
			(xy 88.308244 -279.61151) (xy 88.360206 -279.62337) (xy 88.40982 -279.642842) (xy 88.455978 -279.669491)
			(xy 88.497649 -279.702722) (xy 88.533901 -279.741793) (xy 88.563925 -279.78583) (xy 88.587051 -279.833851)
			(xy 88.602761 -279.884781) (xy 88.610704 -279.937485) (xy 88.611201 -279.9641) (xy 88.838327 -279.9641)
			(xy 88.84231 -279.910956) (xy 88.854168 -279.858999) (xy 88.873638 -279.80939) (xy 88.900284 -279.763237)
			(xy 88.933512 -279.721571) (xy 88.972578 -279.685322) (xy 89.01661 -279.655301) (xy 89.064625 -279.632177)
			(xy 89.11555 -279.616468) (xy 89.168248 -279.608524) (xy 89.194894 -279.608026) (xy 89.21992 -279.608439)
			(xy 89.269478 -279.615447) (xy 89.317567 -279.629326) (xy 89.363238 -279.649802) (xy 89.405592 -279.676472)
			(xy 89.443794 -279.70881) (xy 89.477091 -279.746179) (xy 89.491312 -279.766776) (xy 89.838276 -279.766776)
			(xy 89.852514 -279.746192) (xy 89.885809 -279.708824) (xy 89.924008 -279.676486) (xy 89.966359 -279.649816)
			(xy 90.012028 -279.62934) (xy 90.060114 -279.61546) (xy 90.109669 -279.608451) (xy 90.134694 -279.608026)
			(xy 90.161348 -279.608431) (xy 90.214061 -279.616375) (xy 90.265 -279.632087) (xy 90.31303 -279.655216)
			(xy 90.357075 -279.685245) (xy 90.396153 -279.721503) (xy 90.42939 -279.763181) (xy 90.456044 -279.809347)
			(xy 90.47552 -279.85897) (xy 90.487382 -279.910941) (xy 90.491366 -279.9641) (xy 90.489366 -279.990783)
			(xy 91.658938 -279.990783) (xy 91.658938 -279.937485) (xy 91.666881 -279.884781) (xy 91.682591 -279.833851)
			(xy 91.705717 -279.78583) (xy 91.735741 -279.741793) (xy 91.771993 -279.702722) (xy 91.813664 -279.669491)
			(xy 91.859822 -279.642842) (xy 91.909436 -279.62337) (xy 91.961398 -279.61151) (xy 92.014548 -279.607527)
			(xy 92.067698 -279.61151) (xy 92.11966 -279.62337) (xy 92.169274 -279.642842) (xy 92.215432 -279.669491)
			(xy 92.257103 -279.702722) (xy 92.293355 -279.741793) (xy 92.323379 -279.78583) (xy 92.346505 -279.833851)
			(xy 92.362215 -279.884781) (xy 92.370158 -279.937485) (xy 92.370656 -279.964134) (xy 92.370158 -279.990783)
			(xy 92.598738 -279.990783) (xy 92.598738 -279.937485) (xy 92.606681 -279.884781) (xy 92.622391 -279.833851)
			(xy 92.645517 -279.78583) (xy 92.675541 -279.741793) (xy 92.711793 -279.702722) (xy 92.753464 -279.669491)
			(xy 92.799622 -279.642842) (xy 92.849236 -279.62337) (xy 92.901198 -279.61151) (xy 92.954348 -279.607527)
			(xy 93.007498 -279.61151) (xy 93.05946 -279.62337) (xy 93.109074 -279.642842) (xy 93.155232 -279.669491)
			(xy 93.196903 -279.702722) (xy 93.233155 -279.741793) (xy 93.263179 -279.78583) (xy 93.286305 -279.833851)
			(xy 93.302015 -279.884781) (xy 93.309958 -279.937485) (xy 93.310456 -279.964134) (xy 93.309958 -279.990783)
			(xy 94.478084 -279.990783) (xy 94.478084 -279.937485) (xy 94.486027 -279.884781) (xy 94.501737 -279.833851)
			(xy 94.524863 -279.78583) (xy 94.554887 -279.741793) (xy 94.591139 -279.702722) (xy 94.63281 -279.669491)
			(xy 94.678968 -279.642842) (xy 94.728582 -279.62337) (xy 94.780544 -279.61151) (xy 94.833694 -279.607527)
			(xy 94.886844 -279.61151) (xy 94.938806 -279.62337) (xy 94.98842 -279.642842) (xy 95.034578 -279.669491)
			(xy 95.076249 -279.702722) (xy 95.112501 -279.741793) (xy 95.142525 -279.78583) (xy 95.165651 -279.833851)
			(xy 95.181361 -279.884781) (xy 95.189304 -279.937485) (xy 95.189802 -279.964134) (xy 95.189304 -279.990783)
			(xy 95.418138 -279.990783) (xy 95.418138 -279.937485) (xy 95.426081 -279.884781) (xy 95.441791 -279.833851)
			(xy 95.464917 -279.78583) (xy 95.494941 -279.741793) (xy 95.531193 -279.702722) (xy 95.572864 -279.669491)
			(xy 95.619022 -279.642842) (xy 95.668636 -279.62337) (xy 95.720598 -279.61151) (xy 95.773748 -279.607527)
			(xy 95.826898 -279.61151) (xy 95.87886 -279.62337) (xy 95.928474 -279.642842) (xy 95.974632 -279.669491)
			(xy 96.016303 -279.702722) (xy 96.052555 -279.741793) (xy 96.082579 -279.78583) (xy 96.105705 -279.833851)
			(xy 96.121415 -279.884781) (xy 96.129358 -279.937485) (xy 96.129856 -279.964134) (xy 96.35744 -279.964134)
			(xy 96.357938 -279.937485) (xy 96.365881 -279.884781) (xy 96.381591 -279.833851) (xy 96.404717 -279.78583)
			(xy 96.434741 -279.741793) (xy 96.470993 -279.702722) (xy 96.512664 -279.669491) (xy 96.558822 -279.642842)
			(xy 96.608436 -279.62337) (xy 96.660398 -279.61151) (xy 96.713548 -279.607527) (xy 96.766698 -279.61151)
			(xy 96.81866 -279.62337) (xy 96.868274 -279.642842) (xy 96.914432 -279.669491) (xy 96.956103 -279.702722)
			(xy 96.992355 -279.741793) (xy 97.022379 -279.78583) (xy 97.045505 -279.833851) (xy 97.061215 -279.884781)
			(xy 97.069158 -279.937485) (xy 97.069656 -279.964134) (xy 97.069304 -279.987423) (xy 97.068866 -279.990783)
			(xy 97.297738 -279.990783) (xy 97.297738 -279.937485) (xy 97.305681 -279.884781) (xy 97.321391 -279.833851)
			(xy 97.344517 -279.78583) (xy 97.374541 -279.741793) (xy 97.410793 -279.702722) (xy 97.452464 -279.669491)
			(xy 97.498622 -279.642842) (xy 97.548236 -279.62337) (xy 97.600198 -279.61151) (xy 97.653348 -279.607527)
			(xy 97.706498 -279.61151) (xy 97.75846 -279.62337) (xy 97.808074 -279.642842) (xy 97.854232 -279.669491)
			(xy 97.895903 -279.702722) (xy 97.932155 -279.741793) (xy 97.962179 -279.78583) (xy 97.985305 -279.833851)
			(xy 98.001015 -279.884781) (xy 98.008958 -279.937485) (xy 98.009456 -279.964134) (xy 98.008958 -279.990783)
			(xy 98.237538 -279.990783) (xy 98.237538 -279.937485) (xy 98.245481 -279.884781) (xy 98.261191 -279.833851)
			(xy 98.284317 -279.78583) (xy 98.314341 -279.741793) (xy 98.350593 -279.702722) (xy 98.392264 -279.669491)
			(xy 98.438422 -279.642842) (xy 98.488036 -279.62337) (xy 98.539998 -279.61151) (xy 98.593148 -279.607527)
			(xy 98.646298 -279.61151) (xy 98.69826 -279.62337) (xy 98.747874 -279.642842) (xy 98.794032 -279.669491)
			(xy 98.835703 -279.702722) (xy 98.871955 -279.741793) (xy 98.901979 -279.78583) (xy 98.925105 -279.833851)
			(xy 98.940815 -279.884781) (xy 98.948758 -279.937485) (xy 98.949256 -279.964134) (xy 98.948758 -279.990783)
			(xy 100.117138 -279.990783) (xy 100.117138 -279.937485) (xy 100.125081 -279.884781) (xy 100.140791 -279.833851)
			(xy 100.163917 -279.78583) (xy 100.193941 -279.741793) (xy 100.230193 -279.702722) (xy 100.271864 -279.669491)
			(xy 100.318022 -279.642842) (xy 100.367636 -279.62337) (xy 100.419598 -279.61151) (xy 100.472748 -279.607527)
			(xy 100.525898 -279.61151) (xy 100.57786 -279.62337) (xy 100.627474 -279.642842) (xy 100.673632 -279.669491)
			(xy 100.715303 -279.702722) (xy 100.751555 -279.741793) (xy 100.781579 -279.78583) (xy 100.804705 -279.833851)
			(xy 100.820415 -279.884781) (xy 100.828358 -279.937485) (xy 100.828856 -279.964134) (xy 100.828358 -279.990783)
			(xy 101.056938 -279.990783) (xy 101.056938 -279.937485) (xy 101.064881 -279.884781) (xy 101.080591 -279.833851)
			(xy 101.103717 -279.78583) (xy 101.133741 -279.741793) (xy 101.169993 -279.702722) (xy 101.211664 -279.669491)
			(xy 101.257822 -279.642842) (xy 101.307436 -279.62337) (xy 101.359398 -279.61151) (xy 101.412548 -279.607527)
			(xy 101.465698 -279.61151) (xy 101.51766 -279.62337) (xy 101.567274 -279.642842) (xy 101.613432 -279.669491)
			(xy 101.655103 -279.702722) (xy 101.691355 -279.741793) (xy 101.721379 -279.78583) (xy 101.744505 -279.833851)
			(xy 101.760215 -279.884781) (xy 101.768158 -279.937485) (xy 101.768656 -279.964134) (xy 101.768158 -279.990783)
			(xy 101.760215 -280.043487) (xy 101.744505 -280.094417) (xy 101.721379 -280.142438) (xy 101.691355 -280.186475)
			(xy 101.655103 -280.225546) (xy 101.613432 -280.258777) (xy 101.567274 -280.285426) (xy 101.51766 -280.304898)
			(xy 101.465698 -280.316758) (xy 101.412548 -280.320742) (xy 101.359398 -280.316758) (xy 101.307436 -280.304898)
			(xy 101.257822 -280.285426) (xy 101.211664 -280.258777) (xy 101.169993 -280.225546) (xy 101.133741 -280.186475)
			(xy 101.103717 -280.142438) (xy 101.080591 -280.094417) (xy 101.064881 -280.043487) (xy 101.056938 -279.990783)
			(xy 100.828358 -279.990783) (xy 100.820415 -280.043487) (xy 100.804705 -280.094417) (xy 100.781579 -280.142438)
			(xy 100.751555 -280.186475) (xy 100.715303 -280.225546) (xy 100.673632 -280.258777) (xy 100.627474 -280.285426)
			(xy 100.57786 -280.304898) (xy 100.525898 -280.316758) (xy 100.472748 -280.320742) (xy 100.419598 -280.316758)
			(xy 100.367636 -280.304898) (xy 100.318022 -280.285426) (xy 100.271864 -280.258777) (xy 100.230193 -280.225546)
			(xy 100.193941 -280.186475) (xy 100.163917 -280.142438) (xy 100.140791 -280.094417) (xy 100.125081 -280.043487)
			(xy 100.117138 -279.990783) (xy 98.948758 -279.990783) (xy 98.940815 -280.043487) (xy 98.925105 -280.094417)
			(xy 98.901979 -280.142438) (xy 98.871955 -280.186475) (xy 98.835703 -280.225546) (xy 98.794032 -280.258777)
			(xy 98.747874 -280.285426) (xy 98.69826 -280.304898) (xy 98.646298 -280.316758) (xy 98.593148 -280.320742)
			(xy 98.539998 -280.316758) (xy 98.488036 -280.304898) (xy 98.438422 -280.285426) (xy 98.392264 -280.258777)
			(xy 98.350593 -280.225546) (xy 98.314341 -280.186475) (xy 98.284317 -280.142438) (xy 98.261191 -280.094417)
			(xy 98.245481 -280.043487) (xy 98.237538 -279.990783) (xy 98.008958 -279.990783) (xy 98.001015 -280.043487)
			(xy 97.985305 -280.094417) (xy 97.962179 -280.142438) (xy 97.932155 -280.186475) (xy 97.895903 -280.225546)
			(xy 97.854232 -280.258777) (xy 97.808074 -280.285426) (xy 97.75846 -280.304898) (xy 97.706498 -280.316758)
			(xy 97.653348 -280.320742) (xy 97.600198 -280.316758) (xy 97.548236 -280.304898) (xy 97.498622 -280.285426)
			(xy 97.452464 -280.258777) (xy 97.410793 -280.225546) (xy 97.374541 -280.186475) (xy 97.344517 -280.142438)
			(xy 97.321391 -280.094417) (xy 97.305681 -280.043487) (xy 97.297738 -279.990783) (xy 97.068866 -279.990783)
			(xy 97.063283 -280.033609) (xy 97.051282 -280.078613) (xy 97.042732 -280.100278) (xy 97.03308 -280.123392)
			(xy 97.205546 -280.421842) (xy 97.230184 -280.425144) (xy 97.255513 -280.429049) (xy 97.304814 -280.443031)
			(xy 97.351603 -280.463934) (xy 97.394914 -280.491325) (xy 97.433852 -280.524641) (xy 97.467614 -280.563193)
			(xy 97.495503 -280.606185) (xy 97.516944 -280.65273) (xy 97.531493 -280.701867) (xy 97.53885 -280.752581)
			(xy 97.539302 -280.778204) (xy 97.538804 -280.804853) (xy 97.530861 -280.857557) (xy 97.515151 -280.908487)
			(xy 97.492025 -280.956508) (xy 97.462001 -281.000545) (xy 97.425749 -281.039616) (xy 97.384078 -281.072847)
			(xy 97.33792 -281.099496) (xy 97.288306 -281.118968) (xy 97.236344 -281.130828) (xy 97.183194 -281.134812)
			(xy 97.130044 -281.130828) (xy 97.078082 -281.118968) (xy 97.028468 -281.099496) (xy 96.98231 -281.072847)
			(xy 96.940639 -281.039616) (xy 96.904387 -281.000545) (xy 96.874363 -280.956508) (xy 96.851237 -280.908487)
			(xy 96.835527 -280.857557) (xy 96.827584 -280.804853) (xy 96.827086 -280.778204) (xy 96.827457 -280.754959)
			(xy 96.833503 -280.708863) (xy 96.845493 -280.663946) (xy 96.85401 -280.642314) (xy 96.863662 -280.6192)
			(xy 96.690942 -280.320496) (xy 96.666304 -280.317194) (xy 96.640977 -280.313345) (xy 96.591703 -280.299328)
			(xy 96.544946 -280.278397) (xy 96.501668 -280.250986) (xy 96.462763 -280.217658) (xy 96.429033 -280.179101)
			(xy 96.401173 -280.136111) (xy 96.379758 -280.089573) (xy 96.365229 -280.040448) (xy 96.357887 -279.989748)
			(xy 96.35744 -279.964134) (xy 96.129856 -279.964134) (xy 96.129358 -279.990783) (xy 96.121415 -280.043487)
			(xy 96.105705 -280.094417) (xy 96.082579 -280.142438) (xy 96.052555 -280.186475) (xy 96.016303 -280.225546)
			(xy 95.974632 -280.258777) (xy 95.928474 -280.285426) (xy 95.87886 -280.304898) (xy 95.826898 -280.316758)
			(xy 95.773748 -280.320742) (xy 95.720598 -280.316758) (xy 95.668636 -280.304898) (xy 95.619022 -280.285426)
			(xy 95.572864 -280.258777) (xy 95.531193 -280.225546) (xy 95.494941 -280.186475) (xy 95.464917 -280.142438)
			(xy 95.441791 -280.094417) (xy 95.426081 -280.043487) (xy 95.418138 -279.990783) (xy 95.189304 -279.990783)
			(xy 95.181361 -280.043487) (xy 95.165651 -280.094417) (xy 95.142525 -280.142438) (xy 95.112501 -280.186475)
			(xy 95.076249 -280.225546) (xy 95.034578 -280.258777) (xy 94.98842 -280.285426) (xy 94.938806 -280.304898)
			(xy 94.886844 -280.316758) (xy 94.833694 -280.320742) (xy 94.780544 -280.316758) (xy 94.728582 -280.304898)
			(xy 94.678968 -280.285426) (xy 94.63281 -280.258777) (xy 94.591139 -280.225546) (xy 94.554887 -280.186475)
			(xy 94.524863 -280.142438) (xy 94.501737 -280.094417) (xy 94.486027 -280.043487) (xy 94.478084 -279.990783)
			(xy 93.309958 -279.990783) (xy 93.302015 -280.043487) (xy 93.286305 -280.094417) (xy 93.263179 -280.142438)
			(xy 93.233155 -280.186475) (xy 93.196903 -280.225546) (xy 93.155232 -280.258777) (xy 93.109074 -280.285426)
			(xy 93.05946 -280.304898) (xy 93.007498 -280.316758) (xy 92.954348 -280.320742) (xy 92.901198 -280.316758)
			(xy 92.849236 -280.304898) (xy 92.799622 -280.285426) (xy 92.753464 -280.258777) (xy 92.711793 -280.225546)
			(xy 92.675541 -280.186475) (xy 92.645517 -280.142438) (xy 92.622391 -280.094417) (xy 92.606681 -280.043487)
			(xy 92.598738 -279.990783) (xy 92.370158 -279.990783) (xy 92.362215 -280.043487) (xy 92.346505 -280.094417)
			(xy 92.323379 -280.142438) (xy 92.293355 -280.186475) (xy 92.257103 -280.225546) (xy 92.215432 -280.258777)
			(xy 92.169274 -280.285426) (xy 92.11966 -280.304898) (xy 92.067698 -280.316758) (xy 92.014548 -280.320742)
			(xy 91.961398 -280.316758) (xy 91.909436 -280.304898) (xy 91.859822 -280.285426) (xy 91.813664 -280.258777)
			(xy 91.771993 -280.225546) (xy 91.735741 -280.186475) (xy 91.705717 -280.142438) (xy 91.682591 -280.094417)
			(xy 91.666881 -280.043487) (xy 91.658938 -279.990783) (xy 90.489366 -279.990783) (xy 90.487382 -280.017259)
			(xy 90.47552 -280.06923) (xy 90.456044 -280.118853) (xy 90.42939 -280.165019) (xy 90.396153 -280.206697)
			(xy 90.357075 -280.242955) (xy 90.31303 -280.272984) (xy 90.265 -280.296113) (xy 90.214061 -280.311825)
			(xy 90.161348 -280.319769) (xy 90.134694 -280.320242) (xy 90.109669 -280.319809) (xy 90.060113 -280.3128)
			(xy 90.012026 -280.298923) (xy 89.966356 -280.278449) (xy 89.924002 -280.251783) (xy 89.885799 -280.21945)
			(xy 89.852499 -280.182086) (xy 89.838276 -280.161492) (xy 89.491312 -280.161492) (xy 89.477103 -280.182097)
			(xy 89.443801 -280.219461) (xy 89.405596 -280.251795) (xy 89.36324 -280.278461) (xy 89.317567 -280.298935)
			(xy 89.269478 -280.312811) (xy 89.21992 -280.319818) (xy 89.194894 -280.320242) (xy 89.168248 -280.319676)
			(xy 89.11555 -280.311732) (xy 89.064625 -280.296023) (xy 89.01661 -280.272899) (xy 88.972578 -280.242878)
			(xy 88.933512 -280.206629) (xy 88.900284 -280.164963) (xy 88.873638 -280.11881) (xy 88.854168 -280.069201)
			(xy 88.84231 -280.017244) (xy 88.838327 -279.9641) (xy 88.611201 -279.9641) (xy 88.611202 -279.964134)
			(xy 88.610704 -279.990783) (xy 88.602761 -280.043487) (xy 88.587051 -280.094417) (xy 88.563925 -280.142438)
			(xy 88.533901 -280.186475) (xy 88.497649 -280.225546) (xy 88.455978 -280.258777) (xy 88.40982 -280.285426)
			(xy 88.360206 -280.304898) (xy 88.308244 -280.316758) (xy 88.255094 -280.320742) (xy 88.201944 -280.316758)
			(xy 88.149982 -280.304898) (xy 88.100368 -280.285426) (xy 88.05421 -280.258777) (xy 88.012539 -280.225546)
			(xy 87.976287 -280.186475) (xy 87.946263 -280.142438) (xy 87.923137 -280.094417) (xy 87.907427 -280.043487)
			(xy 87.899484 -279.990783) (xy 87.670904 -279.990783) (xy 87.662961 -280.043487) (xy 87.647251 -280.094417)
			(xy 87.624125 -280.142438) (xy 87.594101 -280.186475) (xy 87.557849 -280.225546) (xy 87.516178 -280.258777)
			(xy 87.47002 -280.285426) (xy 87.420406 -280.304898) (xy 87.368444 -280.316758) (xy 87.315294 -280.320742)
			(xy 87.262144 -280.316758) (xy 87.210182 -280.304898) (xy 87.160568 -280.285426) (xy 87.11441 -280.258777)
			(xy 87.072739 -280.225546) (xy 87.036487 -280.186475) (xy 87.006463 -280.142438) (xy 86.983337 -280.094417)
			(xy 86.967627 -280.043487) (xy 86.959684 -279.990783) (xy 86.731104 -279.990783) (xy 86.723161 -280.043487)
			(xy 86.707451 -280.094417) (xy 86.684325 -280.142438) (xy 86.654301 -280.186475) (xy 86.618049 -280.225546)
			(xy 86.576378 -280.258777) (xy 86.53022 -280.285426) (xy 86.480606 -280.304898) (xy 86.428644 -280.316758)
			(xy 86.375494 -280.320742) (xy 86.322344 -280.316758) (xy 86.270382 -280.304898) (xy 86.220768 -280.285426)
			(xy 86.17461 -280.258777) (xy 86.132939 -280.225546) (xy 86.096687 -280.186475) (xy 86.066663 -280.142438)
			(xy 86.043537 -280.094417) (xy 86.027827 -280.043487) (xy 86.019884 -279.990783) (xy 85.52688 -279.990783)
			(xy 85.52688 -280.42997) (xy 85.527355 -280.444243) (xy 85.535247 -280.471677) (xy 85.550422 -280.495855)
			(xy 85.571695 -280.51489) (xy 85.597406 -280.527295) (xy 85.625544 -280.5321) (xy 85.653914 -280.52893)
			(xy 85.680299 -280.518034) (xy 85.691726 -280.509472) (xy 85.714695 -280.491965) (xy 85.765267 -280.464083)
			(xy 85.819786 -280.445042) (xy 85.87672 -280.435376) (xy 85.905594 -280.434796) (xy 85.931295 -280.435252)
			(xy 85.982122 -280.442912) (xy 86.03124 -280.458062) (xy 86.077551 -280.480364) (xy 86.120021 -280.509319)
			(xy 86.157702 -280.54428) (xy 86.18975 -280.584467) (xy 86.215451 -280.628982) (xy 86.23423 -280.67683)
			(xy 86.245668 -280.726942) (xy 86.24951 -280.7782) (xy 86.488796 -280.7782) (xy 86.492779 -280.725052)
			(xy 86.504639 -280.67309) (xy 86.524111 -280.623477) (xy 86.550759 -280.57732) (xy 86.583989 -280.53565)
			(xy 86.623059 -280.499398) (xy 86.667095 -280.469374) (xy 86.715114 -280.446249) (xy 86.766043 -280.430538)
			(xy 86.818745 -280.422594) (xy 86.845394 -280.422096) (xy 86.870407 -280.422545) (xy 86.919944 -280.429528)
			(xy 86.968016 -280.443373) (xy 87.013679 -280.463807) (xy 87.056035 -280.490427) (xy 87.094249 -280.522711)
			(xy 87.127572 -280.560023) (xy 87.141812 -280.580592) (xy 87.488776 -280.580592) (xy 87.502997 -280.56001)
			(xy 87.536329 -280.522703) (xy 87.574549 -280.490422) (xy 87.616907 -280.463802) (xy 87.662571 -280.443366)
			(xy 87.710643 -280.429514) (xy 87.76018 -280.422518) (xy 87.785194 -280.422096) (xy 87.811846 -280.422561)
			(xy 87.864554 -280.430504) (xy 87.915489 -280.446215) (xy 87.963515 -280.469342) (xy 88.007556 -280.499369)
			(xy 88.046631 -280.535624) (xy 88.079865 -280.577298) (xy 88.106517 -280.62346) (xy 88.125991 -280.673079)
			(xy 88.137853 -280.725046) (xy 88.141836 -280.7782) (xy 88.137853 -280.831354) (xy 88.125991 -280.883321)
			(xy 88.106517 -280.93294) (xy 88.079865 -280.979102) (xy 88.046631 -281.020776) (xy 88.007556 -281.057031)
			(xy 87.963515 -281.087058) (xy 87.915489 -281.110185) (xy 87.864554 -281.125896) (xy 87.811846 -281.133839)
			(xy 87.785194 -281.134312) (xy 87.760181 -281.133869) (xy 87.710644 -281.126884) (xy 87.662572 -281.113038)
			(xy 87.616909 -281.092603) (xy 87.574553 -281.065982) (xy 87.536339 -281.033698) (xy 87.503016 -280.996385)
			(xy 87.488776 -280.975816) (xy 87.141812 -280.975816) (xy 87.127601 -280.996405) (xy 87.094267 -281.033712)
			(xy 87.056045 -281.065992) (xy 87.013685 -281.092611) (xy 86.96802 -281.113046) (xy 86.919947 -281.126897)
			(xy 86.870409 -281.13389) (xy 86.845394 -281.134312) (xy 86.818745 -281.133806) (xy 86.766043 -281.125862)
			(xy 86.715114 -281.110151) (xy 86.667095 -281.087026) (xy 86.623059 -281.057002) (xy 86.583989 -281.02075)
			(xy 86.550759 -280.97908) (xy 86.524111 -280.932923) (xy 86.504639 -280.88331) (xy 86.492779 -280.831348)
			(xy 86.488796 -280.7782) (xy 86.24951 -280.7782) (xy 86.245668 -280.829458) (xy 86.23423 -280.87957)
			(xy 86.215451 -280.927418) (xy 86.18975 -280.971933) (xy 86.157702 -281.01212) (xy 86.120021 -281.047081)
			(xy 86.077551 -281.076036) (xy 86.03124 -281.098338) (xy 85.982122 -281.113488) (xy 85.931295 -281.121148)
			(xy 85.905594 -281.121612) (xy 85.87672 -281.121019) (xy 85.819787 -281.111362) (xy 85.765269 -281.092321)
			(xy 85.714703 -281.064432) (xy 85.691726 -281.046936) (xy 85.680266 -281.03843) (xy 85.653899 -281.02754)
			(xy 85.625547 -281.024372) (xy 85.597427 -281.029174) (xy 85.571734 -281.041571) (xy 85.550475 -281.060594)
			(xy 85.535311 -281.084758) (xy 85.527426 -281.112174) (xy 85.52688 -281.126438) (xy 85.52688 -281.618669)
			(xy 86.019884 -281.618669) (xy 86.019884 -281.565371) (xy 86.027827 -281.512667) (xy 86.043537 -281.461737)
			(xy 86.066663 -281.413716) (xy 86.096687 -281.369679) (xy 86.132939 -281.330608) (xy 86.17461 -281.297377)
			(xy 86.220768 -281.270728) (xy 86.270382 -281.251256) (xy 86.322344 -281.239396) (xy 86.375494 -281.235413)
			(xy 86.428644 -281.239396) (xy 86.480606 -281.251256) (xy 86.53022 -281.270728) (xy 86.576378 -281.297377)
			(xy 86.618049 -281.330608) (xy 86.654301 -281.369679) (xy 86.684325 -281.413716) (xy 86.707451 -281.461737)
			(xy 86.723161 -281.512667) (xy 86.731104 -281.565371) (xy 86.731602 -281.59202) (xy 86.731104 -281.618669)
			(xy 86.723161 -281.671373) (xy 86.707451 -281.722303) (xy 86.684325 -281.770324) (xy 86.654301 -281.814361)
			(xy 86.618049 -281.853432) (xy 86.576378 -281.886663) (xy 86.53022 -281.913312) (xy 86.480606 -281.932784)
			(xy 86.428644 -281.944644) (xy 86.375494 -281.948628) (xy 86.322344 -281.944644) (xy 86.270382 -281.932784)
			(xy 86.220768 -281.913312) (xy 86.17461 -281.886663) (xy 86.132939 -281.853432) (xy 86.096687 -281.814361)
			(xy 86.066663 -281.770324) (xy 86.043537 -281.722303) (xy 86.027827 -281.671373) (xy 86.019884 -281.618669)
			(xy 85.52688 -281.618669) (xy 85.52688 -282.0416) (xy 85.527328 -282.055736) (xy 85.535058 -282.082929)
			(xy 85.549952 -282.106957) (xy 85.570867 -282.125977) (xy 85.596199 -282.138528) (xy 85.624002 -282.143647)
			(xy 85.652142 -282.140942) (xy 85.67846 -282.130619) (xy 85.689948 -282.122372) (xy 85.713352 -282.105289)
			(xy 85.764541 -282.078146) (xy 85.819447 -282.059642) (xy 85.876624 -282.050266) (xy 85.905594 -282.049728)
			(xy 85.932243 -282.050201) (xy 85.984945 -282.058143) (xy 86.035875 -282.073852) (xy 86.083895 -282.096977)
			(xy 86.127931 -282.127) (xy 86.167001 -282.163251) (xy 86.200232 -282.20492) (xy 86.226881 -282.251077)
			(xy 86.246353 -282.30069) (xy 86.258213 -282.352652) (xy 86.262196 -282.4058) (xy 86.262193 -282.405836)
			(xy 86.48954 -282.405836) (xy 86.490004 -282.380208) (xy 86.497335 -282.32948) (xy 86.511864 -282.280327)
			(xy 86.533292 -282.233765) (xy 86.561175 -282.190758) (xy 86.594936 -282.152193) (xy 86.63388 -282.118868)
			(xy 86.677199 -282.091472) (xy 86.723999 -282.070571) (xy 86.773313 -282.056597) (xy 86.798658 -282.052776)
			(xy 86.823296 -282.049474) (xy 86.995762 -281.75077) (xy 86.986364 -281.727656) (xy 86.977868 -281.706062)
			(xy 86.965893 -281.661229) (xy 86.959833 -281.615222) (xy 86.95944 -281.59202) (xy 86.959938 -281.565371)
			(xy 86.967881 -281.512667) (xy 86.983591 -281.461737) (xy 87.006717 -281.413716) (xy 87.036741 -281.369679)
			(xy 87.072993 -281.330608) (xy 87.114664 -281.297377) (xy 87.160822 -281.270728) (xy 87.210436 -281.251256)
			(xy 87.262398 -281.239396) (xy 87.315548 -281.235413) (xy 87.368698 -281.239396) (xy 87.42066 -281.251256)
			(xy 87.470274 -281.270728) (xy 87.516432 -281.297377) (xy 87.558103 -281.330608) (xy 87.594355 -281.369679)
			(xy 87.624379 -281.413716) (xy 87.647505 -281.461737) (xy 87.663215 -281.512667) (xy 87.671158 -281.565371)
			(xy 87.671656 -281.59202) (xy 87.671247 -281.617649) (xy 87.671099 -281.618669) (xy 87.899484 -281.618669)
			(xy 87.899484 -281.565371) (xy 87.907427 -281.512667) (xy 87.923137 -281.461737) (xy 87.946263 -281.413716)
			(xy 87.976287 -281.369679) (xy 88.012539 -281.330608) (xy 88.05421 -281.297377) (xy 88.100368 -281.270728)
			(xy 88.149982 -281.251256) (xy 88.201944 -281.239396) (xy 88.255094 -281.235413) (xy 88.308244 -281.239396)
			(xy 88.360206 -281.251256) (xy 88.40982 -281.270728) (xy 88.455978 -281.297377) (xy 88.497649 -281.330608)
			(xy 88.533901 -281.369679) (xy 88.563925 -281.413716) (xy 88.587051 -281.461737) (xy 88.602761 -281.512667)
			(xy 88.610704 -281.565371) (xy 88.611202 -281.59202) (xy 88.83904 -281.59202) (xy 88.83949 -281.566392)
			(xy 88.846822 -281.515663) (xy 88.861354 -281.466509) (xy 88.882783 -281.419948) (xy 88.910668 -281.37694)
			(xy 88.944431 -281.338376) (xy 88.983376 -281.305051) (xy 89.026696 -281.277655) (xy 89.073498 -281.256755)
			(xy 89.122812 -281.242781) (xy 89.148158 -281.23896) (xy 89.17305 -281.235658) (xy 89.345262 -280.937462)
			(xy 89.33561 -280.914348) (xy 89.327087 -280.892674) (xy 89.315089 -280.847672) (xy 89.309051 -280.801491)
			(xy 89.308686 -280.778204) (xy 89.309184 -280.751555) (xy 89.317127 -280.698851) (xy 89.332837 -280.647921)
			(xy 89.355963 -280.5999) (xy 89.385987 -280.555863) (xy 89.422239 -280.516792) (xy 89.46391 -280.483561)
			(xy 89.510068 -280.456912) (xy 89.559682 -280.43744) (xy 89.611644 -280.42558) (xy 89.664794 -280.421597)
			(xy 89.717944 -280.42558) (xy 89.769906 -280.43744) (xy 89.81952 -280.456912) (xy 89.865678 -280.483561)
			(xy 89.907349 -280.516792) (xy 89.943601 -280.555863) (xy 89.973625 -280.5999) (xy 89.996751 -280.647921)
			(xy 90.012461 -280.698851) (xy 90.020404 -280.751555) (xy 90.020902 -280.778204) (xy 90.020467 -280.803822)
			(xy 90.020318 -280.804853) (xy 90.248984 -280.804853) (xy 90.248984 -280.751555) (xy 90.256927 -280.698851)
			(xy 90.272637 -280.647921) (xy 90.295763 -280.5999) (xy 90.325787 -280.555863) (xy 90.362039 -280.516792)
			(xy 90.40371 -280.483561) (xy 90.449868 -280.456912) (xy 90.499482 -280.43744) (xy 90.551444 -280.42558)
			(xy 90.604594 -280.421597) (xy 90.657744 -280.42558) (xy 90.709706 -280.43744) (xy 90.75932 -280.456912)
			(xy 90.805478 -280.483561) (xy 90.847149 -280.516792) (xy 90.883401 -280.555863) (xy 90.913425 -280.5999)
			(xy 90.936551 -280.647921) (xy 90.952261 -280.698851) (xy 90.960204 -280.751555) (xy 90.960702 -280.778204)
			(xy 92.12834 -280.778204) (xy 92.128838 -280.751555) (xy 92.136781 -280.698851) (xy 92.152491 -280.647921)
			(xy 92.175617 -280.5999) (xy 92.205641 -280.555863) (xy 92.241893 -280.516792) (xy 92.283564 -280.483561)
			(xy 92.329722 -280.456912) (xy 92.379336 -280.43744) (xy 92.431298 -280.42558) (xy 92.484448 -280.421597)
			(xy 92.537598 -280.42558) (xy 92.58956 -280.43744) (xy 92.639174 -280.456912) (xy 92.685332 -280.483561)
			(xy 92.727003 -280.516792) (xy 92.763255 -280.555863) (xy 92.793279 -280.5999) (xy 92.816405 -280.647921)
			(xy 92.832115 -280.698851) (xy 92.840058 -280.751555) (xy 92.840556 -280.778204) (xy 92.840226 -280.801494)
			(xy 92.839787 -280.804853) (xy 94.008438 -280.804853) (xy 94.008438 -280.751555) (xy 94.016381 -280.698851)
			(xy 94.032091 -280.647921) (xy 94.055217 -280.5999) (xy 94.085241 -280.555863) (xy 94.121493 -280.516792)
			(xy 94.163164 -280.483561) (xy 94.209322 -280.456912) (xy 94.258936 -280.43744) (xy 94.310898 -280.42558)
			(xy 94.364048 -280.421597) (xy 94.417198 -280.42558) (xy 94.46916 -280.43744) (xy 94.518774 -280.456912)
			(xy 94.564932 -280.483561) (xy 94.606603 -280.516792) (xy 94.642855 -280.555863) (xy 94.672879 -280.5999)
			(xy 94.696005 -280.647921) (xy 94.711715 -280.698851) (xy 94.719658 -280.751555) (xy 94.720156 -280.7782)
			(xy 94.946996 -280.7782) (xy 94.950979 -280.725052) (xy 94.962839 -280.67309) (xy 94.982311 -280.623477)
			(xy 95.008959 -280.57732) (xy 95.042189 -280.53565) (xy 95.081259 -280.499398) (xy 95.125295 -280.469374)
			(xy 95.173314 -280.446249) (xy 95.224243 -280.430538) (xy 95.276945 -280.422594) (xy 95.303594 -280.422096)
			(xy 95.328607 -280.422545) (xy 95.378144 -280.429528) (xy 95.426216 -280.443373) (xy 95.471879 -280.463807)
			(xy 95.514235 -280.490427) (xy 95.552449 -280.522711) (xy 95.585772 -280.560023) (xy 95.600012 -280.580592)
			(xy 95.94723 -280.580592) (xy 95.961481 -280.560031) (xy 95.994807 -280.522724) (xy 96.033023 -280.490442)
			(xy 96.075376 -280.463819) (xy 96.121034 -280.443379) (xy 96.169102 -280.429522) (xy 96.218635 -280.422522)
			(xy 96.243648 -280.422096) (xy 96.270295 -280.422589) (xy 96.322994 -280.430539) (xy 96.373919 -280.446253)
			(xy 96.421934 -280.469381) (xy 96.465965 -280.499407) (xy 96.50503 -280.535659) (xy 96.538257 -280.577329)
			(xy 96.564902 -280.623484) (xy 96.584371 -280.673096) (xy 96.596229 -280.725054) (xy 96.600212 -280.7782)
			(xy 96.596229 -280.831346) (xy 96.584371 -280.883304) (xy 96.564902 -280.932916) (xy 96.538257 -280.979071)
			(xy 96.50503 -281.020741) (xy 96.465965 -281.056993) (xy 96.421934 -281.087019) (xy 96.373919 -281.110147)
			(xy 96.322994 -281.125861) (xy 96.270295 -281.133811) (xy 96.243648 -281.134312) (xy 96.218633 -281.133904)
			(xy 96.169095 -281.126912) (xy 96.121022 -281.11306) (xy 96.075359 -281.09262) (xy 96.033004 -281.065994)
			(xy 95.99479 -281.033704) (xy 95.961469 -280.996387) (xy 95.94723 -280.975816) (xy 95.600012 -280.975816)
			(xy 95.585801 -280.996405) (xy 95.552467 -281.033712) (xy 95.514245 -281.065992) (xy 95.471885 -281.092611)
			(xy 95.42622 -281.113046) (xy 95.378147 -281.126897) (xy 95.328609 -281.13389) (xy 95.303594 -281.134312)
			(xy 95.276945 -281.133806) (xy 95.224243 -281.125862) (xy 95.173314 -281.110151) (xy 95.125295 -281.087026)
			(xy 95.081259 -281.057002) (xy 95.042189 -281.02075) (xy 95.008959 -280.97908) (xy 94.982311 -280.932923)
			(xy 94.962839 -280.88331) (xy 94.950979 -280.831348) (xy 94.946996 -280.7782) (xy 94.720156 -280.7782)
			(xy 94.720156 -280.778204) (xy 94.719658 -280.804853) (xy 94.711715 -280.857557) (xy 94.696005 -280.908487)
			(xy 94.672879 -280.956508) (xy 94.642855 -281.000545) (xy 94.606603 -281.039616) (xy 94.564932 -281.072847)
			(xy 94.518774 -281.099496) (xy 94.46916 -281.118968) (xy 94.417198 -281.130828) (xy 94.364048 -281.134812)
			(xy 94.310898 -281.130828) (xy 94.258936 -281.118968) (xy 94.209322 -281.099496) (xy 94.163164 -281.072847)
			(xy 94.121493 -281.039616) (xy 94.085241 -281.000545) (xy 94.055217 -280.956508) (xy 94.032091 -280.908487)
			(xy 94.016381 -280.857557) (xy 94.008438 -280.804853) (xy 92.839787 -280.804853) (xy 92.834196 -280.84768)
			(xy 92.822186 -280.892684) (xy 92.813632 -280.914348) (xy 92.80398 -280.937462) (xy 92.976192 -281.235658)
			(xy 93.001084 -281.23896) (xy 93.026416 -281.24285) (xy 93.075718 -281.256833) (xy 93.122508 -281.277736)
			(xy 93.165819 -281.305129) (xy 93.204758 -281.338447) (xy 93.23852 -281.377) (xy 93.266409 -281.419994)
			(xy 93.287848 -281.466541) (xy 93.302396 -281.51568) (xy 93.309751 -281.566397) (xy 93.310202 -281.59202)
			(xy 93.309704 -281.618669) (xy 93.301761 -281.671373) (xy 93.286051 -281.722303) (xy 93.262925 -281.770324)
			(xy 93.232901 -281.814361) (xy 93.196649 -281.853432) (xy 93.154978 -281.886663) (xy 93.10882 -281.913312)
			(xy 93.059206 -281.932784) (xy 93.007244 -281.944644) (xy 92.954094 -281.948628) (xy 92.900944 -281.944644)
			(xy 92.848982 -281.932784) (xy 92.799368 -281.913312) (xy 92.75321 -281.886663) (xy 92.711539 -281.853432)
			(xy 92.675287 -281.814361) (xy 92.645263 -281.770324) (xy 92.622137 -281.722303) (xy 92.606427 -281.671373)
			(xy 92.598484 -281.618669) (xy 92.597986 -281.59202) (xy 92.598374 -281.568817) (xy 92.604421 -281.522807)
			(xy 92.616402 -281.477974) (xy 92.62491 -281.456384) (xy 92.634308 -281.43327) (xy 92.461842 -281.134566)
			(xy 92.437204 -281.131264) (xy 92.411889 -281.127348) (xy 92.362621 -281.113334) (xy 92.315867 -281.092409)
			(xy 92.272593 -281.065004) (xy 92.233689 -281.031684) (xy 92.199958 -280.993135) (xy 92.172096 -280.950153)
			(xy 92.150677 -280.903624) (xy 92.136142 -280.854507) (xy 92.128792 -280.803815) (xy 92.12834 -280.778204)
			(xy 90.960702 -280.778204) (xy 90.960204 -280.804853) (xy 90.952261 -280.857557) (xy 90.936551 -280.908487)
			(xy 90.913425 -280.956508) (xy 90.883401 -281.000545) (xy 90.847149 -281.039616) (xy 90.805478 -281.072847)
			(xy 90.75932 -281.099496) (xy 90.709706 -281.118968) (xy 90.657744 -281.130828) (xy 90.604594 -281.134812)
			(xy 90.551444 -281.130828) (xy 90.499482 -281.118968) (xy 90.449868 -281.099496) (xy 90.40371 -281.072847)
			(xy 90.362039 -281.039616) (xy 90.325787 -281.000545) (xy 90.295763 -280.956508) (xy 90.272637 -280.908487)
			(xy 90.256927 -280.857557) (xy 90.248984 -280.804853) (xy 90.020318 -280.804853) (xy 90.01315 -280.854534)
			(xy 89.998638 -280.903672) (xy 89.977232 -280.950222) (xy 89.949374 -280.993223) (xy 89.915638 -281.031786)
			(xy 89.876723 -281.065114) (xy 89.833432 -281.092519) (xy 89.78666 -281.113435) (xy 89.737372 -281.12743)
			(xy 89.712038 -281.131264) (xy 89.6874 -281.134566) (xy 89.514934 -281.433016) (xy 89.524332 -281.45613)
			(xy 89.532852 -281.477761) (xy 89.544839 -281.522679) (xy 89.550882 -281.568775) (xy 89.551256 -281.59202)
			(xy 89.550758 -281.618669) (xy 89.779084 -281.618669) (xy 89.779084 -281.565371) (xy 89.787027 -281.512667)
			(xy 89.802737 -281.461737) (xy 89.825863 -281.413716) (xy 89.855887 -281.369679) (xy 89.892139 -281.330608)
			(xy 89.93381 -281.297377) (xy 89.979968 -281.270728) (xy 90.029582 -281.251256) (xy 90.081544 -281.239396)
			(xy 90.134694 -281.235413) (xy 90.187844 -281.239396) (xy 90.239806 -281.251256) (xy 90.28942 -281.270728)
			(xy 90.335578 -281.297377) (xy 90.377249 -281.330608) (xy 90.413501 -281.369679) (xy 90.443525 -281.413716)
			(xy 90.466651 -281.461737) (xy 90.482361 -281.512667) (xy 90.490304 -281.565371) (xy 90.490802 -281.592)
			(xy 90.717913 -281.592) (xy 90.721896 -281.538854) (xy 90.733755 -281.486895) (xy 90.753225 -281.437284)
			(xy 90.779873 -281.391129) (xy 90.813101 -281.349461) (xy 90.852169 -281.313211) (xy 90.896203 -281.283189)
			(xy 90.94422 -281.260064) (xy 90.995147 -281.244355) (xy 91.047847 -281.236411) (xy 91.074494 -281.235912)
			(xy 91.099508 -281.236354) (xy 91.149045 -281.243338) (xy 91.197118 -281.257183) (xy 91.242781 -281.277618)
			(xy 91.285136 -281.304239) (xy 91.323351 -281.336525) (xy 91.356673 -281.373839) (xy 91.370912 -281.394408)
			(xy 91.717876 -281.394408) (xy 91.732102 -281.37383) (xy 91.765433 -281.336522) (xy 91.803652 -281.30424)
			(xy 91.846009 -281.27762) (xy 91.891672 -281.257182) (xy 91.939744 -281.24333) (xy 91.98928 -281.236334)
			(xy 92.014294 -281.235912) (xy 92.040947 -281.236345) (xy 92.093658 -281.244289) (xy 92.144595 -281.26)
			(xy 92.192623 -281.283128) (xy 92.236666 -281.313156) (xy 92.275742 -281.349413) (xy 92.308978 -281.391089)
			(xy 92.335632 -281.437253) (xy 92.355107 -281.486874) (xy 92.366968 -281.538843) (xy 92.370952 -281.592)
			(xy 92.366968 -281.645157) (xy 92.355107 -281.697126) (xy 92.335632 -281.746747) (xy 92.308978 -281.792911)
			(xy 92.275742 -281.834587) (xy 92.236666 -281.870844) (xy 92.192623 -281.900872) (xy 92.144595 -281.924)
			(xy 92.093658 -281.939711) (xy 92.040947 -281.947655) (xy 92.014294 -281.948128) (xy 91.989279 -281.947722)
			(xy 91.939739 -281.940735) (xy 91.891664 -281.926885) (xy 91.846 -281.906446) (xy 91.803645 -281.879818)
			(xy 91.765432 -281.847526) (xy 91.732113 -281.810205) (xy 91.717876 -281.789632) (xy 91.370912 -281.789632)
			(xy 91.356706 -281.810225) (xy 91.323371 -281.847531) (xy 91.285148 -281.87981) (xy 91.242787 -281.906428)
			(xy 91.197121 -281.926863) (xy 91.149047 -281.940713) (xy 91.099509 -281.947706) (xy 91.074494 -281.948128)
			(xy 91.047847 -281.947589) (xy 90.995147 -281.939645) (xy 90.94422 -281.923936) (xy 90.896203 -281.900811)
			(xy 90.852169 -281.870789) (xy 90.813101 -281.834539) (xy 90.779873 -281.792871) (xy 90.753225 -281.746716)
			(xy 90.733755 -281.697105) (xy 90.721896 -281.645146) (xy 90.717913 -281.592) (xy 90.490802 -281.592)
			(xy 90.490802 -281.59202) (xy 90.490304 -281.618669) (xy 90.482361 -281.671373) (xy 90.466651 -281.722303)
			(xy 90.443525 -281.770324) (xy 90.413501 -281.814361) (xy 90.377249 -281.853432) (xy 90.335578 -281.886663)
			(xy 90.28942 -281.913312) (xy 90.239806 -281.932784) (xy 90.187844 -281.944644) (xy 90.134694 -281.948628)
			(xy 90.081544 -281.944644) (xy 90.029582 -281.932784) (xy 89.979968 -281.913312) (xy 89.93381 -281.886663)
			(xy 89.892139 -281.853432) (xy 89.855887 -281.814361) (xy 89.825863 -281.770324) (xy 89.802737 -281.722303)
			(xy 89.787027 -281.671373) (xy 89.779084 -281.618669) (xy 89.550758 -281.618669) (xy 89.542815 -281.671373)
			(xy 89.527105 -281.722303) (xy 89.503979 -281.770324) (xy 89.473955 -281.814361) (xy 89.437703 -281.853432)
			(xy 89.396032 -281.886663) (xy 89.349874 -281.913312) (xy 89.30026 -281.932784) (xy 89.248298 -281.944644)
			(xy 89.195148 -281.948628) (xy 89.141998 -281.944644) (xy 89.090036 -281.932784) (xy 89.040422 -281.913312)
			(xy 88.994264 -281.886663) (xy 88.952593 -281.853432) (xy 88.916341 -281.814361) (xy 88.886317 -281.770324)
			(xy 88.863191 -281.722303) (xy 88.847481 -281.671373) (xy 88.839538 -281.618669) (xy 88.83904 -281.59202)
			(xy 88.611202 -281.59202) (xy 88.610704 -281.618669) (xy 88.602761 -281.671373) (xy 88.587051 -281.722303)
			(xy 88.563925 -281.770324) (xy 88.533901 -281.814361) (xy 88.497649 -281.853432) (xy 88.455978 -281.886663)
			(xy 88.40982 -281.913312) (xy 88.360206 -281.932784) (xy 88.308244 -281.944644) (xy 88.255094 -281.948628)
			(xy 88.201944 -281.944644) (xy 88.149982 -281.932784) (xy 88.100368 -281.913312) (xy 88.05421 -281.886663)
			(xy 88.012539 -281.853432) (xy 87.976287 -281.814361) (xy 87.946263 -281.770324) (xy 87.923137 -281.722303)
			(xy 87.907427 -281.671373) (xy 87.899484 -281.618669) (xy 87.671099 -281.618669) (xy 87.663908 -281.66838)
			(xy 87.649372 -281.717535) (xy 87.627937 -281.764097) (xy 87.600048 -281.807104) (xy 87.56628 -281.845668)
			(xy 87.527331 -281.878992) (xy 87.484007 -281.906387) (xy 87.437203 -281.927287) (xy 87.387885 -281.941259)
			(xy 87.362538 -281.94508) (xy 87.3379 -281.948382) (xy 87.165434 -282.247086) (xy 87.174832 -282.2702)
			(xy 87.183315 -282.291799) (xy 87.195295 -282.336629) (xy 87.20136 -282.382635) (xy 87.201756 -282.405836)
			(xy 87.429086 -282.405836) (xy 87.429584 -282.379187) (xy 87.437527 -282.326483) (xy 87.453237 -282.275553)
			(xy 87.476363 -282.227532) (xy 87.506387 -282.183495) (xy 87.542639 -282.144424) (xy 87.58431 -282.111193)
			(xy 87.630468 -282.084544) (xy 87.680082 -282.065072) (xy 87.732044 -282.053212) (xy 87.785194 -282.049229)
			(xy 87.838344 -282.053212) (xy 87.890306 -282.065072) (xy 87.93992 -282.084544) (xy 87.986078 -282.111193)
			(xy 88.027749 -282.144424) (xy 88.064001 -282.183495) (xy 88.094025 -282.227532) (xy 88.117151 -282.275553)
			(xy 88.132861 -282.326483) (xy 88.140804 -282.379187) (xy 88.141301 -282.4058) (xy 88.368604 -282.4058)
			(xy 88.372588 -282.352648) (xy 88.384449 -282.300683) (xy 88.403924 -282.251066) (xy 88.430577 -282.204907)
			(xy 88.463812 -282.163236) (xy 88.502888 -282.126985) (xy 88.54693 -282.096963) (xy 88.594955 -282.073841)
			(xy 88.64589 -282.058135) (xy 88.698597 -282.050198) (xy 88.725248 -282.049728) (xy 88.750263 -282.050122)
			(xy 88.799803 -282.057113) (xy 88.847877 -282.070967) (xy 88.893541 -282.091409) (xy 88.935896 -282.118038)
			(xy 88.974109 -282.150331) (xy 89.007428 -282.187651) (xy 89.021666 -282.208224) (xy 89.36863 -282.208224)
			(xy 89.382891 -282.18767) (xy 89.416215 -282.150361) (xy 89.454428 -282.118078) (xy 89.496779 -282.091454)
			(xy 89.542436 -282.071012) (xy 89.590503 -282.057155) (xy 89.640036 -282.050154) (xy 89.665048 -282.049728)
			(xy 89.691698 -282.050157) (xy 89.744401 -282.058107) (xy 89.795331 -282.073823) (xy 89.84335 -282.096954)
			(xy 89.887385 -282.126982) (xy 89.926454 -282.163238) (xy 89.959683 -282.204911) (xy 89.986331 -282.251071)
			(xy 90.005802 -282.300686) (xy 90.017661 -282.35265) (xy 90.021644 -282.4058) (xy 90.019644 -282.432485)
			(xy 90.249238 -282.432485) (xy 90.249238 -282.379187) (xy 90.257181 -282.326483) (xy 90.272891 -282.275553)
			(xy 90.296017 -282.227532) (xy 90.326041 -282.183495) (xy 90.362293 -282.144424) (xy 90.403964 -282.111193)
			(xy 90.450122 -282.084544) (xy 90.499736 -282.065072) (xy 90.551698 -282.053212) (xy 90.604848 -282.049229)
			(xy 90.657998 -282.053212) (xy 90.70996 -282.065072) (xy 90.759574 -282.084544) (xy 90.805732 -282.111193)
			(xy 90.847403 -282.144424) (xy 90.883655 -282.183495) (xy 90.913679 -282.227532) (xy 90.936805 -282.275553)
			(xy 90.952515 -282.326483) (xy 90.960458 -282.379187) (xy 90.960956 -282.405836) (xy 90.960458 -282.432485)
			(xy 90.952515 -282.485189) (xy 90.936805 -282.536119) (xy 90.913679 -282.58414) (xy 90.883655 -282.628177)
			(xy 90.847403 -282.667248) (xy 90.805732 -282.700479) (xy 90.759574 -282.727128) (xy 90.70996 -282.7466)
			(xy 90.657998 -282.75846) (xy 90.604848 -282.762444) (xy 90.551698 -282.75846) (xy 90.499736 -282.7466)
			(xy 90.450122 -282.727128) (xy 90.403964 -282.700479) (xy 90.362293 -282.667248) (xy 90.326041 -282.628177)
			(xy 90.296017 -282.58414) (xy 90.272891 -282.536119) (xy 90.257181 -282.485189) (xy 90.249238 -282.432485)
			(xy 90.019644 -282.432485) (xy 90.017661 -282.45895) (xy 90.005802 -282.510914) (xy 89.986331 -282.560529)
			(xy 89.959683 -282.606689) (xy 89.926454 -282.648362) (xy 89.887385 -282.684618) (xy 89.84335 -282.714646)
			(xy 89.795331 -282.737777) (xy 89.744401 -282.753493) (xy 89.691698 -282.761443) (xy 89.665048 -282.761944)
			(xy 89.640032 -282.761566) (xy 89.590491 -282.754573) (xy 89.542416 -282.740718) (xy 89.496752 -282.720274)
			(xy 89.454397 -282.693642) (xy 89.416185 -282.661346) (xy 89.382867 -282.624022) (xy 89.36863 -282.603448)
			(xy 89.021666 -282.603448) (xy 89.007399 -282.623997) (xy 88.974077 -282.661307) (xy 88.935865 -282.693592)
			(xy 88.893515 -282.720217) (xy 88.847858 -282.740659) (xy 88.799792 -282.754517) (xy 88.75026 -282.761518)
			(xy 88.725248 -282.761944) (xy 88.698597 -282.761402) (xy 88.64589 -282.753465) (xy 88.594955 -282.737759)
			(xy 88.54693 -282.714637) (xy 88.502887 -282.684615) (xy 88.463812 -282.648364) (xy 88.430577 -282.606693)
			(xy 88.403924 -282.560534) (xy 88.384449 -282.510917) (xy 88.372588 -282.458952) (xy 88.368604 -282.4058)
			(xy 88.141301 -282.4058) (xy 88.141302 -282.405836) (xy 88.140912 -282.42908) (xy 88.134874 -282.475175)
			(xy 88.122892 -282.520094) (xy 88.114378 -282.541726) (xy 88.104726 -282.56484) (xy 88.277446 -282.863544)
			(xy 88.302084 -282.866846) (xy 88.327413 -282.87075) (xy 88.376715 -282.884731) (xy 88.423504 -282.905634)
			(xy 88.466815 -282.933026) (xy 88.505753 -282.966342) (xy 88.539515 -283.004894) (xy 88.567404 -283.047886)
			(xy 88.588844 -283.094431) (xy 88.603393 -283.143568) (xy 88.61075 -283.194283) (xy 88.611202 -283.219906)
			(xy 88.610704 -283.246555) (xy 88.839284 -283.246555) (xy 88.839284 -283.193257) (xy 88.847227 -283.140553)
			(xy 88.862937 -283.089623) (xy 88.886063 -283.041602) (xy 88.916087 -282.997565) (xy 88.952339 -282.958494)
			(xy 88.99401 -282.925263) (xy 89.040168 -282.898614) (xy 89.089782 -282.879142) (xy 89.141744 -282.867282)
			(xy 89.194894 -282.863299) (xy 89.248044 -282.867282) (xy 89.300006 -282.879142) (xy 89.34962 -282.898614)
			(xy 89.395778 -282.925263) (xy 89.437449 -282.958494) (xy 89.473701 -282.997565) (xy 89.503725 -283.041602)
			(xy 89.526851 -283.089623) (xy 89.542561 -283.140553) (xy 89.550504 -283.193257) (xy 89.551002 -283.219906)
			(xy 89.550504 -283.246555) (xy 89.779084 -283.246555) (xy 89.779084 -283.193257) (xy 89.787027 -283.140553)
			(xy 89.802737 -283.089623) (xy 89.825863 -283.041602) (xy 89.855887 -282.997565) (xy 89.892139 -282.958494)
			(xy 89.93381 -282.925263) (xy 89.979968 -282.898614) (xy 90.029582 -282.879142) (xy 90.081544 -282.867282)
			(xy 90.134694 -282.863299) (xy 90.187844 -282.867282) (xy 90.239806 -282.879142) (xy 90.28942 -282.898614)
			(xy 90.335578 -282.925263) (xy 90.377249 -282.958494) (xy 90.413501 -282.997565) (xy 90.443525 -283.041602)
			(xy 90.466651 -283.089623) (xy 90.482361 -283.140553) (xy 90.490304 -283.193257) (xy 90.490802 -283.219906)
			(xy 90.718386 -283.219906) (xy 90.718783 -283.194276) (xy 90.726119 -283.143542) (xy 90.740654 -283.094386)
			(xy 90.762089 -283.047822) (xy 90.789979 -283.004812) (xy 90.823749 -282.966247) (xy 90.8627 -282.932924)
			(xy 90.906027 -282.90553) (xy 90.952835 -282.884633) (xy 91.002156 -282.870664) (xy 91.027504 -282.866846)
			(xy 91.052396 -282.863544) (xy 91.224862 -282.564586) (xy 91.215464 -282.541472) (xy 91.206973 -282.519876)
			(xy 91.194996 -282.475044) (xy 91.188934 -282.429038) (xy 91.18854 -282.405836) (xy 91.189038 -282.379187)
			(xy 91.196981 -282.326483) (xy 91.212691 -282.275553) (xy 91.235817 -282.227532) (xy 91.265841 -282.183495)
			(xy 91.302093 -282.144424) (xy 91.343764 -282.111193) (xy 91.389922 -282.084544) (xy 91.439536 -282.065072)
			(xy 91.491498 -282.053212) (xy 91.544648 -282.049229) (xy 91.597798 -282.053212) (xy 91.64976 -282.065072)
			(xy 91.699374 -282.084544) (xy 91.745532 -282.111193) (xy 91.787203 -282.144424) (xy 91.823455 -282.183495)
			(xy 91.853479 -282.227532) (xy 91.876605 -282.275553) (xy 91.892315 -282.326483) (xy 91.900258 -282.379187)
			(xy 91.900756 -282.405836) (xy 91.900327 -282.431476) (xy 91.900181 -282.432485) (xy 92.128838 -282.432485)
			(xy 92.128838 -282.379187) (xy 92.136781 -282.326483) (xy 92.152491 -282.275553) (xy 92.175617 -282.227532)
			(xy 92.205641 -282.183495) (xy 92.241893 -282.144424) (xy 92.283564 -282.111193) (xy 92.329722 -282.084544)
			(xy 92.379336 -282.065072) (xy 92.431298 -282.053212) (xy 92.484448 -282.049229) (xy 92.537598 -282.053212)
			(xy 92.58956 -282.065072) (xy 92.639174 -282.084544) (xy 92.685332 -282.111193) (xy 92.727003 -282.144424)
			(xy 92.763255 -282.183495) (xy 92.793279 -282.227532) (xy 92.816405 -282.275553) (xy 92.832115 -282.326483)
			(xy 92.840058 -282.379187) (xy 92.840556 -282.405836) (xy 93.06814 -282.405836) (xy 93.068604 -282.380208)
			(xy 93.075935 -282.32948) (xy 93.090464 -282.280327) (xy 93.111892 -282.233765) (xy 93.139775 -282.190758)
			(xy 93.173536 -282.152193) (xy 93.21248 -282.118868) (xy 93.255799 -282.091472) (xy 93.302599 -282.070571)
			(xy 93.351913 -282.056597) (xy 93.377258 -282.052776) (xy 93.401896 -282.049474) (xy 93.574362 -281.751024)
			(xy 93.56471 -281.72791) (xy 93.556199 -281.706276) (xy 93.54421 -281.661359) (xy 93.538163 -281.615265)
			(xy 93.537786 -281.59202) (xy 93.538284 -281.565371) (xy 93.546227 -281.512667) (xy 93.561937 -281.461737)
			(xy 93.585063 -281.413716) (xy 93.615087 -281.369679) (xy 93.651339 -281.330608) (xy 93.69301 -281.297377)
			(xy 93.739168 -281.270728) (xy 93.788782 -281.251256) (xy 93.840744 -281.239396) (xy 93.893894 -281.235413)
			(xy 93.947044 -281.239396) (xy 93.999006 -281.251256) (xy 94.04862 -281.270728) (xy 94.094778 -281.297377)
			(xy 94.136449 -281.330608) (xy 94.172701 -281.369679) (xy 94.202725 -281.413716) (xy 94.225851 -281.461737)
			(xy 94.241561 -281.512667) (xy 94.249504 -281.565371) (xy 94.250002 -281.59202) (xy 94.249582 -281.617639)
			(xy 94.249433 -281.618669) (xy 94.478084 -281.618669) (xy 94.478084 -281.565371) (xy 94.486027 -281.512667)
			(xy 94.501737 -281.461737) (xy 94.524863 -281.413716) (xy 94.554887 -281.369679) (xy 94.591139 -281.330608)
			(xy 94.63281 -281.297377) (xy 94.678968 -281.270728) (xy 94.728582 -281.251256) (xy 94.780544 -281.239396)
			(xy 94.833694 -281.235413) (xy 94.886844 -281.239396) (xy 94.938806 -281.251256) (xy 94.98842 -281.270728)
			(xy 95.034578 -281.297377) (xy 95.076249 -281.330608) (xy 95.112501 -281.369679) (xy 95.142525 -281.413716)
			(xy 95.165651 -281.461737) (xy 95.181361 -281.512667) (xy 95.189304 -281.565371) (xy 95.189802 -281.59202)
			(xy 95.189304 -281.618669) (xy 95.181361 -281.671373) (xy 95.165651 -281.722303) (xy 95.142525 -281.770324)
			(xy 95.112501 -281.814361) (xy 95.076249 -281.853432) (xy 95.034578 -281.886663) (xy 94.98842 -281.913312)
			(xy 94.938806 -281.932784) (xy 94.886844 -281.944644) (xy 94.833694 -281.948628) (xy 94.780544 -281.944644)
			(xy 94.728582 -281.932784) (xy 94.678968 -281.913312) (xy 94.63281 -281.886663) (xy 94.591139 -281.853432)
			(xy 94.554887 -281.814361) (xy 94.524863 -281.770324) (xy 94.501737 -281.722303) (xy 94.486027 -281.671373)
			(xy 94.478084 -281.618669) (xy 94.249433 -281.618669) (xy 94.242262 -281.668351) (xy 94.227749 -281.717489)
			(xy 94.20634 -281.76404) (xy 94.17848 -281.80704) (xy 94.144744 -281.845603) (xy 94.105827 -281.878931)
			(xy 94.062535 -281.906336) (xy 94.015761 -281.927252) (xy 93.966472 -281.941246) (xy 93.941138 -281.94508)
			(xy 93.916246 -281.948382) (xy 93.74378 -282.246832) (xy 93.753432 -282.269946) (xy 93.761957 -282.291575)
			(xy 93.773942 -282.336494) (xy 93.779983 -282.382591) (xy 93.780356 -282.405836) (xy 93.779858 -282.432485)
			(xy 94.008438 -282.432485) (xy 94.008438 -282.379187) (xy 94.016381 -282.326483) (xy 94.032091 -282.275553)
			(xy 94.055217 -282.227532) (xy 94.085241 -282.183495) (xy 94.121493 -282.144424) (xy 94.163164 -282.111193)
			(xy 94.209322 -282.084544) (xy 94.258936 -282.065072) (xy 94.310898 -282.053212) (xy 94.364048 -282.049229)
			(xy 94.417198 -282.053212) (xy 94.46916 -282.065072) (xy 94.518774 -282.084544) (xy 94.564932 -282.111193)
			(xy 94.606603 -282.144424) (xy 94.642855 -282.183495) (xy 94.672879 -282.227532) (xy 94.696005 -282.275553)
			(xy 94.711715 -282.326483) (xy 94.719658 -282.379187) (xy 94.720156 -282.405836) (xy 94.947486 -282.405836)
			(xy 94.947911 -282.380206) (xy 94.955242 -282.329474) (xy 94.969774 -282.280318) (xy 94.991205 -282.233754)
			(xy 95.019092 -282.190745) (xy 95.052859 -282.15218) (xy 95.091807 -282.118855) (xy 95.135132 -282.091461)
			(xy 95.181938 -282.070564) (xy 95.231257 -282.056595) (xy 95.256604 -282.052776) (xy 95.281242 -282.049474)
			(xy 95.453962 -281.750516) (xy 95.44431 -281.727402) (xy 95.43584 -281.705851) (xy 95.423956 -281.661095)
			(xy 95.417989 -281.615174) (xy 95.41764 -281.59202) (xy 95.418138 -281.565371) (xy 95.426081 -281.512667)
			(xy 95.441791 -281.461737) (xy 95.464917 -281.413716) (xy 95.494941 -281.369679) (xy 95.531193 -281.330608)
			(xy 95.572864 -281.297377) (xy 95.619022 -281.270728) (xy 95.668636 -281.251256) (xy 95.720598 -281.239396)
			(xy 95.773748 -281.235413) (xy 95.826898 -281.239396) (xy 95.87886 -281.251256) (xy 95.928474 -281.270728)
			(xy 95.974632 -281.297377) (xy 96.016303 -281.330608) (xy 96.052555 -281.369679) (xy 96.082579 -281.413716)
			(xy 96.105705 -281.461737) (xy 96.121415 -281.512667) (xy 96.129358 -281.565371) (xy 96.129856 -281.59202)
			(xy 96.129412 -281.61766) (xy 96.129266 -281.618669) (xy 96.357938 -281.618669) (xy 96.357938 -281.565371)
			(xy 96.365881 -281.512667) (xy 96.381591 -281.461737) (xy 96.404717 -281.413716) (xy 96.434741 -281.369679)
			(xy 96.470993 -281.330608) (xy 96.512664 -281.297377) (xy 96.558822 -281.270728) (xy 96.608436 -281.251256)
			(xy 96.660398 -281.239396) (xy 96.713548 -281.235413) (xy 96.766698 -281.239396) (xy 96.81866 -281.251256)
			(xy 96.868274 -281.270728) (xy 96.914432 -281.297377) (xy 96.956103 -281.330608) (xy 96.992355 -281.369679)
			(xy 97.022379 -281.413716) (xy 97.045505 -281.461737) (xy 97.061215 -281.512667) (xy 97.069158 -281.565371)
			(xy 97.069656 -281.59202) (xy 97.29724 -281.59202) (xy 97.29769 -281.566392) (xy 97.305022 -281.515663)
			(xy 97.319554 -281.466509) (xy 97.340983 -281.419948) (xy 97.368868 -281.37694) (xy 97.402631 -281.338376)
			(xy 97.441576 -281.305051) (xy 97.484896 -281.277655) (xy 97.531698 -281.256755) (xy 97.581012 -281.242781)
			(xy 97.606358 -281.23896) (xy 97.630996 -281.235658) (xy 97.803462 -280.937208) (xy 97.79381 -280.914094)
			(xy 97.785294 -280.892462) (xy 97.773307 -280.847544) (xy 97.767262 -280.801449) (xy 97.766886 -280.778204)
			(xy 97.767384 -280.751555) (xy 97.775327 -280.698851) (xy 97.791037 -280.647921) (xy 97.814163 -280.5999)
			(xy 97.844187 -280.555863) (xy 97.880439 -280.516792) (xy 97.92211 -280.483561) (xy 97.968268 -280.456912)
			(xy 98.017882 -280.43744) (xy 98.069844 -280.42558) (xy 98.122994 -280.421597) (xy 98.176144 -280.42558)
			(xy 98.228106 -280.43744) (xy 98.27772 -280.456912) (xy 98.323878 -280.483561) (xy 98.365549 -280.516792)
			(xy 98.401801 -280.555863) (xy 98.431825 -280.5999) (xy 98.454951 -280.647921) (xy 98.470661 -280.698851)
			(xy 98.478604 -280.751555) (xy 98.479102 -280.778204) (xy 98.478667 -280.803822) (xy 98.478518 -280.804853)
			(xy 98.707184 -280.804853) (xy 98.707184 -280.751555) (xy 98.715127 -280.698851) (xy 98.730837 -280.647921)
			(xy 98.753963 -280.5999) (xy 98.783987 -280.555863) (xy 98.820239 -280.516792) (xy 98.86191 -280.483561)
			(xy 98.908068 -280.456912) (xy 98.957682 -280.43744) (xy 99.009644 -280.42558) (xy 99.062794 -280.421597)
			(xy 99.115944 -280.42558) (xy 99.167906 -280.43744) (xy 99.21752 -280.456912) (xy 99.263678 -280.483561)
			(xy 99.305349 -280.516792) (xy 99.341601 -280.555863) (xy 99.371625 -280.5999) (xy 99.394751 -280.647921)
			(xy 99.410461 -280.698851) (xy 99.418404 -280.751555) (xy 99.418902 -280.778204) (xy 100.586286 -280.778204)
			(xy 100.586784 -280.751555) (xy 100.594727 -280.698851) (xy 100.610437 -280.647921) (xy 100.633563 -280.5999)
			(xy 100.663587 -280.555863) (xy 100.699839 -280.516792) (xy 100.74151 -280.483561) (xy 100.787668 -280.456912)
			(xy 100.837282 -280.43744) (xy 100.889244 -280.42558) (xy 100.942394 -280.421597) (xy 100.995544 -280.42558)
			(xy 101.047506 -280.43744) (xy 101.09712 -280.456912) (xy 101.143278 -280.483561) (xy 101.184949 -280.516792)
			(xy 101.221201 -280.555863) (xy 101.251225 -280.5999) (xy 101.274351 -280.647921) (xy 101.290061 -280.698851)
			(xy 101.298004 -280.751555) (xy 101.298502 -280.778204) (xy 101.298132 -280.801355) (xy 101.297676 -280.804853)
			(xy 101.526584 -280.804853) (xy 101.526584 -280.751555) (xy 101.534527 -280.698851) (xy 101.550237 -280.647921)
			(xy 101.573363 -280.5999) (xy 101.603387 -280.555863) (xy 101.639639 -280.516792) (xy 101.68131 -280.483561)
			(xy 101.727468 -280.456912) (xy 101.777082 -280.43744) (xy 101.829044 -280.42558) (xy 101.882194 -280.421597)
			(xy 101.935344 -280.42558) (xy 101.987306 -280.43744) (xy 102.03692 -280.456912) (xy 102.083078 -280.483561)
			(xy 102.124749 -280.516792) (xy 102.161001 -280.555863) (xy 102.191025 -280.5999) (xy 102.214151 -280.647921)
			(xy 102.229861 -280.698851) (xy 102.237804 -280.751555) (xy 102.238302 -280.778204) (xy 102.237804 -280.804853)
			(xy 102.466638 -280.804853) (xy 102.466638 -280.751555) (xy 102.474581 -280.698851) (xy 102.490291 -280.647921)
			(xy 102.513417 -280.5999) (xy 102.543441 -280.555863) (xy 102.579693 -280.516792) (xy 102.621364 -280.483561)
			(xy 102.667522 -280.456912) (xy 102.717136 -280.43744) (xy 102.769098 -280.42558) (xy 102.822248 -280.421597)
			(xy 102.875398 -280.42558) (xy 102.92736 -280.43744) (xy 102.976974 -280.456912) (xy 103.023132 -280.483561)
			(xy 103.064803 -280.516792) (xy 103.101055 -280.555863) (xy 103.131079 -280.5999) (xy 103.154205 -280.647921)
			(xy 103.169915 -280.698851) (xy 103.177858 -280.751555) (xy 103.178356 -280.778204) (xy 103.405686 -280.778204)
			(xy 103.406184 -280.751555) (xy 103.414127 -280.698851) (xy 103.429837 -280.647921) (xy 103.452963 -280.5999)
			(xy 103.482987 -280.555863) (xy 103.519239 -280.516792) (xy 103.56091 -280.483561) (xy 103.607068 -280.456912)
			(xy 103.656682 -280.43744) (xy 103.708644 -280.42558) (xy 103.761794 -280.421597) (xy 103.814944 -280.42558)
			(xy 103.866906 -280.43744) (xy 103.91652 -280.456912) (xy 103.962678 -280.483561) (xy 104.004349 -280.516792)
			(xy 104.040601 -280.555863) (xy 104.070625 -280.5999) (xy 104.093751 -280.647921) (xy 104.109461 -280.698851)
			(xy 104.117404 -280.751555) (xy 104.117902 -280.778204) (xy 104.345486 -280.778204) (xy 104.345881 -280.752573)
			(xy 104.353217 -280.70184) (xy 104.367753 -280.652684) (xy 104.389188 -280.606119) (xy 104.417078 -280.56311)
			(xy 104.450848 -280.524545) (xy 104.489799 -280.491222) (xy 104.533127 -280.463828) (xy 104.579935 -280.442931)
			(xy 104.629256 -280.428962) (xy 104.654604 -280.425144) (xy 104.679242 -280.421842) (xy 104.851962 -280.122884)
			(xy 104.842564 -280.09977) (xy 104.834072 -280.078174) (xy 104.822095 -280.033342) (xy 104.816034 -279.987336)
			(xy 104.81564 -279.964134) (xy 104.816138 -279.937485) (xy 104.824081 -279.884781) (xy 104.839791 -279.833851)
			(xy 104.862917 -279.78583) (xy 104.892941 -279.741793) (xy 104.929193 -279.702722) (xy 104.970864 -279.669491)
			(xy 105.017022 -279.642842) (xy 105.066636 -279.62337) (xy 105.118598 -279.61151) (xy 105.171748 -279.607527)
			(xy 105.224898 -279.61151) (xy 105.27686 -279.62337) (xy 105.326474 -279.642842) (xy 105.372632 -279.669491)
			(xy 105.414303 -279.702722) (xy 105.450555 -279.741793) (xy 105.480579 -279.78583) (xy 105.503705 -279.833851)
			(xy 105.519415 -279.884781) (xy 105.527358 -279.937485) (xy 105.527856 -279.964134) (xy 105.527425 -279.989774)
			(xy 105.527279 -279.990783) (xy 105.755938 -279.990783) (xy 105.755938 -279.937485) (xy 105.763881 -279.884781)
			(xy 105.779591 -279.833851) (xy 105.802717 -279.78583) (xy 105.832741 -279.741793) (xy 105.868993 -279.702722)
			(xy 105.910664 -279.669491) (xy 105.956822 -279.642842) (xy 106.006436 -279.62337) (xy 106.058398 -279.61151)
			(xy 106.111548 -279.607527) (xy 106.164698 -279.61151) (xy 106.21666 -279.62337) (xy 106.266274 -279.642842)
			(xy 106.312432 -279.669491) (xy 106.354103 -279.702722) (xy 106.390355 -279.741793) (xy 106.420379 -279.78583)
			(xy 106.443505 -279.833851) (xy 106.459215 -279.884781) (xy 106.467158 -279.937485) (xy 106.467656 -279.964134)
			(xy 106.467158 -279.990783) (xy 106.459215 -280.043487) (xy 106.443505 -280.094417) (xy 106.420379 -280.142438)
			(xy 106.390355 -280.186475) (xy 106.354103 -280.225546) (xy 106.312432 -280.258777) (xy 106.266274 -280.285426)
			(xy 106.21666 -280.304898) (xy 106.164698 -280.316758) (xy 106.111548 -280.320742) (xy 106.058398 -280.316758)
			(xy 106.006436 -280.304898) (xy 105.956822 -280.285426) (xy 105.910664 -280.258777) (xy 105.868993 -280.225546)
			(xy 105.832741 -280.186475) (xy 105.802717 -280.142438) (xy 105.779591 -280.094417) (xy 105.763881 -280.043487)
			(xy 105.755938 -279.990783) (xy 105.527279 -279.990783) (xy 105.520078 -280.040525) (xy 105.505527 -280.089697)
			(xy 105.484073 -280.136273) (xy 105.456159 -280.17929) (xy 105.422362 -280.217857) (xy 105.383383 -280.251177)
			(xy 105.340027 -280.278561) (xy 105.293191 -280.299443) (xy 105.243844 -280.313389) (xy 105.218484 -280.317194)
			(xy 105.193846 -280.320496) (xy 105.021126 -280.6192) (xy 105.030778 -280.642314) (xy 105.039296 -280.663945)
			(xy 105.051282 -280.708864) (xy 105.057327 -280.754959) (xy 105.057702 -280.778204) (xy 105.057204 -280.804853)
			(xy 105.049261 -280.857557) (xy 105.033551 -280.908487) (xy 105.010425 -280.956508) (xy 104.980401 -281.000545)
			(xy 104.944149 -281.039616) (xy 104.902478 -281.072847) (xy 104.85632 -281.099496) (xy 104.806706 -281.118968)
			(xy 104.754744 -281.130828) (xy 104.701594 -281.134812) (xy 104.648444 -281.130828) (xy 104.596482 -281.118968)
			(xy 104.546868 -281.099496) (xy 104.50071 -281.072847) (xy 104.459039 -281.039616) (xy 104.422787 -281.000545)
			(xy 104.392763 -280.956508) (xy 104.369637 -280.908487) (xy 104.353927 -280.857557) (xy 104.345984 -280.804853)
			(xy 104.345486 -280.778204) (xy 104.117902 -280.778204) (xy 104.117532 -280.801355) (xy 104.111545 -280.84727)
			(xy 104.099672 -280.892024) (xy 104.091232 -280.913586) (xy 104.08158 -280.9367) (xy 104.2543 -281.235658)
			(xy 104.278938 -281.23896) (xy 104.304276 -281.242808) (xy 104.353579 -281.256797) (xy 104.400369 -281.277708)
			(xy 104.44368 -281.305107) (xy 104.482617 -281.338429) (xy 104.516378 -281.376987) (xy 104.544265 -281.419985)
			(xy 104.565703 -281.466535) (xy 104.58025 -281.515676) (xy 104.587605 -281.566395) (xy 104.588056 -281.59202)
			(xy 104.587558 -281.618669) (xy 104.816138 -281.618669) (xy 104.816138 -281.565371) (xy 104.824081 -281.512667)
			(xy 104.839791 -281.461737) (xy 104.862917 -281.413716) (xy 104.892941 -281.369679) (xy 104.929193 -281.330608)
			(xy 104.970864 -281.297377) (xy 105.017022 -281.270728) (xy 105.066636 -281.251256) (xy 105.118598 -281.239396)
			(xy 105.171748 -281.235413) (xy 105.224898 -281.239396) (xy 105.27686 -281.251256) (xy 105.326474 -281.270728)
			(xy 105.372632 -281.297377) (xy 105.414303 -281.330608) (xy 105.450555 -281.369679) (xy 105.480579 -281.413716)
			(xy 105.503705 -281.461737) (xy 105.519415 -281.512667) (xy 105.527358 -281.565371) (xy 105.527856 -281.59202)
			(xy 105.527358 -281.618669) (xy 105.519415 -281.671373) (xy 105.503705 -281.722303) (xy 105.480579 -281.770324)
			(xy 105.450555 -281.814361) (xy 105.414303 -281.853432) (xy 105.372632 -281.886663) (xy 105.326474 -281.913312)
			(xy 105.27686 -281.932784) (xy 105.224898 -281.944644) (xy 105.171748 -281.948628) (xy 105.118598 -281.944644)
			(xy 105.066636 -281.932784) (xy 105.017022 -281.913312) (xy 104.970864 -281.886663) (xy 104.929193 -281.853432)
			(xy 104.892941 -281.814361) (xy 104.862917 -281.770324) (xy 104.839791 -281.722303) (xy 104.824081 -281.671373)
			(xy 104.816138 -281.618669) (xy 104.587558 -281.618669) (xy 104.579615 -281.671373) (xy 104.563905 -281.722303)
			(xy 104.540779 -281.770324) (xy 104.510755 -281.814361) (xy 104.474503 -281.853432) (xy 104.432832 -281.886663)
			(xy 104.386674 -281.913312) (xy 104.33706 -281.932784) (xy 104.285098 -281.944644) (xy 104.231948 -281.948628)
			(xy 104.178798 -281.944644) (xy 104.126836 -281.932784) (xy 104.077222 -281.913312) (xy 104.031064 -281.886663)
			(xy 103.989393 -281.853432) (xy 103.953141 -281.814361) (xy 103.923117 -281.770324) (xy 103.899991 -281.722303)
			(xy 103.884281 -281.671373) (xy 103.876338 -281.618669) (xy 103.87584 -281.59202) (xy 103.876213 -281.568775)
			(xy 103.882257 -281.522679) (xy 103.894247 -281.477762) (xy 103.902764 -281.45613) (xy 103.912416 -281.433016)
			(xy 103.73995 -281.134566) (xy 103.715058 -281.131264) (xy 103.689692 -281.127505) (xy 103.640351 -281.113542)
			(xy 103.593522 -281.092647) (xy 103.550172 -281.065253) (xy 103.511199 -281.031927) (xy 103.477408 -280.993356)
			(xy 103.449496 -280.950339) (xy 103.428041 -280.903763) (xy 103.413486 -280.854593) (xy 103.406132 -280.803844)
			(xy 103.405686 -280.778204) (xy 103.178356 -280.778204) (xy 103.177858 -280.804853) (xy 103.169915 -280.857557)
			(xy 103.154205 -280.908487) (xy 103.131079 -280.956508) (xy 103.101055 -281.000545) (xy 103.064803 -281.039616)
			(xy 103.023132 -281.072847) (xy 102.976974 -281.099496) (xy 102.92736 -281.118968) (xy 102.875398 -281.130828)
			(xy 102.822248 -281.134812) (xy 102.769098 -281.130828) (xy 102.717136 -281.118968) (xy 102.667522 -281.099496)
			(xy 102.621364 -281.072847) (xy 102.579693 -281.039616) (xy 102.543441 -281.000545) (xy 102.513417 -280.956508)
			(xy 102.490291 -280.908487) (xy 102.474581 -280.857557) (xy 102.466638 -280.804853) (xy 102.237804 -280.804853)
			(xy 102.229861 -280.857557) (xy 102.214151 -280.908487) (xy 102.191025 -280.956508) (xy 102.161001 -281.000545)
			(xy 102.124749 -281.039616) (xy 102.083078 -281.072847) (xy 102.03692 -281.099496) (xy 101.987306 -281.118968)
			(xy 101.935344 -281.130828) (xy 101.882194 -281.134812) (xy 101.829044 -281.130828) (xy 101.777082 -281.118968)
			(xy 101.727468 -281.099496) (xy 101.68131 -281.072847) (xy 101.639639 -281.039616) (xy 101.603387 -281.000545)
			(xy 101.573363 -280.956508) (xy 101.550237 -280.908487) (xy 101.534527 -280.857557) (xy 101.526584 -280.804853)
			(xy 101.297676 -280.804853) (xy 101.292145 -280.84727) (xy 101.280272 -280.892024) (xy 101.271832 -280.913586)
			(xy 101.26218 -280.9367) (xy 101.4349 -281.235658) (xy 101.459538 -281.23896) (xy 101.484876 -281.242808)
			(xy 101.534179 -281.256797) (xy 101.580969 -281.277708) (xy 101.62428 -281.305107) (xy 101.663217 -281.338429)
			(xy 101.696978 -281.376987) (xy 101.724865 -281.419985) (xy 101.746303 -281.466535) (xy 101.76085 -281.515676)
			(xy 101.768205 -281.566395) (xy 101.768656 -281.59202) (xy 101.768158 -281.618669) (xy 101.760215 -281.671373)
			(xy 101.744505 -281.722303) (xy 101.721379 -281.770324) (xy 101.691355 -281.814361) (xy 101.655103 -281.853432)
			(xy 101.613432 -281.886663) (xy 101.567274 -281.913312) (xy 101.51766 -281.932784) (xy 101.465698 -281.944644)
			(xy 101.412548 -281.948628) (xy 101.359398 -281.944644) (xy 101.307436 -281.932784) (xy 101.257822 -281.913312)
			(xy 101.211664 -281.886663) (xy 101.169993 -281.853432) (xy 101.133741 -281.814361) (xy 101.103717 -281.770324)
			(xy 101.080591 -281.722303) (xy 101.064881 -281.671373) (xy 101.056938 -281.618669) (xy 101.05644 -281.59202)
			(xy 101.056813 -281.568775) (xy 101.062857 -281.522679) (xy 101.074847 -281.477762) (xy 101.083364 -281.45613)
			(xy 101.093016 -281.433016) (xy 100.92055 -281.134566) (xy 100.895658 -281.131264) (xy 100.870292 -281.127505)
			(xy 100.820951 -281.113542) (xy 100.774122 -281.092647) (xy 100.730772 -281.065253) (xy 100.691799 -281.031927)
			(xy 100.658008 -280.993356) (xy 100.630096 -280.950339) (xy 100.608641 -280.903763) (xy 100.594086 -280.854593)
			(xy 100.586732 -280.803844) (xy 100.586286 -280.778204) (xy 99.418902 -280.778204) (xy 99.418404 -280.804853)
			(xy 99.410461 -280.857557) (xy 99.394751 -280.908487) (xy 99.371625 -280.956508) (xy 99.341601 -281.000545)
			(xy 99.305349 -281.039616) (xy 99.263678 -281.072847) (xy 99.21752 -281.099496) (xy 99.167906 -281.118968)
			(xy 99.115944 -281.130828) (xy 99.062794 -281.134812) (xy 99.009644 -281.130828) (xy 98.957682 -281.118968)
			(xy 98.908068 -281.099496) (xy 98.86191 -281.072847) (xy 98.820239 -281.039616) (xy 98.783987 -281.000545)
			(xy 98.753963 -280.956508) (xy 98.730837 -280.908487) (xy 98.715127 -280.857557) (xy 98.707184 -280.804853)
			(xy 98.478518 -280.804853) (xy 98.47135 -280.854534) (xy 98.456838 -280.903672) (xy 98.435432 -280.950222)
			(xy 98.407574 -280.993223) (xy 98.373838 -281.031786) (xy 98.334923 -281.065114) (xy 98.291632 -281.092519)
			(xy 98.24486 -281.113435) (xy 98.195572 -281.12743) (xy 98.170238 -281.131264) (xy 98.145346 -281.134566)
			(xy 97.97288 -281.433016) (xy 97.982532 -281.45613) (xy 97.991052 -281.477761) (xy 98.003039 -281.522679)
			(xy 98.009082 -281.568775) (xy 98.009456 -281.59202) (xy 98.008958 -281.618669) (xy 98.237538 -281.618669)
			(xy 98.237538 -281.565371) (xy 98.245481 -281.512667) (xy 98.261191 -281.461737) (xy 98.284317 -281.413716)
			(xy 98.314341 -281.369679) (xy 98.350593 -281.330608) (xy 98.392264 -281.297377) (xy 98.438422 -281.270728)
			(xy 98.488036 -281.251256) (xy 98.539998 -281.239396) (xy 98.593148 -281.235413) (xy 98.646298 -281.239396)
			(xy 98.69826 -281.251256) (xy 98.747874 -281.270728) (xy 98.794032 -281.297377) (xy 98.835703 -281.330608)
			(xy 98.871955 -281.369679) (xy 98.901979 -281.413716) (xy 98.925105 -281.461737) (xy 98.940815 -281.512667)
			(xy 98.948758 -281.565371) (xy 98.949256 -281.592) (xy 99.176288 -281.592) (xy 99.180272 -281.538845)
			(xy 99.192134 -281.486878) (xy 99.21161 -281.437259) (xy 99.238264 -281.391098) (xy 99.2715 -281.349425)
			(xy 99.310578 -281.313172) (xy 99.354622 -281.283149) (xy 99.402649 -281.260026) (xy 99.453587 -281.24432)
			(xy 99.506296 -281.236382) (xy 99.532948 -281.235912) (xy 99.557963 -281.236313) (xy 99.607502 -281.243304)
			(xy 99.655576 -281.257157) (xy 99.701239 -281.277598) (xy 99.743594 -281.304226) (xy 99.781807 -281.336517)
			(xy 99.815128 -281.373836) (xy 99.829366 -281.394408) (xy 100.17633 -281.394408) (xy 100.190586 -281.373851)
			(xy 100.223911 -281.336543) (xy 100.262125 -281.30426) (xy 100.304477 -281.277636) (xy 100.350135 -281.257195)
			(xy 100.398203 -281.243338) (xy 100.447736 -281.236338) (xy 100.472748 -281.235912) (xy 100.499396 -281.236373)
			(xy 100.552097 -281.244323) (xy 100.603025 -281.260038) (xy 100.651042 -281.283168) (xy 100.695075 -281.313195)
			(xy 100.734142 -281.349448) (xy 100.76737 -281.39112) (xy 100.794016 -281.437278) (xy 100.813486 -281.486891)
			(xy 100.825345 -281.538852) (xy 100.829328 -281.592) (xy 100.825345 -281.645148) (xy 100.813486 -281.697109)
			(xy 100.794016 -281.746723) (xy 100.76737 -281.79288) (xy 100.734142 -281.834552) (xy 100.695075 -281.870805)
			(xy 100.651042 -281.900832) (xy 100.603025 -281.923962) (xy 100.552097 -281.939677) (xy 100.499396 -281.947627)
			(xy 100.472748 -281.948128) (xy 100.447732 -281.947757) (xy 100.39819 -281.940764) (xy 100.350115 -281.926908)
			(xy 100.30445 -281.906463) (xy 100.262096 -281.879829) (xy 100.223884 -281.847532) (xy 100.190566 -281.810207)
			(xy 100.17633 -281.789632) (xy 99.829366 -281.789632) (xy 99.815126 -281.8102) (xy 99.781796 -281.847506)
			(xy 99.743579 -281.879787) (xy 99.701224 -281.906408) (xy 99.655564 -281.926847) (xy 99.607495 -281.940703)
			(xy 99.557961 -281.947703) (xy 99.532948 -281.948128) (xy 99.506296 -281.947618) (xy 99.453587 -281.93968)
			(xy 99.402649 -281.923974) (xy 99.354622 -281.900851) (xy 99.310578 -281.870828) (xy 99.2715 -281.834575)
			(xy 99.238264 -281.792902) (xy 99.21161 -281.746741) (xy 99.192134 -281.697122) (xy 99.180272 -281.645155)
			(xy 99.176288 -281.592) (xy 98.949256 -281.592) (xy 98.949256 -281.59202) (xy 98.948758 -281.618669)
			(xy 98.940815 -281.671373) (xy 98.925105 -281.722303) (xy 98.901979 -281.770324) (xy 98.871955 -281.814361)
			(xy 98.835703 -281.853432) (xy 98.794032 -281.886663) (xy 98.747874 -281.913312) (xy 98.69826 -281.932784)
			(xy 98.646298 -281.944644) (xy 98.593148 -281.948628) (xy 98.539998 -281.944644) (xy 98.488036 -281.932784)
			(xy 98.438422 -281.913312) (xy 98.392264 -281.886663) (xy 98.350593 -281.853432) (xy 98.314341 -281.814361)
			(xy 98.284317 -281.770324) (xy 98.261191 -281.722303) (xy 98.245481 -281.671373) (xy 98.237538 -281.618669)
			(xy 98.008958 -281.618669) (xy 98.001015 -281.671373) (xy 97.985305 -281.722303) (xy 97.962179 -281.770324)
			(xy 97.932155 -281.814361) (xy 97.895903 -281.853432) (xy 97.854232 -281.886663) (xy 97.808074 -281.913312)
			(xy 97.75846 -281.932784) (xy 97.706498 -281.944644) (xy 97.653348 -281.948628) (xy 97.600198 -281.944644)
			(xy 97.548236 -281.932784) (xy 97.498622 -281.913312) (xy 97.452464 -281.886663) (xy 97.410793 -281.853432)
			(xy 97.374541 -281.814361) (xy 97.344517 -281.770324) (xy 97.321391 -281.722303) (xy 97.305681 -281.671373)
			(xy 97.297738 -281.618669) (xy 97.29724 -281.59202) (xy 97.069656 -281.59202) (xy 97.069158 -281.618669)
			(xy 97.061215 -281.671373) (xy 97.045505 -281.722303) (xy 97.022379 -281.770324) (xy 96.992355 -281.814361)
			(xy 96.956103 -281.853432) (xy 96.914432 -281.886663) (xy 96.868274 -281.913312) (xy 96.81866 -281.932784)
			(xy 96.766698 -281.944644) (xy 96.713548 -281.948628) (xy 96.660398 -281.944644) (xy 96.608436 -281.932784)
			(xy 96.558822 -281.913312) (xy 96.512664 -281.886663) (xy 96.470993 -281.853432) (xy 96.434741 -281.814361)
			(xy 96.404717 -281.770324) (xy 96.381591 -281.722303) (xy 96.365881 -281.671373) (xy 96.357938 -281.618669)
			(xy 96.129266 -281.618669) (xy 96.122067 -281.66841) (xy 96.107518 -281.717582) (xy 96.086065 -281.764158)
			(xy 96.058153 -281.807175) (xy 96.024358 -281.845742) (xy 95.98538 -281.879063) (xy 95.942025 -281.906447)
			(xy 95.89519 -281.927328) (xy 95.845844 -281.941275) (xy 95.820484 -281.94508) (xy 95.795592 -281.948382)
			(xy 95.623126 -282.246832) (xy 95.632778 -282.269946) (xy 95.641305 -282.291574) (xy 95.653288 -282.336494)
			(xy 95.659329 -282.382591) (xy 95.659702 -282.405836) (xy 95.887286 -282.405836) (xy 95.887784 -282.379187)
			(xy 95.895727 -282.326483) (xy 95.911437 -282.275553) (xy 95.934563 -282.227532) (xy 95.964587 -282.183495)
			(xy 96.000839 -282.144424) (xy 96.04251 -282.111193) (xy 96.088668 -282.084544) (xy 96.138282 -282.065072)
			(xy 96.190244 -282.053212) (xy 96.243394 -282.049229) (xy 96.296544 -282.053212) (xy 96.348506 -282.065072)
			(xy 96.39812 -282.084544) (xy 96.444278 -282.111193) (xy 96.485949 -282.144424) (xy 96.522201 -282.183495)
			(xy 96.552225 -282.227532) (xy 96.575351 -282.275553) (xy 96.591061 -282.326483) (xy 96.599004 -282.379187)
			(xy 96.599501 -282.4058) (xy 96.826629 -282.4058) (xy 96.830612 -282.352656) (xy 96.84247 -282.3007)
			(xy 96.86194 -282.251091) (xy 96.888586 -282.204938) (xy 96.921813 -282.163272) (xy 96.960879 -282.127024)
			(xy 97.004911 -282.097002) (xy 97.052926 -282.073879) (xy 97.10385 -282.05817) (xy 97.156548 -282.050226)
			(xy 97.183194 -282.049728) (xy 97.208208 -282.050163) (xy 97.257746 -282.057147) (xy 97.305819 -282.070993)
			(xy 97.351482 -282.091429) (xy 97.393838 -282.118051) (xy 97.432052 -282.150338) (xy 97.465374 -282.187654)
			(xy 97.479612 -282.208224) (xy 97.826576 -282.208224) (xy 97.840807 -282.187649) (xy 97.874136 -282.15034)
			(xy 97.912354 -282.118058) (xy 97.954711 -282.091437) (xy 98.000373 -282.070999) (xy 98.048444 -282.057146)
			(xy 98.09798 -282.05015) (xy 98.122994 -282.049728) (xy 98.149648 -282.050129) (xy 98.202361 -282.058073)
			(xy 98.253301 -282.073785) (xy 98.301331 -282.096914) (xy 98.345376 -282.126944) (xy 98.384454 -282.163202)
			(xy 98.417692 -282.20488) (xy 98.444346 -282.251046) (xy 98.463822 -282.300669) (xy 98.475684 -282.352641)
			(xy 98.479668 -282.4058) (xy 98.477668 -282.432485) (xy 98.707184 -282.432485) (xy 98.707184 -282.379187)
			(xy 98.715127 -282.326483) (xy 98.730837 -282.275553) (xy 98.753963 -282.227532) (xy 98.783987 -282.183495)
			(xy 98.820239 -282.144424) (xy 98.86191 -282.111193) (xy 98.908068 -282.084544) (xy 98.957682 -282.065072)
			(xy 99.009644 -282.053212) (xy 99.062794 -282.049229) (xy 99.115944 -282.053212) (xy 99.167906 -282.065072)
			(xy 99.21752 -282.084544) (xy 99.263678 -282.111193) (xy 99.305349 -282.144424) (xy 99.341601 -282.183495)
			(xy 99.371625 -282.227532) (xy 99.394751 -282.275553) (xy 99.410461 -282.326483) (xy 99.418404 -282.379187)
			(xy 99.418902 -282.405836) (xy 99.418404 -282.432485) (xy 99.410461 -282.485189) (xy 99.394751 -282.536119)
			(xy 99.371625 -282.58414) (xy 99.341601 -282.628177) (xy 99.305349 -282.667248) (xy 99.263678 -282.700479)
			(xy 99.21752 -282.727128) (xy 99.167906 -282.7466) (xy 99.115944 -282.75846) (xy 99.062794 -282.762444)
			(xy 99.009644 -282.75846) (xy 98.957682 -282.7466) (xy 98.908068 -282.727128) (xy 98.86191 -282.700479)
			(xy 98.820239 -282.667248) (xy 98.783987 -282.628177) (xy 98.753963 -282.58414) (xy 98.730837 -282.536119)
			(xy 98.715127 -282.485189) (xy 98.707184 -282.432485) (xy 98.477668 -282.432485) (xy 98.475684 -282.458959)
			(xy 98.463822 -282.510931) (xy 98.444346 -282.560554) (xy 98.417692 -282.60672) (xy 98.384454 -282.648398)
			(xy 98.345376 -282.684656) (xy 98.301331 -282.714686) (xy 98.253301 -282.737815) (xy 98.202361 -282.753527)
			(xy 98.149648 -282.761471) (xy 98.122994 -282.761944) (xy 98.097979 -282.761531) (xy 98.04844 -282.754544)
			(xy 98.000366 -282.740695) (xy 97.954702 -282.720257) (xy 97.912346 -282.69363) (xy 97.874133 -282.66134)
			(xy 97.840813 -282.62402) (xy 97.826576 -282.603448) (xy 97.479612 -282.603448) (xy 97.465379 -282.624022)
			(xy 97.432051 -282.661332) (xy 97.393834 -282.693615) (xy 97.351478 -282.720237) (xy 97.305816 -282.740675)
			(xy 97.257744 -282.754527) (xy 97.208208 -282.761522) (xy 97.183194 -282.761944) (xy 97.156548 -282.761374)
			(xy 97.10385 -282.75343) (xy 97.052926 -282.737721) (xy 97.004911 -282.714598) (xy 96.960879 -282.684576)
			(xy 96.921813 -282.648328) (xy 96.888586 -282.606662) (xy 96.86194 -282.560509) (xy 96.84247 -282.5109)
			(xy 96.830612 -282.458944) (xy 96.826629 -282.4058) (xy 96.599501 -282.4058) (xy 96.599502 -282.405836)
			(xy 96.599132 -282.42904) (xy 96.593078 -282.47505) (xy 96.58109 -282.519883) (xy 96.572578 -282.541472)
			(xy 96.56318 -282.564586) (xy 96.7359 -282.863544) (xy 96.760538 -282.866846) (xy 96.785874 -282.870707)
			(xy 96.835176 -282.884696) (xy 96.881965 -282.905605) (xy 96.925275 -282.933003) (xy 96.964212 -282.966324)
			(xy 96.997973 -283.00488) (xy 97.02586 -283.047876) (xy 97.0473 -283.094425) (xy 97.061848 -283.143565)
			(xy 97.069204 -283.194282) (xy 97.069656 -283.219906) (xy 97.069158 -283.246555) (xy 97.297484 -283.246555)
			(xy 97.297484 -283.193257) (xy 97.305427 -283.140553) (xy 97.321137 -283.089623) (xy 97.344263 -283.041602)
			(xy 97.374287 -282.997565) (xy 97.410539 -282.958494) (xy 97.45221 -282.925263) (xy 97.498368 -282.898614)
			(xy 97.547982 -282.879142) (xy 97.599944 -282.867282) (xy 97.653094 -282.863299) (xy 97.706244 -282.867282)
			(xy 97.758206 -282.879142) (xy 97.80782 -282.898614) (xy 97.853978 -282.925263) (xy 97.895649 -282.958494)
			(xy 97.931901 -282.997565) (xy 97.961925 -283.041602) (xy 97.985051 -283.089623) (xy 98.000761 -283.140553)
			(xy 98.008704 -283.193257) (xy 98.009202 -283.219906) (xy 98.008704 -283.246555) (xy 98.237284 -283.246555)
			(xy 98.237284 -283.193257) (xy 98.245227 -283.140553) (xy 98.260937 -283.089623) (xy 98.284063 -283.041602)
			(xy 98.314087 -282.997565) (xy 98.350339 -282.958494) (xy 98.39201 -282.925263) (xy 98.438168 -282.898614)
			(xy 98.487782 -282.879142) (xy 98.539744 -282.867282) (xy 98.592894 -282.863299) (xy 98.646044 -282.867282)
			(xy 98.698006 -282.879142) (xy 98.74762 -282.898614) (xy 98.793778 -282.925263) (xy 98.835449 -282.958494)
			(xy 98.871701 -282.997565) (xy 98.901725 -283.041602) (xy 98.924851 -283.089623) (xy 98.940561 -283.140553)
			(xy 98.948504 -283.193257) (xy 98.949002 -283.219906) (xy 99.17684 -283.219906) (xy 99.177277 -283.194277)
			(xy 99.184611 -283.143548) (xy 99.199145 -283.094394) (xy 99.220576 -283.047833) (xy 99.248462 -283.004825)
			(xy 99.282227 -282.966261) (xy 99.321172 -282.932936) (xy 99.364494 -282.905541) (xy 99.411296 -282.884641)
			(xy 99.460612 -282.870667) (xy 99.485958 -282.866846) (xy 99.510596 -282.863544) (xy 99.683062 -282.565094)
			(xy 99.67341 -282.54198) (xy 99.664897 -282.520302) (xy 99.652895 -282.475302) (xy 99.646853 -282.429123)
			(xy 99.646486 -282.405836) (xy 99.646984 -282.379187) (xy 99.654927 -282.326483) (xy 99.670637 -282.275553)
			(xy 99.693763 -282.227532) (xy 99.723787 -282.183495) (xy 99.760039 -282.144424) (xy 99.80171 -282.111193)
			(xy 99.847868 -282.084544) (xy 99.897482 -282.065072) (xy 99.949444 -282.053212) (xy 100.002594 -282.049229)
			(xy 100.055744 -282.053212) (xy 100.107706 -282.065072) (xy 100.15732 -282.084544) (xy 100.203478 -282.111193)
			(xy 100.245149 -282.144424) (xy 100.281401 -282.183495) (xy 100.311425 -282.227532) (xy 100.334551 -282.275553)
			(xy 100.350261 -282.326483) (xy 100.358204 -282.379187) (xy 100.358702 -282.405836) (xy 100.358296 -282.431455)
			(xy 100.358147 -282.432485) (xy 100.586784 -282.432485) (xy 100.586784 -282.379187) (xy 100.594727 -282.326483)
			(xy 100.610437 -282.275553) (xy 100.633563 -282.227532) (xy 100.663587 -282.183495) (xy 100.699839 -282.144424)
			(xy 100.74151 -282.111193) (xy 100.787668 -282.084544) (xy 100.837282 -282.065072) (xy 100.889244 -282.053212)
			(xy 100.942394 -282.049229) (xy 100.995544 -282.053212) (xy 101.047506 -282.065072) (xy 101.09712 -282.084544)
			(xy 101.143278 -282.111193) (xy 101.184949 -282.144424) (xy 101.221201 -282.183495) (xy 101.251225 -282.227532)
			(xy 101.274351 -282.275553) (xy 101.290061 -282.326483) (xy 101.298004 -282.379187) (xy 101.298502 -282.405836)
			(xy 101.526086 -282.405836) (xy 101.526511 -282.380206) (xy 101.533842 -282.329474) (xy 101.548374 -282.280318)
			(xy 101.569805 -282.233754) (xy 101.597692 -282.190745) (xy 101.631459 -282.15218) (xy 101.670407 -282.118855)
			(xy 101.713732 -282.091461) (xy 101.760538 -282.070564) (xy 101.809857 -282.056595) (xy 101.835204 -282.052776)
			(xy 101.859842 -282.049474) (xy 102.032562 -281.750516) (xy 102.02291 -281.727402) (xy 102.01444 -281.705851)
			(xy 102.002556 -281.661095) (xy 101.996589 -281.615174) (xy 101.99624 -281.59202) (xy 101.996738 -281.565371)
			(xy 102.004681 -281.512667) (xy 102.020391 -281.461737) (xy 102.043517 -281.413716) (xy 102.073541 -281.369679)
			(xy 102.109793 -281.330608) (xy 102.151464 -281.297377) (xy 102.197622 -281.270728) (xy 102.247236 -281.251256)
			(xy 102.299198 -281.239396) (xy 102.352348 -281.235413) (xy 102.405498 -281.239396) (xy 102.45746 -281.251256)
			(xy 102.507074 -281.270728) (xy 102.553232 -281.297377) (xy 102.594903 -281.330608) (xy 102.631155 -281.369679)
			(xy 102.661179 -281.413716) (xy 102.684305 -281.461737) (xy 102.700015 -281.512667) (xy 102.707958 -281.565371)
			(xy 102.708456 -281.59202) (xy 102.708012 -281.61766) (xy 102.707866 -281.618669) (xy 102.936284 -281.618669)
			(xy 102.936284 -281.565371) (xy 102.944227 -281.512667) (xy 102.959937 -281.461737) (xy 102.983063 -281.413716)
			(xy 103.013087 -281.369679) (xy 103.049339 -281.330608) (xy 103.09101 -281.297377) (xy 103.137168 -281.270728)
			(xy 103.186782 -281.251256) (xy 103.238744 -281.239396) (xy 103.291894 -281.235413) (xy 103.345044 -281.239396)
			(xy 103.397006 -281.251256) (xy 103.44662 -281.270728) (xy 103.492778 -281.297377) (xy 103.534449 -281.330608)
			(xy 103.570701 -281.369679) (xy 103.600725 -281.413716) (xy 103.623851 -281.461737) (xy 103.639561 -281.512667)
			(xy 103.647504 -281.565371) (xy 103.648002 -281.59202) (xy 103.647504 -281.618669) (xy 103.639561 -281.671373)
			(xy 103.623851 -281.722303) (xy 103.600725 -281.770324) (xy 103.570701 -281.814361) (xy 103.534449 -281.853432)
			(xy 103.492778 -281.886663) (xy 103.44662 -281.913312) (xy 103.397006 -281.932784) (xy 103.345044 -281.944644)
			(xy 103.291894 -281.948628) (xy 103.238744 -281.944644) (xy 103.186782 -281.932784) (xy 103.137168 -281.913312)
			(xy 103.09101 -281.886663) (xy 103.049339 -281.853432) (xy 103.013087 -281.814361) (xy 102.983063 -281.770324)
			(xy 102.959937 -281.722303) (xy 102.944227 -281.671373) (xy 102.936284 -281.618669) (xy 102.707866 -281.618669)
			(xy 102.700667 -281.66841) (xy 102.686118 -281.717582) (xy 102.664665 -281.764158) (xy 102.636753 -281.807175)
			(xy 102.602958 -281.845742) (xy 102.56398 -281.879063) (xy 102.520625 -281.906447) (xy 102.47379 -281.927328)
			(xy 102.424444 -281.941275) (xy 102.399084 -281.94508) (xy 102.374192 -281.948382) (xy 102.201726 -282.246832)
			(xy 102.211378 -282.269946) (xy 102.219905 -282.291574) (xy 102.231888 -282.336494) (xy 102.237929 -282.382591)
			(xy 102.238302 -282.405836) (xy 102.237804 -282.432485) (xy 102.466638 -282.432485) (xy 102.466638 -282.379187)
			(xy 102.474581 -282.326483) (xy 102.490291 -282.275553) (xy 102.513417 -282.227532) (xy 102.543441 -282.183495)
			(xy 102.579693 -282.144424) (xy 102.621364 -282.111193) (xy 102.667522 -282.084544) (xy 102.717136 -282.065072)
			(xy 102.769098 -282.053212) (xy 102.822248 -282.049229) (xy 102.875398 -282.053212) (xy 102.92736 -282.065072)
			(xy 102.976974 -282.084544) (xy 103.023132 -282.111193) (xy 103.064803 -282.144424) (xy 103.101055 -282.183495)
			(xy 103.131079 -282.227532) (xy 103.154205 -282.275553) (xy 103.169915 -282.326483) (xy 103.177858 -282.379187)
			(xy 103.178356 -282.405836) (xy 103.177858 -282.432485) (xy 103.169915 -282.485189) (xy 103.154205 -282.536119)
			(xy 103.131079 -282.58414) (xy 103.101055 -282.628177) (xy 103.064803 -282.667248) (xy 103.023132 -282.700479)
			(xy 102.976974 -282.727128) (xy 102.92736 -282.7466) (xy 102.875398 -282.75846) (xy 102.822248 -282.762444)
			(xy 102.769098 -282.75846) (xy 102.717136 -282.7466) (xy 102.667522 -282.727128) (xy 102.621364 -282.700479)
			(xy 102.579693 -282.667248) (xy 102.543441 -282.628177) (xy 102.513417 -282.58414) (xy 102.490291 -282.536119)
			(xy 102.474581 -282.485189) (xy 102.466638 -282.432485) (xy 102.237804 -282.432485) (xy 102.229861 -282.485189)
			(xy 102.214151 -282.536119) (xy 102.191025 -282.58414) (xy 102.161001 -282.628177) (xy 102.124749 -282.667248)
			(xy 102.083078 -282.700479) (xy 102.03692 -282.727128) (xy 101.987306 -282.7466) (xy 101.935344 -282.75846)
			(xy 101.882194 -282.762444) (xy 101.829044 -282.75846) (xy 101.777082 -282.7466) (xy 101.727468 -282.727128)
			(xy 101.68131 -282.700479) (xy 101.639639 -282.667248) (xy 101.603387 -282.628177) (xy 101.573363 -282.58414)
			(xy 101.550237 -282.536119) (xy 101.534527 -282.485189) (xy 101.526584 -282.432485) (xy 101.526086 -282.405836)
			(xy 101.298502 -282.405836) (xy 101.298004 -282.432485) (xy 101.290061 -282.485189) (xy 101.274351 -282.536119)
			(xy 101.251225 -282.58414) (xy 101.221201 -282.628177) (xy 101.184949 -282.667248) (xy 101.143278 -282.700479)
			(xy 101.09712 -282.727128) (xy 101.047506 -282.7466) (xy 100.995544 -282.75846) (xy 100.942394 -282.762444)
			(xy 100.889244 -282.75846) (xy 100.837282 -282.7466) (xy 100.787668 -282.727128) (xy 100.74151 -282.700479)
			(xy 100.699839 -282.667248) (xy 100.663587 -282.628177) (xy 100.633563 -282.58414) (xy 100.610437 -282.536119)
			(xy 100.594727 -282.485189) (xy 100.586784 -282.432485) (xy 100.358147 -282.432485) (xy 100.350975 -282.482168)
			(xy 100.336459 -282.531306) (xy 100.315049 -282.577857) (xy 100.287187 -282.620858) (xy 100.253449 -282.65942)
			(xy 100.214531 -282.692748) (xy 100.171237 -282.720153) (xy 100.124463 -282.741068) (xy 100.075173 -282.755062)
			(xy 100.049838 -282.758896) (xy 100.0252 -282.762198) (xy 99.85248 -283.060902) (xy 99.862132 -283.084016)
			(xy 99.870648 -283.105648) (xy 99.882636 -283.150566) (xy 99.888681 -283.196661) (xy 99.889056 -283.219906)
			(xy 99.888558 -283.246555) (xy 100.116884 -283.246555) (xy 100.116884 -283.193257) (xy 100.124827 -283.140553)
			(xy 100.140537 -283.089623) (xy 100.163663 -283.041602) (xy 100.193687 -282.997565) (xy 100.229939 -282.958494)
			(xy 100.27161 -282.925263) (xy 100.317768 -282.898614) (xy 100.367382 -282.879142) (xy 100.419344 -282.867282)
			(xy 100.472494 -282.863299) (xy 100.525644 -282.867282) (xy 100.577606 -282.879142) (xy 100.62722 -282.898614)
			(xy 100.673378 -282.925263) (xy 100.715049 -282.958494) (xy 100.751301 -282.997565) (xy 100.781325 -283.041602)
			(xy 100.804451 -283.089623) (xy 100.820161 -283.140553) (xy 100.828104 -283.193257) (xy 100.828602 -283.2199)
			(xy 101.055874 -283.2199) (xy 101.059858 -283.166743) (xy 101.071721 -283.114774) (xy 101.091197 -283.065153)
			(xy 101.117852 -283.01899) (xy 101.15109 -282.977316) (xy 101.190169 -282.941061) (xy 101.234215 -282.911037)
			(xy 101.282244 -282.887913) (xy 101.333183 -282.872206) (xy 101.385895 -282.864268) (xy 101.412548 -282.863798)
			(xy 101.437572 -282.864258) (xy 101.487128 -282.871259) (xy 101.535215 -282.885131) (xy 101.580885 -282.905599)
			(xy 101.62324 -282.932262) (xy 101.661443 -282.964593) (xy 101.694743 -283.001955) (xy 101.708966 -283.022548)
			(xy 102.05593 -283.022548) (xy 102.070124 -283.001933) (xy 102.103427 -282.964566) (xy 102.141635 -282.932232)
			(xy 102.183993 -282.905566) (xy 102.229669 -282.885095) (xy 102.277761 -282.871221) (xy 102.327321 -282.864219)
			(xy 102.352348 -282.863798) (xy 102.378995 -282.864287) (xy 102.431694 -282.872237) (xy 102.48262 -282.887951)
			(xy 102.530635 -282.91108) (xy 102.574666 -282.941105) (xy 102.613732 -282.977358) (xy 102.646958 -283.019028)
			(xy 102.673604 -283.065184) (xy 102.693073 -283.114795) (xy 102.704931 -283.166754) (xy 102.708914 -283.2199)
			(xy 102.706916 -283.246555) (xy 102.936284 -283.246555) (xy 102.936284 -283.193257) (xy 102.944227 -283.140553)
			(xy 102.959937 -283.089623) (xy 102.983063 -283.041602) (xy 103.013087 -282.997565) (xy 103.049339 -282.958494)
			(xy 103.09101 -282.925263) (xy 103.137168 -282.898614) (xy 103.186782 -282.879142) (xy 103.238744 -282.867282)
			(xy 103.291894 -282.863299) (xy 103.345044 -282.867282) (xy 103.397006 -282.879142) (xy 103.44662 -282.898614)
			(xy 103.492778 -282.925263) (xy 103.534449 -282.958494) (xy 103.570701 -282.997565) (xy 103.600725 -283.041602)
			(xy 103.623851 -283.089623) (xy 103.639561 -283.140553) (xy 103.647504 -283.193257) (xy 103.648002 -283.219906)
			(xy 103.647504 -283.246555) (xy 103.639561 -283.299259) (xy 103.623851 -283.350189) (xy 103.600725 -283.39821)
			(xy 103.570701 -283.442247) (xy 103.534449 -283.481318) (xy 103.492778 -283.514549) (xy 103.44662 -283.541198)
			(xy 103.397006 -283.56067) (xy 103.345044 -283.57253) (xy 103.291894 -283.576514) (xy 103.238744 -283.57253)
			(xy 103.186782 -283.56067) (xy 103.137168 -283.541198) (xy 103.09101 -283.514549) (xy 103.049339 -283.481318)
			(xy 103.013087 -283.442247) (xy 102.983063 -283.39821) (xy 102.959937 -283.350189) (xy 102.944227 -283.299259)
			(xy 102.936284 -283.246555) (xy 102.706916 -283.246555) (xy 102.704931 -283.273046) (xy 102.693073 -283.325005)
			(xy 102.673604 -283.374616) (xy 102.646958 -283.420772) (xy 102.613732 -283.462442) (xy 102.574666 -283.498695)
			(xy 102.530635 -283.52872) (xy 102.48262 -283.551849) (xy 102.431694 -283.567563) (xy 102.378995 -283.575513)
			(xy 102.352348 -283.576014) (xy 102.327324 -283.575552) (xy 102.277769 -283.56855) (xy 102.229682 -283.554679)
			(xy 102.184011 -283.53421) (xy 102.141657 -283.507548) (xy 102.103453 -283.475218) (xy 102.070153 -283.437857)
			(xy 102.05593 -283.417264) (xy 101.708966 -283.417264) (xy 101.694714 -283.437838) (xy 101.66142 -283.475204)
			(xy 101.623223 -283.507541) (xy 101.580874 -283.534211) (xy 101.535208 -283.55469) (xy 101.487125 -283.568573)
			(xy 101.437572 -283.575586) (xy 101.412548 -283.576014) (xy 101.385895 -283.575532) (xy 101.333183 -283.567594)
			(xy 101.282244 -283.551887) (xy 101.234215 -283.528763) (xy 101.190169 -283.498739) (xy 101.15109 -283.462484)
			(xy 101.117852 -283.42081) (xy 101.091197 -283.374647) (xy 101.071721 -283.325026) (xy 101.059858 -283.273057)
			(xy 101.055874 -283.2199) (xy 100.828602 -283.2199) (xy 100.828602 -283.219906) (xy 100.828104 -283.246555)
			(xy 100.820161 -283.299259) (xy 100.804451 -283.350189) (xy 100.781325 -283.39821) (xy 100.751301 -283.442247)
			(xy 100.715049 -283.481318) (xy 100.673378 -283.514549) (xy 100.62722 -283.541198) (xy 100.577606 -283.56067)
			(xy 100.525644 -283.57253) (xy 100.472494 -283.576514) (xy 100.419344 -283.57253) (xy 100.367382 -283.56067)
			(xy 100.317768 -283.541198) (xy 100.27161 -283.514549) (xy 100.229939 -283.481318) (xy 100.193687 -283.442247)
			(xy 100.163663 -283.39821) (xy 100.140537 -283.350189) (xy 100.124827 -283.299259) (xy 100.116884 -283.246555)
			(xy 99.888558 -283.246555) (xy 99.880615 -283.299259) (xy 99.864905 -283.350189) (xy 99.841779 -283.39821)
			(xy 99.811755 -283.442247) (xy 99.775503 -283.481318) (xy 99.733832 -283.514549) (xy 99.687674 -283.541198)
			(xy 99.63806 -283.56067) (xy 99.586098 -283.57253) (xy 99.532948 -283.576514) (xy 99.479798 -283.57253)
			(xy 99.427836 -283.56067) (xy 99.378222 -283.541198) (xy 99.332064 -283.514549) (xy 99.290393 -283.481318)
			(xy 99.254141 -283.442247) (xy 99.224117 -283.39821) (xy 99.200991 -283.350189) (xy 99.185281 -283.299259)
			(xy 99.177338 -283.246555) (xy 99.17684 -283.219906) (xy 98.949002 -283.219906) (xy 98.948504 -283.246555)
			(xy 98.940561 -283.299259) (xy 98.924851 -283.350189) (xy 98.901725 -283.39821) (xy 98.871701 -283.442247)
			(xy 98.835449 -283.481318) (xy 98.793778 -283.514549) (xy 98.74762 -283.541198) (xy 98.698006 -283.56067)
			(xy 98.646044 -283.57253) (xy 98.592894 -283.576514) (xy 98.539744 -283.57253) (xy 98.487782 -283.56067)
			(xy 98.438168 -283.541198) (xy 98.39201 -283.514549) (xy 98.350339 -283.481318) (xy 98.314087 -283.442247)
			(xy 98.284063 -283.39821) (xy 98.260937 -283.350189) (xy 98.245227 -283.299259) (xy 98.237284 -283.246555)
			(xy 98.008704 -283.246555) (xy 98.000761 -283.299259) (xy 97.985051 -283.350189) (xy 97.961925 -283.39821)
			(xy 97.931901 -283.442247) (xy 97.895649 -283.481318) (xy 97.853978 -283.514549) (xy 97.80782 -283.541198)
			(xy 97.758206 -283.56067) (xy 97.706244 -283.57253) (xy 97.653094 -283.576514) (xy 97.599944 -283.57253)
			(xy 97.547982 -283.56067) (xy 97.498368 -283.541198) (xy 97.45221 -283.514549) (xy 97.410539 -283.481318)
			(xy 97.374287 -283.442247) (xy 97.344263 -283.39821) (xy 97.321137 -283.350189) (xy 97.305427 -283.299259)
			(xy 97.297484 -283.246555) (xy 97.069158 -283.246555) (xy 97.061215 -283.299259) (xy 97.045505 -283.350189)
			(xy 97.022379 -283.39821) (xy 96.992355 -283.442247) (xy 96.956103 -283.481318) (xy 96.914432 -283.514549)
			(xy 96.868274 -283.541198) (xy 96.81866 -283.56067) (xy 96.766698 -283.57253) (xy 96.713548 -283.576514)
			(xy 96.660398 -283.57253) (xy 96.608436 -283.56067) (xy 96.558822 -283.541198) (xy 96.512664 -283.514549)
			(xy 96.470993 -283.481318) (xy 96.434741 -283.442247) (xy 96.404717 -283.39821) (xy 96.381591 -283.350189)
			(xy 96.365881 -283.299259) (xy 96.357938 -283.246555) (xy 96.35744 -283.219906) (xy 96.357808 -283.196661)
			(xy 96.363855 -283.150565) (xy 96.375846 -283.105648) (xy 96.384364 -283.084016) (xy 96.394016 -283.060902)
			(xy 96.221296 -282.762198) (xy 96.196658 -282.758896) (xy 96.171298 -282.755106) (xy 96.121959 -282.741144)
			(xy 96.075131 -282.720252) (xy 96.031784 -282.692861) (xy 95.992811 -282.659538) (xy 95.959019 -282.620972)
			(xy 95.931107 -282.577958) (xy 95.90965 -282.531387) (xy 95.895092 -282.48222) (xy 95.887735 -282.431474)
			(xy 95.887286 -282.405836) (xy 95.659702 -282.405836) (xy 95.659204 -282.432485) (xy 95.651261 -282.485189)
			(xy 95.635551 -282.536119) (xy 95.612425 -282.58414) (xy 95.582401 -282.628177) (xy 95.546149 -282.667248)
			(xy 95.504478 -282.700479) (xy 95.45832 -282.727128) (xy 95.408706 -282.7466) (xy 95.356744 -282.75846)
			(xy 95.303594 -282.762444) (xy 95.250444 -282.75846) (xy 95.198482 -282.7466) (xy 95.148868 -282.727128)
			(xy 95.10271 -282.700479) (xy 95.061039 -282.667248) (xy 95.024787 -282.628177) (xy 94.994763 -282.58414)
			(xy 94.971637 -282.536119) (xy 94.955927 -282.485189) (xy 94.947984 -282.432485) (xy 94.947486 -282.405836)
			(xy 94.720156 -282.405836) (xy 94.719658 -282.432485) (xy 94.711715 -282.485189) (xy 94.696005 -282.536119)
			(xy 94.672879 -282.58414) (xy 94.642855 -282.628177) (xy 94.606603 -282.667248) (xy 94.564932 -282.700479)
			(xy 94.518774 -282.727128) (xy 94.46916 -282.7466) (xy 94.417198 -282.75846) (xy 94.364048 -282.762444)
			(xy 94.310898 -282.75846) (xy 94.258936 -282.7466) (xy 94.209322 -282.727128) (xy 94.163164 -282.700479)
			(xy 94.121493 -282.667248) (xy 94.085241 -282.628177) (xy 94.055217 -282.58414) (xy 94.032091 -282.536119)
			(xy 94.016381 -282.485189) (xy 94.008438 -282.432485) (xy 93.779858 -282.432485) (xy 93.771915 -282.485189)
			(xy 93.756205 -282.536119) (xy 93.733079 -282.58414) (xy 93.703055 -282.628177) (xy 93.666803 -282.667248)
			(xy 93.625132 -282.700479) (xy 93.578974 -282.727128) (xy 93.52936 -282.7466) (xy 93.477398 -282.75846)
			(xy 93.424248 -282.762444) (xy 93.371098 -282.75846) (xy 93.319136 -282.7466) (xy 93.269522 -282.727128)
			(xy 93.223364 -282.700479) (xy 93.181693 -282.667248) (xy 93.145441 -282.628177) (xy 93.115417 -282.58414)
			(xy 93.092291 -282.536119) (xy 93.076581 -282.485189) (xy 93.068638 -282.432485) (xy 93.06814 -282.405836)
			(xy 92.840556 -282.405836) (xy 92.840058 -282.432485) (xy 92.832115 -282.485189) (xy 92.816405 -282.536119)
			(xy 92.793279 -282.58414) (xy 92.763255 -282.628177) (xy 92.727003 -282.667248) (xy 92.685332 -282.700479)
			(xy 92.639174 -282.727128) (xy 92.58956 -282.7466) (xy 92.537598 -282.75846) (xy 92.484448 -282.762444)
			(xy 92.431298 -282.75846) (xy 92.379336 -282.7466) (xy 92.329722 -282.727128) (xy 92.283564 -282.700479)
			(xy 92.241893 -282.667248) (xy 92.205641 -282.628177) (xy 92.175617 -282.58414) (xy 92.152491 -282.536119)
			(xy 92.136781 -282.485189) (xy 92.128838 -282.432485) (xy 91.900181 -282.432485) (xy 91.89298 -282.482227)
			(xy 91.878429 -282.531399) (xy 91.856974 -282.577975) (xy 91.829059 -282.620992) (xy 91.795263 -282.659559)
			(xy 91.756283 -282.692879) (xy 91.712927 -282.720263) (xy 91.666091 -282.741145) (xy 91.616744 -282.755091)
			(xy 91.591384 -282.758896) (xy 91.566492 -282.762198) (xy 91.394026 -283.060902) (xy 91.403678 -283.084016)
			(xy 91.412196 -283.105647) (xy 91.424183 -283.150565) (xy 91.430227 -283.196661) (xy 91.430602 -283.219906)
			(xy 91.430104 -283.246555) (xy 91.658684 -283.246555) (xy 91.658684 -283.193257) (xy 91.666627 -283.140553)
			(xy 91.682337 -283.089623) (xy 91.705463 -283.041602) (xy 91.735487 -282.997565) (xy 91.771739 -282.958494)
			(xy 91.81341 -282.925263) (xy 91.859568 -282.898614) (xy 91.909182 -282.879142) (xy 91.961144 -282.867282)
			(xy 92.014294 -282.863299) (xy 92.067444 -282.867282) (xy 92.119406 -282.879142) (xy 92.16902 -282.898614)
			(xy 92.215178 -282.925263) (xy 92.256849 -282.958494) (xy 92.293101 -282.997565) (xy 92.323125 -283.041602)
			(xy 92.346251 -283.089623) (xy 92.361961 -283.140553) (xy 92.369904 -283.193257) (xy 92.370402 -283.2199)
			(xy 92.597498 -283.2199) (xy 92.601481 -283.166752) (xy 92.613341 -283.114791) (xy 92.632812 -283.065178)
			(xy 92.659461 -283.019021) (xy 92.692691 -282.977351) (xy 92.73176 -282.9411) (xy 92.775796 -282.911076)
			(xy 92.823815 -282.887951) (xy 92.874744 -282.87224) (xy 92.927445 -282.864296) (xy 92.954094 -282.863798)
			(xy 92.979119 -282.864223) (xy 93.028676 -282.87123) (xy 93.076764 -282.885108) (xy 93.122435 -282.905583)
			(xy 93.164789 -282.93225) (xy 93.202992 -282.964586) (xy 93.23629 -283.001953) (xy 93.250512 -283.022548)
			(xy 93.597476 -283.022548) (xy 93.611705 -283.001958) (xy 93.645002 -282.964591) (xy 93.683203 -282.932255)
			(xy 93.725556 -282.905586) (xy 93.771226 -282.885111) (xy 93.819313 -282.871232) (xy 93.868869 -282.864223)
			(xy 93.893894 -282.863798) (xy 93.920546 -282.864259) (xy 93.973254 -282.872203) (xy 94.02419 -282.887913)
			(xy 94.072216 -282.91104) (xy 94.116257 -282.941067) (xy 94.155332 -282.977322) (xy 94.188567 -283.018997)
			(xy 94.215219 -283.065159) (xy 94.234693 -283.114778) (xy 94.246555 -283.166745) (xy 94.250538 -283.2199)
			(xy 94.248541 -283.246555) (xy 94.478084 -283.246555) (xy 94.478084 -283.193257) (xy 94.486027 -283.140553)
			(xy 94.501737 -283.089623) (xy 94.524863 -283.041602) (xy 94.554887 -282.997565) (xy 94.591139 -282.958494)
			(xy 94.63281 -282.925263) (xy 94.678968 -282.898614) (xy 94.728582 -282.879142) (xy 94.780544 -282.867282)
			(xy 94.833694 -282.863299) (xy 94.886844 -282.867282) (xy 94.938806 -282.879142) (xy 94.98842 -282.898614)
			(xy 95.034578 -282.925263) (xy 95.076249 -282.958494) (xy 95.112501 -282.997565) (xy 95.142525 -283.041602)
			(xy 95.165651 -283.089623) (xy 95.181361 -283.140553) (xy 95.189304 -283.193257) (xy 95.189802 -283.219906)
			(xy 95.189304 -283.246555) (xy 95.417884 -283.246555) (xy 95.417884 -283.193257) (xy 95.425827 -283.140553)
			(xy 95.441537 -283.089623) (xy 95.464663 -283.041602) (xy 95.494687 -282.997565) (xy 95.530939 -282.958494)
			(xy 95.57261 -282.925263) (xy 95.618768 -282.898614) (xy 95.668382 -282.879142) (xy 95.720344 -282.867282)
			(xy 95.773494 -282.863299) (xy 95.826644 -282.867282) (xy 95.878606 -282.879142) (xy 95.92822 -282.898614)
			(xy 95.974378 -282.925263) (xy 96.016049 -282.958494) (xy 96.052301 -282.997565) (xy 96.082325 -283.041602)
			(xy 96.105451 -283.089623) (xy 96.121161 -283.140553) (xy 96.129104 -283.193257) (xy 96.129602 -283.219906)
			(xy 96.129104 -283.246555) (xy 96.121161 -283.299259) (xy 96.105451 -283.350189) (xy 96.082325 -283.39821)
			(xy 96.052301 -283.442247) (xy 96.016049 -283.481318) (xy 95.974378 -283.514549) (xy 95.92822 -283.541198)
			(xy 95.878606 -283.56067) (xy 95.826644 -283.57253) (xy 95.773494 -283.576514) (xy 95.720344 -283.57253)
			(xy 95.668382 -283.56067) (xy 95.618768 -283.541198) (xy 95.57261 -283.514549) (xy 95.530939 -283.481318)
			(xy 95.494687 -283.442247) (xy 95.464663 -283.39821) (xy 95.441537 -283.350189) (xy 95.425827 -283.299259)
			(xy 95.417884 -283.246555) (xy 95.189304 -283.246555) (xy 95.181361 -283.299259) (xy 95.165651 -283.350189)
			(xy 95.142525 -283.39821) (xy 95.112501 -283.442247) (xy 95.076249 -283.481318) (xy 95.034578 -283.514549)
			(xy 94.98842 -283.541198) (xy 94.938806 -283.56067) (xy 94.886844 -283.57253) (xy 94.833694 -283.576514)
			(xy 94.780544 -283.57253) (xy 94.728582 -283.56067) (xy 94.678968 -283.541198) (xy 94.63281 -283.514549)
			(xy 94.591139 -283.481318) (xy 94.554887 -283.442247) (xy 94.524863 -283.39821) (xy 94.501737 -283.350189)
			(xy 94.486027 -283.299259) (xy 94.478084 -283.246555) (xy 94.248541 -283.246555) (xy 94.246555 -283.273055)
			(xy 94.234693 -283.325022) (xy 94.215219 -283.374641) (xy 94.188567 -283.420803) (xy 94.155332 -283.462478)
			(xy 94.116257 -283.498733) (xy 94.072216 -283.52876) (xy 94.02419 -283.551887) (xy 93.973254 -283.567597)
			(xy 93.920546 -283.575541) (xy 93.893894 -283.576014) (xy 93.868869 -283.575593) (xy 93.819312 -283.568584)
			(xy 93.771224 -283.554705) (xy 93.725553 -283.53423) (xy 93.683199 -283.507562) (xy 93.644997 -283.475226)
			(xy 93.611698 -283.437859) (xy 93.597476 -283.417264) (xy 93.250512 -283.417264) (xy 93.236294 -283.437863)
			(xy 93.202995 -283.475229) (xy 93.164792 -283.507564) (xy 93.122437 -283.534231) (xy 93.076765 -283.554705)
			(xy 93.028677 -283.568583) (xy 92.979119 -283.57559) (xy 92.954094 -283.576014) (xy 92.927445 -283.575504)
			(xy 92.874744 -283.56756) (xy 92.823815 -283.551849) (xy 92.775796 -283.528724) (xy 92.73176 -283.4987)
			(xy 92.692691 -283.462449) (xy 92.659461 -283.420779) (xy 92.632812 -283.374622) (xy 92.613341 -283.325009)
			(xy 92.601481 -283.273048) (xy 92.597498 -283.2199) (xy 92.370402 -283.2199) (xy 92.370402 -283.219906)
			(xy 92.369904 -283.246555) (xy 92.361961 -283.299259) (xy 92.346251 -283.350189) (xy 92.323125 -283.39821)
			(xy 92.293101 -283.442247) (xy 92.256849 -283.481318) (xy 92.215178 -283.514549) (xy 92.16902 -283.541198)
			(xy 92.119406 -283.56067) (xy 92.067444 -283.57253) (xy 92.014294 -283.576514) (xy 91.961144 -283.57253)
			(xy 91.909182 -283.56067) (xy 91.859568 -283.541198) (xy 91.81341 -283.514549) (xy 91.771739 -283.481318)
			(xy 91.735487 -283.442247) (xy 91.705463 -283.39821) (xy 91.682337 -283.350189) (xy 91.666627 -283.299259)
			(xy 91.658684 -283.246555) (xy 91.430104 -283.246555) (xy 91.422161 -283.299259) (xy 91.406451 -283.350189)
			(xy 91.383325 -283.39821) (xy 91.353301 -283.442247) (xy 91.317049 -283.481318) (xy 91.275378 -283.514549)
			(xy 91.22922 -283.541198) (xy 91.179606 -283.56067) (xy 91.127644 -283.57253) (xy 91.074494 -283.576514)
			(xy 91.021344 -283.57253) (xy 90.969382 -283.56067) (xy 90.919768 -283.541198) (xy 90.87361 -283.514549)
			(xy 90.831939 -283.481318) (xy 90.795687 -283.442247) (xy 90.765663 -283.39821) (xy 90.742537 -283.350189)
			(xy 90.726827 -283.299259) (xy 90.718884 -283.246555) (xy 90.718386 -283.219906) (xy 90.490802 -283.219906)
			(xy 90.490304 -283.246555) (xy 90.482361 -283.299259) (xy 90.466651 -283.350189) (xy 90.443525 -283.39821)
			(xy 90.413501 -283.442247) (xy 90.377249 -283.481318) (xy 90.335578 -283.514549) (xy 90.28942 -283.541198)
			(xy 90.239806 -283.56067) (xy 90.187844 -283.57253) (xy 90.134694 -283.576514) (xy 90.081544 -283.57253)
			(xy 90.029582 -283.56067) (xy 89.979968 -283.541198) (xy 89.93381 -283.514549) (xy 89.892139 -283.481318)
			(xy 89.855887 -283.442247) (xy 89.825863 -283.39821) (xy 89.802737 -283.350189) (xy 89.787027 -283.299259)
			(xy 89.779084 -283.246555) (xy 89.550504 -283.246555) (xy 89.542561 -283.299259) (xy 89.526851 -283.350189)
			(xy 89.503725 -283.39821) (xy 89.473701 -283.442247) (xy 89.437449 -283.481318) (xy 89.395778 -283.514549)
			(xy 89.34962 -283.541198) (xy 89.300006 -283.56067) (xy 89.248044 -283.57253) (xy 89.194894 -283.576514)
			(xy 89.141744 -283.57253) (xy 89.089782 -283.56067) (xy 89.040168 -283.541198) (xy 88.99401 -283.514549)
			(xy 88.952339 -283.481318) (xy 88.916087 -283.442247) (xy 88.886063 -283.39821) (xy 88.862937 -283.350189)
			(xy 88.847227 -283.299259) (xy 88.839284 -283.246555) (xy 88.610704 -283.246555) (xy 88.602761 -283.299259)
			(xy 88.587051 -283.350189) (xy 88.563925 -283.39821) (xy 88.533901 -283.442247) (xy 88.497649 -283.481318)
			(xy 88.455978 -283.514549) (xy 88.40982 -283.541198) (xy 88.360206 -283.56067) (xy 88.308244 -283.57253)
			(xy 88.255094 -283.576514) (xy 88.201944 -283.57253) (xy 88.149982 -283.56067) (xy 88.100368 -283.541198)
			(xy 88.05421 -283.514549) (xy 88.012539 -283.481318) (xy 87.976287 -283.442247) (xy 87.946263 -283.39821)
			(xy 87.923137 -283.350189) (xy 87.907427 -283.299259) (xy 87.899484 -283.246555) (xy 87.898986 -283.219906)
			(xy 87.899358 -283.196661) (xy 87.905403 -283.150565) (xy 87.917393 -283.105648) (xy 87.92591 -283.084016)
			(xy 87.935562 -283.060902) (xy 87.762842 -282.762198) (xy 87.738204 -282.758896) (xy 87.712863 -282.755058)
			(xy 87.663557 -282.741071) (xy 87.616765 -282.720163) (xy 87.573452 -282.692764) (xy 87.534512 -282.659441)
			(xy 87.500751 -282.620881) (xy 87.472864 -282.577881) (xy 87.451427 -282.531328) (xy 87.436884 -282.482183)
			(xy 87.429534 -282.431462) (xy 87.429086 -282.405836) (xy 87.201756 -282.405836) (xy 87.201258 -282.432485)
			(xy 87.193315 -282.485189) (xy 87.177605 -282.536119) (xy 87.154479 -282.58414) (xy 87.124455 -282.628177)
			(xy 87.088203 -282.667248) (xy 87.046532 -282.700479) (xy 87.000374 -282.727128) (xy 86.95076 -282.7466)
			(xy 86.898798 -282.75846) (xy 86.845648 -282.762444) (xy 86.792498 -282.75846) (xy 86.740536 -282.7466)
			(xy 86.690922 -282.727128) (xy 86.644764 -282.700479) (xy 86.603093 -282.667248) (xy 86.566841 -282.628177)
			(xy 86.536817 -282.58414) (xy 86.513691 -282.536119) (xy 86.497981 -282.485189) (xy 86.490038 -282.432485)
			(xy 86.48954 -282.405836) (xy 86.262193 -282.405836) (xy 86.258213 -282.458948) (xy 86.246353 -282.51091)
			(xy 86.226881 -282.560523) (xy 86.200232 -282.60668) (xy 86.167001 -282.648349) (xy 86.127931 -282.6846)
			(xy 86.083895 -282.714623) (xy 86.035875 -282.737748) (xy 85.984945 -282.753457) (xy 85.932243 -282.761399)
			(xy 85.905594 -282.761944) (xy 85.876625 -282.761377) (xy 85.819451 -282.752006) (xy 85.764545 -282.733512)
			(xy 85.713352 -282.70638) (xy 85.689948 -282.6893) (xy 85.678429 -282.681126) (xy 85.652128 -282.670858)
			(xy 85.62402 -282.668185) (xy 85.596255 -282.673312) (xy 85.570955 -282.685846) (xy 85.550054 -282.704829)
			(xy 85.535151 -282.72881) (xy 85.527385 -282.755955) (xy 85.52688 -282.770072) (xy 85.52688 -282.873958)
			(xy 85.5599 -282.88615) (xy 85.585072 -282.896054) (xy 85.632331 -282.92237) (xy 85.675067 -282.955529)
			(xy 85.712296 -282.994771) (xy 85.743162 -283.039192) (xy 85.766955 -283.087769) (xy 85.783127 -283.139387)
			(xy 85.791308 -283.192856) (xy 85.791307 -283.246555) (xy 86.019884 -283.246555) (xy 86.019884 -283.193257)
			(xy 86.027827 -283.140553) (xy 86.043537 -283.089623) (xy 86.066663 -283.041602) (xy 86.096687 -282.997565)
			(xy 86.132939 -282.958494) (xy 86.17461 -282.925263) (xy 86.220768 -282.898614) (xy 86.270382 -282.879142)
			(xy 86.322344 -282.867282) (xy 86.375494 -282.863299) (xy 86.428644 -282.867282) (xy 86.480606 -282.879142)
			(xy 86.53022 -282.898614) (xy 86.576378 -282.925263) (xy 86.618049 -282.958494) (xy 86.654301 -282.997565)
			(xy 86.684325 -283.041602) (xy 86.707451 -283.089623) (xy 86.723161 -283.140553) (xy 86.731104 -283.193257)
			(xy 86.731602 -283.219906) (xy 86.731104 -283.246555) (xy 86.959684 -283.246555) (xy 86.959684 -283.193257)
			(xy 86.967627 -283.140553) (xy 86.983337 -283.089623) (xy 87.006463 -283.041602) (xy 87.036487 -282.997565)
			(xy 87.072739 -282.958494) (xy 87.11441 -282.925263) (xy 87.160568 -282.898614) (xy 87.210182 -282.879142)
			(xy 87.262144 -282.867282) (xy 87.315294 -282.863299) (xy 87.368444 -282.867282) (xy 87.420406 -282.879142)
			(xy 87.47002 -282.898614) (xy 87.516178 -282.925263) (xy 87.557849 -282.958494) (xy 87.594101 -282.997565)
			(xy 87.624125 -283.041602) (xy 87.647251 -283.089623) (xy 87.662961 -283.140553) (xy 87.670904 -283.193257)
			(xy 87.671402 -283.219906) (xy 87.670904 -283.246555) (xy 87.662961 -283.299259) (xy 87.647251 -283.350189)
			(xy 87.624125 -283.39821) (xy 87.594101 -283.442247) (xy 87.557849 -283.481318) (xy 87.516178 -283.514549)
			(xy 87.47002 -283.541198) (xy 87.420406 -283.56067) (xy 87.368444 -283.57253) (xy 87.315294 -283.576514)
			(xy 87.262144 -283.57253) (xy 87.210182 -283.56067) (xy 87.160568 -283.541198) (xy 87.11441 -283.514549)
			(xy 87.072739 -283.481318) (xy 87.036487 -283.442247) (xy 87.006463 -283.39821) (xy 86.983337 -283.350189)
			(xy 86.967627 -283.299259) (xy 86.959684 -283.246555) (xy 86.731104 -283.246555) (xy 86.723161 -283.299259)
			(xy 86.707451 -283.350189) (xy 86.684325 -283.39821) (xy 86.654301 -283.442247) (xy 86.618049 -283.481318)
			(xy 86.576378 -283.514549) (xy 86.53022 -283.541198) (xy 86.480606 -283.56067) (xy 86.428644 -283.57253)
			(xy 86.375494 -283.576514) (xy 86.322344 -283.57253) (xy 86.270382 -283.56067) (xy 86.220768 -283.541198)
			(xy 86.17461 -283.514549) (xy 86.132939 -283.481318) (xy 86.096687 -283.442247) (xy 86.066663 -283.39821)
			(xy 86.043537 -283.350189) (xy 86.027827 -283.299259) (xy 86.019884 -283.246555) (xy 85.791307 -283.246555)
			(xy 85.791307 -283.246948) (xy 85.783126 -283.300417) (xy 85.766953 -283.352034) (xy 85.74316 -283.400612)
			(xy 85.712293 -283.445032) (xy 85.675064 -283.484273) (xy 85.632328 -283.517433) (xy 85.585068 -283.543748)
			(xy 85.5599 -283.553662) (xy 85.52688 -283.565854) (xy 85.52688 -284.033722) (xy 86.48954 -284.033722)
			(xy 86.490038 -284.007073) (xy 86.497981 -283.954369) (xy 86.513691 -283.903439) (xy 86.536817 -283.855418)
			(xy 86.566841 -283.811381) (xy 86.603093 -283.77231) (xy 86.644764 -283.739079) (xy 86.690922 -283.71243)
			(xy 86.740536 -283.692958) (xy 86.792498 -283.681098) (xy 86.845648 -283.677115) (xy 86.898798 -283.681098)
			(xy 86.95076 -283.692958) (xy 87.000374 -283.71243) (xy 87.046532 -283.739079) (xy 87.088203 -283.77231)
			(xy 87.124455 -283.811381) (xy 87.154479 -283.855418) (xy 87.177605 -283.903439) (xy 87.193315 -283.954369)
			(xy 87.201258 -284.007073) (xy 87.201756 -284.033722) (xy 87.201397 -284.056968) (xy 87.20095 -284.060371)
			(xy 87.429584 -284.060371) (xy 87.429584 -284.007073) (xy 87.437527 -283.954369) (xy 87.453237 -283.903439)
			(xy 87.476363 -283.855418) (xy 87.506387 -283.811381) (xy 87.542639 -283.77231) (xy 87.58431 -283.739079)
			(xy 87.630468 -283.71243) (xy 87.680082 -283.692958) (xy 87.732044 -283.681098) (xy 87.785194 -283.677115)
			(xy 87.838344 -283.681098) (xy 87.890306 -283.692958) (xy 87.93992 -283.71243) (xy 87.986078 -283.739079)
			(xy 88.027749 -283.77231) (xy 88.064001 -283.811381) (xy 88.094025 -283.855418) (xy 88.117151 -283.903439)
			(xy 88.132861 -283.954369) (xy 88.140804 -284.007073) (xy 88.141302 -284.033722) (xy 88.140804 -284.060371)
			(xy 88.369638 -284.060371) (xy 88.369638 -284.007073) (xy 88.377581 -283.954369) (xy 88.393291 -283.903439)
			(xy 88.416417 -283.855418) (xy 88.446441 -283.811381) (xy 88.482693 -283.77231) (xy 88.524364 -283.739079)
			(xy 88.570522 -283.71243) (xy 88.620136 -283.692958) (xy 88.672098 -283.681098) (xy 88.725248 -283.677115)
			(xy 88.778398 -283.681098) (xy 88.83036 -283.692958) (xy 88.879974 -283.71243) (xy 88.926132 -283.739079)
			(xy 88.967803 -283.77231) (xy 89.004055 -283.811381) (xy 89.034079 -283.855418) (xy 89.057205 -283.903439)
			(xy 89.072915 -283.954369) (xy 89.080858 -284.007073) (xy 89.081356 -284.033722) (xy 89.080858 -284.060371)
			(xy 90.248984 -284.060371) (xy 90.248984 -284.007073) (xy 90.256927 -283.954369) (xy 90.272637 -283.903439)
			(xy 90.295763 -283.855418) (xy 90.325787 -283.811381) (xy 90.362039 -283.77231) (xy 90.40371 -283.739079)
			(xy 90.449868 -283.71243) (xy 90.499482 -283.692958) (xy 90.551444 -283.681098) (xy 90.604594 -283.677115)
			(xy 90.657744 -283.681098) (xy 90.709706 -283.692958) (xy 90.75932 -283.71243) (xy 90.805478 -283.739079)
			(xy 90.847149 -283.77231) (xy 90.883401 -283.811381) (xy 90.913425 -283.855418) (xy 90.936551 -283.903439)
			(xy 90.952261 -283.954369) (xy 90.960204 -284.007073) (xy 90.960702 -284.033722) (xy 90.960204 -284.060371)
			(xy 91.188784 -284.060371) (xy 91.188784 -284.007073) (xy 91.196727 -283.954369) (xy 91.212437 -283.903439)
			(xy 91.235563 -283.855418) (xy 91.265587 -283.811381) (xy 91.301839 -283.77231) (xy 91.34351 -283.739079)
			(xy 91.389668 -283.71243) (xy 91.439282 -283.692958) (xy 91.491244 -283.681098) (xy 91.544394 -283.677115)
			(xy 91.597544 -283.681098) (xy 91.649506 -283.692958) (xy 91.69912 -283.71243) (xy 91.745278 -283.739079)
			(xy 91.786949 -283.77231) (xy 91.823201 -283.811381) (xy 91.853225 -283.855418) (xy 91.876351 -283.903439)
			(xy 91.892061 -283.954369) (xy 91.900004 -284.007073) (xy 91.900502 -284.033722) (xy 91.900004 -284.060371)
			(xy 92.128584 -284.060371) (xy 92.128584 -284.007073) (xy 92.136527 -283.954369) (xy 92.152237 -283.903439)
			(xy 92.175363 -283.855418) (xy 92.205387 -283.811381) (xy 92.241639 -283.77231) (xy 92.28331 -283.739079)
			(xy 92.329468 -283.71243) (xy 92.379082 -283.692958) (xy 92.431044 -283.681098) (xy 92.484194 -283.677115)
			(xy 92.537344 -283.681098) (xy 92.589306 -283.692958) (xy 92.63892 -283.71243) (xy 92.685078 -283.739079)
			(xy 92.726749 -283.77231) (xy 92.763001 -283.811381) (xy 92.793025 -283.855418) (xy 92.816151 -283.903439)
			(xy 92.831861 -283.954369) (xy 92.839804 -284.007073) (xy 92.840302 -284.033722) (xy 92.839804 -284.060371)
			(xy 93.068384 -284.060371) (xy 93.068384 -284.007073) (xy 93.076327 -283.954369) (xy 93.092037 -283.903439)
			(xy 93.115163 -283.855418) (xy 93.145187 -283.811381) (xy 93.181439 -283.77231) (xy 93.22311 -283.739079)
			(xy 93.269268 -283.71243) (xy 93.318882 -283.692958) (xy 93.370844 -283.681098) (xy 93.423994 -283.677115)
			(xy 93.477144 -283.681098) (xy 93.529106 -283.692958) (xy 93.57872 -283.71243) (xy 93.624878 -283.739079)
			(xy 93.666549 -283.77231) (xy 93.702801 -283.811381) (xy 93.732825 -283.855418) (xy 93.755951 -283.903439)
			(xy 93.771661 -283.954369) (xy 93.779604 -284.007073) (xy 93.780102 -284.033722) (xy 93.779604 -284.060371)
			(xy 94.008184 -284.060371) (xy 94.008184 -284.007073) (xy 94.016127 -283.954369) (xy 94.031837 -283.903439)
			(xy 94.054963 -283.855418) (xy 94.084987 -283.811381) (xy 94.121239 -283.77231) (xy 94.16291 -283.739079)
			(xy 94.209068 -283.71243) (xy 94.258682 -283.692958) (xy 94.310644 -283.681098) (xy 94.363794 -283.677115)
			(xy 94.416944 -283.681098) (xy 94.468906 -283.692958) (xy 94.51852 -283.71243) (xy 94.564678 -283.739079)
			(xy 94.606349 -283.77231) (xy 94.642601 -283.811381) (xy 94.672625 -283.855418) (xy 94.695751 -283.903439)
			(xy 94.711461 -283.954369) (xy 94.719404 -284.007073) (xy 94.719902 -284.033722) (xy 94.719404 -284.060371)
			(xy 94.947984 -284.060371) (xy 94.947984 -284.007073) (xy 94.955927 -283.954369) (xy 94.971637 -283.903439)
			(xy 94.994763 -283.855418) (xy 95.024787 -283.811381) (xy 95.061039 -283.77231) (xy 95.10271 -283.739079)
			(xy 95.148868 -283.71243) (xy 95.198482 -283.692958) (xy 95.250444 -283.681098) (xy 95.303594 -283.677115)
			(xy 95.356744 -283.681098) (xy 95.408706 -283.692958) (xy 95.45832 -283.71243) (xy 95.504478 -283.739079)
			(xy 95.546149 -283.77231) (xy 95.582401 -283.811381) (xy 95.612425 -283.855418) (xy 95.635551 -283.903439)
			(xy 95.651261 -283.954369) (xy 95.659204 -284.007073) (xy 95.659702 -284.033722) (xy 95.659204 -284.060371)
			(xy 95.887784 -284.060371) (xy 95.887784 -284.007073) (xy 95.895727 -283.954369) (xy 95.911437 -283.903439)
			(xy 95.934563 -283.855418) (xy 95.964587 -283.811381) (xy 96.000839 -283.77231) (xy 96.04251 -283.739079)
			(xy 96.088668 -283.71243) (xy 96.138282 -283.692958) (xy 96.190244 -283.681098) (xy 96.243394 -283.677115)
			(xy 96.296544 -283.681098) (xy 96.348506 -283.692958) (xy 96.39812 -283.71243) (xy 96.444278 -283.739079)
			(xy 96.485949 -283.77231) (xy 96.522201 -283.811381) (xy 96.552225 -283.855418) (xy 96.575351 -283.903439)
			(xy 96.591061 -283.954369) (xy 96.599004 -284.007073) (xy 96.599502 -284.033722) (xy 96.599004 -284.060371)
			(xy 96.827584 -284.060371) (xy 96.827584 -284.007073) (xy 96.835527 -283.954369) (xy 96.851237 -283.903439)
			(xy 96.874363 -283.855418) (xy 96.904387 -283.811381) (xy 96.940639 -283.77231) (xy 96.98231 -283.739079)
			(xy 97.028468 -283.71243) (xy 97.078082 -283.692958) (xy 97.130044 -283.681098) (xy 97.183194 -283.677115)
			(xy 97.236344 -283.681098) (xy 97.288306 -283.692958) (xy 97.33792 -283.71243) (xy 97.384078 -283.739079)
			(xy 97.425749 -283.77231) (xy 97.462001 -283.811381) (xy 97.492025 -283.855418) (xy 97.515151 -283.903439)
			(xy 97.530861 -283.954369) (xy 97.538804 -284.007073) (xy 97.539302 -284.033722) (xy 97.538804 -284.060371)
			(xy 97.767384 -284.060371) (xy 97.767384 -284.007073) (xy 97.775327 -283.954369) (xy 97.791037 -283.903439)
			(xy 97.814163 -283.855418) (xy 97.844187 -283.811381) (xy 97.880439 -283.77231) (xy 97.92211 -283.739079)
			(xy 97.968268 -283.71243) (xy 98.017882 -283.692958) (xy 98.069844 -283.681098) (xy 98.122994 -283.677115)
			(xy 98.176144 -283.681098) (xy 98.228106 -283.692958) (xy 98.27772 -283.71243) (xy 98.323878 -283.739079)
			(xy 98.365549 -283.77231) (xy 98.401801 -283.811381) (xy 98.431825 -283.855418) (xy 98.454951 -283.903439)
			(xy 98.470661 -283.954369) (xy 98.478604 -284.007073) (xy 98.479102 -284.033722) (xy 98.478604 -284.060371)
			(xy 98.707184 -284.060371) (xy 98.707184 -284.007073) (xy 98.715127 -283.954369) (xy 98.730837 -283.903439)
			(xy 98.753963 -283.855418) (xy 98.783987 -283.811381) (xy 98.820239 -283.77231) (xy 98.86191 -283.739079)
			(xy 98.908068 -283.71243) (xy 98.957682 -283.692958) (xy 99.009644 -283.681098) (xy 99.062794 -283.677115)
			(xy 99.115944 -283.681098) (xy 99.167906 -283.692958) (xy 99.21752 -283.71243) (xy 99.263678 -283.739079)
			(xy 99.305349 -283.77231) (xy 99.341601 -283.811381) (xy 99.371625 -283.855418) (xy 99.394751 -283.903439)
			(xy 99.410461 -283.954369) (xy 99.418404 -284.007073) (xy 99.418902 -284.033722) (xy 99.418404 -284.060371)
			(xy 99.646984 -284.060371) (xy 99.646984 -284.007073) (xy 99.654927 -283.954369) (xy 99.670637 -283.903439)
			(xy 99.693763 -283.855418) (xy 99.723787 -283.811381) (xy 99.760039 -283.77231) (xy 99.80171 -283.739079)
			(xy 99.847868 -283.71243) (xy 99.897482 -283.692958) (xy 99.949444 -283.681098) (xy 100.002594 -283.677115)
			(xy 100.055744 -283.681098) (xy 100.107706 -283.692958) (xy 100.15732 -283.71243) (xy 100.203478 -283.739079)
			(xy 100.245149 -283.77231) (xy 100.281401 -283.811381) (xy 100.311425 -283.855418) (xy 100.334551 -283.903439)
			(xy 100.350261 -283.954369) (xy 100.358204 -284.007073) (xy 100.358702 -284.033722) (xy 100.358204 -284.060371)
			(xy 100.586784 -284.060371) (xy 100.586784 -284.007073) (xy 100.594727 -283.954369) (xy 100.610437 -283.903439)
			(xy 100.633563 -283.855418) (xy 100.663587 -283.811381) (xy 100.699839 -283.77231) (xy 100.74151 -283.739079)
			(xy 100.787668 -283.71243) (xy 100.837282 -283.692958) (xy 100.889244 -283.681098) (xy 100.942394 -283.677115)
			(xy 100.995544 -283.681098) (xy 101.047506 -283.692958) (xy 101.09712 -283.71243) (xy 101.143278 -283.739079)
			(xy 101.184949 -283.77231) (xy 101.221201 -283.811381) (xy 101.251225 -283.855418) (xy 101.274351 -283.903439)
			(xy 101.290061 -283.954369) (xy 101.298004 -284.007073) (xy 101.298502 -284.033722) (xy 101.298004 -284.060371)
			(xy 101.526584 -284.060371) (xy 101.526584 -284.007073) (xy 101.534527 -283.954369) (xy 101.550237 -283.903439)
			(xy 101.573363 -283.855418) (xy 101.603387 -283.811381) (xy 101.639639 -283.77231) (xy 101.68131 -283.739079)
			(xy 101.727468 -283.71243) (xy 101.777082 -283.692958) (xy 101.829044 -283.681098) (xy 101.882194 -283.677115)
			(xy 101.935344 -283.681098) (xy 101.987306 -283.692958) (xy 102.03692 -283.71243) (xy 102.083078 -283.739079)
			(xy 102.124749 -283.77231) (xy 102.161001 -283.811381) (xy 102.191025 -283.855418) (xy 102.214151 -283.903439)
			(xy 102.229861 -283.954369) (xy 102.237804 -284.007073) (xy 102.238302 -284.033722) (xy 102.237804 -284.060371)
			(xy 102.466384 -284.060371) (xy 102.466384 -284.007073) (xy 102.474327 -283.954369) (xy 102.490037 -283.903439)
			(xy 102.513163 -283.855418) (xy 102.543187 -283.811381) (xy 102.579439 -283.77231) (xy 102.62111 -283.739079)
			(xy 102.667268 -283.71243) (xy 102.716882 -283.692958) (xy 102.768844 -283.681098) (xy 102.821994 -283.677115)
			(xy 102.875144 -283.681098) (xy 102.927106 -283.692958) (xy 102.97672 -283.71243) (xy 103.022878 -283.739079)
			(xy 103.064549 -283.77231) (xy 103.100801 -283.811381) (xy 103.130825 -283.855418) (xy 103.153951 -283.903439)
			(xy 103.169661 -283.954369) (xy 103.177604 -284.007073) (xy 103.178102 -284.033722) (xy 103.177604 -284.060371)
			(xy 103.169661 -284.113075) (xy 103.153951 -284.164005) (xy 103.130825 -284.212026) (xy 103.100801 -284.256063)
			(xy 103.064549 -284.295134) (xy 103.022878 -284.328365) (xy 102.97672 -284.355014) (xy 102.927106 -284.374486)
			(xy 102.875144 -284.386346) (xy 102.821994 -284.39033) (xy 102.768844 -284.386346) (xy 102.716882 -284.374486)
			(xy 102.667268 -284.355014) (xy 102.62111 -284.328365) (xy 102.579439 -284.295134) (xy 102.543187 -284.256063)
			(xy 102.513163 -284.212026) (xy 102.490037 -284.164005) (xy 102.474327 -284.113075) (xy 102.466384 -284.060371)
			(xy 102.237804 -284.060371) (xy 102.229861 -284.113075) (xy 102.214151 -284.164005) (xy 102.191025 -284.212026)
			(xy 102.161001 -284.256063) (xy 102.124749 -284.295134) (xy 102.083078 -284.328365) (xy 102.03692 -284.355014)
			(xy 101.987306 -284.374486) (xy 101.935344 -284.386346) (xy 101.882194 -284.39033) (xy 101.829044 -284.386346)
			(xy 101.777082 -284.374486) (xy 101.727468 -284.355014) (xy 101.68131 -284.328365) (xy 101.639639 -284.295134)
			(xy 101.603387 -284.256063) (xy 101.573363 -284.212026) (xy 101.550237 -284.164005) (xy 101.534527 -284.113075)
			(xy 101.526584 -284.060371) (xy 101.298004 -284.060371) (xy 101.290061 -284.113075) (xy 101.274351 -284.164005)
			(xy 101.251225 -284.212026) (xy 101.221201 -284.256063) (xy 101.184949 -284.295134) (xy 101.143278 -284.328365)
			(xy 101.09712 -284.355014) (xy 101.047506 -284.374486) (xy 100.995544 -284.386346) (xy 100.942394 -284.39033)
			(xy 100.889244 -284.386346) (xy 100.837282 -284.374486) (xy 100.787668 -284.355014) (xy 100.74151 -284.328365)
			(xy 100.699839 -284.295134) (xy 100.663587 -284.256063) (xy 100.633563 -284.212026) (xy 100.610437 -284.164005)
			(xy 100.594727 -284.113075) (xy 100.586784 -284.060371) (xy 100.358204 -284.060371) (xy 100.350261 -284.113075)
			(xy 100.334551 -284.164005) (xy 100.311425 -284.212026) (xy 100.281401 -284.256063) (xy 100.245149 -284.295134)
			(xy 100.203478 -284.328365) (xy 100.15732 -284.355014) (xy 100.107706 -284.374486) (xy 100.055744 -284.386346)
			(xy 100.002594 -284.39033) (xy 99.949444 -284.386346) (xy 99.897482 -284.374486) (xy 99.847868 -284.355014)
			(xy 99.80171 -284.328365) (xy 99.760039 -284.295134) (xy 99.723787 -284.256063) (xy 99.693763 -284.212026)
			(xy 99.670637 -284.164005) (xy 99.654927 -284.113075) (xy 99.646984 -284.060371) (xy 99.418404 -284.060371)
			(xy 99.410461 -284.113075) (xy 99.394751 -284.164005) (xy 99.371625 -284.212026) (xy 99.341601 -284.256063)
			(xy 99.305349 -284.295134) (xy 99.263678 -284.328365) (xy 99.21752 -284.355014) (xy 99.167906 -284.374486)
			(xy 99.115944 -284.386346) (xy 99.062794 -284.39033) (xy 99.009644 -284.386346) (xy 98.957682 -284.374486)
			(xy 98.908068 -284.355014) (xy 98.86191 -284.328365) (xy 98.820239 -284.295134) (xy 98.783987 -284.256063)
			(xy 98.753963 -284.212026) (xy 98.730837 -284.164005) (xy 98.715127 -284.113075) (xy 98.707184 -284.060371)
			(xy 98.478604 -284.060371) (xy 98.470661 -284.113075) (xy 98.454951 -284.164005) (xy 98.431825 -284.212026)
			(xy 98.401801 -284.256063) (xy 98.365549 -284.295134) (xy 98.323878 -284.328365) (xy 98.27772 -284.355014)
			(xy 98.228106 -284.374486) (xy 98.176144 -284.386346) (xy 98.122994 -284.39033) (xy 98.069844 -284.386346)
			(xy 98.017882 -284.374486) (xy 97.968268 -284.355014) (xy 97.92211 -284.328365) (xy 97.880439 -284.295134)
			(xy 97.844187 -284.256063) (xy 97.814163 -284.212026) (xy 97.791037 -284.164005) (xy 97.775327 -284.113075)
			(xy 97.767384 -284.060371) (xy 97.538804 -284.060371) (xy 97.530861 -284.113075) (xy 97.515151 -284.164005)
			(xy 97.492025 -284.212026) (xy 97.462001 -284.256063) (xy 97.425749 -284.295134) (xy 97.384078 -284.328365)
			(xy 97.33792 -284.355014) (xy 97.288306 -284.374486) (xy 97.236344 -284.386346) (xy 97.183194 -284.39033)
			(xy 97.130044 -284.386346) (xy 97.078082 -284.374486) (xy 97.028468 -284.355014) (xy 96.98231 -284.328365)
			(xy 96.940639 -284.295134) (xy 96.904387 -284.256063) (xy 96.874363 -284.212026) (xy 96.851237 -284.164005)
			(xy 96.835527 -284.113075) (xy 96.827584 -284.060371) (xy 96.599004 -284.060371) (xy 96.591061 -284.113075)
			(xy 96.575351 -284.164005) (xy 96.552225 -284.212026) (xy 96.522201 -284.256063) (xy 96.485949 -284.295134)
			(xy 96.444278 -284.328365) (xy 96.39812 -284.355014) (xy 96.348506 -284.374486) (xy 96.296544 -284.386346)
			(xy 96.243394 -284.39033) (xy 96.190244 -284.386346) (xy 96.138282 -284.374486) (xy 96.088668 -284.355014)
			(xy 96.04251 -284.328365) (xy 96.000839 -284.295134) (xy 95.964587 -284.256063) (xy 95.934563 -284.212026)
			(xy 95.911437 -284.164005) (xy 95.895727 -284.113075) (xy 95.887784 -284.060371) (xy 95.659204 -284.060371)
			(xy 95.651261 -284.113075) (xy 95.635551 -284.164005) (xy 95.612425 -284.212026) (xy 95.582401 -284.256063)
			(xy 95.546149 -284.295134) (xy 95.504478 -284.328365) (xy 95.45832 -284.355014) (xy 95.408706 -284.374486)
			(xy 95.356744 -284.386346) (xy 95.303594 -284.39033) (xy 95.250444 -284.386346) (xy 95.198482 -284.374486)
			(xy 95.148868 -284.355014) (xy 95.10271 -284.328365) (xy 95.061039 -284.295134) (xy 95.024787 -284.256063)
			(xy 94.994763 -284.212026) (xy 94.971637 -284.164005) (xy 94.955927 -284.113075) (xy 94.947984 -284.060371)
			(xy 94.719404 -284.060371) (xy 94.711461 -284.113075) (xy 94.695751 -284.164005) (xy 94.672625 -284.212026)
			(xy 94.642601 -284.256063) (xy 94.606349 -284.295134) (xy 94.564678 -284.328365) (xy 94.51852 -284.355014)
			(xy 94.468906 -284.374486) (xy 94.416944 -284.386346) (xy 94.363794 -284.39033) (xy 94.310644 -284.386346)
			(xy 94.258682 -284.374486) (xy 94.209068 -284.355014) (xy 94.16291 -284.328365) (xy 94.121239 -284.295134)
			(xy 94.084987 -284.256063) (xy 94.054963 -284.212026) (xy 94.031837 -284.164005) (xy 94.016127 -284.113075)
			(xy 94.008184 -284.060371) (xy 93.779604 -284.060371) (xy 93.771661 -284.113075) (xy 93.755951 -284.164005)
			(xy 93.732825 -284.212026) (xy 93.702801 -284.256063) (xy 93.666549 -284.295134) (xy 93.624878 -284.328365)
			(xy 93.57872 -284.355014) (xy 93.529106 -284.374486) (xy 93.477144 -284.386346) (xy 93.423994 -284.39033)
			(xy 93.370844 -284.386346) (xy 93.318882 -284.374486) (xy 93.269268 -284.355014) (xy 93.22311 -284.328365)
			(xy 93.181439 -284.295134) (xy 93.145187 -284.256063) (xy 93.115163 -284.212026) (xy 93.092037 -284.164005)
			(xy 93.076327 -284.113075) (xy 93.068384 -284.060371) (xy 92.839804 -284.060371) (xy 92.831861 -284.113075)
			(xy 92.816151 -284.164005) (xy 92.793025 -284.212026) (xy 92.763001 -284.256063) (xy 92.726749 -284.295134)
			(xy 92.685078 -284.328365) (xy 92.63892 -284.355014) (xy 92.589306 -284.374486) (xy 92.537344 -284.386346)
			(xy 92.484194 -284.39033) (xy 92.431044 -284.386346) (xy 92.379082 -284.374486) (xy 92.329468 -284.355014)
			(xy 92.28331 -284.328365) (xy 92.241639 -284.295134) (xy 92.205387 -284.256063) (xy 92.175363 -284.212026)
			(xy 92.152237 -284.164005) (xy 92.136527 -284.113075) (xy 92.128584 -284.060371) (xy 91.900004 -284.060371)
			(xy 91.892061 -284.113075) (xy 91.876351 -284.164005) (xy 91.853225 -284.212026) (xy 91.823201 -284.256063)
			(xy 91.786949 -284.295134) (xy 91.745278 -284.328365) (xy 91.69912 -284.355014) (xy 91.649506 -284.374486)
			(xy 91.597544 -284.386346) (xy 91.544394 -284.39033) (xy 91.491244 -284.386346) (xy 91.439282 -284.374486)
			(xy 91.389668 -284.355014) (xy 91.34351 -284.328365) (xy 91.301839 -284.295134) (xy 91.265587 -284.256063)
			(xy 91.235563 -284.212026) (xy 91.212437 -284.164005) (xy 91.196727 -284.113075) (xy 91.188784 -284.060371)
			(xy 90.960204 -284.060371) (xy 90.952261 -284.113075) (xy 90.936551 -284.164005) (xy 90.913425 -284.212026)
			(xy 90.883401 -284.256063) (xy 90.847149 -284.295134) (xy 90.805478 -284.328365) (xy 90.75932 -284.355014)
			(xy 90.709706 -284.374486) (xy 90.657744 -284.386346) (xy 90.604594 -284.39033) (xy 90.551444 -284.386346)
			(xy 90.499482 -284.374486) (xy 90.449868 -284.355014) (xy 90.40371 -284.328365) (xy 90.362039 -284.295134)
			(xy 90.325787 -284.256063) (xy 90.295763 -284.212026) (xy 90.272637 -284.164005) (xy 90.256927 -284.113075)
			(xy 90.248984 -284.060371) (xy 89.080858 -284.060371) (xy 89.072915 -284.113075) (xy 89.057205 -284.164005)
			(xy 89.034079 -284.212026) (xy 89.004055 -284.256063) (xy 88.967803 -284.295134) (xy 88.926132 -284.328365)
			(xy 88.879974 -284.355014) (xy 88.83036 -284.374486) (xy 88.778398 -284.386346) (xy 88.725248 -284.39033)
			(xy 88.672098 -284.386346) (xy 88.620136 -284.374486) (xy 88.570522 -284.355014) (xy 88.524364 -284.328365)
			(xy 88.482693 -284.295134) (xy 88.446441 -284.256063) (xy 88.416417 -284.212026) (xy 88.393291 -284.164005)
			(xy 88.377581 -284.113075) (xy 88.369638 -284.060371) (xy 88.140804 -284.060371) (xy 88.132861 -284.113075)
			(xy 88.117151 -284.164005) (xy 88.094025 -284.212026) (xy 88.064001 -284.256063) (xy 88.027749 -284.295134)
			(xy 87.986078 -284.328365) (xy 87.93992 -284.355014) (xy 87.890306 -284.374486) (xy 87.838344 -284.386346)
			(xy 87.785194 -284.39033) (xy 87.732044 -284.386346) (xy 87.680082 -284.374486) (xy 87.630468 -284.355014)
			(xy 87.58431 -284.328365) (xy 87.542639 -284.295134) (xy 87.506387 -284.256063) (xy 87.476363 -284.212026)
			(xy 87.453237 -284.164005) (xy 87.437527 -284.113075) (xy 87.429584 -284.060371) (xy 87.20095 -284.060371)
			(xy 87.195347 -284.103063) (xy 87.183352 -284.147981) (xy 87.174832 -284.169612) (xy 87.16518 -284.192726)
			(xy 87.337646 -284.491176) (xy 87.362284 -284.494478) (xy 87.387619 -284.498351) (xy 87.436923 -284.512334)
			(xy 87.483714 -284.533239) (xy 87.527026 -284.560634) (xy 87.565965 -284.593953) (xy 87.599727 -284.632509)
			(xy 87.627615 -284.675505) (xy 87.649053 -284.722055) (xy 87.663599 -284.771195) (xy 87.670952 -284.821914)
			(xy 87.671402 -284.847538) (xy 87.670904 -284.874187) (xy 87.662961 -284.926891) (xy 87.647251 -284.977821)
			(xy 87.624125 -285.025842) (xy 87.594101 -285.069879) (xy 87.557849 -285.10895) (xy 87.516178 -285.142181)
			(xy 87.47002 -285.16883) (xy 87.420406 -285.188302) (xy 87.368444 -285.200162) (xy 87.315294 -285.204146)
			(xy 87.262144 -285.200162) (xy 87.210182 -285.188302) (xy 87.160568 -285.16883) (xy 87.11441 -285.142181)
			(xy 87.072739 -285.10895) (xy 87.036487 -285.069879) (xy 87.006463 -285.025842) (xy 86.983337 -284.977821)
			(xy 86.967627 -284.926891) (xy 86.959684 -284.874187) (xy 86.959186 -284.847538) (xy 86.959568 -284.824293)
			(xy 86.965609 -284.778198) (xy 86.977595 -284.73328) (xy 86.98611 -284.711648) (xy 86.995762 -284.688534)
			(xy 86.823296 -284.390084) (xy 86.798658 -284.386782) (xy 86.773309 -284.382994) (xy 86.724002 -284.369)
			(xy 86.677209 -284.348085) (xy 86.633896 -284.32068) (xy 86.594957 -284.287351) (xy 86.561197 -284.248786)
			(xy 86.533311 -284.20578) (xy 86.511877 -284.159223) (xy 86.497335 -284.110074) (xy 86.489987 -284.059349)
			(xy 86.48954 -284.033722) (xy 85.52688 -284.033722) (xy 85.52688 -284.50159) (xy 85.5599 -284.513782)
			(xy 85.585886 -284.524035) (xy 85.634554 -284.551455) (xy 85.678343 -284.586138) (xy 85.716179 -284.627234)
			(xy 85.732112 -284.65018) (xy 86.079076 -284.65018) (xy 86.093297 -284.629583) (xy 86.126593 -284.592212)
			(xy 86.164795 -284.559872) (xy 86.207149 -284.5332) (xy 86.25282 -284.512722) (xy 86.300909 -284.498841)
			(xy 86.350468 -284.491832) (xy 86.375494 -284.49143) (xy 86.402143 -284.491903) (xy 86.454845 -284.499845)
			(xy 86.505774 -284.515554) (xy 86.553794 -284.538679) (xy 86.59783 -284.568701) (xy 86.6369 -284.604952)
			(xy 86.67013 -284.646622) (xy 86.696779 -284.692778) (xy 86.716251 -284.742391) (xy 86.728111 -284.794352)
			(xy 86.732094 -284.8475) (xy 86.728111 -284.900648) (xy 86.716251 -284.952609) (xy 86.696779 -285.002222)
			(xy 86.670131 -285.048378) (xy 86.6369 -285.090048) (xy 86.59783 -285.126299) (xy 86.553794 -285.156321)
			(xy 86.505774 -285.179446) (xy 86.454845 -285.195155) (xy 86.402143 -285.203097) (xy 86.375494 -285.203646)
			(xy 86.350469 -285.203221) (xy 86.300911 -285.196213) (xy 86.252823 -285.182335) (xy 86.207152 -285.161861)
			(xy 86.164796 -285.135195) (xy 86.126592 -285.102861) (xy 86.093291 -285.065496) (xy 86.079076 -285.044896)
			(xy 85.732112 -285.044896) (xy 85.716181 -285.067844) (xy 85.678345 -285.108942) (xy 85.634558 -285.14363)
			(xy 85.585893 -285.171057) (xy 85.5599 -285.181294) (xy 85.52688 -285.193486) (xy 85.52688 -285.297118)
			(xy 85.52733 -285.311252) (xy 85.535063 -285.33844) (xy 85.549958 -285.362464) (xy 85.570872 -285.38148)
			(xy 85.5962 -285.394029) (xy 85.624 -285.399147) (xy 85.652137 -285.396443) (xy 85.678452 -285.386123)
			(xy 85.689948 -285.37789) (xy 85.713354 -285.360811) (xy 85.764544 -285.333673) (xy 85.81945 -285.315174)
			(xy 85.876625 -285.305801) (xy 85.905594 -285.305246) (xy 85.932249 -285.305719) (xy 85.984963 -285.313664)
			(xy 86.035905 -285.329376) (xy 86.083936 -285.352506) (xy 86.127982 -285.382536) (xy 86.167062 -285.418795)
			(xy 86.2003 -285.460474) (xy 86.226955 -285.506642) (xy 86.246431 -285.556266) (xy 86.258294 -285.608239)
			(xy 86.262278 -285.6614) (xy 86.260284 -285.688003) (xy 86.489784 -285.688003) (xy 86.489784 -285.634705)
			(xy 86.497727 -285.582001) (xy 86.513437 -285.531071) (xy 86.536563 -285.48305) (xy 86.566587 -285.439013)
			(xy 86.602839 -285.399942) (xy 86.64451 -285.366711) (xy 86.690668 -285.340062) (xy 86.740282 -285.32059)
			(xy 86.792244 -285.30873) (xy 86.845394 -285.304747) (xy 86.898544 -285.30873) (xy 86.950506 -285.32059)
			(xy 87.00012 -285.340062) (xy 87.046278 -285.366711) (xy 87.087949 -285.399942) (xy 87.124201 -285.439013)
			(xy 87.154225 -285.48305) (xy 87.177351 -285.531071) (xy 87.193061 -285.582001) (xy 87.201004 -285.634705)
			(xy 87.201502 -285.661354) (xy 87.429086 -285.661354) (xy 87.429527 -285.635725) (xy 87.436856 -285.584993)
			(xy 87.451386 -285.535838) (xy 87.472814 -285.489274) (xy 87.500699 -285.446264) (xy 87.534464 -285.407699)
			(xy 87.573411 -285.374374) (xy 87.616735 -285.34698) (xy 87.663539 -285.326082) (xy 87.712857 -285.312113)
			(xy 87.738204 -285.308294) (xy 87.762842 -285.304992) (xy 87.935308 -285.006288) (xy 87.92591 -284.983174)
			(xy 87.917417 -284.961579) (xy 87.905441 -284.916747) (xy 87.89938 -284.87074) (xy 87.898986 -284.847538)
			(xy 87.899484 -284.820889) (xy 87.907427 -284.768185) (xy 87.923137 -284.717255) (xy 87.946263 -284.669234)
			(xy 87.976287 -284.625197) (xy 88.012539 -284.586126) (xy 88.05421 -284.552895) (xy 88.100368 -284.526246)
			(xy 88.149982 -284.506774) (xy 88.201944 -284.494914) (xy 88.255094 -284.490931) (xy 88.308244 -284.494914)
			(xy 88.360206 -284.506774) (xy 88.40982 -284.526246) (xy 88.455978 -284.552895) (xy 88.497649 -284.586126)
			(xy 88.533901 -284.625197) (xy 88.563925 -284.669234) (xy 88.587051 -284.717255) (xy 88.602761 -284.768185)
			(xy 88.610704 -284.820889) (xy 88.611202 -284.847538) (xy 88.610764 -284.873167) (xy 88.610617 -284.874187)
			(xy 88.839284 -284.874187) (xy 88.839284 -284.820889) (xy 88.847227 -284.768185) (xy 88.862937 -284.717255)
			(xy 88.886063 -284.669234) (xy 88.916087 -284.625197) (xy 88.952339 -284.586126) (xy 88.99401 -284.552895)
			(xy 89.040168 -284.526246) (xy 89.089782 -284.506774) (xy 89.141744 -284.494914) (xy 89.194894 -284.490931)
			(xy 89.248044 -284.494914) (xy 89.300006 -284.506774) (xy 89.34962 -284.526246) (xy 89.395778 -284.552895)
			(xy 89.437449 -284.586126) (xy 89.473701 -284.625197) (xy 89.503725 -284.669234) (xy 89.526851 -284.717255)
			(xy 89.542561 -284.768185) (xy 89.550504 -284.820889) (xy 89.551002 -284.847538) (xy 89.550504 -284.874187)
			(xy 89.542561 -284.926891) (xy 89.526851 -284.977821) (xy 89.503725 -285.025842) (xy 89.473701 -285.069879)
			(xy 89.437449 -285.10895) (xy 89.395778 -285.142181) (xy 89.34962 -285.16883) (xy 89.300006 -285.188302)
			(xy 89.248044 -285.200162) (xy 89.194894 -285.204146) (xy 89.141744 -285.200162) (xy 89.089782 -285.188302)
			(xy 89.040168 -285.16883) (xy 88.99401 -285.142181) (xy 88.952339 -285.10895) (xy 88.916087 -285.069879)
			(xy 88.886063 -285.025842) (xy 88.862937 -284.977821) (xy 88.847227 -284.926891) (xy 88.839284 -284.874187)
			(xy 88.610617 -284.874187) (xy 88.603435 -284.923899) (xy 88.588907 -284.973056) (xy 88.567478 -285.01962)
			(xy 88.539593 -285.06263) (xy 88.505827 -285.101196) (xy 88.46688 -285.13452) (xy 88.423555 -285.161915)
			(xy 88.37675 -285.182812) (xy 88.327431 -285.19678) (xy 88.302084 -285.200598) (xy 88.277446 -285.2039)
			(xy 88.10498 -285.502604) (xy 88.114378 -285.525718) (xy 88.122868 -285.547314) (xy 88.134845 -285.592146)
			(xy 88.140907 -285.638152) (xy 88.141302 -285.661354) (xy 88.140804 -285.688003) (xy 88.369384 -285.688003)
			(xy 88.369384 -285.634705) (xy 88.377327 -285.582001) (xy 88.393037 -285.531071) (xy 88.416163 -285.48305)
			(xy 88.446187 -285.439013) (xy 88.482439 -285.399942) (xy 88.52411 -285.366711) (xy 88.570268 -285.340062)
			(xy 88.619882 -285.32059) (xy 88.671844 -285.30873) (xy 88.724994 -285.304747) (xy 88.778144 -285.30873)
			(xy 88.830106 -285.32059) (xy 88.87972 -285.340062) (xy 88.925878 -285.366711) (xy 88.967549 -285.399942)
			(xy 89.003801 -285.439013) (xy 89.033825 -285.48305) (xy 89.056951 -285.531071) (xy 89.072661 -285.582001)
			(xy 89.080604 -285.634705) (xy 89.081102 -285.661354) (xy 89.308686 -285.661354) (xy 89.309184 -285.634705)
			(xy 89.317127 -285.582001) (xy 89.332837 -285.531071) (xy 89.355963 -285.48305) (xy 89.385987 -285.439013)
			(xy 89.422239 -285.399942) (xy 89.46391 -285.366711) (xy 89.510068 -285.340062) (xy 89.559682 -285.32059)
			(xy 89.611644 -285.30873) (xy 89.664794 -285.304747) (xy 89.717944 -285.30873) (xy 89.769906 -285.32059)
			(xy 89.81952 -285.340062) (xy 89.865678 -285.366711) (xy 89.907349 -285.399942) (xy 89.943601 -285.439013)
			(xy 89.973625 -285.48305) (xy 89.996751 -285.531071) (xy 90.012461 -285.582001) (xy 90.020404 -285.634705)
			(xy 90.020902 -285.661354) (xy 90.24874 -285.661354) (xy 90.249221 -285.635727) (xy 90.256549 -285.584999)
			(xy 90.271076 -285.535846) (xy 90.292501 -285.489285) (xy 90.320382 -285.446277) (xy 90.354142 -285.407712)
			(xy 90.393084 -285.374387) (xy 90.436402 -285.346991) (xy 90.483201 -285.32609) (xy 90.532513 -285.312115)
			(xy 90.557858 -285.308294) (xy 90.582496 -285.304992) (xy 90.754962 -285.006542) (xy 90.74531 -284.983428)
			(xy 90.736804 -284.961792) (xy 90.724813 -284.916876) (xy 90.718764 -284.870782) (xy 90.718386 -284.847538)
			(xy 90.718884 -284.820889) (xy 90.726827 -284.768185) (xy 90.742537 -284.717255) (xy 90.765663 -284.669234)
			(xy 90.795687 -284.625197) (xy 90.831939 -284.586126) (xy 90.87361 -284.552895) (xy 90.919768 -284.526246)
			(xy 90.969382 -284.506774) (xy 91.021344 -284.494914) (xy 91.074494 -284.490931) (xy 91.127644 -284.494914)
			(xy 91.179606 -284.506774) (xy 91.22922 -284.526246) (xy 91.275378 -284.552895) (xy 91.317049 -284.586126)
			(xy 91.353301 -284.625197) (xy 91.383325 -284.669234) (xy 91.406451 -284.717255) (xy 91.422161 -284.768185)
			(xy 91.430104 -284.820889) (xy 91.430602 -284.847538) (xy 91.430198 -284.873157) (xy 91.422876 -284.92387)
			(xy 91.40836 -284.973009) (xy 91.38695 -285.019559) (xy 91.359088 -285.06256) (xy 91.325349 -285.101122)
			(xy 91.286431 -285.13445) (xy 91.243138 -285.161855) (xy 91.196363 -285.18277) (xy 91.147073 -285.196764)
			(xy 91.121738 -285.200598) (xy 91.096846 -285.2039) (xy 90.92438 -285.50235) (xy 90.934032 -285.525464)
			(xy 90.942532 -285.547102) (xy 90.954526 -285.592017) (xy 90.960577 -285.63811) (xy 90.960956 -285.661354)
			(xy 91.18854 -285.661354) (xy 91.189038 -285.634705) (xy 91.196981 -285.582001) (xy 91.212691 -285.531071)
			(xy 91.235817 -285.48305) (xy 91.265841 -285.439013) (xy 91.302093 -285.399942) (xy 91.343764 -285.366711)
			(xy 91.389922 -285.340062) (xy 91.439536 -285.32059) (xy 91.491498 -285.30873) (xy 91.544648 -285.304747)
			(xy 91.597798 -285.30873) (xy 91.64976 -285.32059) (xy 91.699374 -285.340062) (xy 91.745532 -285.366711)
			(xy 91.787203 -285.399942) (xy 91.823455 -285.439013) (xy 91.853479 -285.48305) (xy 91.876605 -285.531071)
			(xy 91.892315 -285.582001) (xy 91.900258 -285.634705) (xy 91.900756 -285.661354) (xy 92.128086 -285.661354)
			(xy 92.128527 -285.635725) (xy 92.135856 -285.584993) (xy 92.150386 -285.535838) (xy 92.171814 -285.489274)
			(xy 92.199699 -285.446264) (xy 92.233464 -285.407699) (xy 92.272411 -285.374374) (xy 92.315735 -285.34698)
			(xy 92.362539 -285.326082) (xy 92.411857 -285.312113) (xy 92.437204 -285.308294) (xy 92.461842 -285.304992)
			(xy 92.634562 -285.006034) (xy 92.62491 -284.98292) (xy 92.616445 -284.961367) (xy 92.60456 -284.916612)
			(xy 92.59859 -284.870692) (xy 92.59824 -284.847538) (xy 92.598738 -284.820889) (xy 92.606681 -284.768185)
			(xy 92.622391 -284.717255) (xy 92.645517 -284.669234) (xy 92.675541 -284.625197) (xy 92.711793 -284.586126)
			(xy 92.753464 -284.552895) (xy 92.799622 -284.526246) (xy 92.849236 -284.506774) (xy 92.901198 -284.494914)
			(xy 92.954348 -284.490931) (xy 93.007498 -284.494914) (xy 93.05946 -284.506774) (xy 93.109074 -284.526246)
			(xy 93.155232 -284.552895) (xy 93.196903 -284.586126) (xy 93.233155 -284.625197) (xy 93.263179 -284.669234)
			(xy 93.286305 -284.717255) (xy 93.302015 -284.768185) (xy 93.309958 -284.820889) (xy 93.310456 -284.847538)
			(xy 93.310029 -284.873178) (xy 93.302682 -284.923929) (xy 93.28813 -284.973101) (xy 93.266675 -285.019677)
			(xy 93.23876 -285.062694) (xy 93.204964 -285.101261) (xy 93.165984 -285.134582) (xy 93.122628 -285.161966)
			(xy 93.075791 -285.182847) (xy 93.026444 -285.196793) (xy 93.001084 -285.200598) (xy 92.976192 -285.2039)
			(xy 92.803726 -285.50235) (xy 92.813378 -285.525464) (xy 92.821881 -285.547101) (xy 92.833873 -285.592016)
			(xy 92.839924 -285.63811) (xy 92.840302 -285.661354) (xy 93.067886 -285.661354) (xy 93.068384 -285.634705)
			(xy 93.076327 -285.582001) (xy 93.092037 -285.531071) (xy 93.115163 -285.48305) (xy 93.145187 -285.439013)
			(xy 93.181439 -285.399942) (xy 93.22311 -285.366711) (xy 93.269268 -285.340062) (xy 93.318882 -285.32059)
			(xy 93.370844 -285.30873) (xy 93.423994 -285.304747) (xy 93.477144 -285.30873) (xy 93.529106 -285.32059)
			(xy 93.57872 -285.340062) (xy 93.624878 -285.366711) (xy 93.666549 -285.399942) (xy 93.702801 -285.439013)
			(xy 93.732825 -285.48305) (xy 93.755951 -285.531071) (xy 93.771661 -285.582001) (xy 93.779604 -285.634705)
			(xy 93.780102 -285.661354) (xy 94.007686 -285.661354) (xy 94.008127 -285.635725) (xy 94.015456 -285.584993)
			(xy 94.029986 -285.535838) (xy 94.051414 -285.489274) (xy 94.079299 -285.446264) (xy 94.113064 -285.407699)
			(xy 94.152011 -285.374374) (xy 94.195335 -285.34698) (xy 94.242139 -285.326082) (xy 94.291457 -285.312113)
			(xy 94.316804 -285.308294) (xy 94.341442 -285.304992) (xy 94.514162 -285.006034) (xy 94.50451 -284.98292)
			(xy 94.496045 -284.961367) (xy 94.48416 -284.916612) (xy 94.47819 -284.870692) (xy 94.47784 -284.847538)
			(xy 94.478338 -284.820889) (xy 94.486281 -284.768185) (xy 94.501991 -284.717255) (xy 94.525117 -284.669234)
			(xy 94.555141 -284.625197) (xy 94.591393 -284.586126) (xy 94.633064 -284.552895) (xy 94.679222 -284.526246)
			(xy 94.728836 -284.506774) (xy 94.780798 -284.494914) (xy 94.833948 -284.490931) (xy 94.887098 -284.494914)
			(xy 94.93906 -284.506774) (xy 94.988674 -284.526246) (xy 95.034832 -284.552895) (xy 95.076503 -284.586126)
			(xy 95.112755 -284.625197) (xy 95.142779 -284.669234) (xy 95.165905 -284.717255) (xy 95.181615 -284.768185)
			(xy 95.189558 -284.820889) (xy 95.190056 -284.847538) (xy 95.189629 -284.873178) (xy 95.182282 -284.923929)
			(xy 95.16773 -284.973101) (xy 95.146275 -285.019677) (xy 95.11836 -285.062694) (xy 95.084564 -285.101261)
			(xy 95.045584 -285.134582) (xy 95.002228 -285.161966) (xy 94.955391 -285.182847) (xy 94.906044 -285.196793)
			(xy 94.880684 -285.200598) (xy 94.855792 -285.2039) (xy 94.683326 -285.50235) (xy 94.692978 -285.525464)
			(xy 94.701481 -285.547101) (xy 94.713473 -285.592016) (xy 94.719524 -285.63811) (xy 94.719902 -285.661354)
			(xy 94.947486 -285.661354) (xy 94.947984 -285.634705) (xy 94.955927 -285.582001) (xy 94.971637 -285.531071)
			(xy 94.994763 -285.48305) (xy 95.024787 -285.439013) (xy 95.061039 -285.399942) (xy 95.10271 -285.366711)
			(xy 95.148868 -285.340062) (xy 95.198482 -285.32059) (xy 95.250444 -285.30873) (xy 95.303594 -285.304747)
			(xy 95.356744 -285.30873) (xy 95.408706 -285.32059) (xy 95.45832 -285.340062) (xy 95.504478 -285.366711)
			(xy 95.546149 -285.399942) (xy 95.582401 -285.439013) (xy 95.612425 -285.48305) (xy 95.635551 -285.531071)
			(xy 95.651261 -285.582001) (xy 95.659204 -285.634705) (xy 95.659702 -285.661354) (xy 95.887286 -285.661354)
			(xy 95.887727 -285.635725) (xy 95.895056 -285.584993) (xy 95.909586 -285.535838) (xy 95.931014 -285.489274)
			(xy 95.958899 -285.446264) (xy 95.992664 -285.407699) (xy 96.031611 -285.374374) (xy 96.074935 -285.34698)
			(xy 96.121739 -285.326082) (xy 96.171057 -285.312113) (xy 96.196404 -285.308294) (xy 96.221042 -285.304992)
			(xy 96.393762 -285.006034) (xy 96.38411 -284.98292) (xy 96.375645 -284.961367) (xy 96.36376 -284.916612)
			(xy 96.35779 -284.870692) (xy 96.35744 -284.847538) (xy 96.357938 -284.820889) (xy 96.365881 -284.768185)
			(xy 96.381591 -284.717255) (xy 96.404717 -284.669234) (xy 96.434741 -284.625197) (xy 96.470993 -284.586126)
			(xy 96.512664 -284.552895) (xy 96.558822 -284.526246) (xy 96.608436 -284.506774) (xy 96.660398 -284.494914)
			(xy 96.713548 -284.490931) (xy 96.766698 -284.494914) (xy 96.81866 -284.506774) (xy 96.868274 -284.526246)
			(xy 96.914432 -284.552895) (xy 96.956103 -284.586126) (xy 96.992355 -284.625197) (xy 97.022379 -284.669234)
			(xy 97.045505 -284.717255) (xy 97.061215 -284.768185) (xy 97.069158 -284.820889) (xy 97.069656 -284.847538)
			(xy 97.069229 -284.873178) (xy 97.061882 -284.923929) (xy 97.04733 -284.973101) (xy 97.025875 -285.019677)
			(xy 96.99796 -285.062694) (xy 96.964164 -285.101261) (xy 96.925184 -285.134582) (xy 96.881828 -285.161966)
			(xy 96.834991 -285.182847) (xy 96.785644 -285.196793) (xy 96.760284 -285.200598) (xy 96.735392 -285.2039)
			(xy 96.562926 -285.50235) (xy 96.572578 -285.525464) (xy 96.581081 -285.547101) (xy 96.593073 -285.592016)
			(xy 96.599124 -285.63811) (xy 96.599502 -285.661354) (xy 96.827086 -285.661354) (xy 96.827584 -285.634705)
			(xy 96.835527 -285.582001) (xy 96.851237 -285.531071) (xy 96.874363 -285.48305) (xy 96.904387 -285.439013)
			(xy 96.940639 -285.399942) (xy 96.98231 -285.366711) (xy 97.028468 -285.340062) (xy 97.078082 -285.32059)
			(xy 97.130044 -285.30873) (xy 97.183194 -285.304747) (xy 97.236344 -285.30873) (xy 97.288306 -285.32059)
			(xy 97.33792 -285.340062) (xy 97.384078 -285.366711) (xy 97.425749 -285.399942) (xy 97.462001 -285.439013)
			(xy 97.492025 -285.48305) (xy 97.515151 -285.531071) (xy 97.530861 -285.582001) (xy 97.538804 -285.634705)
			(xy 97.539302 -285.661354) (xy 97.766886 -285.661354) (xy 97.767327 -285.635725) (xy 97.774656 -285.584993)
			(xy 97.789186 -285.535838) (xy 97.810614 -285.489274) (xy 97.838499 -285.446264) (xy 97.872264 -285.407699)
			(xy 97.911211 -285.374374) (xy 97.954535 -285.34698) (xy 98.001339 -285.326082) (xy 98.050657 -285.312113)
			(xy 98.076004 -285.308294) (xy 98.100642 -285.304992) (xy 98.273362 -285.006034) (xy 98.26371 -284.98292)
			(xy 98.255245 -284.961367) (xy 98.24336 -284.916612) (xy 98.23739 -284.870692) (xy 98.23704 -284.847538)
			(xy 98.237538 -284.820889) (xy 98.245481 -284.768185) (xy 98.261191 -284.717255) (xy 98.284317 -284.669234)
			(xy 98.314341 -284.625197) (xy 98.350593 -284.586126) (xy 98.392264 -284.552895) (xy 98.438422 -284.526246)
			(xy 98.488036 -284.506774) (xy 98.539998 -284.494914) (xy 98.593148 -284.490931) (xy 98.646298 -284.494914)
			(xy 98.69826 -284.506774) (xy 98.747874 -284.526246) (xy 98.794032 -284.552895) (xy 98.835703 -284.586126)
			(xy 98.871955 -284.625197) (xy 98.901979 -284.669234) (xy 98.925105 -284.717255) (xy 98.940815 -284.768185)
			(xy 98.948758 -284.820889) (xy 98.949256 -284.847538) (xy 98.948829 -284.873178) (xy 98.941482 -284.923929)
			(xy 98.92693 -284.973101) (xy 98.905475 -285.019677) (xy 98.87756 -285.062694) (xy 98.843764 -285.101261)
			(xy 98.804784 -285.134582) (xy 98.761428 -285.161966) (xy 98.714591 -285.182847) (xy 98.665244 -285.196793)
			(xy 98.639884 -285.200598) (xy 98.614992 -285.2039) (xy 98.442526 -285.50235) (xy 98.452178 -285.525464)
			(xy 98.460681 -285.547101) (xy 98.472673 -285.592016) (xy 98.478724 -285.63811) (xy 98.479102 -285.661354)
			(xy 98.706686 -285.661354) (xy 98.707184 -285.634705) (xy 98.715127 -285.582001) (xy 98.730837 -285.531071)
			(xy 98.753963 -285.48305) (xy 98.783987 -285.439013) (xy 98.820239 -285.399942) (xy 98.86191 -285.366711)
			(xy 98.908068 -285.340062) (xy 98.957682 -285.32059) (xy 99.009644 -285.30873) (xy 99.062794 -285.304747)
			(xy 99.115944 -285.30873) (xy 99.167906 -285.32059) (xy 99.21752 -285.340062) (xy 99.263678 -285.366711)
			(xy 99.305349 -285.399942) (xy 99.341601 -285.439013) (xy 99.371625 -285.48305) (xy 99.394751 -285.531071)
			(xy 99.410461 -285.582001) (xy 99.418404 -285.634705) (xy 99.418902 -285.661354) (xy 99.646486 -285.661354)
			(xy 99.646927 -285.635725) (xy 99.654256 -285.584993) (xy 99.668786 -285.535838) (xy 99.690214 -285.489274)
			(xy 99.718099 -285.446264) (xy 99.751864 -285.407699) (xy 99.790811 -285.374374) (xy 99.834135 -285.34698)
			(xy 99.880939 -285.326082) (xy 99.930257 -285.312113) (xy 99.955604 -285.308294) (xy 99.980242 -285.304992)
			(xy 100.152962 -285.006034) (xy 100.14331 -284.98292) (xy 100.134845 -284.961367) (xy 100.12296 -284.916612)
			(xy 100.11699 -284.870692) (xy 100.11664 -284.847538) (xy 100.117138 -284.820889) (xy 100.125081 -284.768185)
			(xy 100.140791 -284.717255) (xy 100.163917 -284.669234) (xy 100.193941 -284.625197) (xy 100.230193 -284.586126)
			(xy 100.271864 -284.552895) (xy 100.318022 -284.526246) (xy 100.367636 -284.506774) (xy 100.419598 -284.494914)
			(xy 100.472748 -284.490931) (xy 100.525898 -284.494914) (xy 100.57786 -284.506774) (xy 100.627474 -284.526246)
			(xy 100.673632 -284.552895) (xy 100.715303 -284.586126) (xy 100.751555 -284.625197) (xy 100.781579 -284.669234)
			(xy 100.804705 -284.717255) (xy 100.820415 -284.768185) (xy 100.828358 -284.820889) (xy 100.828856 -284.847538)
			(xy 100.828429 -284.873178) (xy 100.828283 -284.874187) (xy 101.056938 -284.874187) (xy 101.056938 -284.820889)
			(xy 101.064881 -284.768185) (xy 101.080591 -284.717255) (xy 101.103717 -284.669234) (xy 101.133741 -284.625197)
			(xy 101.169993 -284.586126) (xy 101.211664 -284.552895) (xy 101.257822 -284.526246) (xy 101.307436 -284.506774)
			(xy 101.359398 -284.494914) (xy 101.412548 -284.490931) (xy 101.465698 -284.494914) (xy 101.51766 -284.506774)
			(xy 101.567274 -284.526246) (xy 101.613432 -284.552895) (xy 101.655103 -284.586126) (xy 101.691355 -284.625197)
			(xy 101.721379 -284.669234) (xy 101.744505 -284.717255) (xy 101.760215 -284.768185) (xy 101.768158 -284.820889)
			(xy 101.768656 -284.847538) (xy 101.768158 -284.874187) (xy 101.760215 -284.926891) (xy 101.744505 -284.977821)
			(xy 101.721379 -285.025842) (xy 101.691355 -285.069879) (xy 101.655103 -285.10895) (xy 101.613432 -285.142181)
			(xy 101.567274 -285.16883) (xy 101.51766 -285.188302) (xy 101.465698 -285.200162) (xy 101.412548 -285.204146)
			(xy 101.359398 -285.200162) (xy 101.307436 -285.188302) (xy 101.257822 -285.16883) (xy 101.211664 -285.142181)
			(xy 101.169993 -285.10895) (xy 101.133741 -285.069879) (xy 101.103717 -285.025842) (xy 101.080591 -284.977821)
			(xy 101.064881 -284.926891) (xy 101.056938 -284.874187) (xy 100.828283 -284.874187) (xy 100.821082 -284.923929)
			(xy 100.80653 -284.973101) (xy 100.785075 -285.019677) (xy 100.75716 -285.062694) (xy 100.723364 -285.101261)
			(xy 100.684384 -285.134582) (xy 100.641028 -285.161966) (xy 100.594191 -285.182847) (xy 100.544844 -285.196793)
			(xy 100.519484 -285.200598) (xy 100.494592 -285.2039) (xy 100.322126 -285.50235) (xy 100.331778 -285.525464)
			(xy 100.340281 -285.547101) (xy 100.352273 -285.592016) (xy 100.358324 -285.63811) (xy 100.358702 -285.661354)
			(xy 100.586286 -285.661354) (xy 100.586784 -285.634705) (xy 100.594727 -285.582001) (xy 100.610437 -285.531071)
			(xy 100.633563 -285.48305) (xy 100.663587 -285.439013) (xy 100.699839 -285.399942) (xy 100.74151 -285.366711)
			(xy 100.787668 -285.340062) (xy 100.837282 -285.32059) (xy 100.889244 -285.30873) (xy 100.942394 -285.304747)
			(xy 100.995544 -285.30873) (xy 101.047506 -285.32059) (xy 101.09712 -285.340062) (xy 101.143278 -285.366711)
			(xy 101.184949 -285.399942) (xy 101.221201 -285.439013) (xy 101.251225 -285.48305) (xy 101.274351 -285.531071)
			(xy 101.290061 -285.582001) (xy 101.298004 -285.634705) (xy 101.298502 -285.661354) (xy 101.526086 -285.661354)
			(xy 101.526527 -285.635725) (xy 101.533856 -285.584993) (xy 101.548386 -285.535838) (xy 101.569814 -285.489274)
			(xy 101.597699 -285.446264) (xy 101.631464 -285.407699) (xy 101.670411 -285.374374) (xy 101.713735 -285.34698)
			(xy 101.760539 -285.326082) (xy 101.809857 -285.312113) (xy 101.835204 -285.308294) (xy 101.859842 -285.304992)
			(xy 102.032562 -285.006034) (xy 102.02291 -284.98292) (xy 102.014445 -284.961367) (xy 102.00256 -284.916612)
			(xy 101.99659 -284.870692) (xy 101.99624 -284.847538) (xy 101.996738 -284.820889) (xy 102.004681 -284.768185)
			(xy 102.020391 -284.717255) (xy 102.043517 -284.669234) (xy 102.073541 -284.625197) (xy 102.109793 -284.586126)
			(xy 102.151464 -284.552895) (xy 102.197622 -284.526246) (xy 102.247236 -284.506774) (xy 102.299198 -284.494914)
			(xy 102.352348 -284.490931) (xy 102.405498 -284.494914) (xy 102.45746 -284.506774) (xy 102.507074 -284.526246)
			(xy 102.553232 -284.552895) (xy 102.594903 -284.586126) (xy 102.631155 -284.625197) (xy 102.661179 -284.669234)
			(xy 102.684305 -284.717255) (xy 102.700015 -284.768185) (xy 102.707958 -284.820889) (xy 102.708456 -284.847538)
			(xy 102.708029 -284.873178) (xy 102.707883 -284.874187) (xy 102.936284 -284.874187) (xy 102.936284 -284.820889)
			(xy 102.944227 -284.768185) (xy 102.959937 -284.717255) (xy 102.983063 -284.669234) (xy 103.013087 -284.625197)
			(xy 103.049339 -284.586126) (xy 103.09101 -284.552895) (xy 103.137168 -284.526246) (xy 103.186782 -284.506774)
			(xy 103.238744 -284.494914) (xy 103.291894 -284.490931) (xy 103.345044 -284.494914) (xy 103.397006 -284.506774)
			(xy 103.44662 -284.526246) (xy 103.492778 -284.552895) (xy 103.534449 -284.586126) (xy 103.570701 -284.625197)
			(xy 103.600725 -284.669234) (xy 103.623851 -284.717255) (xy 103.639561 -284.768185) (xy 103.647504 -284.820889)
			(xy 103.648002 -284.847538) (xy 103.647504 -284.874187) (xy 103.639561 -284.926891) (xy 103.623851 -284.977821)
			(xy 103.600725 -285.025842) (xy 103.570701 -285.069879) (xy 103.534449 -285.10895) (xy 103.492778 -285.142181)
			(xy 103.44662 -285.16883) (xy 103.397006 -285.188302) (xy 103.345044 -285.200162) (xy 103.291894 -285.204146)
			(xy 103.238744 -285.200162) (xy 103.186782 -285.188302) (xy 103.137168 -285.16883) (xy 103.09101 -285.142181)
			(xy 103.049339 -285.10895) (xy 103.013087 -285.069879) (xy 102.983063 -285.025842) (xy 102.959937 -284.977821)
			(xy 102.944227 -284.926891) (xy 102.936284 -284.874187) (xy 102.707883 -284.874187) (xy 102.700682 -284.923929)
			(xy 102.68613 -284.973101) (xy 102.664675 -285.019677) (xy 102.63676 -285.062694) (xy 102.602964 -285.101261)
			(xy 102.563984 -285.134582) (xy 102.520628 -285.161966) (xy 102.473791 -285.182847) (xy 102.424444 -285.196793)
			(xy 102.399084 -285.200598) (xy 102.374192 -285.2039) (xy 102.201726 -285.50235) (xy 102.211378 -285.525464)
			(xy 102.219881 -285.547101) (xy 102.231873 -285.592016) (xy 102.237924 -285.63811) (xy 102.238302 -285.661354)
			(xy 102.465886 -285.661354) (xy 102.466384 -285.634705) (xy 102.474327 -285.582001) (xy 102.490037 -285.531071)
			(xy 102.513163 -285.48305) (xy 102.543187 -285.439013) (xy 102.579439 -285.399942) (xy 102.62111 -285.366711)
			(xy 102.667268 -285.340062) (xy 102.716882 -285.32059) (xy 102.768844 -285.30873) (xy 102.821994 -285.304747)
			(xy 102.875144 -285.30873) (xy 102.927106 -285.32059) (xy 102.97672 -285.340062) (xy 103.022878 -285.366711)
			(xy 103.064549 -285.399942) (xy 103.100801 -285.439013) (xy 103.130825 -285.48305) (xy 103.153951 -285.531071)
			(xy 103.169661 -285.582001) (xy 103.177604 -285.634705) (xy 103.178102 -285.661354) (xy 103.177706 -285.684557)
			(xy 103.171663 -285.730567) (xy 103.159685 -285.7754) (xy 103.151178 -285.79699) (xy 103.14178 -285.820104)
			(xy 103.3145 -286.119062) (xy 103.339138 -286.122364) (xy 103.364477 -286.126208) (xy 103.41378 -286.140198)
			(xy 103.46057 -286.161108) (xy 103.503881 -286.188508) (xy 103.542818 -286.221831) (xy 103.576579 -286.260389)
			(xy 103.604466 -286.303387) (xy 103.625904 -286.349938) (xy 103.640451 -286.39908) (xy 103.647805 -286.449799)
			(xy 103.648256 -286.475424) (xy 103.647758 -286.502073) (xy 103.639815 -286.554777) (xy 103.624105 -286.605707)
			(xy 103.600979 -286.653728) (xy 103.570955 -286.697765) (xy 103.534703 -286.736836) (xy 103.493032 -286.770067)
			(xy 103.446874 -286.796716) (xy 103.39726 -286.816188) (xy 103.345298 -286.828048) (xy 103.292148 -286.832032)
			(xy 103.238998 -286.828048) (xy 103.187036 -286.816188) (xy 103.137422 -286.796716) (xy 103.091264 -286.770067)
			(xy 103.049593 -286.736836) (xy 103.013341 -286.697765) (xy 102.983317 -286.653728) (xy 102.960191 -286.605707)
			(xy 102.944481 -286.554777) (xy 102.936538 -286.502073) (xy 102.93604 -286.475424) (xy 102.936414 -286.452179)
			(xy 102.942458 -286.406083) (xy 102.954447 -286.361166) (xy 102.962964 -286.339534) (xy 102.972616 -286.31642)
			(xy 102.799896 -286.017716) (xy 102.775258 -286.014414) (xy 102.749901 -286.010607) (xy 102.700563 -285.996646)
			(xy 102.653737 -285.975755) (xy 102.61039 -285.948366) (xy 102.571418 -285.915045) (xy 102.537626 -285.87648)
			(xy 102.509713 -285.833469) (xy 102.488255 -285.7869) (xy 102.473695 -285.737735) (xy 102.466336 -285.686991)
			(xy 102.465886 -285.661354) (xy 102.238302 -285.661354) (xy 102.237804 -285.688003) (xy 102.229861 -285.740707)
			(xy 102.214151 -285.791637) (xy 102.191025 -285.839658) (xy 102.161001 -285.883695) (xy 102.124749 -285.922766)
			(xy 102.083078 -285.955997) (xy 102.03692 -285.982646) (xy 101.987306 -286.002118) (xy 101.935344 -286.013978)
			(xy 101.882194 -286.017962) (xy 101.829044 -286.013978) (xy 101.777082 -286.002118) (xy 101.727468 -285.982646)
			(xy 101.68131 -285.955997) (xy 101.639639 -285.922766) (xy 101.603387 -285.883695) (xy 101.573363 -285.839658)
			(xy 101.550237 -285.791637) (xy 101.534527 -285.740707) (xy 101.526584 -285.688003) (xy 101.526086 -285.661354)
			(xy 101.298502 -285.661354) (xy 101.298106 -285.684557) (xy 101.292063 -285.730567) (xy 101.280085 -285.7754)
			(xy 101.271578 -285.79699) (xy 101.26218 -285.820104) (xy 101.4349 -286.119062) (xy 101.459538 -286.122364)
			(xy 101.484877 -286.126208) (xy 101.53418 -286.140198) (xy 101.58097 -286.161108) (xy 101.624281 -286.188508)
			(xy 101.663218 -286.221831) (xy 101.696979 -286.260389) (xy 101.724866 -286.303387) (xy 101.746304 -286.349938)
			(xy 101.760851 -286.39908) (xy 101.768205 -286.449799) (xy 101.768656 -286.475424) (xy 101.768158 -286.502073)
			(xy 101.996484 -286.502073) (xy 101.996484 -286.448775) (xy 102.004427 -286.396071) (xy 102.020137 -286.345141)
			(xy 102.043263 -286.29712) (xy 102.073287 -286.253083) (xy 102.109539 -286.214012) (xy 102.15121 -286.180781)
			(xy 102.197368 -286.154132) (xy 102.246982 -286.13466) (xy 102.298944 -286.1228) (xy 102.352094 -286.118817)
			(xy 102.405244 -286.1228) (xy 102.457206 -286.13466) (xy 102.50682 -286.154132) (xy 102.552978 -286.180781)
			(xy 102.594649 -286.214012) (xy 102.630901 -286.253083) (xy 102.660925 -286.29712) (xy 102.684051 -286.345141)
			(xy 102.699761 -286.396071) (xy 102.707704 -286.448775) (xy 102.708202 -286.475424) (xy 102.707704 -286.502073)
			(xy 102.699761 -286.554777) (xy 102.684051 -286.605707) (xy 102.660925 -286.653728) (xy 102.630901 -286.697765)
			(xy 102.594649 -286.736836) (xy 102.552978 -286.770067) (xy 102.50682 -286.796716) (xy 102.457206 -286.816188)
			(xy 102.405244 -286.828048) (xy 102.352094 -286.832032) (xy 102.298944 -286.828048) (xy 102.246982 -286.816188)
			(xy 102.197368 -286.796716) (xy 102.15121 -286.770067) (xy 102.109539 -286.736836) (xy 102.073287 -286.697765)
			(xy 102.043263 -286.653728) (xy 102.020137 -286.605707) (xy 102.004427 -286.554777) (xy 101.996484 -286.502073)
			(xy 101.768158 -286.502073) (xy 101.760215 -286.554777) (xy 101.744505 -286.605707) (xy 101.721379 -286.653728)
			(xy 101.691355 -286.697765) (xy 101.655103 -286.736836) (xy 101.613432 -286.770067) (xy 101.567274 -286.796716)
			(xy 101.51766 -286.816188) (xy 101.465698 -286.828048) (xy 101.412548 -286.832032) (xy 101.359398 -286.828048)
			(xy 101.307436 -286.816188) (xy 101.257822 -286.796716) (xy 101.211664 -286.770067) (xy 101.169993 -286.736836)
			(xy 101.133741 -286.697765) (xy 101.103717 -286.653728) (xy 101.080591 -286.605707) (xy 101.064881 -286.554777)
			(xy 101.056938 -286.502073) (xy 101.05644 -286.475424) (xy 101.056814 -286.452179) (xy 101.062858 -286.406083)
			(xy 101.074847 -286.361166) (xy 101.083364 -286.339534) (xy 101.093016 -286.31642) (xy 100.920296 -286.017716)
			(xy 100.895658 -286.014414) (xy 100.870301 -286.010607) (xy 100.820963 -285.996646) (xy 100.774137 -285.975755)
			(xy 100.73079 -285.948366) (xy 100.691818 -285.915045) (xy 100.658026 -285.87648) (xy 100.630113 -285.833469)
			(xy 100.608655 -285.7869) (xy 100.594095 -285.737735) (xy 100.586736 -285.686991) (xy 100.586286 -285.661354)
			(xy 100.358702 -285.661354) (xy 100.358204 -285.688003) (xy 100.350261 -285.740707) (xy 100.334551 -285.791637)
			(xy 100.311425 -285.839658) (xy 100.281401 -285.883695) (xy 100.245149 -285.922766) (xy 100.203478 -285.955997)
			(xy 100.15732 -285.982646) (xy 100.107706 -286.002118) (xy 100.055744 -286.013978) (xy 100.002594 -286.017962)
			(xy 99.949444 -286.013978) (xy 99.897482 -286.002118) (xy 99.847868 -285.982646) (xy 99.80171 -285.955997)
			(xy 99.760039 -285.922766) (xy 99.723787 -285.883695) (xy 99.693763 -285.839658) (xy 99.670637 -285.791637)
			(xy 99.654927 -285.740707) (xy 99.646984 -285.688003) (xy 99.646486 -285.661354) (xy 99.418902 -285.661354)
			(xy 99.418506 -285.684557) (xy 99.412463 -285.730567) (xy 99.400485 -285.7754) (xy 99.391978 -285.79699)
			(xy 99.38258 -285.820104) (xy 99.5553 -286.119062) (xy 99.579938 -286.122364) (xy 99.605277 -286.126208)
			(xy 99.65458 -286.140198) (xy 99.70137 -286.161108) (xy 99.744681 -286.188508) (xy 99.783618 -286.221831)
			(xy 99.817379 -286.260389) (xy 99.845266 -286.303387) (xy 99.866704 -286.349938) (xy 99.881251 -286.39908)
			(xy 99.888605 -286.449799) (xy 99.889056 -286.475424) (xy 99.888558 -286.502073) (xy 100.116884 -286.502073)
			(xy 100.116884 -286.448775) (xy 100.124827 -286.396071) (xy 100.140537 -286.345141) (xy 100.163663 -286.29712)
			(xy 100.193687 -286.253083) (xy 100.229939 -286.214012) (xy 100.27161 -286.180781) (xy 100.317768 -286.154132)
			(xy 100.367382 -286.13466) (xy 100.419344 -286.1228) (xy 100.472494 -286.118817) (xy 100.525644 -286.1228)
			(xy 100.577606 -286.13466) (xy 100.62722 -286.154132) (xy 100.673378 -286.180781) (xy 100.715049 -286.214012)
			(xy 100.751301 -286.253083) (xy 100.781325 -286.29712) (xy 100.804451 -286.345141) (xy 100.820161 -286.396071)
			(xy 100.828104 -286.448775) (xy 100.828602 -286.475424) (xy 100.828104 -286.502073) (xy 100.820161 -286.554777)
			(xy 100.804451 -286.605707) (xy 100.781325 -286.653728) (xy 100.751301 -286.697765) (xy 100.715049 -286.736836)
			(xy 100.673378 -286.770067) (xy 100.62722 -286.796716) (xy 100.577606 -286.816188) (xy 100.525644 -286.828048)
			(xy 100.472494 -286.832032) (xy 100.419344 -286.828048) (xy 100.367382 -286.816188) (xy 100.317768 -286.796716)
			(xy 100.27161 -286.770067) (xy 100.229939 -286.736836) (xy 100.193687 -286.697765) (xy 100.163663 -286.653728)
			(xy 100.140537 -286.605707) (xy 100.124827 -286.554777) (xy 100.116884 -286.502073) (xy 99.888558 -286.502073)
			(xy 99.880615 -286.554777) (xy 99.864905 -286.605707) (xy 99.841779 -286.653728) (xy 99.811755 -286.697765)
			(xy 99.775503 -286.736836) (xy 99.733832 -286.770067) (xy 99.687674 -286.796716) (xy 99.63806 -286.816188)
			(xy 99.586098 -286.828048) (xy 99.532948 -286.832032) (xy 99.479798 -286.828048) (xy 99.427836 -286.816188)
			(xy 99.378222 -286.796716) (xy 99.332064 -286.770067) (xy 99.290393 -286.736836) (xy 99.254141 -286.697765)
			(xy 99.224117 -286.653728) (xy 99.200991 -286.605707) (xy 99.185281 -286.554777) (xy 99.177338 -286.502073)
			(xy 99.17684 -286.475424) (xy 99.177214 -286.452179) (xy 99.183258 -286.406083) (xy 99.195247 -286.361166)
			(xy 99.203764 -286.339534) (xy 99.213416 -286.31642) (xy 99.040696 -286.017716) (xy 99.016058 -286.014414)
			(xy 98.990701 -286.010607) (xy 98.941363 -285.996646) (xy 98.894537 -285.975755) (xy 98.85119 -285.948366)
			(xy 98.812218 -285.915045) (xy 98.778426 -285.87648) (xy 98.750513 -285.833469) (xy 98.729055 -285.7869)
			(xy 98.714495 -285.737735) (xy 98.707136 -285.686991) (xy 98.706686 -285.661354) (xy 98.479102 -285.661354)
			(xy 98.478604 -285.688003) (xy 98.470661 -285.740707) (xy 98.454951 -285.791637) (xy 98.431825 -285.839658)
			(xy 98.401801 -285.883695) (xy 98.365549 -285.922766) (xy 98.323878 -285.955997) (xy 98.27772 -285.982646)
			(xy 98.228106 -286.002118) (xy 98.176144 -286.013978) (xy 98.122994 -286.017962) (xy 98.069844 -286.013978)
			(xy 98.017882 -286.002118) (xy 97.968268 -285.982646) (xy 97.92211 -285.955997) (xy 97.880439 -285.922766)
			(xy 97.844187 -285.883695) (xy 97.814163 -285.839658) (xy 97.791037 -285.791637) (xy 97.775327 -285.740707)
			(xy 97.767384 -285.688003) (xy 97.766886 -285.661354) (xy 97.539302 -285.661354) (xy 97.538906 -285.684557)
			(xy 97.532863 -285.730567) (xy 97.520885 -285.7754) (xy 97.512378 -285.79699) (xy 97.50298 -285.820104)
			(xy 97.6757 -286.119062) (xy 97.700338 -286.122364) (xy 97.725677 -286.126208) (xy 97.77498 -286.140198)
			(xy 97.82177 -286.161108) (xy 97.865081 -286.188508) (xy 97.904018 -286.221831) (xy 97.937779 -286.260389)
			(xy 97.965666 -286.303387) (xy 97.987104 -286.349938) (xy 98.001651 -286.39908) (xy 98.009005 -286.449799)
			(xy 98.009456 -286.475424) (xy 98.008958 -286.502073) (xy 98.237284 -286.502073) (xy 98.237284 -286.448775)
			(xy 98.245227 -286.396071) (xy 98.260937 -286.345141) (xy 98.284063 -286.29712) (xy 98.314087 -286.253083)
			(xy 98.350339 -286.214012) (xy 98.39201 -286.180781) (xy 98.438168 -286.154132) (xy 98.487782 -286.13466)
			(xy 98.539744 -286.1228) (xy 98.592894 -286.118817) (xy 98.646044 -286.1228) (xy 98.698006 -286.13466)
			(xy 98.74762 -286.154132) (xy 98.793778 -286.180781) (xy 98.835449 -286.214012) (xy 98.871701 -286.253083)
			(xy 98.901725 -286.29712) (xy 98.924851 -286.345141) (xy 98.940561 -286.396071) (xy 98.948504 -286.448775)
			(xy 98.949002 -286.475424) (xy 98.948504 -286.502073) (xy 98.940561 -286.554777) (xy 98.924851 -286.605707)
			(xy 98.901725 -286.653728) (xy 98.871701 -286.697765) (xy 98.835449 -286.736836) (xy 98.793778 -286.770067)
			(xy 98.74762 -286.796716) (xy 98.698006 -286.816188) (xy 98.646044 -286.828048) (xy 98.592894 -286.832032)
			(xy 98.539744 -286.828048) (xy 98.487782 -286.816188) (xy 98.438168 -286.796716) (xy 98.39201 -286.770067)
			(xy 98.350339 -286.736836) (xy 98.314087 -286.697765) (xy 98.284063 -286.653728) (xy 98.260937 -286.605707)
			(xy 98.245227 -286.554777) (xy 98.237284 -286.502073) (xy 98.008958 -286.502073) (xy 98.001015 -286.554777)
			(xy 97.985305 -286.605707) (xy 97.962179 -286.653728) (xy 97.932155 -286.697765) (xy 97.895903 -286.736836)
			(xy 97.854232 -286.770067) (xy 97.808074 -286.796716) (xy 97.75846 -286.816188) (xy 97.706498 -286.828048)
			(xy 97.653348 -286.832032) (xy 97.600198 -286.828048) (xy 97.548236 -286.816188) (xy 97.498622 -286.796716)
			(xy 97.452464 -286.770067) (xy 97.410793 -286.736836) (xy 97.374541 -286.697765) (xy 97.344517 -286.653728)
			(xy 97.321391 -286.605707) (xy 97.305681 -286.554777) (xy 97.297738 -286.502073) (xy 97.29724 -286.475424)
			(xy 97.297614 -286.452179) (xy 97.303658 -286.406083) (xy 97.315647 -286.361166) (xy 97.324164 -286.339534)
			(xy 97.333816 -286.31642) (xy 97.161096 -286.017716) (xy 97.136458 -286.014414) (xy 97.111101 -286.010607)
			(xy 97.061763 -285.996646) (xy 97.014937 -285.975755) (xy 96.97159 -285.948366) (xy 96.932618 -285.915045)
			(xy 96.898826 -285.87648) (xy 96.870913 -285.833469) (xy 96.849455 -285.7869) (xy 96.834895 -285.737735)
			(xy 96.827536 -285.686991) (xy 96.827086 -285.661354) (xy 96.599502 -285.661354) (xy 96.599004 -285.688003)
			(xy 96.591061 -285.740707) (xy 96.575351 -285.791637) (xy 96.552225 -285.839658) (xy 96.522201 -285.883695)
			(xy 96.485949 -285.922766) (xy 96.444278 -285.955997) (xy 96.39812 -285.982646) (xy 96.348506 -286.002118)
			(xy 96.296544 -286.013978) (xy 96.243394 -286.017962) (xy 96.190244 -286.013978) (xy 96.138282 -286.002118)
			(xy 96.088668 -285.982646) (xy 96.04251 -285.955997) (xy 96.000839 -285.922766) (xy 95.964587 -285.883695)
			(xy 95.934563 -285.839658) (xy 95.911437 -285.791637) (xy 95.895727 -285.740707) (xy 95.887784 -285.688003)
			(xy 95.887286 -285.661354) (xy 95.659702 -285.661354) (xy 95.659306 -285.684557) (xy 95.653263 -285.730567)
			(xy 95.641285 -285.7754) (xy 95.632778 -285.79699) (xy 95.62338 -285.820104) (xy 95.7961 -286.119062)
			(xy 95.820738 -286.122364) (xy 95.846077 -286.126208) (xy 95.89538 -286.140198) (xy 95.94217 -286.161108)
			(xy 95.985481 -286.188508) (xy 96.024418 -286.221831) (xy 96.058179 -286.260389) (xy 96.086066 -286.303387)
			(xy 96.107504 -286.349938) (xy 96.122051 -286.39908) (xy 96.129405 -286.449799) (xy 96.129856 -286.475424)
			(xy 96.129358 -286.502073) (xy 96.357684 -286.502073) (xy 96.357684 -286.448775) (xy 96.365627 -286.396071)
			(xy 96.381337 -286.345141) (xy 96.404463 -286.29712) (xy 96.434487 -286.253083) (xy 96.470739 -286.214012)
			(xy 96.51241 -286.180781) (xy 96.558568 -286.154132) (xy 96.608182 -286.13466) (xy 96.660144 -286.1228)
			(xy 96.713294 -286.118817) (xy 96.766444 -286.1228) (xy 96.818406 -286.13466) (xy 96.86802 -286.154132)
			(xy 96.914178 -286.180781) (xy 96.955849 -286.214012) (xy 96.992101 -286.253083) (xy 97.022125 -286.29712)
			(xy 97.045251 -286.345141) (xy 97.060961 -286.396071) (xy 97.068904 -286.448775) (xy 97.069402 -286.475424)
			(xy 97.068904 -286.502073) (xy 97.060961 -286.554777) (xy 97.045251 -286.605707) (xy 97.022125 -286.653728)
			(xy 96.992101 -286.697765) (xy 96.955849 -286.736836) (xy 96.914178 -286.770067) (xy 96.86802 -286.796716)
			(xy 96.818406 -286.816188) (xy 96.766444 -286.828048) (xy 96.713294 -286.832032) (xy 96.660144 -286.828048)
			(xy 96.608182 -286.816188) (xy 96.558568 -286.796716) (xy 96.51241 -286.770067) (xy 96.470739 -286.736836)
			(xy 96.434487 -286.697765) (xy 96.404463 -286.653728) (xy 96.381337 -286.605707) (xy 96.365627 -286.554777)
			(xy 96.357684 -286.502073) (xy 96.129358 -286.502073) (xy 96.121415 -286.554777) (xy 96.105705 -286.605707)
			(xy 96.082579 -286.653728) (xy 96.052555 -286.697765) (xy 96.016303 -286.736836) (xy 95.974632 -286.770067)
			(xy 95.928474 -286.796716) (xy 95.87886 -286.816188) (xy 95.826898 -286.828048) (xy 95.773748 -286.832032)
			(xy 95.720598 -286.828048) (xy 95.668636 -286.816188) (xy 95.619022 -286.796716) (xy 95.572864 -286.770067)
			(xy 95.531193 -286.736836) (xy 95.494941 -286.697765) (xy 95.464917 -286.653728) (xy 95.441791 -286.605707)
			(xy 95.426081 -286.554777) (xy 95.418138 -286.502073) (xy 95.41764 -286.475424) (xy 95.418014 -286.452179)
			(xy 95.424058 -286.406083) (xy 95.436047 -286.361166) (xy 95.444564 -286.339534) (xy 95.454216 -286.31642)
			(xy 95.281496 -286.017716) (xy 95.256858 -286.014414) (xy 95.231501 -286.010607) (xy 95.182163 -285.996646)
			(xy 95.135337 -285.975755) (xy 95.09199 -285.948366) (xy 95.053018 -285.915045) (xy 95.019226 -285.87648)
			(xy 94.991313 -285.833469) (xy 94.969855 -285.7869) (xy 94.955295 -285.737735) (xy 94.947936 -285.686991)
			(xy 94.947486 -285.661354) (xy 94.719902 -285.661354) (xy 94.719404 -285.688003) (xy 94.711461 -285.740707)
			(xy 94.695751 -285.791637) (xy 94.672625 -285.839658) (xy 94.642601 -285.883695) (xy 94.606349 -285.922766)
			(xy 94.564678 -285.955997) (xy 94.51852 -285.982646) (xy 94.468906 -286.002118) (xy 94.416944 -286.013978)
			(xy 94.363794 -286.017962) (xy 94.310644 -286.013978) (xy 94.258682 -286.002118) (xy 94.209068 -285.982646)
			(xy 94.16291 -285.955997) (xy 94.121239 -285.922766) (xy 94.084987 -285.883695) (xy 94.054963 -285.839658)
			(xy 94.031837 -285.791637) (xy 94.016127 -285.740707) (xy 94.008184 -285.688003) (xy 94.007686 -285.661354)
			(xy 93.780102 -285.661354) (xy 93.779706 -285.684557) (xy 93.773663 -285.730567) (xy 93.761685 -285.7754)
			(xy 93.753178 -285.79699) (xy 93.74378 -285.820104) (xy 93.9165 -286.119062) (xy 93.941138 -286.122364)
			(xy 93.966477 -286.126208) (xy 94.01578 -286.140198) (xy 94.06257 -286.161108) (xy 94.105881 -286.188508)
			(xy 94.144818 -286.221831) (xy 94.178579 -286.260389) (xy 94.206466 -286.303387) (xy 94.227904 -286.349938)
			(xy 94.242451 -286.39908) (xy 94.249805 -286.449799) (xy 94.250256 -286.475424) (xy 94.249758 -286.502073)
			(xy 94.478084 -286.502073) (xy 94.478084 -286.448775) (xy 94.486027 -286.396071) (xy 94.501737 -286.345141)
			(xy 94.524863 -286.29712) (xy 94.554887 -286.253083) (xy 94.591139 -286.214012) (xy 94.63281 -286.180781)
			(xy 94.678968 -286.154132) (xy 94.728582 -286.13466) (xy 94.780544 -286.1228) (xy 94.833694 -286.118817)
			(xy 94.886844 -286.1228) (xy 94.938806 -286.13466) (xy 94.98842 -286.154132) (xy 95.034578 -286.180781)
			(xy 95.076249 -286.214012) (xy 95.112501 -286.253083) (xy 95.142525 -286.29712) (xy 95.165651 -286.345141)
			(xy 95.181361 -286.396071) (xy 95.189304 -286.448775) (xy 95.189802 -286.475424) (xy 95.189304 -286.502073)
			(xy 95.181361 -286.554777) (xy 95.165651 -286.605707) (xy 95.142525 -286.653728) (xy 95.112501 -286.697765)
			(xy 95.076249 -286.736836) (xy 95.034578 -286.770067) (xy 94.98842 -286.796716) (xy 94.938806 -286.816188)
			(xy 94.886844 -286.828048) (xy 94.833694 -286.832032) (xy 94.780544 -286.828048) (xy 94.728582 -286.816188)
			(xy 94.678968 -286.796716) (xy 94.63281 -286.770067) (xy 94.591139 -286.736836) (xy 94.554887 -286.697765)
			(xy 94.524863 -286.653728) (xy 94.501737 -286.605707) (xy 94.486027 -286.554777) (xy 94.478084 -286.502073)
			(xy 94.249758 -286.502073) (xy 94.241815 -286.554777) (xy 94.226105 -286.605707) (xy 94.202979 -286.653728)
			(xy 94.172955 -286.697765) (xy 94.136703 -286.736836) (xy 94.095032 -286.770067) (xy 94.048874 -286.796716)
			(xy 93.99926 -286.816188) (xy 93.947298 -286.828048) (xy 93.894148 -286.832032) (xy 93.840998 -286.828048)
			(xy 93.789036 -286.816188) (xy 93.739422 -286.796716) (xy 93.693264 -286.770067) (xy 93.651593 -286.736836)
			(xy 93.615341 -286.697765) (xy 93.585317 -286.653728) (xy 93.562191 -286.605707) (xy 93.546481 -286.554777)
			(xy 93.538538 -286.502073) (xy 93.53804 -286.475424) (xy 93.538414 -286.452179) (xy 93.544458 -286.406083)
			(xy 93.556447 -286.361166) (xy 93.564964 -286.339534) (xy 93.574616 -286.31642) (xy 93.401896 -286.017716)
			(xy 93.377258 -286.014414) (xy 93.351901 -286.010607) (xy 93.302563 -285.996646) (xy 93.255737 -285.975755)
			(xy 93.21239 -285.948366) (xy 93.173418 -285.915045) (xy 93.139626 -285.87648) (xy 93.111713 -285.833469)
			(xy 93.090255 -285.7869) (xy 93.075695 -285.737735) (xy 93.068336 -285.686991) (xy 93.067886 -285.661354)
			(xy 92.840302 -285.661354) (xy 92.839804 -285.688003) (xy 92.831861 -285.740707) (xy 92.816151 -285.791637)
			(xy 92.793025 -285.839658) (xy 92.763001 -285.883695) (xy 92.726749 -285.922766) (xy 92.685078 -285.955997)
			(xy 92.63892 -285.982646) (xy 92.589306 -286.002118) (xy 92.537344 -286.013978) (xy 92.484194 -286.017962)
			(xy 92.431044 -286.013978) (xy 92.379082 -286.002118) (xy 92.329468 -285.982646) (xy 92.28331 -285.955997)
			(xy 92.241639 -285.922766) (xy 92.205387 -285.883695) (xy 92.175363 -285.839658) (xy 92.152237 -285.791637)
			(xy 92.136527 -285.740707) (xy 92.128584 -285.688003) (xy 92.128086 -285.661354) (xy 91.900756 -285.661354)
			(xy 91.900375 -285.684599) (xy 91.894334 -285.730694) (xy 91.882348 -285.775612) (xy 91.873832 -285.797244)
			(xy 91.86418 -285.820358) (xy 92.0369 -286.119062) (xy 92.061538 -286.122364) (xy 92.086877 -286.126208)
			(xy 92.13618 -286.140198) (xy 92.18297 -286.161108) (xy 92.226281 -286.188508) (xy 92.265218 -286.221831)
			(xy 92.298979 -286.260389) (xy 92.326866 -286.303387) (xy 92.348304 -286.349938) (xy 92.362851 -286.39908)
			(xy 92.370205 -286.449799) (xy 92.370656 -286.475424) (xy 92.370158 -286.502073) (xy 92.598738 -286.502073)
			(xy 92.598738 -286.448775) (xy 92.606681 -286.396071) (xy 92.622391 -286.345141) (xy 92.645517 -286.29712)
			(xy 92.675541 -286.253083) (xy 92.711793 -286.214012) (xy 92.753464 -286.180781) (xy 92.799622 -286.154132)
			(xy 92.849236 -286.13466) (xy 92.901198 -286.1228) (xy 92.954348 -286.118817) (xy 93.007498 -286.1228)
			(xy 93.05946 -286.13466) (xy 93.109074 -286.154132) (xy 93.155232 -286.180781) (xy 93.196903 -286.214012)
			(xy 93.233155 -286.253083) (xy 93.263179 -286.29712) (xy 93.286305 -286.345141) (xy 93.302015 -286.396071)
			(xy 93.309958 -286.448775) (xy 93.310456 -286.475424) (xy 93.309958 -286.502073) (xy 93.302015 -286.554777)
			(xy 93.286305 -286.605707) (xy 93.263179 -286.653728) (xy 93.233155 -286.697765) (xy 93.196903 -286.736836)
			(xy 93.155232 -286.770067) (xy 93.109074 -286.796716) (xy 93.05946 -286.816188) (xy 93.007498 -286.828048)
			(xy 92.954348 -286.832032) (xy 92.901198 -286.828048) (xy 92.849236 -286.816188) (xy 92.799622 -286.796716)
			(xy 92.753464 -286.770067) (xy 92.711793 -286.736836) (xy 92.675541 -286.697765) (xy 92.645517 -286.653728)
			(xy 92.622391 -286.605707) (xy 92.606681 -286.554777) (xy 92.598738 -286.502073) (xy 92.370158 -286.502073)
			(xy 92.362215 -286.554777) (xy 92.346505 -286.605707) (xy 92.323379 -286.653728) (xy 92.293355 -286.697765)
			(xy 92.257103 -286.736836) (xy 92.215432 -286.770067) (xy 92.169274 -286.796716) (xy 92.11966 -286.816188)
			(xy 92.067698 -286.828048) (xy 92.014548 -286.832032) (xy 91.961398 -286.828048) (xy 91.909436 -286.816188)
			(xy 91.859822 -286.796716) (xy 91.813664 -286.770067) (xy 91.771993 -286.736836) (xy 91.735741 -286.697765)
			(xy 91.705717 -286.653728) (xy 91.682591 -286.605707) (xy 91.666881 -286.554777) (xy 91.658938 -286.502073)
			(xy 91.65844 -286.475424) (xy 91.658814 -286.452179) (xy 91.664858 -286.406083) (xy 91.676847 -286.361166)
			(xy 91.685364 -286.339534) (xy 91.695016 -286.31642) (xy 91.522296 -286.017716) (xy 91.497658 -286.014414)
			(xy 91.472315 -286.010595) (xy 91.42301 -285.996603) (xy 91.376218 -285.97569) (xy 91.332907 -285.948288)
			(xy 91.293969 -285.914963) (xy 91.260208 -285.876401) (xy 91.232322 -285.8334) (xy 91.210885 -285.786847)
			(xy 91.196341 -285.737702) (xy 91.188989 -285.68698) (xy 91.18854 -285.661354) (xy 90.960956 -285.661354)
			(xy 90.960458 -285.688003) (xy 90.952515 -285.740707) (xy 90.936805 -285.791637) (xy 90.913679 -285.839658)
			(xy 90.883655 -285.883695) (xy 90.847403 -285.922766) (xy 90.805732 -285.955997) (xy 90.759574 -285.982646)
			(xy 90.70996 -286.002118) (xy 90.657998 -286.013978) (xy 90.604848 -286.017962) (xy 90.551698 -286.013978)
			(xy 90.499736 -286.002118) (xy 90.450122 -285.982646) (xy 90.403964 -285.955997) (xy 90.362293 -285.922766)
			(xy 90.326041 -285.883695) (xy 90.296017 -285.839658) (xy 90.272891 -285.791637) (xy 90.257181 -285.740707)
			(xy 90.249238 -285.688003) (xy 90.24874 -285.661354) (xy 90.020902 -285.661354) (xy 90.020518 -285.684599)
			(xy 90.014477 -285.730694) (xy 90.002493 -285.775612) (xy 89.993978 -285.797244) (xy 89.984326 -285.820358)
			(xy 90.157046 -286.119062) (xy 90.181684 -286.122364) (xy 90.207016 -286.12625) (xy 90.256319 -286.140233)
			(xy 90.303109 -286.161137) (xy 90.346421 -286.188531) (xy 90.38536 -286.221848) (xy 90.419122 -286.260402)
			(xy 90.44701 -286.303397) (xy 90.468449 -286.349944) (xy 90.482996 -286.399084) (xy 90.490351 -286.4498)
			(xy 90.490802 -286.475424) (xy 90.490304 -286.502073) (xy 90.718884 -286.502073) (xy 90.718884 -286.448775)
			(xy 90.726827 -286.396071) (xy 90.742537 -286.345141) (xy 90.765663 -286.29712) (xy 90.795687 -286.253083)
			(xy 90.831939 -286.214012) (xy 90.87361 -286.180781) (xy 90.919768 -286.154132) (xy 90.969382 -286.13466)
			(xy 91.021344 -286.1228) (xy 91.074494 -286.118817) (xy 91.127644 -286.1228) (xy 91.179606 -286.13466)
			(xy 91.22922 -286.154132) (xy 91.275378 -286.180781) (xy 91.317049 -286.214012) (xy 91.353301 -286.253083)
			(xy 91.383325 -286.29712) (xy 91.406451 -286.345141) (xy 91.422161 -286.396071) (xy 91.430104 -286.448775)
			(xy 91.430602 -286.475424) (xy 91.430104 -286.502073) (xy 91.422161 -286.554777) (xy 91.406451 -286.605707)
			(xy 91.383325 -286.653728) (xy 91.353301 -286.697765) (xy 91.317049 -286.736836) (xy 91.275378 -286.770067)
			(xy 91.22922 -286.796716) (xy 91.179606 -286.816188) (xy 91.127644 -286.828048) (xy 91.074494 -286.832032)
			(xy 91.021344 -286.828048) (xy 90.969382 -286.816188) (xy 90.919768 -286.796716) (xy 90.87361 -286.770067)
			(xy 90.831939 -286.736836) (xy 90.795687 -286.697765) (xy 90.765663 -286.653728) (xy 90.742537 -286.605707)
			(xy 90.726827 -286.554777) (xy 90.718884 -286.502073) (xy 90.490304 -286.502073) (xy 90.482361 -286.554777)
			(xy 90.466651 -286.605707) (xy 90.443525 -286.653728) (xy 90.413501 -286.697765) (xy 90.377249 -286.736836)
			(xy 90.335578 -286.770067) (xy 90.28942 -286.796716) (xy 90.239806 -286.816188) (xy 90.187844 -286.828048)
			(xy 90.134694 -286.832032) (xy 90.081544 -286.828048) (xy 90.029582 -286.816188) (xy 89.979968 -286.796716)
			(xy 89.93381 -286.770067) (xy 89.892139 -286.736836) (xy 89.855887 -286.697765) (xy 89.825863 -286.653728)
			(xy 89.802737 -286.605707) (xy 89.787027 -286.554777) (xy 89.779084 -286.502073) (xy 89.778586 -286.475424)
			(xy 89.778963 -286.452179) (xy 89.785007 -286.406084) (xy 89.796994 -286.361166) (xy 89.80551 -286.339534)
			(xy 89.815162 -286.31642) (xy 89.642442 -286.017716) (xy 89.617804 -286.014414) (xy 89.592466 -286.010558)
			(xy 89.543162 -285.996573) (xy 89.49637 -285.975666) (xy 89.453058 -285.948269) (xy 89.414119 -285.914948)
			(xy 89.380357 -285.87639) (xy 89.35247 -285.833392) (xy 89.331032 -285.786841) (xy 89.316487 -285.737699)
			(xy 89.309135 -285.686979) (xy 89.308686 -285.661354) (xy 89.081102 -285.661354) (xy 89.080604 -285.688003)
			(xy 89.072661 -285.740707) (xy 89.056951 -285.791637) (xy 89.033825 -285.839658) (xy 89.003801 -285.883695)
			(xy 88.967549 -285.922766) (xy 88.925878 -285.955997) (xy 88.87972 -285.982646) (xy 88.830106 -286.002118)
			(xy 88.778144 -286.013978) (xy 88.724994 -286.017962) (xy 88.671844 -286.013978) (xy 88.619882 -286.002118)
			(xy 88.570268 -285.982646) (xy 88.52411 -285.955997) (xy 88.482439 -285.922766) (xy 88.446187 -285.883695)
			(xy 88.416163 -285.839658) (xy 88.393037 -285.791637) (xy 88.377327 -285.740707) (xy 88.369384 -285.688003)
			(xy 88.140804 -285.688003) (xy 88.132861 -285.740707) (xy 88.117151 -285.791637) (xy 88.094025 -285.839658)
			(xy 88.064001 -285.883695) (xy 88.027749 -285.922766) (xy 87.986078 -285.955997) (xy 87.93992 -285.982646)
			(xy 87.890306 -286.002118) (xy 87.838344 -286.013978) (xy 87.785194 -286.017962) (xy 87.732044 -286.013978)
			(xy 87.680082 -286.002118) (xy 87.630468 -285.982646) (xy 87.58431 -285.955997) (xy 87.542639 -285.922766)
			(xy 87.506387 -285.883695) (xy 87.476363 -285.839658) (xy 87.453237 -285.791637) (xy 87.437527 -285.740707)
			(xy 87.429584 -285.688003) (xy 87.429086 -285.661354) (xy 87.201502 -285.661354) (xy 87.201004 -285.688003)
			(xy 87.193061 -285.740707) (xy 87.177351 -285.791637) (xy 87.154225 -285.839658) (xy 87.124201 -285.883695)
			(xy 87.087949 -285.922766) (xy 87.046278 -285.955997) (xy 87.00012 -285.982646) (xy 86.950506 -286.002118)
			(xy 86.898544 -286.013978) (xy 86.845394 -286.017962) (xy 86.792244 -286.013978) (xy 86.740282 -286.002118)
			(xy 86.690668 -285.982646) (xy 86.64451 -285.955997) (xy 86.602839 -285.922766) (xy 86.566587 -285.883695)
			(xy 86.536563 -285.839658) (xy 86.513437 -285.791637) (xy 86.497727 -285.740707) (xy 86.489784 -285.688003)
			(xy 86.260284 -285.688003) (xy 86.258294 -285.714561) (xy 86.246431 -285.766534) (xy 86.226955 -285.816158)
			(xy 86.2003 -285.862326) (xy 86.167062 -285.904005) (xy 86.127982 -285.940264) (xy 86.083936 -285.970294)
			(xy 86.035905 -285.993424) (xy 85.984963 -286.009136) (xy 85.932249 -286.017081) (xy 85.905594 -286.017462)
			(xy 85.876625 -286.016895) (xy 85.81945 -286.007525) (xy 85.764544 -285.989031) (xy 85.713351 -285.961901)
			(xy 85.689948 -285.944818) (xy 85.67843 -285.936643) (xy 85.65213 -285.926373) (xy 85.624022 -285.923699)
			(xy 85.596258 -285.928826) (xy 85.570958 -285.941361) (xy 85.55006 -285.960345) (xy 85.535159 -285.984327)
			(xy 85.527397 -286.011473) (xy 85.52688 -286.02559) (xy 85.52688 -286.129476) (xy 85.5599 -286.141668)
			(xy 85.585071 -286.151572) (xy 85.632327 -286.177887) (xy 85.67506 -286.211046) (xy 85.712287 -286.250287)
			(xy 85.74315 -286.294706) (xy 85.766941 -286.343282) (xy 85.783112 -286.394897) (xy 85.791291 -286.448364)
			(xy 85.79129 -286.475424) (xy 86.019386 -286.475424) (xy 86.019884 -286.448775) (xy 86.027827 -286.396071)
			(xy 86.043537 -286.345141) (xy 86.066663 -286.29712) (xy 86.096687 -286.253083) (xy 86.132939 -286.214012)
			(xy 86.17461 -286.180781) (xy 86.220768 -286.154132) (xy 86.270382 -286.13466) (xy 86.322344 -286.1228)
			(xy 86.375494 -286.118817) (xy 86.428644 -286.1228) (xy 86.480606 -286.13466) (xy 86.53022 -286.154132)
			(xy 86.576378 -286.180781) (xy 86.618049 -286.214012) (xy 86.654301 -286.253083) (xy 86.684325 -286.29712)
			(xy 86.707451 -286.345141) (xy 86.723161 -286.396071) (xy 86.731104 -286.448775) (xy 86.731602 -286.4754)
			(xy 86.958717 -286.4754) (xy 86.9627 -286.422255) (xy 86.974559 -286.370296) (xy 86.994029 -286.320686)
			(xy 87.020676 -286.274532) (xy 87.053904 -286.232864) (xy 87.092971 -286.196614) (xy 87.137005 -286.166592)
			(xy 87.185021 -286.143468) (xy 87.235948 -286.127758) (xy 87.288647 -286.119815) (xy 87.315294 -286.119316)
			(xy 87.340308 -286.119756) (xy 87.389845 -286.12674) (xy 87.437918 -286.140586) (xy 87.483581 -286.16102)
			(xy 87.525937 -286.187642) (xy 87.564151 -286.219928) (xy 87.597473 -286.257242) (xy 87.611712 -286.277812)
			(xy 87.958676 -286.277812) (xy 87.972903 -286.257234) (xy 88.006234 -286.219926) (xy 88.044452 -286.187645)
			(xy 88.086809 -286.161024) (xy 88.132472 -286.140586) (xy 88.180544 -286.126734) (xy 88.23008 -286.119738)
			(xy 88.255094 -286.119316) (xy 88.281747 -286.119741) (xy 88.334458 -286.127685) (xy 88.385397 -286.143397)
			(xy 88.433425 -286.166525) (xy 88.477469 -286.196553) (xy 88.516545 -286.23281) (xy 88.549782 -286.274487)
			(xy 88.576435 -286.320651) (xy 88.59591 -286.370273) (xy 88.607772 -286.422243) (xy 88.611756 -286.4754)
			(xy 88.607772 -286.528557) (xy 88.59591 -286.580527) (xy 88.576435 -286.630149) (xy 88.549782 -286.676313)
			(xy 88.516545 -286.71799) (xy 88.477469 -286.754247) (xy 88.433425 -286.784275) (xy 88.385397 -286.807403)
			(xy 88.334458 -286.823115) (xy 88.281747 -286.831059) (xy 88.255094 -286.831532) (xy 88.230079 -286.831124)
			(xy 88.180539 -286.824137) (xy 88.132465 -286.810288) (xy 88.0868 -286.789848) (xy 88.044445 -286.763221)
			(xy 88.006232 -286.730929) (xy 87.972913 -286.693609) (xy 87.958676 -286.673036) (xy 87.611712 -286.673036)
			(xy 87.597507 -286.69363) (xy 87.564172 -286.730935) (xy 87.525948 -286.763214) (xy 87.483587 -286.789832)
			(xy 87.437922 -286.810267) (xy 87.389847 -286.824117) (xy 87.340309 -286.83111) (xy 87.315294 -286.831532)
			(xy 87.288647 -286.830985) (xy 87.235948 -286.823042) (xy 87.185021 -286.807332) (xy 87.137005 -286.784208)
			(xy 87.092971 -286.754186) (xy 87.053904 -286.717936) (xy 87.020676 -286.676268) (xy 86.994029 -286.630114)
			(xy 86.974559 -286.580504) (xy 86.9627 -286.528545) (xy 86.958717 -286.4754) (xy 86.731602 -286.4754)
			(xy 86.731602 -286.475424) (xy 86.731229 -286.498627) (xy 86.725176 -286.544638) (xy 86.713189 -286.589471)
			(xy 86.704678 -286.61106) (xy 86.69528 -286.634174) (xy 86.867746 -286.932878) (xy 86.892638 -286.93618)
			(xy 86.917966 -286.940021) (xy 86.967238 -286.954042) (xy 87.013994 -286.974976) (xy 87.05727 -287.00239)
			(xy 87.096173 -287.035719) (xy 87.129903 -287.074276) (xy 87.157762 -287.117266) (xy 87.179178 -287.163803)
			(xy 87.193708 -287.212927) (xy 87.201054 -287.263626) (xy 87.201502 -287.28924) (xy 87.201004 -287.315889)
			(xy 87.429584 -287.315889) (xy 87.429584 -287.262591) (xy 87.437527 -287.209887) (xy 87.453237 -287.158957)
			(xy 87.476363 -287.110936) (xy 87.506387 -287.066899) (xy 87.542639 -287.027828) (xy 87.58431 -286.994597)
			(xy 87.630468 -286.967948) (xy 87.680082 -286.948476) (xy 87.732044 -286.936616) (xy 87.785194 -286.932633)
			(xy 87.838344 -286.936616) (xy 87.890306 -286.948476) (xy 87.93992 -286.967948) (xy 87.986078 -286.994597)
			(xy 88.027749 -287.027828) (xy 88.064001 -287.066899) (xy 88.094025 -287.110936) (xy 88.117151 -287.158957)
			(xy 88.132861 -287.209887) (xy 88.140804 -287.262591) (xy 88.141302 -287.28924) (xy 88.140804 -287.315889)
			(xy 88.369384 -287.315889) (xy 88.369384 -287.262591) (xy 88.377327 -287.209887) (xy 88.393037 -287.158957)
			(xy 88.416163 -287.110936) (xy 88.446187 -287.066899) (xy 88.482439 -287.027828) (xy 88.52411 -286.994597)
			(xy 88.570268 -286.967948) (xy 88.619882 -286.948476) (xy 88.671844 -286.936616) (xy 88.724994 -286.932633)
			(xy 88.778144 -286.936616) (xy 88.830106 -286.948476) (xy 88.87972 -286.967948) (xy 88.925878 -286.994597)
			(xy 88.967549 -287.027828) (xy 89.003801 -287.066899) (xy 89.033825 -287.110936) (xy 89.056951 -287.158957)
			(xy 89.072661 -287.209887) (xy 89.080604 -287.262591) (xy 89.081102 -287.28924) (xy 89.080604 -287.315889)
			(xy 89.309184 -287.315889) (xy 89.309184 -287.262591) (xy 89.317127 -287.209887) (xy 89.332837 -287.158957)
			(xy 89.355963 -287.110936) (xy 89.385987 -287.066899) (xy 89.422239 -287.027828) (xy 89.46391 -286.994597)
			(xy 89.510068 -286.967948) (xy 89.559682 -286.948476) (xy 89.611644 -286.936616) (xy 89.664794 -286.932633)
			(xy 89.717944 -286.936616) (xy 89.769906 -286.948476) (xy 89.81952 -286.967948) (xy 89.865678 -286.994597)
			(xy 89.907349 -287.027828) (xy 89.943601 -287.066899) (xy 89.973625 -287.110936) (xy 89.996751 -287.158957)
			(xy 90.012461 -287.209887) (xy 90.020404 -287.262591) (xy 90.020902 -287.28924) (xy 90.020404 -287.315889)
			(xy 90.249238 -287.315889) (xy 90.249238 -287.262591) (xy 90.257181 -287.209887) (xy 90.272891 -287.158957)
			(xy 90.296017 -287.110936) (xy 90.326041 -287.066899) (xy 90.362293 -287.027828) (xy 90.403964 -286.994597)
			(xy 90.450122 -286.967948) (xy 90.499736 -286.948476) (xy 90.551698 -286.936616) (xy 90.604848 -286.932633)
			(xy 90.657998 -286.936616) (xy 90.70996 -286.948476) (xy 90.759574 -286.967948) (xy 90.805732 -286.994597)
			(xy 90.847403 -287.027828) (xy 90.883655 -287.066899) (xy 90.913679 -287.110936) (xy 90.936805 -287.158957)
			(xy 90.952515 -287.209887) (xy 90.960458 -287.262591) (xy 90.960956 -287.28924) (xy 90.960458 -287.315889)
			(xy 91.189038 -287.315889) (xy 91.189038 -287.262591) (xy 91.196981 -287.209887) (xy 91.212691 -287.158957)
			(xy 91.235817 -287.110936) (xy 91.265841 -287.066899) (xy 91.302093 -287.027828) (xy 91.343764 -286.994597)
			(xy 91.389922 -286.967948) (xy 91.439536 -286.948476) (xy 91.491498 -286.936616) (xy 91.544648 -286.932633)
			(xy 91.597798 -286.936616) (xy 91.64976 -286.948476) (xy 91.699374 -286.967948) (xy 91.745532 -286.994597)
			(xy 91.787203 -287.027828) (xy 91.823455 -287.066899) (xy 91.853479 -287.110936) (xy 91.876605 -287.158957)
			(xy 91.892315 -287.209887) (xy 91.900258 -287.262591) (xy 91.900756 -287.28924) (xy 91.900258 -287.315889)
			(xy 92.128838 -287.315889) (xy 92.128838 -287.262591) (xy 92.136781 -287.209887) (xy 92.152491 -287.158957)
			(xy 92.175617 -287.110936) (xy 92.205641 -287.066899) (xy 92.241893 -287.027828) (xy 92.283564 -286.994597)
			(xy 92.329722 -286.967948) (xy 92.379336 -286.948476) (xy 92.431298 -286.936616) (xy 92.484448 -286.932633)
			(xy 92.537598 -286.936616) (xy 92.58956 -286.948476) (xy 92.639174 -286.967948) (xy 92.685332 -286.994597)
			(xy 92.727003 -287.027828) (xy 92.763255 -287.066899) (xy 92.793279 -287.110936) (xy 92.816405 -287.158957)
			(xy 92.832115 -287.209887) (xy 92.840058 -287.262591) (xy 92.840556 -287.28924) (xy 92.840058 -287.315889)
			(xy 93.068384 -287.315889) (xy 93.068384 -287.262591) (xy 93.076327 -287.209887) (xy 93.092037 -287.158957)
			(xy 93.115163 -287.110936) (xy 93.145187 -287.066899) (xy 93.181439 -287.027828) (xy 93.22311 -286.994597)
			(xy 93.269268 -286.967948) (xy 93.318882 -286.948476) (xy 93.370844 -286.936616) (xy 93.423994 -286.932633)
			(xy 93.477144 -286.936616) (xy 93.529106 -286.948476) (xy 93.57872 -286.967948) (xy 93.624878 -286.994597)
			(xy 93.666549 -287.027828) (xy 93.702801 -287.066899) (xy 93.732825 -287.110936) (xy 93.755951 -287.158957)
			(xy 93.771661 -287.209887) (xy 93.779604 -287.262591) (xy 93.780102 -287.28924) (xy 93.779604 -287.315889)
			(xy 94.008184 -287.315889) (xy 94.008184 -287.262591) (xy 94.016127 -287.209887) (xy 94.031837 -287.158957)
			(xy 94.054963 -287.110936) (xy 94.084987 -287.066899) (xy 94.121239 -287.027828) (xy 94.16291 -286.994597)
			(xy 94.209068 -286.967948) (xy 94.258682 -286.948476) (xy 94.310644 -286.936616) (xy 94.363794 -286.932633)
			(xy 94.416944 -286.936616) (xy 94.468906 -286.948476) (xy 94.51852 -286.967948) (xy 94.564678 -286.994597)
			(xy 94.606349 -287.027828) (xy 94.642601 -287.066899) (xy 94.672625 -287.110936) (xy 94.695751 -287.158957)
			(xy 94.711461 -287.209887) (xy 94.719404 -287.262591) (xy 94.719902 -287.28924) (xy 94.719404 -287.315889)
			(xy 94.947984 -287.315889) (xy 94.947984 -287.262591) (xy 94.955927 -287.209887) (xy 94.971637 -287.158957)
			(xy 94.994763 -287.110936) (xy 95.024787 -287.066899) (xy 95.061039 -287.027828) (xy 95.10271 -286.994597)
			(xy 95.148868 -286.967948) (xy 95.198482 -286.948476) (xy 95.250444 -286.936616) (xy 95.303594 -286.932633)
			(xy 95.356744 -286.936616) (xy 95.408706 -286.948476) (xy 95.45832 -286.967948) (xy 95.504478 -286.994597)
			(xy 95.546149 -287.027828) (xy 95.582401 -287.066899) (xy 95.612425 -287.110936) (xy 95.635551 -287.158957)
			(xy 95.651261 -287.209887) (xy 95.659204 -287.262591) (xy 95.659702 -287.28924) (xy 95.659204 -287.315889)
			(xy 95.887784 -287.315889) (xy 95.887784 -287.262591) (xy 95.895727 -287.209887) (xy 95.911437 -287.158957)
			(xy 95.934563 -287.110936) (xy 95.964587 -287.066899) (xy 96.000839 -287.027828) (xy 96.04251 -286.994597)
			(xy 96.088668 -286.967948) (xy 96.138282 -286.948476) (xy 96.190244 -286.936616) (xy 96.243394 -286.932633)
			(xy 96.296544 -286.936616) (xy 96.348506 -286.948476) (xy 96.39812 -286.967948) (xy 96.444278 -286.994597)
			(xy 96.485949 -287.027828) (xy 96.522201 -287.066899) (xy 96.552225 -287.110936) (xy 96.575351 -287.158957)
			(xy 96.591061 -287.209887) (xy 96.599004 -287.262591) (xy 96.599502 -287.28924) (xy 96.599004 -287.315889)
			(xy 96.827584 -287.315889) (xy 96.827584 -287.262591) (xy 96.835527 -287.209887) (xy 96.851237 -287.158957)
			(xy 96.874363 -287.110936) (xy 96.904387 -287.066899) (xy 96.940639 -287.027828) (xy 96.98231 -286.994597)
			(xy 97.028468 -286.967948) (xy 97.078082 -286.948476) (xy 97.130044 -286.936616) (xy 97.183194 -286.932633)
			(xy 97.236344 -286.936616) (xy 97.288306 -286.948476) (xy 97.33792 -286.967948) (xy 97.384078 -286.994597)
			(xy 97.425749 -287.027828) (xy 97.462001 -287.066899) (xy 97.492025 -287.110936) (xy 97.515151 -287.158957)
			(xy 97.530861 -287.209887) (xy 97.538804 -287.262591) (xy 97.539302 -287.28924) (xy 97.538804 -287.315889)
			(xy 97.767384 -287.315889) (xy 97.767384 -287.262591) (xy 97.775327 -287.209887) (xy 97.791037 -287.158957)
			(xy 97.814163 -287.110936) (xy 97.844187 -287.066899) (xy 97.880439 -287.027828) (xy 97.92211 -286.994597)
			(xy 97.968268 -286.967948) (xy 98.017882 -286.948476) (xy 98.069844 -286.936616) (xy 98.122994 -286.932633)
			(xy 98.176144 -286.936616) (xy 98.228106 -286.948476) (xy 98.27772 -286.967948) (xy 98.323878 -286.994597)
			(xy 98.365549 -287.027828) (xy 98.401801 -287.066899) (xy 98.431825 -287.110936) (xy 98.454951 -287.158957)
			(xy 98.470661 -287.209887) (xy 98.478604 -287.262591) (xy 98.479102 -287.28924) (xy 98.478604 -287.315889)
			(xy 98.707184 -287.315889) (xy 98.707184 -287.262591) (xy 98.715127 -287.209887) (xy 98.730837 -287.158957)
			(xy 98.753963 -287.110936) (xy 98.783987 -287.066899) (xy 98.820239 -287.027828) (xy 98.86191 -286.994597)
			(xy 98.908068 -286.967948) (xy 98.957682 -286.948476) (xy 99.009644 -286.936616) (xy 99.062794 -286.932633)
			(xy 99.115944 -286.936616) (xy 99.167906 -286.948476) (xy 99.21752 -286.967948) (xy 99.263678 -286.994597)
			(xy 99.305349 -287.027828) (xy 99.341601 -287.066899) (xy 99.371625 -287.110936) (xy 99.394751 -287.158957)
			(xy 99.410461 -287.209887) (xy 99.418404 -287.262591) (xy 99.418902 -287.28924) (xy 99.418404 -287.315889)
			(xy 99.646984 -287.315889) (xy 99.646984 -287.262591) (xy 99.654927 -287.209887) (xy 99.670637 -287.158957)
			(xy 99.693763 -287.110936) (xy 99.723787 -287.066899) (xy 99.760039 -287.027828) (xy 99.80171 -286.994597)
			(xy 99.847868 -286.967948) (xy 99.897482 -286.948476) (xy 99.949444 -286.936616) (xy 100.002594 -286.932633)
			(xy 100.055744 -286.936616) (xy 100.107706 -286.948476) (xy 100.15732 -286.967948) (xy 100.203478 -286.994597)
			(xy 100.245149 -287.027828) (xy 100.281401 -287.066899) (xy 100.311425 -287.110936) (xy 100.334551 -287.158957)
			(xy 100.350261 -287.209887) (xy 100.358204 -287.262591) (xy 100.358702 -287.28924) (xy 100.358204 -287.315889)
			(xy 100.586784 -287.315889) (xy 100.586784 -287.262591) (xy 100.594727 -287.209887) (xy 100.610437 -287.158957)
			(xy 100.633563 -287.110936) (xy 100.663587 -287.066899) (xy 100.699839 -287.027828) (xy 100.74151 -286.994597)
			(xy 100.787668 -286.967948) (xy 100.837282 -286.948476) (xy 100.889244 -286.936616) (xy 100.942394 -286.932633)
			(xy 100.995544 -286.936616) (xy 101.047506 -286.948476) (xy 101.09712 -286.967948) (xy 101.143278 -286.994597)
			(xy 101.184949 -287.027828) (xy 101.221201 -287.066899) (xy 101.251225 -287.110936) (xy 101.274351 -287.158957)
			(xy 101.290061 -287.209887) (xy 101.298004 -287.262591) (xy 101.298502 -287.28924) (xy 101.298004 -287.315889)
			(xy 101.526584 -287.315889) (xy 101.526584 -287.262591) (xy 101.534527 -287.209887) (xy 101.550237 -287.158957)
			(xy 101.573363 -287.110936) (xy 101.603387 -287.066899) (xy 101.639639 -287.027828) (xy 101.68131 -286.994597)
			(xy 101.727468 -286.967948) (xy 101.777082 -286.948476) (xy 101.829044 -286.936616) (xy 101.882194 -286.932633)
			(xy 101.935344 -286.936616) (xy 101.987306 -286.948476) (xy 102.03692 -286.967948) (xy 102.083078 -286.994597)
			(xy 102.124749 -287.027828) (xy 102.161001 -287.066899) (xy 102.191025 -287.110936) (xy 102.214151 -287.158957)
			(xy 102.229861 -287.209887) (xy 102.237804 -287.262591) (xy 102.238302 -287.28924) (xy 102.237804 -287.315889)
			(xy 102.466384 -287.315889) (xy 102.466384 -287.262591) (xy 102.474327 -287.209887) (xy 102.490037 -287.158957)
			(xy 102.513163 -287.110936) (xy 102.543187 -287.066899) (xy 102.579439 -287.027828) (xy 102.62111 -286.994597)
			(xy 102.667268 -286.967948) (xy 102.716882 -286.948476) (xy 102.768844 -286.936616) (xy 102.821994 -286.932633)
			(xy 102.875144 -286.936616) (xy 102.927106 -286.948476) (xy 102.97672 -286.967948) (xy 103.022878 -286.994597)
			(xy 103.064549 -287.027828) (xy 103.100801 -287.066899) (xy 103.130825 -287.110936) (xy 103.153951 -287.158957)
			(xy 103.169661 -287.209887) (xy 103.177604 -287.262591) (xy 103.178102 -287.28924) (xy 103.177604 -287.315889)
			(xy 103.169661 -287.368593) (xy 103.153951 -287.419523) (xy 103.130825 -287.467544) (xy 103.100801 -287.511581)
			(xy 103.064549 -287.550652) (xy 103.022878 -287.583883) (xy 102.97672 -287.610532) (xy 102.927106 -287.630004)
			(xy 102.875144 -287.641864) (xy 102.821994 -287.645848) (xy 102.768844 -287.641864) (xy 102.716882 -287.630004)
			(xy 102.667268 -287.610532) (xy 102.62111 -287.583883) (xy 102.579439 -287.550652) (xy 102.543187 -287.511581)
			(xy 102.513163 -287.467544) (xy 102.490037 -287.419523) (xy 102.474327 -287.368593) (xy 102.466384 -287.315889)
			(xy 102.237804 -287.315889) (xy 102.229861 -287.368593) (xy 102.214151 -287.419523) (xy 102.191025 -287.467544)
			(xy 102.161001 -287.511581) (xy 102.124749 -287.550652) (xy 102.083078 -287.583883) (xy 102.03692 -287.610532)
			(xy 101.987306 -287.630004) (xy 101.935344 -287.641864) (xy 101.882194 -287.645848) (xy 101.829044 -287.641864)
			(xy 101.777082 -287.630004) (xy 101.727468 -287.610532) (xy 101.68131 -287.583883) (xy 101.639639 -287.550652)
			(xy 101.603387 -287.511581) (xy 101.573363 -287.467544) (xy 101.550237 -287.419523) (xy 101.534527 -287.368593)
			(xy 101.526584 -287.315889) (xy 101.298004 -287.315889) (xy 101.290061 -287.368593) (xy 101.274351 -287.419523)
			(xy 101.251225 -287.467544) (xy 101.221201 -287.511581) (xy 101.184949 -287.550652) (xy 101.143278 -287.583883)
			(xy 101.09712 -287.610532) (xy 101.047506 -287.630004) (xy 100.995544 -287.641864) (xy 100.942394 -287.645848)
			(xy 100.889244 -287.641864) (xy 100.837282 -287.630004) (xy 100.787668 -287.610532) (xy 100.74151 -287.583883)
			(xy 100.699839 -287.550652) (xy 100.663587 -287.511581) (xy 100.633563 -287.467544) (xy 100.610437 -287.419523)
			(xy 100.594727 -287.368593) (xy 100.586784 -287.315889) (xy 100.358204 -287.315889) (xy 100.350261 -287.368593)
			(xy 100.334551 -287.419523) (xy 100.311425 -287.467544) (xy 100.281401 -287.511581) (xy 100.245149 -287.550652)
			(xy 100.203478 -287.583883) (xy 100.15732 -287.610532) (xy 100.107706 -287.630004) (xy 100.055744 -287.641864)
			(xy 100.002594 -287.645848) (xy 99.949444 -287.641864) (xy 99.897482 -287.630004) (xy 99.847868 -287.610532)
			(xy 99.80171 -287.583883) (xy 99.760039 -287.550652) (xy 99.723787 -287.511581) (xy 99.693763 -287.467544)
			(xy 99.670637 -287.419523) (xy 99.654927 -287.368593) (xy 99.646984 -287.315889) (xy 99.418404 -287.315889)
			(xy 99.410461 -287.368593) (xy 99.394751 -287.419523) (xy 99.371625 -287.467544) (xy 99.341601 -287.511581)
			(xy 99.305349 -287.550652) (xy 99.263678 -287.583883) (xy 99.21752 -287.610532) (xy 99.167906 -287.630004)
			(xy 99.115944 -287.641864) (xy 99.062794 -287.645848) (xy 99.009644 -287.641864) (xy 98.957682 -287.630004)
			(xy 98.908068 -287.610532) (xy 98.86191 -287.583883) (xy 98.820239 -287.550652) (xy 98.783987 -287.511581)
			(xy 98.753963 -287.467544) (xy 98.730837 -287.419523) (xy 98.715127 -287.368593) (xy 98.707184 -287.315889)
			(xy 98.478604 -287.315889) (xy 98.470661 -287.368593) (xy 98.454951 -287.419523) (xy 98.431825 -287.467544)
			(xy 98.401801 -287.511581) (xy 98.365549 -287.550652) (xy 98.323878 -287.583883) (xy 98.27772 -287.610532)
			(xy 98.228106 -287.630004) (xy 98.176144 -287.641864) (xy 98.122994 -287.645848) (xy 98.069844 -287.641864)
			(xy 98.017882 -287.630004) (xy 97.968268 -287.610532) (xy 97.92211 -287.583883) (xy 97.880439 -287.550652)
			(xy 97.844187 -287.511581) (xy 97.814163 -287.467544) (xy 97.791037 -287.419523) (xy 97.775327 -287.368593)
			(xy 97.767384 -287.315889) (xy 97.538804 -287.315889) (xy 97.530861 -287.368593) (xy 97.515151 -287.419523)
			(xy 97.492025 -287.467544) (xy 97.462001 -287.511581) (xy 97.425749 -287.550652) (xy 97.384078 -287.583883)
			(xy 97.33792 -287.610532) (xy 97.288306 -287.630004) (xy 97.236344 -287.641864) (xy 97.183194 -287.645848)
			(xy 97.130044 -287.641864) (xy 97.078082 -287.630004) (xy 97.028468 -287.610532) (xy 96.98231 -287.583883)
			(xy 96.940639 -287.550652) (xy 96.904387 -287.511581) (xy 96.874363 -287.467544) (xy 96.851237 -287.419523)
			(xy 96.835527 -287.368593) (xy 96.827584 -287.315889) (xy 96.599004 -287.315889) (xy 96.591061 -287.368593)
			(xy 96.575351 -287.419523) (xy 96.552225 -287.467544) (xy 96.522201 -287.511581) (xy 96.485949 -287.550652)
			(xy 96.444278 -287.583883) (xy 96.39812 -287.610532) (xy 96.348506 -287.630004) (xy 96.296544 -287.641864)
			(xy 96.243394 -287.645848) (xy 96.190244 -287.641864) (xy 96.138282 -287.630004) (xy 96.088668 -287.610532)
			(xy 96.04251 -287.583883) (xy 96.000839 -287.550652) (xy 95.964587 -287.511581) (xy 95.934563 -287.467544)
			(xy 95.911437 -287.419523) (xy 95.895727 -287.368593) (xy 95.887784 -287.315889) (xy 95.659204 -287.315889)
			(xy 95.651261 -287.368593) (xy 95.635551 -287.419523) (xy 95.612425 -287.467544) (xy 95.582401 -287.511581)
			(xy 95.546149 -287.550652) (xy 95.504478 -287.583883) (xy 95.45832 -287.610532) (xy 95.408706 -287.630004)
			(xy 95.356744 -287.641864) (xy 95.303594 -287.645848) (xy 95.250444 -287.641864) (xy 95.198482 -287.630004)
			(xy 95.148868 -287.610532) (xy 95.10271 -287.583883) (xy 95.061039 -287.550652) (xy 95.024787 -287.511581)
			(xy 94.994763 -287.467544) (xy 94.971637 -287.419523) (xy 94.955927 -287.368593) (xy 94.947984 -287.315889)
			(xy 94.719404 -287.315889) (xy 94.711461 -287.368593) (xy 94.695751 -287.419523) (xy 94.672625 -287.467544)
			(xy 94.642601 -287.511581) (xy 94.606349 -287.550652) (xy 94.564678 -287.583883) (xy 94.51852 -287.610532)
			(xy 94.468906 -287.630004) (xy 94.416944 -287.641864) (xy 94.363794 -287.645848) (xy 94.310644 -287.641864)
			(xy 94.258682 -287.630004) (xy 94.209068 -287.610532) (xy 94.16291 -287.583883) (xy 94.121239 -287.550652)
			(xy 94.084987 -287.511581) (xy 94.054963 -287.467544) (xy 94.031837 -287.419523) (xy 94.016127 -287.368593)
			(xy 94.008184 -287.315889) (xy 93.779604 -287.315889) (xy 93.771661 -287.368593) (xy 93.755951 -287.419523)
			(xy 93.732825 -287.467544) (xy 93.702801 -287.511581) (xy 93.666549 -287.550652) (xy 93.624878 -287.583883)
			(xy 93.57872 -287.610532) (xy 93.529106 -287.630004) (xy 93.477144 -287.641864) (xy 93.423994 -287.645848)
			(xy 93.370844 -287.641864) (xy 93.318882 -287.630004) (xy 93.269268 -287.610532) (xy 93.22311 -287.583883)
			(xy 93.181439 -287.550652) (xy 93.145187 -287.511581) (xy 93.115163 -287.467544) (xy 93.092037 -287.419523)
			(xy 93.076327 -287.368593) (xy 93.068384 -287.315889) (xy 92.840058 -287.315889) (xy 92.832115 -287.368593)
			(xy 92.816405 -287.419523) (xy 92.793279 -287.467544) (xy 92.763255 -287.511581) (xy 92.727003 -287.550652)
			(xy 92.685332 -287.583883) (xy 92.639174 -287.610532) (xy 92.58956 -287.630004) (xy 92.537598 -287.641864)
			(xy 92.484448 -287.645848) (xy 92.431298 -287.641864) (xy 92.379336 -287.630004) (xy 92.329722 -287.610532)
			(xy 92.283564 -287.583883) (xy 92.241893 -287.550652) (xy 92.205641 -287.511581) (xy 92.175617 -287.467544)
			(xy 92.152491 -287.419523) (xy 92.136781 -287.368593) (xy 92.128838 -287.315889) (xy 91.900258 -287.315889)
			(xy 91.892315 -287.368593) (xy 91.876605 -287.419523) (xy 91.853479 -287.467544) (xy 91.823455 -287.511581)
			(xy 91.787203 -287.550652) (xy 91.745532 -287.583883) (xy 91.699374 -287.610532) (xy 91.64976 -287.630004)
			(xy 91.597798 -287.641864) (xy 91.544648 -287.645848) (xy 91.491498 -287.641864) (xy 91.439536 -287.630004)
			(xy 91.389922 -287.610532) (xy 91.343764 -287.583883) (xy 91.302093 -287.550652) (xy 91.265841 -287.511581)
			(xy 91.235817 -287.467544) (xy 91.212691 -287.419523) (xy 91.196981 -287.368593) (xy 91.189038 -287.315889)
			(xy 90.960458 -287.315889) (xy 90.952515 -287.368593) (xy 90.936805 -287.419523) (xy 90.913679 -287.467544)
			(xy 90.883655 -287.511581) (xy 90.847403 -287.550652) (xy 90.805732 -287.583883) (xy 90.759574 -287.610532)
			(xy 90.70996 -287.630004) (xy 90.657998 -287.641864) (xy 90.604848 -287.645848) (xy 90.551698 -287.641864)
			(xy 90.499736 -287.630004) (xy 90.450122 -287.610532) (xy 90.403964 -287.583883) (xy 90.362293 -287.550652)
			(xy 90.326041 -287.511581) (xy 90.296017 -287.467544) (xy 90.272891 -287.419523) (xy 90.257181 -287.368593)
			(xy 90.249238 -287.315889) (xy 90.020404 -287.315889) (xy 90.012461 -287.368593) (xy 89.996751 -287.419523)
			(xy 89.973625 -287.467544) (xy 89.943601 -287.511581) (xy 89.907349 -287.550652) (xy 89.865678 -287.583883)
			(xy 89.81952 -287.610532) (xy 89.769906 -287.630004) (xy 89.717944 -287.641864) (xy 89.664794 -287.645848)
			(xy 89.611644 -287.641864) (xy 89.559682 -287.630004) (xy 89.510068 -287.610532) (xy 89.46391 -287.583883)
			(xy 89.422239 -287.550652) (xy 89.385987 -287.511581) (xy 89.355963 -287.467544) (xy 89.332837 -287.419523)
			(xy 89.317127 -287.368593) (xy 89.309184 -287.315889) (xy 89.080604 -287.315889) (xy 89.072661 -287.368593)
			(xy 89.056951 -287.419523) (xy 89.033825 -287.467544) (xy 89.003801 -287.511581) (xy 88.967549 -287.550652)
			(xy 88.925878 -287.583883) (xy 88.87972 -287.610532) (xy 88.830106 -287.630004) (xy 88.778144 -287.641864)
			(xy 88.724994 -287.645848) (xy 88.671844 -287.641864) (xy 88.619882 -287.630004) (xy 88.570268 -287.610532)
			(xy 88.52411 -287.583883) (xy 88.482439 -287.550652) (xy 88.446187 -287.511581) (xy 88.416163 -287.467544)
			(xy 88.393037 -287.419523) (xy 88.377327 -287.368593) (xy 88.369384 -287.315889) (xy 88.140804 -287.315889)
			(xy 88.132861 -287.368593) (xy 88.117151 -287.419523) (xy 88.094025 -287.467544) (xy 88.064001 -287.511581)
			(xy 88.027749 -287.550652) (xy 87.986078 -287.583883) (xy 87.93992 -287.610532) (xy 87.890306 -287.630004)
			(xy 87.838344 -287.641864) (xy 87.785194 -287.645848) (xy 87.732044 -287.641864) (xy 87.680082 -287.630004)
			(xy 87.630468 -287.610532) (xy 87.58431 -287.583883) (xy 87.542639 -287.550652) (xy 87.506387 -287.511581)
			(xy 87.476363 -287.467544) (xy 87.453237 -287.419523) (xy 87.437527 -287.368593) (xy 87.429584 -287.315889)
			(xy 87.201004 -287.315889) (xy 87.193061 -287.368593) (xy 87.177351 -287.419523) (xy 87.154225 -287.467544)
			(xy 87.124201 -287.511581) (xy 87.087949 -287.550652) (xy 87.046278 -287.583883) (xy 87.00012 -287.610532)
			(xy 86.950506 -287.630004) (xy 86.898544 -287.641864) (xy 86.845394 -287.645848) (xy 86.792244 -287.641864)
			(xy 86.740282 -287.630004) (xy 86.690668 -287.610532) (xy 86.64451 -287.583883) (xy 86.602839 -287.550652)
			(xy 86.566587 -287.511581) (xy 86.536563 -287.467544) (xy 86.513437 -287.419523) (xy 86.497727 -287.368593)
			(xy 86.489784 -287.315889) (xy 86.489286 -287.28924) (xy 86.489681 -287.266037) (xy 86.495725 -287.220027)
			(xy 86.507703 -287.175194) (xy 86.51621 -287.153604) (xy 86.525608 -287.13049) (xy 86.353142 -286.831786)
			(xy 86.32825 -286.828484) (xy 86.302931 -286.824591) (xy 86.253664 -286.810571) (xy 86.206912 -286.789641)
			(xy 86.16364 -286.762232) (xy 86.124738 -286.728909) (xy 86.091008 -286.690358) (xy 86.063147 -286.647375)
			(xy 86.041727 -286.600845) (xy 86.027191 -286.551728) (xy 86.019839 -286.501035) (xy 86.019386 -286.475424)
			(xy 85.79129 -286.475424) (xy 85.79129 -286.502453) (xy 85.783109 -286.55592) (xy 85.766935 -286.607534)
			(xy 85.743142 -286.656109) (xy 85.712276 -286.700526) (xy 85.675048 -286.739765) (xy 85.632313 -286.772922)
			(xy 85.585056 -286.799235) (xy 85.5599 -286.80918) (xy 85.52688 -286.821372) (xy 85.52688 -287.597088)
			(xy 86.059497 -288.129705) (xy 86.959684 -288.129705) (xy 86.959684 -288.076407) (xy 86.967627 -288.023703)
			(xy 86.983337 -287.972773) (xy 87.006463 -287.924752) (xy 87.036487 -287.880715) (xy 87.072739 -287.841644)
			(xy 87.11441 -287.808413) (xy 87.160568 -287.781764) (xy 87.210182 -287.762292) (xy 87.262144 -287.750432)
			(xy 87.315294 -287.746449) (xy 87.368444 -287.750432) (xy 87.420406 -287.762292) (xy 87.47002 -287.781764)
			(xy 87.516178 -287.808413) (xy 87.557849 -287.841644) (xy 87.594101 -287.880715) (xy 87.624125 -287.924752)
			(xy 87.647251 -287.972773) (xy 87.662961 -288.023703) (xy 87.670904 -288.076407) (xy 87.671402 -288.103056)
			(xy 87.670904 -288.129705) (xy 87.662961 -288.182409) (xy 87.647251 -288.233339) (xy 87.624125 -288.28136)
			(xy 87.594101 -288.325397) (xy 87.557849 -288.364468) (xy 87.516178 -288.397699) (xy 87.47002 -288.424348)
			(xy 87.420406 -288.44382) (xy 87.368444 -288.45568) (xy 87.315294 -288.459664) (xy 87.262144 -288.45568)
			(xy 87.210182 -288.44382) (xy 87.160568 -288.424348) (xy 87.11441 -288.397699) (xy 87.072739 -288.364468)
			(xy 87.036487 -288.325397) (xy 87.006463 -288.28136) (xy 86.983337 -288.233339) (xy 86.967627 -288.182409)
			(xy 86.959684 -288.129705) (xy 86.059497 -288.129705) (xy 86.7664 -288.836608) (xy 87.436452 -288.836608)
		)
		(stroke
			(width 0)
			(type solid)
		)
		(fill yes)
		(layer "In13.Cu")
		(net "PVCCFA_EHV_FIVRA_CPU1")
	)
	(gr_poly
		(pts
			(xy 335.38795 -288.802318) (xy 335.396774 -288.777816) (xy 335.420566 -288.731493) (xy 335.450852 -288.689129)
			(xy 335.486985 -288.651628) (xy 335.528195 -288.619789) (xy 335.573604 -288.594293) (xy 335.622241 -288.575683)
			(xy 335.673071 -288.564356) (xy 335.725008 -288.560553) (xy 335.776945 -288.564356) (xy 335.827775 -288.575683)
			(xy 335.876412 -288.594293) (xy 335.921821 -288.619789) (xy 335.963031 -288.651628) (xy 335.999164 -288.689129)
			(xy 336.02945 -288.731493) (xy 336.053242 -288.777816) (xy 336.062066 -288.802318) (xy 336.07375 -288.836608)
			(xy 336.316066 -288.836608) (xy 336.32775 -288.802318) (xy 336.337386 -288.775735) (xy 336.363854 -288.725772)
			(xy 336.39788 -288.680617) (xy 336.438611 -288.641402) (xy 336.485024 -288.609111) (xy 336.535954 -288.584556)
			(xy 336.590123 -288.568351) (xy 336.618072 -288.564066) (xy 336.642964 -288.560764) (xy 336.81543 -288.26206)
			(xy 336.805778 -288.238946) (xy 336.797264 -288.217314) (xy 336.78528 -288.172396) (xy 336.77924 -288.126301)
			(xy 336.778854 -288.103056) (xy 336.779352 -288.076407) (xy 336.787295 -288.023703) (xy 336.803005 -287.972773)
			(xy 336.826131 -287.924752) (xy 336.856155 -287.880715) (xy 336.892407 -287.841644) (xy 336.934078 -287.808413)
			(xy 336.980236 -287.781764) (xy 337.02985 -287.762292) (xy 337.081812 -287.750432) (xy 337.134962 -287.746449)
			(xy 337.188112 -287.750432) (xy 337.240074 -287.762292) (xy 337.289688 -287.781764) (xy 337.335846 -287.808413)
			(xy 337.377517 -287.841644) (xy 337.413769 -287.880715) (xy 337.443793 -287.924752) (xy 337.466919 -287.972773)
			(xy 337.482629 -288.023703) (xy 337.490572 -288.076407) (xy 337.49107 -288.103056) (xy 337.490621 -288.128682)
			(xy 337.483269 -288.179404) (xy 337.468724 -288.228549) (xy 337.447288 -288.275103) (xy 337.419402 -288.318105)
			(xy 337.385641 -288.356667) (xy 337.346704 -288.389993) (xy 337.303392 -288.417396) (xy 337.256601 -288.43831)
			(xy 337.207296 -288.452303) (xy 337.181952 -288.456116) (xy 337.157314 -288.459418) (xy 336.984594 -288.75863)
			(xy 336.994246 -288.781744) (xy 337.001866 -288.802318) (xy 337.01355 -288.836608) (xy 337.255866 -288.836608)
			(xy 337.26755 -288.802318) (xy 337.276374 -288.777816) (xy 337.300166 -288.731493) (xy 337.330452 -288.689129)
			(xy 337.366585 -288.651628) (xy 337.407795 -288.619789) (xy 337.453204 -288.594293) (xy 337.501841 -288.575683)
			(xy 337.552671 -288.564356) (xy 337.604608 -288.560553) (xy 337.656545 -288.564356) (xy 337.707375 -288.575683)
			(xy 337.756012 -288.594293) (xy 337.801421 -288.619789) (xy 337.842631 -288.651628) (xy 337.878764 -288.689129)
			(xy 337.90905 -288.731493) (xy 337.932842 -288.777816) (xy 337.941666 -288.802318) (xy 337.95335 -288.836608)
			(xy 338.196174 -288.836608) (xy 338.207858 -288.802318) (xy 338.217485 -288.775748) (xy 338.243928 -288.725808)
			(xy 338.277921 -288.680665) (xy 338.318612 -288.641453) (xy 338.36498 -288.609153) (xy 338.415865 -288.584574)
			(xy 338.46999 -288.568334) (xy 338.497926 -288.564066) (xy 338.522564 -288.560764) (xy 338.69503 -288.26206)
			(xy 338.685378 -288.238946) (xy 338.676864 -288.217314) (xy 338.66488 -288.172396) (xy 338.65884 -288.126301)
			(xy 338.658454 -288.103056) (xy 338.658952 -288.076407) (xy 338.666895 -288.023703) (xy 338.682605 -287.972773)
			(xy 338.705731 -287.924752) (xy 338.735755 -287.880715) (xy 338.772007 -287.841644) (xy 338.813678 -287.808413)
			(xy 338.859836 -287.781764) (xy 338.90945 -287.762292) (xy 338.961412 -287.750432) (xy 339.014562 -287.746449)
			(xy 339.067712 -287.750432) (xy 339.119674 -287.762292) (xy 339.169288 -287.781764) (xy 339.215446 -287.808413)
			(xy 339.257117 -287.841644) (xy 339.293369 -287.880715) (xy 339.323393 -287.924752) (xy 339.346519 -287.972773)
			(xy 339.362229 -288.023703) (xy 339.370172 -288.076407) (xy 339.37067 -288.103056) (xy 339.370221 -288.128682)
			(xy 339.362869 -288.179404) (xy 339.348324 -288.228549) (xy 339.326888 -288.275103) (xy 339.299002 -288.318105)
			(xy 339.265241 -288.356667) (xy 339.226304 -288.389993) (xy 339.182992 -288.417396) (xy 339.136201 -288.43831)
			(xy 339.086896 -288.452303) (xy 339.061552 -288.456116) (xy 339.036914 -288.459418) (xy 338.864448 -288.758122)
			(xy 338.8741 -288.781236) (xy 338.881974 -288.802318) (xy 338.893658 -288.836608) (xy 339.135974 -288.836608)
			(xy 339.147658 -288.802318) (xy 339.156482 -288.777816) (xy 339.180274 -288.731493) (xy 339.21056 -288.689129)
			(xy 339.246693 -288.651628) (xy 339.287903 -288.619789) (xy 339.333312 -288.594293) (xy 339.381949 -288.575683)
			(xy 339.432779 -288.564356) (xy 339.484716 -288.560553) (xy 339.536653 -288.564356) (xy 339.587483 -288.575683)
			(xy 339.63612 -288.594293) (xy 339.681529 -288.619789) (xy 339.722739 -288.651628) (xy 339.758872 -288.689129)
			(xy 339.789158 -288.731493) (xy 339.81295 -288.777816) (xy 339.821774 -288.802318) (xy 339.833458 -288.836608)
			(xy 340.075774 -288.836608) (xy 340.087458 -288.802318) (xy 340.097085 -288.775748) (xy 340.123528 -288.725808)
			(xy 340.157521 -288.680665) (xy 340.198212 -288.641453) (xy 340.24458 -288.609153) (xy 340.295465 -288.584574)
			(xy 340.34959 -288.568334) (xy 340.377526 -288.564066) (xy 340.402164 -288.560764) (xy 340.574884 -288.26206)
			(xy 340.565232 -288.238946) (xy 340.556717 -288.217314) (xy 340.544732 -288.172396) (xy 340.538691 -288.126301)
			(xy 340.538308 -288.103056) (xy 340.538806 -288.076407) (xy 340.546749 -288.023703) (xy 340.562459 -287.972773)
			(xy 340.585585 -287.924752) (xy 340.615609 -287.880715) (xy 340.651861 -287.841644) (xy 340.693532 -287.808413)
			(xy 340.73969 -287.781764) (xy 340.789304 -287.762292) (xy 340.841266 -287.750432) (xy 340.894416 -287.746449)
			(xy 340.947566 -287.750432) (xy 340.999528 -287.762292) (xy 341.049142 -287.781764) (xy 341.0953 -287.808413)
			(xy 341.136971 -287.841644) (xy 341.173223 -287.880715) (xy 341.203247 -287.924752) (xy 341.226373 -287.972773)
			(xy 341.242083 -288.023703) (xy 341.250026 -288.076407) (xy 341.250524 -288.103056) (xy 341.250075 -288.128681)
			(xy 341.242722 -288.179401) (xy 341.228177 -288.228544) (xy 341.20674 -288.275095) (xy 341.178852 -288.318093)
			(xy 341.145091 -288.356652) (xy 341.106152 -288.389974) (xy 341.06284 -288.417371) (xy 341.016049 -288.43828)
			(xy 340.966745 -288.452266) (xy 340.941406 -288.456116) (xy 340.916768 -288.459418) (xy 340.744048 -288.758122)
			(xy 340.7537 -288.781236) (xy 340.761574 -288.802318) (xy 340.773258 -288.836608) (xy 341.015574 -288.836608)
			(xy 341.027258 -288.802318) (xy 341.036082 -288.777816) (xy 341.059874 -288.731493) (xy 341.09016 -288.689129)
			(xy 341.126293 -288.651628) (xy 341.167503 -288.619789) (xy 341.212912 -288.594293) (xy 341.261549 -288.575683)
			(xy 341.312379 -288.564356) (xy 341.364316 -288.560553) (xy 341.416253 -288.564356) (xy 341.467083 -288.575683)
			(xy 341.51572 -288.594293) (xy 341.561129 -288.619789) (xy 341.602339 -288.651628) (xy 341.638472 -288.689129)
			(xy 341.668758 -288.731493) (xy 341.69255 -288.777816) (xy 341.701374 -288.802318) (xy 341.713058 -288.836608)
			(xy 341.955374 -288.836608) (xy 341.967058 -288.802318) (xy 341.976685 -288.775748) (xy 342.003128 -288.725808)
			(xy 342.037121 -288.680665) (xy 342.077812 -288.641453) (xy 342.12418 -288.609153) (xy 342.175065 -288.584574)
			(xy 342.22919 -288.568334) (xy 342.257126 -288.564066) (xy 342.281764 -288.560764) (xy 342.454484 -288.26206)
			(xy 342.444832 -288.238946) (xy 342.436317 -288.217314) (xy 342.424332 -288.172396) (xy 342.418291 -288.126301)
			(xy 342.417908 -288.103056) (xy 342.418406 -288.076407) (xy 342.426349 -288.023703) (xy 342.442059 -287.972773)
			(xy 342.465185 -287.924752) (xy 342.495209 -287.880715) (xy 342.531461 -287.841644) (xy 342.573132 -287.808413)
			(xy 342.61929 -287.781764) (xy 342.668904 -287.762292) (xy 342.720866 -287.750432) (xy 342.774016 -287.746449)
			(xy 342.827166 -287.750432) (xy 342.879128 -287.762292) (xy 342.928742 -287.781764) (xy 342.9749 -287.808413)
			(xy 343.016571 -287.841644) (xy 343.052823 -287.880715) (xy 343.082847 -287.924752) (xy 343.105973 -287.972773)
			(xy 343.121683 -288.023703) (xy 343.129626 -288.076407) (xy 343.130124 -288.103056) (xy 343.129675 -288.128681)
			(xy 343.122322 -288.179401) (xy 343.107777 -288.228544) (xy 343.08634 -288.275095) (xy 343.058452 -288.318093)
			(xy 343.024691 -288.356652) (xy 342.985752 -288.389974) (xy 342.94244 -288.417371) (xy 342.895649 -288.43828)
			(xy 342.846345 -288.452266) (xy 342.821006 -288.456116) (xy 342.796368 -288.459418) (xy 342.623648 -288.758122)
			(xy 342.6333 -288.781236) (xy 342.641174 -288.802318) (xy 342.652858 -288.836608) (xy 342.895174 -288.836608)
			(xy 342.906858 -288.802318) (xy 342.915682 -288.777816) (xy 342.939474 -288.731493) (xy 342.96976 -288.689129)
			(xy 343.005893 -288.651628) (xy 343.047103 -288.619789) (xy 343.092512 -288.594293) (xy 343.141149 -288.575683)
			(xy 343.191979 -288.564356) (xy 343.243916 -288.560553) (xy 343.295853 -288.564356) (xy 343.346683 -288.575683)
			(xy 343.39532 -288.594293) (xy 343.440729 -288.619789) (xy 343.481939 -288.651628) (xy 343.518072 -288.689129)
			(xy 343.548358 -288.731493) (xy 343.57215 -288.777816) (xy 343.580974 -288.802318) (xy 343.592658 -288.836608)
			(xy 343.834974 -288.836608) (xy 343.846658 -288.802318) (xy 343.856285 -288.775748) (xy 343.882728 -288.725808)
			(xy 343.916721 -288.680665) (xy 343.957412 -288.641453) (xy 344.00378 -288.609153) (xy 344.054665 -288.584574)
			(xy 344.10879 -288.568334) (xy 344.136726 -288.564066) (xy 344.161364 -288.560764) (xy 344.334084 -288.26206)
			(xy 344.324432 -288.238946) (xy 344.315917 -288.217314) (xy 344.303932 -288.172396) (xy 344.297891 -288.126301)
			(xy 344.297508 -288.103056) (xy 344.298006 -288.076407) (xy 344.305949 -288.023703) (xy 344.321659 -287.972773)
			(xy 344.344785 -287.924752) (xy 344.374809 -287.880715) (xy 344.411061 -287.841644) (xy 344.452732 -287.808413)
			(xy 344.49889 -287.781764) (xy 344.548504 -287.762292) (xy 344.600466 -287.750432) (xy 344.653616 -287.746449)
			(xy 344.706766 -287.750432) (xy 344.758728 -287.762292) (xy 344.808342 -287.781764) (xy 344.8545 -287.808413)
			(xy 344.896171 -287.841644) (xy 344.932423 -287.880715) (xy 344.962447 -287.924752) (xy 344.985573 -287.972773)
			(xy 345.001283 -288.023703) (xy 345.009226 -288.076407) (xy 345.009724 -288.103056) (xy 345.009275 -288.128681)
			(xy 345.001922 -288.179401) (xy 344.987377 -288.228544) (xy 344.96594 -288.275095) (xy 344.938052 -288.318093)
			(xy 344.904291 -288.356652) (xy 344.865352 -288.389974) (xy 344.82204 -288.417371) (xy 344.775249 -288.43828)
			(xy 344.725945 -288.452266) (xy 344.700606 -288.456116) (xy 344.675968 -288.459418) (xy 344.503248 -288.758122)
			(xy 344.5129 -288.781236) (xy 344.520774 -288.802318) (xy 344.532458 -288.836608) (xy 344.774774 -288.836608)
			(xy 344.786458 -288.802318) (xy 344.795282 -288.777816) (xy 344.819074 -288.731493) (xy 344.84936 -288.689129)
			(xy 344.885493 -288.651628) (xy 344.926703 -288.619789) (xy 344.972112 -288.594293) (xy 345.020749 -288.575683)
			(xy 345.071579 -288.564356) (xy 345.123516 -288.560553) (xy 345.175453 -288.564356) (xy 345.226283 -288.575683)
			(xy 345.27492 -288.594293) (xy 345.320329 -288.619789) (xy 345.361539 -288.651628) (xy 345.397672 -288.689129)
			(xy 345.427958 -288.731493) (xy 345.45175 -288.777816) (xy 345.460574 -288.802318) (xy 345.472258 -288.836608)
			(xy 345.714574 -288.836608) (xy 345.726258 -288.802318) (xy 345.735885 -288.775748) (xy 345.762328 -288.725808)
			(xy 345.796321 -288.680665) (xy 345.837012 -288.641453) (xy 345.88338 -288.609153) (xy 345.934265 -288.584574)
			(xy 345.98839 -288.568334) (xy 346.016326 -288.564066) (xy 346.040964 -288.560764) (xy 346.213684 -288.26206)
			(xy 346.204032 -288.238946) (xy 346.195517 -288.217314) (xy 346.183532 -288.172396) (xy 346.177491 -288.126301)
			(xy 346.177108 -288.103056) (xy 346.177606 -288.076407) (xy 346.185549 -288.023703) (xy 346.201259 -287.972773)
			(xy 346.224385 -287.924752) (xy 346.254409 -287.880715) (xy 346.290661 -287.841644) (xy 346.332332 -287.808413)
			(xy 346.37849 -287.781764) (xy 346.428104 -287.762292) (xy 346.480066 -287.750432) (xy 346.533216 -287.746449)
			(xy 346.586366 -287.750432) (xy 346.638328 -287.762292) (xy 346.687942 -287.781764) (xy 346.7341 -287.808413)
			(xy 346.775771 -287.841644) (xy 346.812023 -287.880715) (xy 346.842047 -287.924752) (xy 346.865173 -287.972773)
			(xy 346.880883 -288.023703) (xy 346.888826 -288.076407) (xy 346.889324 -288.103056) (xy 346.888875 -288.128681)
			(xy 346.881522 -288.179401) (xy 346.866977 -288.228544) (xy 346.84554 -288.275095) (xy 346.817652 -288.318093)
			(xy 346.783891 -288.356652) (xy 346.744952 -288.389974) (xy 346.70164 -288.417371) (xy 346.654849 -288.43828)
			(xy 346.605545 -288.452266) (xy 346.580206 -288.456116) (xy 346.555568 -288.459418) (xy 346.382848 -288.758122)
			(xy 346.3925 -288.781236) (xy 346.400374 -288.802318) (xy 346.412058 -288.836608) (xy 346.654374 -288.836608)
			(xy 346.666058 -288.802318) (xy 346.674882 -288.777816) (xy 346.698674 -288.731493) (xy 346.72896 -288.689129)
			(xy 346.765093 -288.651628) (xy 346.806303 -288.619789) (xy 346.851712 -288.594293) (xy 346.900349 -288.575683)
			(xy 346.951179 -288.564356) (xy 347.003116 -288.560553) (xy 347.055053 -288.564356) (xy 347.105883 -288.575683)
			(xy 347.15452 -288.594293) (xy 347.199929 -288.619789) (xy 347.241139 -288.651628) (xy 347.277272 -288.689129)
			(xy 347.307558 -288.731493) (xy 347.33135 -288.777816) (xy 347.340174 -288.802318) (xy 347.351858 -288.836608)
			(xy 347.594174 -288.836608) (xy 347.605858 -288.802318) (xy 347.615485 -288.775748) (xy 347.641928 -288.725808)
			(xy 347.675921 -288.680665) (xy 347.716612 -288.641453) (xy 347.76298 -288.609153) (xy 347.813865 -288.584574)
			(xy 347.86799 -288.568334) (xy 347.895926 -288.564066) (xy 347.920564 -288.560764) (xy 348.093284 -288.26206)
			(xy 348.083632 -288.238946) (xy 348.075117 -288.217314) (xy 348.063132 -288.172396) (xy 348.057091 -288.126301)
			(xy 348.056708 -288.103056) (xy 348.057206 -288.076407) (xy 348.065149 -288.023703) (xy 348.080859 -287.972773)
			(xy 348.103985 -287.924752) (xy 348.134009 -287.880715) (xy 348.170261 -287.841644) (xy 348.211932 -287.808413)
			(xy 348.25809 -287.781764) (xy 348.307704 -287.762292) (xy 348.359666 -287.750432) (xy 348.412816 -287.746449)
			(xy 348.465966 -287.750432) (xy 348.517928 -287.762292) (xy 348.567542 -287.781764) (xy 348.6137 -287.808413)
			(xy 348.655371 -287.841644) (xy 348.691623 -287.880715) (xy 348.721647 -287.924752) (xy 348.744773 -287.972773)
			(xy 348.760483 -288.023703) (xy 348.768426 -288.076407) (xy 348.768924 -288.103056) (xy 348.768475 -288.128681)
			(xy 348.761122 -288.179401) (xy 348.746577 -288.228544) (xy 348.72514 -288.275095) (xy 348.697252 -288.318093)
			(xy 348.663491 -288.356652) (xy 348.624552 -288.389974) (xy 348.58124 -288.417371) (xy 348.534449 -288.43828)
			(xy 348.485145 -288.452266) (xy 348.459806 -288.456116) (xy 348.435168 -288.459418) (xy 348.262448 -288.758122)
			(xy 348.2721 -288.781236) (xy 348.279974 -288.802318) (xy 348.291658 -288.836608) (xy 348.533974 -288.836608)
			(xy 348.545658 -288.802318) (xy 348.554482 -288.777816) (xy 348.578274 -288.731493) (xy 348.60856 -288.689129)
			(xy 348.644693 -288.651628) (xy 348.685903 -288.619789) (xy 348.731312 -288.594293) (xy 348.779949 -288.575683)
			(xy 348.830779 -288.564356) (xy 348.882716 -288.560553) (xy 348.934653 -288.564356) (xy 348.985483 -288.575683)
			(xy 349.03412 -288.594293) (xy 349.079529 -288.619789) (xy 349.120739 -288.651628) (xy 349.156872 -288.689129)
			(xy 349.187158 -288.731493) (xy 349.21095 -288.777816) (xy 349.219774 -288.802318) (xy 349.231458 -288.836608)
			(xy 349.473774 -288.836608) (xy 349.485458 -288.802318) (xy 349.495085 -288.775748) (xy 349.521528 -288.725808)
			(xy 349.555521 -288.680665) (xy 349.596212 -288.641453) (xy 349.64258 -288.609153) (xy 349.693465 -288.584574)
			(xy 349.74759 -288.568334) (xy 349.775526 -288.564066) (xy 349.800164 -288.560764) (xy 349.972884 -288.26206)
			(xy 349.963232 -288.238946) (xy 349.954717 -288.217314) (xy 349.942732 -288.172396) (xy 349.936691 -288.126301)
			(xy 349.936308 -288.103056) (xy 349.936806 -288.076407) (xy 349.944749 -288.023703) (xy 349.960459 -287.972773)
			(xy 349.983585 -287.924752) (xy 350.013609 -287.880715) (xy 350.049861 -287.841644) (xy 350.091532 -287.808413)
			(xy 350.13769 -287.781764) (xy 350.187304 -287.762292) (xy 350.239266 -287.750432) (xy 350.292416 -287.746449)
			(xy 350.345566 -287.750432) (xy 350.397528 -287.762292) (xy 350.447142 -287.781764) (xy 350.4933 -287.808413)
			(xy 350.534971 -287.841644) (xy 350.571223 -287.880715) (xy 350.601247 -287.924752) (xy 350.624373 -287.972773)
			(xy 350.640083 -288.023703) (xy 350.648026 -288.076407) (xy 350.648524 -288.103056) (xy 350.648075 -288.128681)
			(xy 350.640722 -288.179401) (xy 350.626177 -288.228544) (xy 350.60474 -288.275095) (xy 350.576852 -288.318093)
			(xy 350.543091 -288.356652) (xy 350.504152 -288.389974) (xy 350.46084 -288.417371) (xy 350.414049 -288.43828)
			(xy 350.364745 -288.452266) (xy 350.339406 -288.456116) (xy 350.314768 -288.459418) (xy 350.142048 -288.758122)
			(xy 350.1517 -288.781236) (xy 350.159574 -288.802318) (xy 350.171258 -288.836608) (xy 350.413574 -288.836608)
			(xy 350.425258 -288.802318) (xy 350.434082 -288.777816) (xy 350.457874 -288.731493) (xy 350.48816 -288.689129)
			(xy 350.524293 -288.651628) (xy 350.565503 -288.619789) (xy 350.610912 -288.594293) (xy 350.659549 -288.575683)
			(xy 350.710379 -288.564356) (xy 350.762316 -288.560553) (xy 350.814253 -288.564356) (xy 350.865083 -288.575683)
			(xy 350.91372 -288.594293) (xy 350.959129 -288.619789) (xy 351.000339 -288.651628) (xy 351.036472 -288.689129)
			(xy 351.066758 -288.731493) (xy 351.09055 -288.777816) (xy 351.099374 -288.802318) (xy 351.111058 -288.836608)
			(xy 351.353374 -288.836608) (xy 351.365058 -288.802318) (xy 351.374385 -288.776503) (xy 351.399844 -288.727876)
			(xy 351.432463 -288.683733) (xy 351.47147 -288.645118) (xy 351.515941 -288.612947) (xy 351.564822 -288.587981)
			(xy 351.616955 -288.570813) (xy 351.64395 -288.565844) (xy 351.660206 -288.56305) (xy 351.70364 -288.519616)
			(xy 351.852484 -288.26206) (xy 351.842832 -288.238946) (xy 351.834317 -288.217314) (xy 351.822332 -288.172396)
			(xy 351.816291 -288.126301) (xy 351.815908 -288.103056) (xy 351.816495 -288.073886) (xy 351.826007 -288.016327)
			(xy 351.844768 -287.961087) (xy 351.872278 -287.909641) (xy 351.889568 -287.88614) (xy 351.889568 -287.73882)
			(xy 351.889049 -287.723887) (xy 351.880424 -287.695294) (xy 351.863904 -287.670413) (xy 351.840899 -287.651367)
			(xy 351.813372 -287.639782) (xy 351.783671 -287.636645) (xy 351.768918 -287.638998) (xy 351.752316 -287.641987)
			(xy 351.71873 -287.645166) (xy 351.701862 -287.645348) (xy 351.675212 -287.644848) (xy 351.622507 -287.636898)
			(xy 351.571575 -287.621183) (xy 351.523554 -287.598053) (xy 351.479517 -287.568025) (xy 351.440447 -287.531769)
			(xy 351.407216 -287.490095) (xy 351.380567 -287.443934) (xy 351.361095 -287.394317) (xy 351.349235 -287.342352)
			(xy 351.345252 -287.2892) (xy 351.349235 -287.236048) (xy 351.361095 -287.184083) (xy 351.380567 -287.134466)
			(xy 351.407216 -287.088305) (xy 351.440447 -287.046631) (xy 351.479517 -287.010375) (xy 351.523554 -286.980347)
			(xy 351.571575 -286.957217) (xy 351.622507 -286.941502) (xy 351.675212 -286.933552) (xy 351.701862 -286.933132)
			(xy 351.718729 -286.933329) (xy 351.752314 -286.936505) (xy 351.768918 -286.939482) (xy 351.783682 -286.941772)
			(xy 351.813383 -286.93866) (xy 351.840914 -286.927093) (xy 351.863925 -286.908058) (xy 351.880448 -286.883183)
			(xy 351.889073 -286.854592) (xy 351.889568 -286.83966) (xy 351.889568 -286.692594) (xy 351.874106 -286.671731)
			(xy 351.848749 -286.626416) (xy 351.830242 -286.577899) (xy 351.818978 -286.527208) (xy 351.815194 -286.475419)
			(xy 351.818972 -286.423629) (xy 351.830231 -286.372938) (xy 351.848733 -286.324418) (xy 351.874085 -286.279101)
			(xy 351.889568 -286.258254) (xy 351.889568 -286.110934) (xy 351.88905 -286.096) (xy 351.880428 -286.067403)
			(xy 351.863909 -286.042518) (xy 351.840903 -286.023469) (xy 351.813373 -286.011882) (xy 351.78367 -286.008746)
			(xy 351.768918 -286.011112) (xy 351.752316 -286.014101) (xy 351.71873 -286.017279) (xy 351.701862 -286.017462)
			(xy 351.67388 -286.016939) (xy 351.618606 -286.008178) (xy 351.565382 -285.990878) (xy 351.515521 -285.965465)
			(xy 351.470249 -285.932565) (xy 351.43068 -285.892988) (xy 351.397791 -285.847708) (xy 351.37239 -285.79784)
			(xy 351.355103 -285.744613) (xy 351.346355 -285.689336) (xy 351.345754 -285.661354) (xy 351.346202 -285.635728)
			(xy 351.353554 -285.585006) (xy 351.368097 -285.535861) (xy 351.389534 -285.489307) (xy 351.41742 -285.446306)
			(xy 351.451181 -285.407745) (xy 351.49012 -285.37442) (xy 351.533432 -285.347019) (xy 351.580223 -285.326107)
			(xy 351.629529 -285.312117) (xy 351.654872 -285.308294) (xy 351.67951 -285.304992) (xy 351.85223 -285.006034)
			(xy 351.842578 -284.98292) (xy 351.834136 -284.961359) (xy 351.822259 -284.916604) (xy 351.816267 -284.87069)
			(xy 351.815908 -284.847538) (xy 351.816497 -284.818369) (xy 351.826011 -284.760811) (xy 351.844774 -284.705573)
			(xy 351.872286 -284.654129) (xy 351.889568 -284.630622) (xy 351.889568 -284.483302) (xy 351.889046 -284.468371)
			(xy 351.880418 -284.439782) (xy 351.863898 -284.414906) (xy 351.840894 -284.395864) (xy 351.81337 -284.384281)
			(xy 351.783673 -284.381145) (xy 351.768918 -284.38348) (xy 351.752316 -284.386468) (xy 351.71873 -284.389646)
			(xy 351.701862 -284.38983) (xy 351.675213 -284.38933) (xy 351.622511 -284.381381) (xy 351.571582 -284.365666)
			(xy 351.523563 -284.342538) (xy 351.479528 -284.312511) (xy 351.44046 -284.276256) (xy 351.407231 -284.234585)
			(xy 351.380583 -284.188426) (xy 351.361112 -284.138811) (xy 351.349253 -284.086849) (xy 351.34527 -284.0337)
			(xy 351.349253 -283.980551) (xy 351.361112 -283.928589) (xy 351.380583 -283.878974) (xy 351.407231 -283.832815)
			(xy 351.44046 -283.791144) (xy 351.479528 -283.754889) (xy 351.523563 -283.724862) (xy 351.571582 -283.701734)
			(xy 351.622511 -283.686019) (xy 351.675213 -283.67807) (xy 351.701862 -283.677614) (xy 351.718729 -283.677811)
			(xy 351.752314 -283.680987) (xy 351.768918 -283.683964) (xy 351.783681 -283.686255) (xy 351.81338 -283.683143)
			(xy 351.84091 -283.671575) (xy 351.863918 -283.652539) (xy 351.880438 -283.627663) (xy 351.889057 -283.599073)
			(xy 351.889568 -283.584142) (xy 351.889568 -283.494988) (xy 351.91446 -283.470096) (xy 351.88779 -283.43479)
			(xy 351.870822 -283.411446) (xy 351.843871 -283.360418) (xy 351.825501 -283.305712) (xy 351.816194 -283.24876)
			(xy 351.815654 -283.219906) (xy 351.816202 -283.191922) (xy 351.824957 -283.136641) (xy 351.84225 -283.083411)
			(xy 351.867657 -283.033541) (xy 351.900553 -282.98826) (xy 351.940126 -282.948681) (xy 351.985404 -282.91578)
			(xy 352.03527 -282.890367) (xy 352.088499 -282.873067) (xy 352.143778 -282.864306) (xy 352.171762 -282.863798)
			(xy 352.199241 -282.864306) (xy 352.253545 -282.872753) (xy 352.305905 -282.889452) (xy 352.355072 -282.914006)
			(xy 352.399879 -282.945829) (xy 352.41992 -282.964636) (xy 352.501454 -282.883102) (xy 352.510741 -282.873143)
			(xy 352.524151 -282.849456) (xy 352.530832 -282.823068) (xy 352.530311 -282.795853) (xy 352.522624 -282.769741)
			(xy 352.508317 -282.746584) (xy 352.488405 -282.728025) (xy 352.476562 -282.721304) (xy 352.450478 -282.707012)
			(xy 352.403058 -282.671116) (xy 352.362256 -282.627845) (xy 352.345244 -282.603448) (xy 351.99828 -282.603448)
			(xy 351.984044 -282.624023) (xy 351.950726 -282.661347) (xy 351.912513 -282.693644) (xy 351.870159 -282.720277)
			(xy 351.824495 -282.740723) (xy 351.776419 -282.754579) (xy 351.726878 -282.761573) (xy 351.701862 -282.761944)
			(xy 351.675212 -282.761444) (xy 351.622508 -282.753494) (xy 351.571577 -282.737779) (xy 351.523556 -282.71465)
			(xy 351.479519 -282.684622) (xy 351.440449 -282.648366) (xy 351.407219 -282.606692) (xy 351.380571 -282.560532)
			(xy 351.361099 -282.510916) (xy 351.349239 -282.458951) (xy 351.345256 -282.4058) (xy 351.349239 -282.352649)
			(xy 351.361099 -282.300684) (xy 351.380571 -282.251068) (xy 351.407219 -282.204908) (xy 351.440449 -282.163234)
			(xy 351.479519 -282.126978) (xy 351.523556 -282.09695) (xy 351.571577 -282.073821) (xy 351.622508 -282.058106)
			(xy 351.675212 -282.050156) (xy 351.701862 -282.049728) (xy 351.726874 -282.050154) (xy 351.776405 -282.057157)
			(xy 351.824471 -282.071015) (xy 351.870128 -282.091457) (xy 351.912478 -282.118082) (xy 351.95069 -282.150366)
			(xy 351.984013 -282.187675) (xy 351.99828 -282.208224) (xy 352.345244 -282.208224) (xy 352.359482 -282.187652)
			(xy 352.392802 -282.150332) (xy 352.431015 -282.118041) (xy 352.47337 -282.091412) (xy 352.519034 -282.070971)
			(xy 352.567108 -282.05712) (xy 352.616647 -282.050129) (xy 352.641662 -282.049728) (xy 352.669367 -282.050253)
			(xy 352.72411 -282.058833) (xy 352.776862 -282.075792) (xy 352.826349 -282.100719) (xy 352.871375 -282.133014)
			(xy 352.910854 -282.171896) (xy 352.943831 -282.216425) (xy 352.95713 -282.240736) (xy 352.963801 -282.252626)
			(xy 352.982327 -282.272614) (xy 353.00549 -282.286975) (xy 353.031631 -282.29468) (xy 353.05888 -282.295178)
			(xy 353.085285 -282.288433) (xy 353.108957 -282.274929) (xy 353.118928 -282.265628) (xy 353.705414 -281.679142)
			(xy 353.700842 -281.653234) (xy 353.698344 -281.638054) (xy 353.695669 -281.607403) (xy 353.695508 -281.59202)
			(xy 353.696027 -281.564034) (xy 353.70478 -281.508751) (xy 353.722075 -281.455518) (xy 353.747484 -281.405646)
			(xy 353.780383 -281.360364) (xy 353.819961 -281.320785) (xy 353.865243 -281.287886) (xy 353.915114 -281.262476)
			(xy 353.968347 -281.245181) (xy 354.02363 -281.236427) (xy 354.051616 -281.235912) (xy 354.066999 -281.236091)
			(xy 354.097648 -281.238761) (xy 354.11283 -281.241246) (xy 354.138738 -281.245818) (xy 354.241608 -281.142948)
			(xy 354.25183 -281.131911) (xy 354.265913 -281.105347) (xy 354.271653 -281.075833) (xy 354.268553 -281.045927)
			(xy 354.25688 -281.018218) (xy 354.247704 -281.006296) (xy 354.241634 -280.998948) (xy 354.230197 -280.983701)
			(xy 354.224844 -280.975816) (xy 353.87788 -280.975816) (xy 353.863641 -280.996387) (xy 353.83032 -281.033706)
			(xy 353.792106 -281.065996) (xy 353.749752 -281.092624) (xy 353.704089 -281.113065) (xy 353.656015 -281.126919)
			(xy 353.606477 -281.133911) (xy 353.581462 -281.134312) (xy 353.554814 -281.133812) (xy 353.502115 -281.125863)
			(xy 353.451188 -281.11015) (xy 353.403172 -281.087022) (xy 353.359139 -281.056997) (xy 353.320073 -281.020744)
			(xy 353.286846 -280.979074) (xy 353.260199 -280.932918) (xy 353.24073 -280.883306) (xy 353.228871 -280.831347)
			(xy 353.224888 -280.7782) (xy 353.228871 -280.725053) (xy 353.24073 -280.673094) (xy 353.260199 -280.623482)
			(xy 353.286846 -280.577326) (xy 353.320073 -280.535656) (xy 353.359139 -280.499403) (xy 353.403172 -280.469378)
			(xy 353.451188 -280.44625) (xy 353.502115 -280.430537) (xy 353.554814 -280.422588) (xy 353.581462 -280.422096)
			(xy 353.606474 -280.422522) (xy 353.656007 -280.429524) (xy 353.704074 -280.443382) (xy 353.749731 -280.463823)
			(xy 353.792083 -280.490446) (xy 353.830297 -280.522728) (xy 353.863623 -280.560036) (xy 353.87788 -280.580592)
			(xy 354.224844 -280.580592) (xy 354.239083 -280.560021) (xy 354.272404 -280.522705) (xy 354.310618 -280.490416)
			(xy 354.352973 -280.46379) (xy 354.398636 -280.443351) (xy 354.44671 -280.429501) (xy 354.496248 -280.422511)
			(xy 354.521262 -280.422096) (xy 354.546025 -280.422519) (xy 354.595074 -280.42937) (xy 354.642702 -280.442947)
			(xy 354.687992 -280.462988) (xy 354.73007 -280.489106) (xy 354.749354 -280.504646) (xy 354.761249 -280.513863)
			(xy 354.78896 -280.525553) (xy 354.818876 -280.52865) (xy 354.848394 -280.522883) (xy 354.874944 -280.508755)
			(xy 354.886006 -280.49855) (xy 355.874828 -279.509728) (xy 355.874828 -278.690324) (xy 355.83749 -278.67991)
			(xy 355.812702 -278.672688) (xy 355.765365 -278.652075) (xy 355.721505 -278.624836) (xy 355.682043 -278.591544)
			(xy 355.647807 -278.552897) (xy 355.619517 -278.509708) (xy 355.597766 -278.462884) (xy 355.583011 -278.413407)
			(xy 355.575562 -278.362317) (xy 355.575108 -278.336502) (xy 355.575483 -278.313257) (xy 355.581528 -278.267162)
			(xy 355.593515 -278.222244) (xy 355.602032 -278.200612) (xy 355.611684 -278.177498) (xy 355.438964 -277.878794)
			(xy 355.414326 -277.875492) (xy 355.388966 -277.871688) (xy 355.339618 -277.857742) (xy 355.292781 -277.836862)
			(xy 355.249423 -277.809478) (xy 355.210443 -277.776158) (xy 355.176646 -277.73759) (xy 355.148731 -277.694573)
			(xy 355.127276 -277.647997) (xy 355.112725 -277.598824) (xy 355.105378 -277.548072) (xy 355.104954 -277.522432)
			(xy 355.105501 -277.494446) (xy 355.114251 -277.439163) (xy 355.131543 -277.385929) (xy 355.156948 -277.336056)
			(xy 355.189843 -277.290771) (xy 355.229417 -277.251189) (xy 355.274696 -277.218285) (xy 355.324564 -277.192869)
			(xy 355.377795 -277.175568) (xy 355.433076 -277.166806) (xy 355.461062 -277.166324) (xy 355.487803 -277.166803)
			(xy 355.540683 -277.174805) (xy 355.591769 -277.190634) (xy 355.639909 -277.213933) (xy 355.684018 -277.244177)
			(xy 355.703886 -277.262082) (xy 355.715035 -277.271801) (xy 355.741521 -277.284937) (xy 355.770658 -277.289941)
			(xy 355.800008 -277.286393) (xy 355.827114 -277.27459) (xy 355.849706 -277.25552) (xy 355.865892 -277.230781)
			(xy 355.874318 -277.202443) (xy 355.874828 -277.18766) (xy 355.874828 -277.062438) (xy 355.83749 -277.052024)
			(xy 355.811245 -277.04436) (xy 355.761309 -277.022098) (xy 355.715364 -276.992462) (xy 355.674492 -276.956148)
			(xy 355.639654 -276.914011) (xy 355.611669 -276.867043) (xy 355.591196 -276.816347) (xy 355.578716 -276.763117)
			(xy 355.574522 -276.708604) (xy 355.578714 -276.654092) (xy 355.591193 -276.600861) (xy 355.611665 -276.550165)
			(xy 355.639649 -276.503196) (xy 355.674486 -276.461058) (xy 355.715357 -276.424743) (xy 355.761301 -276.395106)
			(xy 355.811237 -276.372843) (xy 355.83749 -276.365208) (xy 355.874828 -276.354794) (xy 355.874828 -276.229572)
			(xy 355.874325 -276.214793) (xy 355.865867 -276.186472) (xy 355.849666 -276.161751) (xy 355.827072 -276.142693)
			(xy 355.799974 -276.13089) (xy 355.770632 -276.127327) (xy 355.741496 -276.132302) (xy 355.714998 -276.145398)
			(xy 355.703886 -276.15515) (xy 355.68401 -276.173043) (xy 355.639896 -276.203272) (xy 355.591757 -276.226562)
			(xy 355.540675 -276.242389) (xy 355.487801 -276.250398) (xy 355.461062 -276.250908) (xy 355.436049 -276.250483)
			(xy 355.386515 -276.243484) (xy 355.338445 -276.229629) (xy 355.292785 -276.20919) (xy 355.25043 -276.182569)
			(xy 355.212213 -276.150287) (xy 355.178884 -276.11298) (xy 355.164644 -276.092412) (xy 354.81768 -276.092412)
			(xy 354.803441 -276.112984) (xy 354.77012 -276.150302) (xy 354.731907 -276.182593) (xy 354.689552 -276.209221)
			(xy 354.643889 -276.229663) (xy 354.595816 -276.243516) (xy 354.546277 -276.250509) (xy 354.521262 -276.250908)
			(xy 354.494615 -276.250408) (xy 354.441916 -276.242459) (xy 354.39099 -276.226746) (xy 354.342974 -276.203618)
			(xy 354.298942 -276.173593) (xy 354.259876 -276.137341) (xy 354.226649 -276.095672) (xy 354.200003 -276.049516)
			(xy 354.180533 -275.999905) (xy 354.168675 -275.947946) (xy 354.164692 -275.8948) (xy 354.168675 -275.841654)
			(xy 354.180533 -275.789695) (xy 354.200003 -275.740084) (xy 354.226649 -275.693928) (xy 354.259876 -275.652259)
			(xy 354.298942 -275.616007) (xy 354.342974 -275.585982) (xy 354.39099 -275.562854) (xy 354.441916 -275.547141)
			(xy 354.494615 -275.539192) (xy 354.521262 -275.538692) (xy 354.546274 -275.539118) (xy 354.595807 -275.54612)
			(xy 354.643874 -275.559978) (xy 354.689532 -275.580419) (xy 354.731884 -275.607042) (xy 354.770098 -275.639324)
			(xy 354.803424 -275.676631) (xy 354.81768 -275.697188) (xy 355.164644 -275.697188) (xy 355.178883 -275.676618)
			(xy 355.212205 -275.639301) (xy 355.250419 -275.607013) (xy 355.292774 -275.580388) (xy 355.338437 -275.559949)
			(xy 355.38651 -275.546099) (xy 355.436048 -275.539109) (xy 355.461062 -275.538692) (xy 355.487803 -275.539171)
			(xy 355.540684 -275.547172) (xy 355.591771 -275.563) (xy 355.639912 -275.586298) (xy 355.684023 -275.61654)
			(xy 355.703886 -275.63445) (xy 355.71504 -275.644164) (xy 355.741529 -275.657292) (xy 355.770668 -275.662291)
			(xy 355.800018 -275.658742) (xy 355.827125 -275.646942) (xy 355.849722 -275.627877) (xy 355.865918 -275.603144)
			(xy 355.874358 -275.57481) (xy 355.874828 -275.560028) (xy 355.874828 -275.434552) (xy 355.83749 -275.424138)
			(xy 355.811244 -275.416474) (xy 355.761305 -275.394212) (xy 355.715359 -275.364575) (xy 355.674485 -275.32826)
			(xy 355.639645 -275.286122) (xy 355.611659 -275.239152) (xy 355.591184 -275.188455) (xy 355.578703 -275.135223)
			(xy 355.574509 -275.080708) (xy 355.5787 -275.026193) (xy 355.591179 -274.97296) (xy 355.611652 -274.922262)
			(xy 355.639636 -274.875291) (xy 355.674474 -274.833151) (xy 355.715346 -274.796835) (xy 355.761292 -274.767196)
			(xy 355.811229 -274.744931) (xy 355.83749 -274.737322) (xy 355.874828 -274.726908) (xy 355.874828 -274.013168)
			(xy 355.488748 -273.627088) (xy 355.302058 -273.627088) (xy 355.28844 -273.650382) (xy 355.255273 -273.692939)
			(xy 355.216064 -273.730005) (xy 355.171711 -273.760731) (xy 355.123231 -273.784412) (xy 355.071732 -273.800508)
			(xy 355.018394 -273.808649) (xy 354.964438 -273.808649) (xy 354.9111 -273.800508) (xy 354.859601 -273.784412)
			(xy 354.811121 -273.760731) (xy 354.766768 -273.730005) (xy 354.727559 -273.692939) (xy 354.694392 -273.650382)
			(xy 354.680774 -273.627088) (xy 354.362258 -273.627088) (xy 354.34864 -273.650382) (xy 354.315473 -273.692939)
			(xy 354.276264 -273.730005) (xy 354.231911 -273.760731) (xy 354.183431 -273.784412) (xy 354.131932 -273.800508)
			(xy 354.078594 -273.808649) (xy 354.024638 -273.808649) (xy 353.9713 -273.800508) (xy 353.919801 -273.784412)
			(xy 353.871321 -273.760731) (xy 353.826968 -273.730005) (xy 353.787759 -273.692939) (xy 353.754592 -273.650382)
			(xy 353.740974 -273.627088) (xy 352.482658 -273.627088) (xy 352.46904 -273.650382) (xy 352.435873 -273.692939)
			(xy 352.396664 -273.730005) (xy 352.352311 -273.760731) (xy 352.303831 -273.784412) (xy 352.252332 -273.800508)
			(xy 352.198994 -273.808649) (xy 352.145038 -273.808649) (xy 352.0917 -273.800508) (xy 352.040201 -273.784412)
			(xy 351.991721 -273.760731) (xy 351.947368 -273.730005) (xy 351.908159 -273.692939) (xy 351.874992 -273.650382)
			(xy 351.861374 -273.627088) (xy 351.542604 -273.627088) (xy 351.528986 -273.650382) (xy 351.495819 -273.692939)
			(xy 351.45661 -273.730005) (xy 351.412257 -273.760731) (xy 351.363777 -273.784412) (xy 351.312278 -273.800508)
			(xy 351.25894 -273.808649) (xy 351.204984 -273.808649) (xy 351.151646 -273.800508) (xy 351.100147 -273.784412)
			(xy 351.051667 -273.760731) (xy 351.007314 -273.730005) (xy 350.968105 -273.692939) (xy 350.934938 -273.650382)
			(xy 350.92132 -273.627088) (xy 350.603058 -273.627088) (xy 350.58944 -273.650382) (xy 350.556273 -273.692939)
			(xy 350.517064 -273.730005) (xy 350.472711 -273.760731) (xy 350.424231 -273.784412) (xy 350.372732 -273.800508)
			(xy 350.319394 -273.808649) (xy 350.265438 -273.808649) (xy 350.2121 -273.800508) (xy 350.160601 -273.784412)
			(xy 350.112121 -273.760731) (xy 350.067768 -273.730005) (xy 350.028559 -273.692939) (xy 349.995392 -273.650382)
			(xy 349.981774 -273.627088) (xy 349.663004 -273.627088) (xy 349.649386 -273.650382) (xy 349.616219 -273.692939)
			(xy 349.57701 -273.730005) (xy 349.532657 -273.760731) (xy 349.484177 -273.784412) (xy 349.432678 -273.800508)
			(xy 349.37934 -273.808649) (xy 349.325384 -273.808649) (xy 349.272046 -273.800508) (xy 349.220547 -273.784412)
			(xy 349.172067 -273.760731) (xy 349.127714 -273.730005) (xy 349.088505 -273.692939) (xy 349.055338 -273.650382)
			(xy 349.04172 -273.627088) (xy 348.723458 -273.627088) (xy 348.70984 -273.650382) (xy 348.676673 -273.692939)
			(xy 348.637464 -273.730005) (xy 348.593111 -273.760731) (xy 348.544631 -273.784412) (xy 348.493132 -273.800508)
			(xy 348.439794 -273.808649) (xy 348.385838 -273.808649) (xy 348.3325 -273.800508) (xy 348.281001 -273.784412)
			(xy 348.232521 -273.760731) (xy 348.188168 -273.730005) (xy 348.148959 -273.692939) (xy 348.115792 -273.650382)
			(xy 348.102174 -273.627088) (xy 347.783658 -273.627088) (xy 347.77004 -273.650382) (xy 347.736873 -273.692939)
			(xy 347.697664 -273.730005) (xy 347.653311 -273.760731) (xy 347.604831 -273.784412) (xy 347.553332 -273.800508)
			(xy 347.499994 -273.808649) (xy 347.446038 -273.808649) (xy 347.3927 -273.800508) (xy 347.341201 -273.784412)
			(xy 347.292721 -273.760731) (xy 347.248368 -273.730005) (xy 347.209159 -273.692939) (xy 347.175992 -273.650382)
			(xy 347.162374 -273.627088) (xy 346.843858 -273.627088) (xy 346.83024 -273.650382) (xy 346.797073 -273.692939)
			(xy 346.757864 -273.730005) (xy 346.713511 -273.760731) (xy 346.665031 -273.784412) (xy 346.613532 -273.800508)
			(xy 346.560194 -273.808649) (xy 346.506238 -273.808649) (xy 346.4529 -273.800508) (xy 346.401401 -273.784412)
			(xy 346.352921 -273.760731) (xy 346.308568 -273.730005) (xy 346.269359 -273.692939) (xy 346.236192 -273.650382)
			(xy 346.222574 -273.627088) (xy 345.904058 -273.627088) (xy 345.89044 -273.650382) (xy 345.857273 -273.692939)
			(xy 345.818064 -273.730005) (xy 345.773711 -273.760731) (xy 345.725231 -273.784412) (xy 345.673732 -273.800508)
			(xy 345.620394 -273.808649) (xy 345.566438 -273.808649) (xy 345.5131 -273.800508) (xy 345.461601 -273.784412)
			(xy 345.413121 -273.760731) (xy 345.368768 -273.730005) (xy 345.329559 -273.692939) (xy 345.296392 -273.650382)
			(xy 345.282774 -273.627088) (xy 344.964258 -273.627088) (xy 344.95064 -273.650382) (xy 344.917473 -273.692939)
			(xy 344.878264 -273.730005) (xy 344.833911 -273.760731) (xy 344.785431 -273.784412) (xy 344.733932 -273.800508)
			(xy 344.680594 -273.808649) (xy 344.626638 -273.808649) (xy 344.5733 -273.800508) (xy 344.521801 -273.784412)
			(xy 344.473321 -273.760731) (xy 344.428968 -273.730005) (xy 344.389759 -273.692939) (xy 344.356592 -273.650382)
			(xy 344.342974 -273.627088) (xy 344.024458 -273.627088) (xy 344.01084 -273.650382) (xy 343.977673 -273.692939)
			(xy 343.938464 -273.730005) (xy 343.894111 -273.760731) (xy 343.845631 -273.784412) (xy 343.794132 -273.800508)
			(xy 343.740794 -273.808649) (xy 343.686838 -273.808649) (xy 343.6335 -273.800508) (xy 343.582001 -273.784412)
			(xy 343.533521 -273.760731) (xy 343.489168 -273.730005) (xy 343.449959 -273.692939) (xy 343.416792 -273.650382)
			(xy 343.403174 -273.627088) (xy 343.084404 -273.627088) (xy 343.070786 -273.650382) (xy 343.037619 -273.692939)
			(xy 342.99841 -273.730005) (xy 342.954057 -273.760731) (xy 342.905577 -273.784412) (xy 342.854078 -273.800508)
			(xy 342.80074 -273.808649) (xy 342.746784 -273.808649) (xy 342.693446 -273.800508) (xy 342.641947 -273.784412)
			(xy 342.593467 -273.760731) (xy 342.549114 -273.730005) (xy 342.509905 -273.692939) (xy 342.476738 -273.650382)
			(xy 342.46312 -273.627088) (xy 342.144858 -273.627088) (xy 342.13124 -273.650382) (xy 342.098073 -273.692939)
			(xy 342.058864 -273.730005) (xy 342.014511 -273.760731) (xy 341.966031 -273.784412) (xy 341.914532 -273.800508)
			(xy 341.861194 -273.808649) (xy 341.807238 -273.808649) (xy 341.7539 -273.800508) (xy 341.702401 -273.784412)
			(xy 341.653921 -273.760731) (xy 341.609568 -273.730005) (xy 341.570359 -273.692939) (xy 341.537192 -273.650382)
			(xy 341.523574 -273.627088) (xy 341.205058 -273.627088) (xy 341.19144 -273.650382) (xy 341.158273 -273.692939)
			(xy 341.119064 -273.730005) (xy 341.074711 -273.760731) (xy 341.026231 -273.784412) (xy 340.974732 -273.800508)
			(xy 340.921394 -273.808649) (xy 340.867438 -273.808649) (xy 340.8141 -273.800508) (xy 340.762601 -273.784412)
			(xy 340.714121 -273.760731) (xy 340.669768 -273.730005) (xy 340.630559 -273.692939) (xy 340.597392 -273.650382)
			(xy 340.583774 -273.627088) (xy 340.265258 -273.627088) (xy 340.25164 -273.650382) (xy 340.218473 -273.692939)
			(xy 340.179264 -273.730005) (xy 340.134911 -273.760731) (xy 340.086431 -273.784412) (xy 340.034932 -273.800508)
			(xy 339.981594 -273.808649) (xy 339.927638 -273.808649) (xy 339.8743 -273.800508) (xy 339.822801 -273.784412)
			(xy 339.774321 -273.760731) (xy 339.729968 -273.730005) (xy 339.690759 -273.692939) (xy 339.657592 -273.650382)
			(xy 339.643974 -273.627088) (xy 339.325458 -273.627088) (xy 339.31184 -273.650382) (xy 339.278673 -273.692939)
			(xy 339.239464 -273.730005) (xy 339.195111 -273.760731) (xy 339.146631 -273.784412) (xy 339.095132 -273.800508)
			(xy 339.041794 -273.808649) (xy 338.987838 -273.808649) (xy 338.9345 -273.800508) (xy 338.883001 -273.784412)
			(xy 338.834521 -273.760731) (xy 338.790168 -273.730005) (xy 338.750959 -273.692939) (xy 338.717792 -273.650382)
			(xy 338.704174 -273.627088) (xy 338.385404 -273.627088) (xy 338.371786 -273.650382) (xy 338.338619 -273.692939)
			(xy 338.29941 -273.730005) (xy 338.255057 -273.760731) (xy 338.206577 -273.784412) (xy 338.155078 -273.800508)
			(xy 338.10174 -273.808649) (xy 338.047784 -273.808649) (xy 337.994446 -273.800508) (xy 337.942947 -273.784412)
			(xy 337.894467 -273.760731) (xy 337.850114 -273.730005) (xy 337.810905 -273.692939) (xy 337.777738 -273.650382)
			(xy 337.76412 -273.627088) (xy 337.445604 -273.627088) (xy 337.431986 -273.650382) (xy 337.398819 -273.692939)
			(xy 337.35961 -273.730005) (xy 337.315257 -273.760731) (xy 337.266777 -273.784412) (xy 337.215278 -273.800508)
			(xy 337.16194 -273.808649) (xy 337.107984 -273.808649) (xy 337.054646 -273.800508) (xy 337.003147 -273.784412)
			(xy 336.954667 -273.760731) (xy 336.910314 -273.730005) (xy 336.871105 -273.692939) (xy 336.837938 -273.650382)
			(xy 336.82432 -273.627088) (xy 336.505804 -273.627088) (xy 336.492181 -273.650379) (xy 336.459007 -273.69293)
			(xy 336.419796 -273.729994) (xy 336.375445 -273.760721) (xy 336.326969 -273.78441) (xy 336.275474 -273.800518)
			(xy 336.222139 -273.808678) (xy 336.195162 -273.809206) (xy 336.164061 -273.808563) (xy 336.102807 -273.797745)
			(xy 336.044365 -273.776446) (xy 336.017108 -273.761454) (xy 335.983326 -273.74215) (xy 335.909666 -273.81581)
			(xy 335.899459 -273.826741) (xy 335.88533 -273.853082) (xy 335.879444 -273.882388) (xy 335.882308 -273.912142)
			(xy 335.893675 -273.939788) (xy 335.912569 -273.962951) (xy 335.924652 -273.971766) (xy 335.944995 -273.986051)
			(xy 335.981894 -274.019355) (xy 336.013809 -274.057463) (xy 336.040119 -274.099635) (xy 336.060315 -274.145054)
			(xy 336.074005 -274.192838) (xy 336.080923 -274.242061) (xy 336.08137 -274.266914) (xy 336.080873 -274.293563)
			(xy 336.309452 -274.293563) (xy 336.309452 -274.240265) (xy 336.317395 -274.187561) (xy 336.333105 -274.136631)
			(xy 336.356231 -274.08861) (xy 336.386255 -274.044573) (xy 336.422507 -274.005502) (xy 336.464178 -273.972271)
			(xy 336.510336 -273.945622) (xy 336.55995 -273.92615) (xy 336.611912 -273.91429) (xy 336.665062 -273.910307)
			(xy 336.718212 -273.91429) (xy 336.770174 -273.92615) (xy 336.819788 -273.945622) (xy 336.865946 -273.972271)
			(xy 336.907617 -274.005502) (xy 336.943869 -274.044573) (xy 336.973893 -274.08861) (xy 336.997019 -274.136631)
			(xy 337.012729 -274.187561) (xy 337.020672 -274.240265) (xy 337.02117 -274.266914) (xy 337.020672 -274.293563)
			(xy 337.249252 -274.293563) (xy 337.249252 -274.240265) (xy 337.257195 -274.187561) (xy 337.272905 -274.136631)
			(xy 337.296031 -274.08861) (xy 337.326055 -274.044573) (xy 337.362307 -274.005502) (xy 337.403978 -273.972271)
			(xy 337.450136 -273.945622) (xy 337.49975 -273.92615) (xy 337.551712 -273.91429) (xy 337.604862 -273.910307)
			(xy 337.658012 -273.91429) (xy 337.709974 -273.92615) (xy 337.759588 -273.945622) (xy 337.805746 -273.972271)
			(xy 337.847417 -274.005502) (xy 337.883669 -274.044573) (xy 337.913693 -274.08861) (xy 337.936819 -274.136631)
			(xy 337.952529 -274.187561) (xy 337.960472 -274.240265) (xy 337.96097 -274.266914) (xy 337.960472 -274.293563)
			(xy 338.189052 -274.293563) (xy 338.189052 -274.240265) (xy 338.196995 -274.187561) (xy 338.212705 -274.136631)
			(xy 338.235831 -274.08861) (xy 338.265855 -274.044573) (xy 338.302107 -274.005502) (xy 338.343778 -273.972271)
			(xy 338.389936 -273.945622) (xy 338.43955 -273.92615) (xy 338.491512 -273.91429) (xy 338.544662 -273.910307)
			(xy 338.597812 -273.91429) (xy 338.649774 -273.92615) (xy 338.699388 -273.945622) (xy 338.745546 -273.972271)
			(xy 338.787217 -274.005502) (xy 338.823469 -274.044573) (xy 338.853493 -274.08861) (xy 338.876619 -274.136631)
			(xy 338.892329 -274.187561) (xy 338.900272 -274.240265) (xy 338.90077 -274.266914) (xy 338.900272 -274.293563)
			(xy 339.129106 -274.293563) (xy 339.129106 -274.240265) (xy 339.137049 -274.187561) (xy 339.152759 -274.136631)
			(xy 339.175885 -274.08861) (xy 339.205909 -274.044573) (xy 339.242161 -274.005502) (xy 339.283832 -273.972271)
			(xy 339.32999 -273.945622) (xy 339.379604 -273.92615) (xy 339.431566 -273.91429) (xy 339.484716 -273.910307)
			(xy 339.537866 -273.91429) (xy 339.589828 -273.92615) (xy 339.639442 -273.945622) (xy 339.6856 -273.972271)
			(xy 339.727271 -274.005502) (xy 339.763523 -274.044573) (xy 339.793547 -274.08861) (xy 339.816673 -274.136631)
			(xy 339.832383 -274.187561) (xy 339.840326 -274.240265) (xy 339.840824 -274.266914) (xy 339.840326 -274.293563)
			(xy 340.068652 -274.293563) (xy 340.068652 -274.240265) (xy 340.076595 -274.187561) (xy 340.092305 -274.136631)
			(xy 340.115431 -274.08861) (xy 340.145455 -274.044573) (xy 340.181707 -274.005502) (xy 340.223378 -273.972271)
			(xy 340.269536 -273.945622) (xy 340.31915 -273.92615) (xy 340.371112 -273.91429) (xy 340.424262 -273.910307)
			(xy 340.477412 -273.91429) (xy 340.529374 -273.92615) (xy 340.578988 -273.945622) (xy 340.625146 -273.972271)
			(xy 340.666817 -274.005502) (xy 340.703069 -274.044573) (xy 340.733093 -274.08861) (xy 340.756219 -274.136631)
			(xy 340.771929 -274.187561) (xy 340.779872 -274.240265) (xy 340.78037 -274.266914) (xy 340.779872 -274.293563)
			(xy 341.008452 -274.293563) (xy 341.008452 -274.240265) (xy 341.016395 -274.187561) (xy 341.032105 -274.136631)
			(xy 341.055231 -274.08861) (xy 341.085255 -274.044573) (xy 341.121507 -274.005502) (xy 341.163178 -273.972271)
			(xy 341.209336 -273.945622) (xy 341.25895 -273.92615) (xy 341.310912 -273.91429) (xy 341.364062 -273.910307)
			(xy 341.417212 -273.91429) (xy 341.469174 -273.92615) (xy 341.518788 -273.945622) (xy 341.564946 -273.972271)
			(xy 341.606617 -274.005502) (xy 341.642869 -274.044573) (xy 341.672893 -274.08861) (xy 341.696019 -274.136631)
			(xy 341.711729 -274.187561) (xy 341.719672 -274.240265) (xy 341.72017 -274.266914) (xy 341.719672 -274.293563)
			(xy 341.948252 -274.293563) (xy 341.948252 -274.240265) (xy 341.956195 -274.187561) (xy 341.971905 -274.136631)
			(xy 341.995031 -274.08861) (xy 342.025055 -274.044573) (xy 342.061307 -274.005502) (xy 342.102978 -273.972271)
			(xy 342.149136 -273.945622) (xy 342.19875 -273.92615) (xy 342.250712 -273.91429) (xy 342.303862 -273.910307)
			(xy 342.357012 -273.91429) (xy 342.408974 -273.92615) (xy 342.458588 -273.945622) (xy 342.504746 -273.972271)
			(xy 342.546417 -274.005502) (xy 342.582669 -274.044573) (xy 342.612693 -274.08861) (xy 342.635819 -274.136631)
			(xy 342.651529 -274.187561) (xy 342.659472 -274.240265) (xy 342.65997 -274.266914) (xy 342.659472 -274.293563)
			(xy 342.888052 -274.293563) (xy 342.888052 -274.240265) (xy 342.895995 -274.187561) (xy 342.911705 -274.136631)
			(xy 342.934831 -274.08861) (xy 342.964855 -274.044573) (xy 343.001107 -274.005502) (xy 343.042778 -273.972271)
			(xy 343.088936 -273.945622) (xy 343.13855 -273.92615) (xy 343.190512 -273.91429) (xy 343.243662 -273.910307)
			(xy 343.296812 -273.91429) (xy 343.348774 -273.92615) (xy 343.398388 -273.945622) (xy 343.444546 -273.972271)
			(xy 343.486217 -274.005502) (xy 343.522469 -274.044573) (xy 343.552493 -274.08861) (xy 343.575619 -274.136631)
			(xy 343.591329 -274.187561) (xy 343.599272 -274.240265) (xy 343.59977 -274.266914) (xy 343.599272 -274.293563)
			(xy 343.827852 -274.293563) (xy 343.827852 -274.240265) (xy 343.835795 -274.187561) (xy 343.851505 -274.136631)
			(xy 343.874631 -274.08861) (xy 343.904655 -274.044573) (xy 343.940907 -274.005502) (xy 343.982578 -273.972271)
			(xy 344.028736 -273.945622) (xy 344.07835 -273.92615) (xy 344.130312 -273.91429) (xy 344.183462 -273.910307)
			(xy 344.236612 -273.91429) (xy 344.288574 -273.92615) (xy 344.338188 -273.945622) (xy 344.384346 -273.972271)
			(xy 344.426017 -274.005502) (xy 344.462269 -274.044573) (xy 344.492293 -274.08861) (xy 344.515419 -274.136631)
			(xy 344.531129 -274.187561) (xy 344.539072 -274.240265) (xy 344.53957 -274.266914) (xy 344.539072 -274.293563)
			(xy 344.767652 -274.293563) (xy 344.767652 -274.240265) (xy 344.775595 -274.187561) (xy 344.791305 -274.136631)
			(xy 344.814431 -274.08861) (xy 344.844455 -274.044573) (xy 344.880707 -274.005502) (xy 344.922378 -273.972271)
			(xy 344.968536 -273.945622) (xy 345.01815 -273.92615) (xy 345.070112 -273.91429) (xy 345.123262 -273.910307)
			(xy 345.176412 -273.91429) (xy 345.228374 -273.92615) (xy 345.277988 -273.945622) (xy 345.324146 -273.972271)
			(xy 345.365817 -274.005502) (xy 345.402069 -274.044573) (xy 345.432093 -274.08861) (xy 345.455219 -274.136631)
			(xy 345.470929 -274.187561) (xy 345.478872 -274.240265) (xy 345.47937 -274.266914) (xy 345.478872 -274.293563)
			(xy 345.707452 -274.293563) (xy 345.707452 -274.240265) (xy 345.715395 -274.187561) (xy 345.731105 -274.136631)
			(xy 345.754231 -274.08861) (xy 345.784255 -274.044573) (xy 345.820507 -274.005502) (xy 345.862178 -273.972271)
			(xy 345.908336 -273.945622) (xy 345.95795 -273.92615) (xy 346.009912 -273.91429) (xy 346.063062 -273.910307)
			(xy 346.116212 -273.91429) (xy 346.168174 -273.92615) (xy 346.217788 -273.945622) (xy 346.263946 -273.972271)
			(xy 346.305617 -274.005502) (xy 346.341869 -274.044573) (xy 346.371893 -274.08861) (xy 346.395019 -274.136631)
			(xy 346.410729 -274.187561) (xy 346.418672 -274.240265) (xy 346.41917 -274.266914) (xy 346.418672 -274.293563)
			(xy 346.647252 -274.293563) (xy 346.647252 -274.240265) (xy 346.655195 -274.187561) (xy 346.670905 -274.136631)
			(xy 346.694031 -274.08861) (xy 346.724055 -274.044573) (xy 346.760307 -274.005502) (xy 346.801978 -273.972271)
			(xy 346.848136 -273.945622) (xy 346.89775 -273.92615) (xy 346.949712 -273.91429) (xy 347.002862 -273.910307)
			(xy 347.056012 -273.91429) (xy 347.107974 -273.92615) (xy 347.157588 -273.945622) (xy 347.203746 -273.972271)
			(xy 347.245417 -274.005502) (xy 347.281669 -274.044573) (xy 347.311693 -274.08861) (xy 347.334819 -274.136631)
			(xy 347.350529 -274.187561) (xy 347.358472 -274.240265) (xy 347.35897 -274.266914) (xy 347.358472 -274.293563)
			(xy 347.587052 -274.293563) (xy 347.587052 -274.240265) (xy 347.594995 -274.187561) (xy 347.610705 -274.136631)
			(xy 347.633831 -274.08861) (xy 347.663855 -274.044573) (xy 347.700107 -274.005502) (xy 347.741778 -273.972271)
			(xy 347.787936 -273.945622) (xy 347.83755 -273.92615) (xy 347.889512 -273.91429) (xy 347.942662 -273.910307)
			(xy 347.995812 -273.91429) (xy 348.047774 -273.92615) (xy 348.097388 -273.945622) (xy 348.143546 -273.972271)
			(xy 348.185217 -274.005502) (xy 348.221469 -274.044573) (xy 348.251493 -274.08861) (xy 348.274619 -274.136631)
			(xy 348.290329 -274.187561) (xy 348.298272 -274.240265) (xy 348.29877 -274.266914) (xy 348.298272 -274.293563)
			(xy 348.526852 -274.293563) (xy 348.526852 -274.240265) (xy 348.534795 -274.187561) (xy 348.550505 -274.136631)
			(xy 348.573631 -274.08861) (xy 348.603655 -274.044573) (xy 348.639907 -274.005502) (xy 348.681578 -273.972271)
			(xy 348.727736 -273.945622) (xy 348.77735 -273.92615) (xy 348.829312 -273.91429) (xy 348.882462 -273.910307)
			(xy 348.935612 -273.91429) (xy 348.987574 -273.92615) (xy 349.037188 -273.945622) (xy 349.083346 -273.972271)
			(xy 349.125017 -274.005502) (xy 349.161269 -274.044573) (xy 349.191293 -274.08861) (xy 349.214419 -274.136631)
			(xy 349.230129 -274.187561) (xy 349.238072 -274.240265) (xy 349.23857 -274.266914) (xy 349.238072 -274.293563)
			(xy 349.466652 -274.293563) (xy 349.466652 -274.240265) (xy 349.474595 -274.187561) (xy 349.490305 -274.136631)
			(xy 349.513431 -274.08861) (xy 349.543455 -274.044573) (xy 349.579707 -274.005502) (xy 349.621378 -273.972271)
			(xy 349.667536 -273.945622) (xy 349.71715 -273.92615) (xy 349.769112 -273.91429) (xy 349.822262 -273.910307)
			(xy 349.875412 -273.91429) (xy 349.927374 -273.92615) (xy 349.976988 -273.945622) (xy 350.023146 -273.972271)
			(xy 350.064817 -274.005502) (xy 350.101069 -274.044573) (xy 350.131093 -274.08861) (xy 350.154219 -274.136631)
			(xy 350.169929 -274.187561) (xy 350.177872 -274.240265) (xy 350.17837 -274.266914) (xy 350.177872 -274.293563)
			(xy 350.406452 -274.293563) (xy 350.406452 -274.240265) (xy 350.414395 -274.187561) (xy 350.430105 -274.136631)
			(xy 350.453231 -274.08861) (xy 350.483255 -274.044573) (xy 350.519507 -274.005502) (xy 350.561178 -273.972271)
			(xy 350.607336 -273.945622) (xy 350.65695 -273.92615) (xy 350.708912 -273.91429) (xy 350.762062 -273.910307)
			(xy 350.815212 -273.91429) (xy 350.867174 -273.92615) (xy 350.916788 -273.945622) (xy 350.962946 -273.972271)
			(xy 351.004617 -274.005502) (xy 351.040869 -274.044573) (xy 351.070893 -274.08861) (xy 351.094019 -274.136631)
			(xy 351.109729 -274.187561) (xy 351.117672 -274.240265) (xy 351.11817 -274.266914) (xy 351.345754 -274.266914)
			(xy 351.346252 -274.240265) (xy 351.354195 -274.187561) (xy 351.369905 -274.136631) (xy 351.393031 -274.08861)
			(xy 351.423055 -274.044573) (xy 351.459307 -274.005502) (xy 351.500978 -273.972271) (xy 351.547136 -273.945622)
			(xy 351.59675 -273.92615) (xy 351.648712 -273.91429) (xy 351.701862 -273.910307) (xy 351.755012 -273.91429)
			(xy 351.806974 -273.92615) (xy 351.856588 -273.945622) (xy 351.902746 -273.972271) (xy 351.944417 -274.005502)
			(xy 351.980669 -274.044573) (xy 352.010693 -274.08861) (xy 352.033819 -274.136631) (xy 352.049529 -274.187561)
			(xy 352.057472 -274.240265) (xy 352.05797 -274.266914) (xy 352.057605 -274.290066) (xy 352.057149 -274.293563)
			(xy 352.286052 -274.293563) (xy 352.286052 -274.240265) (xy 352.293995 -274.187561) (xy 352.309705 -274.136631)
			(xy 352.332831 -274.08861) (xy 352.362855 -274.044573) (xy 352.399107 -274.005502) (xy 352.440778 -273.972271)
			(xy 352.486936 -273.945622) (xy 352.53655 -273.92615) (xy 352.588512 -273.91429) (xy 352.641662 -273.910307)
			(xy 352.694812 -273.91429) (xy 352.746774 -273.92615) (xy 352.796388 -273.945622) (xy 352.842546 -273.972271)
			(xy 352.884217 -274.005502) (xy 352.920469 -274.044573) (xy 352.950493 -274.08861) (xy 352.973619 -274.136631)
			(xy 352.989329 -274.187561) (xy 352.997272 -274.240265) (xy 352.99777 -274.266914) (xy 352.997272 -274.293563)
			(xy 354.165652 -274.293563) (xy 354.165652 -274.240265) (xy 354.173595 -274.187561) (xy 354.189305 -274.136631)
			(xy 354.212431 -274.08861) (xy 354.242455 -274.044573) (xy 354.278707 -274.005502) (xy 354.320378 -273.972271)
			(xy 354.366536 -273.945622) (xy 354.41615 -273.92615) (xy 354.468112 -273.91429) (xy 354.521262 -273.910307)
			(xy 354.574412 -273.91429) (xy 354.626374 -273.92615) (xy 354.675988 -273.945622) (xy 354.722146 -273.972271)
			(xy 354.763817 -274.005502) (xy 354.800069 -274.044573) (xy 354.830093 -274.08861) (xy 354.853219 -274.136631)
			(xy 354.868929 -274.187561) (xy 354.876872 -274.240265) (xy 354.87737 -274.266914) (xy 354.876872 -274.293563)
			(xy 354.868929 -274.346267) (xy 354.853219 -274.397197) (xy 354.830093 -274.445218) (xy 354.800069 -274.489255)
			(xy 354.763817 -274.528326) (xy 354.722146 -274.561557) (xy 354.675988 -274.588206) (xy 354.626374 -274.607678)
			(xy 354.574412 -274.619538) (xy 354.521262 -274.623522) (xy 354.468112 -274.619538) (xy 354.41615 -274.607678)
			(xy 354.366536 -274.588206) (xy 354.320378 -274.561557) (xy 354.278707 -274.528326) (xy 354.242455 -274.489255)
			(xy 354.212431 -274.445218) (xy 354.189305 -274.397197) (xy 354.173595 -274.346267) (xy 354.165652 -274.293563)
			(xy 352.997272 -274.293563) (xy 352.989329 -274.346267) (xy 352.973619 -274.397197) (xy 352.950493 -274.445218)
			(xy 352.920469 -274.489255) (xy 352.884217 -274.528326) (xy 352.842546 -274.561557) (xy 352.796388 -274.588206)
			(xy 352.746774 -274.607678) (xy 352.694812 -274.619538) (xy 352.641662 -274.623522) (xy 352.588512 -274.619538)
			(xy 352.53655 -274.607678) (xy 352.486936 -274.588206) (xy 352.440778 -274.561557) (xy 352.399107 -274.528326)
			(xy 352.362855 -274.489255) (xy 352.332831 -274.445218) (xy 352.309705 -274.397197) (xy 352.293995 -274.346267)
			(xy 352.286052 -274.293563) (xy 352.057149 -274.293563) (xy 352.051616 -274.33598) (xy 352.039741 -274.380735)
			(xy 352.0313 -274.402296) (xy 352.021648 -274.42541) (xy 352.194368 -274.724368) (xy 352.219006 -274.72767)
			(xy 352.244342 -274.731533) (xy 352.293646 -274.745519) (xy 352.340436 -274.766426) (xy 352.383747 -274.793823)
			(xy 352.422686 -274.827143) (xy 352.456447 -274.8657) (xy 352.484335 -274.908697) (xy 352.505773 -274.955246)
			(xy 352.52032 -275.004387) (xy 352.527674 -275.055106) (xy 352.528124 -275.08073) (xy 352.527626 -275.107379)
			(xy 352.519683 -275.160083) (xy 352.503973 -275.211013) (xy 352.480847 -275.259034) (xy 352.450823 -275.303071)
			(xy 352.414571 -275.342142) (xy 352.3729 -275.375373) (xy 352.326742 -275.402022) (xy 352.277128 -275.421494)
			(xy 352.225166 -275.433354) (xy 352.172016 -275.437338) (xy 352.118866 -275.433354) (xy 352.066904 -275.421494)
			(xy 352.01729 -275.402022) (xy 351.971132 -275.375373) (xy 351.929461 -275.342142) (xy 351.893209 -275.303071)
			(xy 351.863185 -275.259034) (xy 351.840059 -275.211013) (xy 351.824349 -275.160083) (xy 351.816406 -275.107379)
			(xy 351.815908 -275.08073) (xy 351.816286 -275.057485) (xy 351.822329 -275.01139) (xy 351.834316 -274.966472)
			(xy 351.842832 -274.94484) (xy 351.852484 -274.921726) (xy 351.680018 -274.623276) (xy 351.655126 -274.619974)
			(xy 351.629771 -274.616152) (xy 351.58043 -274.602198) (xy 351.533601 -274.581312) (xy 351.490252 -274.553927)
			(xy 351.451277 -274.520608) (xy 351.417484 -274.482044) (xy 351.38957 -274.439033) (xy 351.368113 -274.392463)
			(xy 351.353557 -274.343297) (xy 351.346201 -274.292552) (xy 351.345754 -274.266914) (xy 351.11817 -274.266914)
			(xy 351.117672 -274.293563) (xy 351.109729 -274.346267) (xy 351.094019 -274.397197) (xy 351.070893 -274.445218)
			(xy 351.040869 -274.489255) (xy 351.004617 -274.528326) (xy 350.962946 -274.561557) (xy 350.916788 -274.588206)
			(xy 350.867174 -274.607678) (xy 350.815212 -274.619538) (xy 350.762062 -274.623522) (xy 350.708912 -274.619538)
			(xy 350.65695 -274.607678) (xy 350.607336 -274.588206) (xy 350.561178 -274.561557) (xy 350.519507 -274.528326)
			(xy 350.483255 -274.489255) (xy 350.453231 -274.445218) (xy 350.430105 -274.397197) (xy 350.414395 -274.346267)
			(xy 350.406452 -274.293563) (xy 350.177872 -274.293563) (xy 350.169929 -274.346267) (xy 350.154219 -274.397197)
			(xy 350.131093 -274.445218) (xy 350.101069 -274.489255) (xy 350.064817 -274.528326) (xy 350.023146 -274.561557)
			(xy 349.976988 -274.588206) (xy 349.927374 -274.607678) (xy 349.875412 -274.619538) (xy 349.822262 -274.623522)
			(xy 349.769112 -274.619538) (xy 349.71715 -274.607678) (xy 349.667536 -274.588206) (xy 349.621378 -274.561557)
			(xy 349.579707 -274.528326) (xy 349.543455 -274.489255) (xy 349.513431 -274.445218) (xy 349.490305 -274.397197)
			(xy 349.474595 -274.346267) (xy 349.466652 -274.293563) (xy 349.238072 -274.293563) (xy 349.230129 -274.346267)
			(xy 349.214419 -274.397197) (xy 349.191293 -274.445218) (xy 349.161269 -274.489255) (xy 349.125017 -274.528326)
			(xy 349.083346 -274.561557) (xy 349.037188 -274.588206) (xy 348.987574 -274.607678) (xy 348.935612 -274.619538)
			(xy 348.882462 -274.623522) (xy 348.829312 -274.619538) (xy 348.77735 -274.607678) (xy 348.727736 -274.588206)
			(xy 348.681578 -274.561557) (xy 348.639907 -274.528326) (xy 348.603655 -274.489255) (xy 348.573631 -274.445218)
			(xy 348.550505 -274.397197) (xy 348.534795 -274.346267) (xy 348.526852 -274.293563) (xy 348.298272 -274.293563)
			(xy 348.290329 -274.346267) (xy 348.274619 -274.397197) (xy 348.251493 -274.445218) (xy 348.221469 -274.489255)
			(xy 348.185217 -274.528326) (xy 348.143546 -274.561557) (xy 348.097388 -274.588206) (xy 348.047774 -274.607678)
			(xy 347.995812 -274.619538) (xy 347.942662 -274.623522) (xy 347.889512 -274.619538) (xy 347.83755 -274.607678)
			(xy 347.787936 -274.588206) (xy 347.741778 -274.561557) (xy 347.700107 -274.528326) (xy 347.663855 -274.489255)
			(xy 347.633831 -274.445218) (xy 347.610705 -274.397197) (xy 347.594995 -274.346267) (xy 347.587052 -274.293563)
			(xy 347.358472 -274.293563) (xy 347.350529 -274.346267) (xy 347.334819 -274.397197) (xy 347.311693 -274.445218)
			(xy 347.281669 -274.489255) (xy 347.245417 -274.528326) (xy 347.203746 -274.561557) (xy 347.157588 -274.588206)
			(xy 347.107974 -274.607678) (xy 347.056012 -274.619538) (xy 347.002862 -274.623522) (xy 346.949712 -274.619538)
			(xy 346.89775 -274.607678) (xy 346.848136 -274.588206) (xy 346.801978 -274.561557) (xy 346.760307 -274.528326)
			(xy 346.724055 -274.489255) (xy 346.694031 -274.445218) (xy 346.670905 -274.397197) (xy 346.655195 -274.346267)
			(xy 346.647252 -274.293563) (xy 346.418672 -274.293563) (xy 346.410729 -274.346267) (xy 346.395019 -274.397197)
			(xy 346.371893 -274.445218) (xy 346.341869 -274.489255) (xy 346.305617 -274.528326) (xy 346.263946 -274.561557)
			(xy 346.217788 -274.588206) (xy 346.168174 -274.607678) (xy 346.116212 -274.619538) (xy 346.063062 -274.623522)
			(xy 346.009912 -274.619538) (xy 345.95795 -274.607678) (xy 345.908336 -274.588206) (xy 345.862178 -274.561557)
			(xy 345.820507 -274.528326) (xy 345.784255 -274.489255) (xy 345.754231 -274.445218) (xy 345.731105 -274.397197)
			(xy 345.715395 -274.346267) (xy 345.707452 -274.293563) (xy 345.478872 -274.293563) (xy 345.470929 -274.346267)
			(xy 345.455219 -274.397197) (xy 345.432093 -274.445218) (xy 345.402069 -274.489255) (xy 345.365817 -274.528326)
			(xy 345.324146 -274.561557) (xy 345.277988 -274.588206) (xy 345.228374 -274.607678) (xy 345.176412 -274.619538)
			(xy 345.123262 -274.623522) (xy 345.070112 -274.619538) (xy 345.01815 -274.607678) (xy 344.968536 -274.588206)
			(xy 344.922378 -274.561557) (xy 344.880707 -274.528326) (xy 344.844455 -274.489255) (xy 344.814431 -274.445218)
			(xy 344.791305 -274.397197) (xy 344.775595 -274.346267) (xy 344.767652 -274.293563) (xy 344.539072 -274.293563)
			(xy 344.531129 -274.346267) (xy 344.515419 -274.397197) (xy 344.492293 -274.445218) (xy 344.462269 -274.489255)
			(xy 344.426017 -274.528326) (xy 344.384346 -274.561557) (xy 344.338188 -274.588206) (xy 344.288574 -274.607678)
			(xy 344.236612 -274.619538) (xy 344.183462 -274.623522) (xy 344.130312 -274.619538) (xy 344.07835 -274.607678)
			(xy 344.028736 -274.588206) (xy 343.982578 -274.561557) (xy 343.940907 -274.528326) (xy 343.904655 -274.489255)
			(xy 343.874631 -274.445218) (xy 343.851505 -274.397197) (xy 343.835795 -274.346267) (xy 343.827852 -274.293563)
			(xy 343.599272 -274.293563) (xy 343.591329 -274.346267) (xy 343.575619 -274.397197) (xy 343.552493 -274.445218)
			(xy 343.522469 -274.489255) (xy 343.486217 -274.528326) (xy 343.444546 -274.561557) (xy 343.398388 -274.588206)
			(xy 343.348774 -274.607678) (xy 343.296812 -274.619538) (xy 343.243662 -274.623522) (xy 343.190512 -274.619538)
			(xy 343.13855 -274.607678) (xy 343.088936 -274.588206) (xy 343.042778 -274.561557) (xy 343.001107 -274.528326)
			(xy 342.964855 -274.489255) (xy 342.934831 -274.445218) (xy 342.911705 -274.397197) (xy 342.895995 -274.346267)
			(xy 342.888052 -274.293563) (xy 342.659472 -274.293563) (xy 342.651529 -274.346267) (xy 342.635819 -274.397197)
			(xy 342.612693 -274.445218) (xy 342.582669 -274.489255) (xy 342.546417 -274.528326) (xy 342.504746 -274.561557)
			(xy 342.458588 -274.588206) (xy 342.408974 -274.607678) (xy 342.357012 -274.619538) (xy 342.303862 -274.623522)
			(xy 342.250712 -274.619538) (xy 342.19875 -274.607678) (xy 342.149136 -274.588206) (xy 342.102978 -274.561557)
			(xy 342.061307 -274.528326) (xy 342.025055 -274.489255) (xy 341.995031 -274.445218) (xy 341.971905 -274.397197)
			(xy 341.956195 -274.346267) (xy 341.948252 -274.293563) (xy 341.719672 -274.293563) (xy 341.711729 -274.346267)
			(xy 341.696019 -274.397197) (xy 341.672893 -274.445218) (xy 341.642869 -274.489255) (xy 341.606617 -274.528326)
			(xy 341.564946 -274.561557) (xy 341.518788 -274.588206) (xy 341.469174 -274.607678) (xy 341.417212 -274.619538)
			(xy 341.364062 -274.623522) (xy 341.310912 -274.619538) (xy 341.25895 -274.607678) (xy 341.209336 -274.588206)
			(xy 341.163178 -274.561557) (xy 341.121507 -274.528326) (xy 341.085255 -274.489255) (xy 341.055231 -274.445218)
			(xy 341.032105 -274.397197) (xy 341.016395 -274.346267) (xy 341.008452 -274.293563) (xy 340.779872 -274.293563)
			(xy 340.771929 -274.346267) (xy 340.756219 -274.397197) (xy 340.733093 -274.445218) (xy 340.703069 -274.489255)
			(xy 340.666817 -274.528326) (xy 340.625146 -274.561557) (xy 340.578988 -274.588206) (xy 340.529374 -274.607678)
			(xy 340.477412 -274.619538) (xy 340.424262 -274.623522) (xy 340.371112 -274.619538) (xy 340.31915 -274.607678)
			(xy 340.269536 -274.588206) (xy 340.223378 -274.561557) (xy 340.181707 -274.528326) (xy 340.145455 -274.489255)
			(xy 340.115431 -274.445218) (xy 340.092305 -274.397197) (xy 340.076595 -274.346267) (xy 340.068652 -274.293563)
			(xy 339.840326 -274.293563) (xy 339.832383 -274.346267) (xy 339.816673 -274.397197) (xy 339.793547 -274.445218)
			(xy 339.763523 -274.489255) (xy 339.727271 -274.528326) (xy 339.6856 -274.561557) (xy 339.639442 -274.588206)
			(xy 339.589828 -274.607678) (xy 339.537866 -274.619538) (xy 339.484716 -274.623522) (xy 339.431566 -274.619538)
			(xy 339.379604 -274.607678) (xy 339.32999 -274.588206) (xy 339.283832 -274.561557) (xy 339.242161 -274.528326)
			(xy 339.205909 -274.489255) (xy 339.175885 -274.445218) (xy 339.152759 -274.397197) (xy 339.137049 -274.346267)
			(xy 339.129106 -274.293563) (xy 338.900272 -274.293563) (xy 338.892329 -274.346267) (xy 338.876619 -274.397197)
			(xy 338.853493 -274.445218) (xy 338.823469 -274.489255) (xy 338.787217 -274.528326) (xy 338.745546 -274.561557)
			(xy 338.699388 -274.588206) (xy 338.649774 -274.607678) (xy 338.597812 -274.619538) (xy 338.544662 -274.623522)
			(xy 338.491512 -274.619538) (xy 338.43955 -274.607678) (xy 338.389936 -274.588206) (xy 338.343778 -274.561557)
			(xy 338.302107 -274.528326) (xy 338.265855 -274.489255) (xy 338.235831 -274.445218) (xy 338.212705 -274.397197)
			(xy 338.196995 -274.346267) (xy 338.189052 -274.293563) (xy 337.960472 -274.293563) (xy 337.952529 -274.346267)
			(xy 337.936819 -274.397197) (xy 337.913693 -274.445218) (xy 337.883669 -274.489255) (xy 337.847417 -274.528326)
			(xy 337.805746 -274.561557) (xy 337.759588 -274.588206) (xy 337.709974 -274.607678) (xy 337.658012 -274.619538)
			(xy 337.604862 -274.623522) (xy 337.551712 -274.619538) (xy 337.49975 -274.607678) (xy 337.450136 -274.588206)
			(xy 337.403978 -274.561557) (xy 337.362307 -274.528326) (xy 337.326055 -274.489255) (xy 337.296031 -274.445218)
			(xy 337.272905 -274.397197) (xy 337.257195 -274.346267) (xy 337.249252 -274.293563) (xy 337.020672 -274.293563)
			(xy 337.012729 -274.346267) (xy 336.997019 -274.397197) (xy 336.973893 -274.445218) (xy 336.943869 -274.489255)
			(xy 336.907617 -274.528326) (xy 336.865946 -274.561557) (xy 336.819788 -274.588206) (xy 336.770174 -274.607678)
			(xy 336.718212 -274.619538) (xy 336.665062 -274.623522) (xy 336.611912 -274.619538) (xy 336.55995 -274.607678)
			(xy 336.510336 -274.588206) (xy 336.464178 -274.561557) (xy 336.422507 -274.528326) (xy 336.386255 -274.489255)
			(xy 336.356231 -274.445218) (xy 336.333105 -274.397197) (xy 336.317395 -274.346267) (xy 336.309452 -274.293563)
			(xy 336.080873 -274.293563) (xy 336.080848 -274.294898) (xy 336.072091 -274.350175) (xy 336.054793 -274.403402)
			(xy 336.029382 -274.453268) (xy 335.996482 -274.498544) (xy 335.956904 -274.538116) (xy 335.911623 -274.571009)
			(xy 335.861754 -274.596413) (xy 335.808525 -274.613703) (xy 335.753246 -274.622452) (xy 335.725262 -274.623022)
			(xy 335.700406 -274.622594) (xy 335.651176 -274.615691) (xy 335.603383 -274.602009) (xy 335.557958 -274.581815)
			(xy 335.515781 -274.555501) (xy 335.477674 -274.523578) (xy 335.444374 -274.486666) (xy 335.430114 -274.466304)
			(xy 335.4213 -274.454234) (xy 335.39811 -274.435404) (xy 335.370468 -274.424074) (xy 335.340733 -274.421212)
			(xy 335.311438 -274.427059) (xy 335.285081 -274.441119) (xy 335.274158 -274.451318) (xy 335.174082 -274.551394)
			(xy 335.163833 -274.562477) (xy 335.14974 -274.589154) (xy 335.144056 -274.618785) (xy 335.147277 -274.648783)
			(xy 335.159122 -274.676532) (xy 335.178558 -274.699608) (xy 335.203888 -274.716) (xy 335.232901 -274.724275)
			(xy 335.247996 -274.724622) (xy 335.255108 -274.724622) (xy 335.282185 -274.725128) (xy 335.335715 -274.73333)
			(xy 335.387386 -274.749542) (xy 335.436006 -274.773392) (xy 335.480454 -274.804329) (xy 335.519704 -274.84164)
			(xy 335.552853 -274.884465) (xy 335.579134 -274.931814) (xy 335.597942 -274.982598) (xy 335.608844 -275.035644)
			(xy 335.611588 -275.089729) (xy 335.609793 -275.107379) (xy 335.839552 -275.107379) (xy 335.839552 -275.054081)
			(xy 335.847495 -275.001377) (xy 335.863205 -274.950447) (xy 335.886331 -274.902426) (xy 335.916355 -274.858389)
			(xy 335.952607 -274.819318) (xy 335.994278 -274.786087) (xy 336.040436 -274.759438) (xy 336.09005 -274.739966)
			(xy 336.142012 -274.728106) (xy 336.195162 -274.724123) (xy 336.248312 -274.728106) (xy 336.300274 -274.739966)
			(xy 336.349888 -274.759438) (xy 336.396046 -274.786087) (xy 336.437717 -274.819318) (xy 336.473969 -274.858389)
			(xy 336.503993 -274.902426) (xy 336.527119 -274.950447) (xy 336.542829 -275.001377) (xy 336.550772 -275.054081)
			(xy 336.55127 -275.08073) (xy 336.550772 -275.107379) (xy 336.779352 -275.107379) (xy 336.779352 -275.054081)
			(xy 336.787295 -275.001377) (xy 336.803005 -274.950447) (xy 336.826131 -274.902426) (xy 336.856155 -274.858389)
			(xy 336.892407 -274.819318) (xy 336.934078 -274.786087) (xy 336.980236 -274.759438) (xy 337.02985 -274.739966)
			(xy 337.081812 -274.728106) (xy 337.134962 -274.724123) (xy 337.188112 -274.728106) (xy 337.240074 -274.739966)
			(xy 337.289688 -274.759438) (xy 337.335846 -274.786087) (xy 337.377517 -274.819318) (xy 337.413769 -274.858389)
			(xy 337.443793 -274.902426) (xy 337.466919 -274.950447) (xy 337.482629 -275.001377) (xy 337.490572 -275.054081)
			(xy 337.49107 -275.08073) (xy 337.490572 -275.107379) (xy 337.719152 -275.107379) (xy 337.719152 -275.054081)
			(xy 337.727095 -275.001377) (xy 337.742805 -274.950447) (xy 337.765931 -274.902426) (xy 337.795955 -274.858389)
			(xy 337.832207 -274.819318) (xy 337.873878 -274.786087) (xy 337.920036 -274.759438) (xy 337.96965 -274.739966)
			(xy 338.021612 -274.728106) (xy 338.074762 -274.724123) (xy 338.127912 -274.728106) (xy 338.179874 -274.739966)
			(xy 338.229488 -274.759438) (xy 338.275646 -274.786087) (xy 338.317317 -274.819318) (xy 338.353569 -274.858389)
			(xy 338.383593 -274.902426) (xy 338.406719 -274.950447) (xy 338.422429 -275.001377) (xy 338.430372 -275.054081)
			(xy 338.43087 -275.08073) (xy 338.430372 -275.107379) (xy 338.659206 -275.107379) (xy 338.659206 -275.054081)
			(xy 338.667149 -275.001377) (xy 338.682859 -274.950447) (xy 338.705985 -274.902426) (xy 338.736009 -274.858389)
			(xy 338.772261 -274.819318) (xy 338.813932 -274.786087) (xy 338.86009 -274.759438) (xy 338.909704 -274.739966)
			(xy 338.961666 -274.728106) (xy 339.014816 -274.724123) (xy 339.067966 -274.728106) (xy 339.119928 -274.739966)
			(xy 339.169542 -274.759438) (xy 339.2157 -274.786087) (xy 339.257371 -274.819318) (xy 339.293623 -274.858389)
			(xy 339.323647 -274.902426) (xy 339.346773 -274.950447) (xy 339.362483 -275.001377) (xy 339.370426 -275.054081)
			(xy 339.370924 -275.08073) (xy 339.370426 -275.107379) (xy 339.598752 -275.107379) (xy 339.598752 -275.054081)
			(xy 339.606695 -275.001377) (xy 339.622405 -274.950447) (xy 339.645531 -274.902426) (xy 339.675555 -274.858389)
			(xy 339.711807 -274.819318) (xy 339.753478 -274.786087) (xy 339.799636 -274.759438) (xy 339.84925 -274.739966)
			(xy 339.901212 -274.728106) (xy 339.954362 -274.724123) (xy 340.007512 -274.728106) (xy 340.059474 -274.739966)
			(xy 340.109088 -274.759438) (xy 340.155246 -274.786087) (xy 340.196917 -274.819318) (xy 340.233169 -274.858389)
			(xy 340.263193 -274.902426) (xy 340.286319 -274.950447) (xy 340.302029 -275.001377) (xy 340.309972 -275.054081)
			(xy 340.31047 -275.08073) (xy 340.309972 -275.107379) (xy 340.538806 -275.107379) (xy 340.538806 -275.054081)
			(xy 340.546749 -275.001377) (xy 340.562459 -274.950447) (xy 340.585585 -274.902426) (xy 340.615609 -274.858389)
			(xy 340.651861 -274.819318) (xy 340.693532 -274.786087) (xy 340.73969 -274.759438) (xy 340.789304 -274.739966)
			(xy 340.841266 -274.728106) (xy 340.894416 -274.724123) (xy 340.947566 -274.728106) (xy 340.999528 -274.739966)
			(xy 341.049142 -274.759438) (xy 341.0953 -274.786087) (xy 341.136971 -274.819318) (xy 341.173223 -274.858389)
			(xy 341.203247 -274.902426) (xy 341.226373 -274.950447) (xy 341.242083 -275.001377) (xy 341.250026 -275.054081)
			(xy 341.250524 -275.08073) (xy 341.250026 -275.107379) (xy 341.478606 -275.107379) (xy 341.478606 -275.054081)
			(xy 341.486549 -275.001377) (xy 341.502259 -274.950447) (xy 341.525385 -274.902426) (xy 341.555409 -274.858389)
			(xy 341.591661 -274.819318) (xy 341.633332 -274.786087) (xy 341.67949 -274.759438) (xy 341.729104 -274.739966)
			(xy 341.781066 -274.728106) (xy 341.834216 -274.724123) (xy 341.887366 -274.728106) (xy 341.939328 -274.739966)
			(xy 341.988942 -274.759438) (xy 342.0351 -274.786087) (xy 342.076771 -274.819318) (xy 342.113023 -274.858389)
			(xy 342.143047 -274.902426) (xy 342.166173 -274.950447) (xy 342.181883 -275.001377) (xy 342.189826 -275.054081)
			(xy 342.190324 -275.08073) (xy 342.189826 -275.107379) (xy 342.418406 -275.107379) (xy 342.418406 -275.054081)
			(xy 342.426349 -275.001377) (xy 342.442059 -274.950447) (xy 342.465185 -274.902426) (xy 342.495209 -274.858389)
			(xy 342.531461 -274.819318) (xy 342.573132 -274.786087) (xy 342.61929 -274.759438) (xy 342.668904 -274.739966)
			(xy 342.720866 -274.728106) (xy 342.774016 -274.724123) (xy 342.827166 -274.728106) (xy 342.879128 -274.739966)
			(xy 342.928742 -274.759438) (xy 342.9749 -274.786087) (xy 343.016571 -274.819318) (xy 343.052823 -274.858389)
			(xy 343.082847 -274.902426) (xy 343.105973 -274.950447) (xy 343.121683 -275.001377) (xy 343.129626 -275.054081)
			(xy 343.130124 -275.08073) (xy 343.129626 -275.107379) (xy 343.358206 -275.107379) (xy 343.358206 -275.054081)
			(xy 343.366149 -275.001377) (xy 343.381859 -274.950447) (xy 343.404985 -274.902426) (xy 343.435009 -274.858389)
			(xy 343.471261 -274.819318) (xy 343.512932 -274.786087) (xy 343.55909 -274.759438) (xy 343.608704 -274.739966)
			(xy 343.660666 -274.728106) (xy 343.713816 -274.724123) (xy 343.766966 -274.728106) (xy 343.818928 -274.739966)
			(xy 343.868542 -274.759438) (xy 343.9147 -274.786087) (xy 343.956371 -274.819318) (xy 343.992623 -274.858389)
			(xy 344.022647 -274.902426) (xy 344.045773 -274.950447) (xy 344.061483 -275.001377) (xy 344.069426 -275.054081)
			(xy 344.069924 -275.08073) (xy 344.069426 -275.107379) (xy 344.298006 -275.107379) (xy 344.298006 -275.054081)
			(xy 344.305949 -275.001377) (xy 344.321659 -274.950447) (xy 344.344785 -274.902426) (xy 344.374809 -274.858389)
			(xy 344.411061 -274.819318) (xy 344.452732 -274.786087) (xy 344.49889 -274.759438) (xy 344.548504 -274.739966)
			(xy 344.600466 -274.728106) (xy 344.653616 -274.724123) (xy 344.706766 -274.728106) (xy 344.758728 -274.739966)
			(xy 344.808342 -274.759438) (xy 344.8545 -274.786087) (xy 344.896171 -274.819318) (xy 344.932423 -274.858389)
			(xy 344.962447 -274.902426) (xy 344.985573 -274.950447) (xy 345.001283 -275.001377) (xy 345.009226 -275.054081)
			(xy 345.009724 -275.08073) (xy 345.009226 -275.107379) (xy 345.237806 -275.107379) (xy 345.237806 -275.054081)
			(xy 345.245749 -275.001377) (xy 345.261459 -274.950447) (xy 345.284585 -274.902426) (xy 345.314609 -274.858389)
			(xy 345.350861 -274.819318) (xy 345.392532 -274.786087) (xy 345.43869 -274.759438) (xy 345.488304 -274.739966)
			(xy 345.540266 -274.728106) (xy 345.593416 -274.724123) (xy 345.646566 -274.728106) (xy 345.698528 -274.739966)
			(xy 345.748142 -274.759438) (xy 345.7943 -274.786087) (xy 345.835971 -274.819318) (xy 345.872223 -274.858389)
			(xy 345.902247 -274.902426) (xy 345.925373 -274.950447) (xy 345.941083 -275.001377) (xy 345.949026 -275.054081)
			(xy 345.949524 -275.08073) (xy 345.949026 -275.107379) (xy 346.177352 -275.107379) (xy 346.177352 -275.054081)
			(xy 346.185295 -275.001377) (xy 346.201005 -274.950447) (xy 346.224131 -274.902426) (xy 346.254155 -274.858389)
			(xy 346.290407 -274.819318) (xy 346.332078 -274.786087) (xy 346.378236 -274.759438) (xy 346.42785 -274.739966)
			(xy 346.479812 -274.728106) (xy 346.532962 -274.724123) (xy 346.586112 -274.728106) (xy 346.638074 -274.739966)
			(xy 346.687688 -274.759438) (xy 346.733846 -274.786087) (xy 346.775517 -274.819318) (xy 346.811769 -274.858389)
			(xy 346.841793 -274.902426) (xy 346.864919 -274.950447) (xy 346.880629 -275.001377) (xy 346.888572 -275.054081)
			(xy 346.88907 -275.08073) (xy 346.888572 -275.107379) (xy 347.117406 -275.107379) (xy 347.117406 -275.054081)
			(xy 347.125349 -275.001377) (xy 347.141059 -274.950447) (xy 347.164185 -274.902426) (xy 347.194209 -274.858389)
			(xy 347.230461 -274.819318) (xy 347.272132 -274.786087) (xy 347.31829 -274.759438) (xy 347.367904 -274.739966)
			(xy 347.419866 -274.728106) (xy 347.473016 -274.724123) (xy 347.526166 -274.728106) (xy 347.578128 -274.739966)
			(xy 347.627742 -274.759438) (xy 347.6739 -274.786087) (xy 347.715571 -274.819318) (xy 347.751823 -274.858389)
			(xy 347.781847 -274.902426) (xy 347.804973 -274.950447) (xy 347.820683 -275.001377) (xy 347.828626 -275.054081)
			(xy 347.829124 -275.08073) (xy 347.828626 -275.107379) (xy 348.057206 -275.107379) (xy 348.057206 -275.054081)
			(xy 348.065149 -275.001377) (xy 348.080859 -274.950447) (xy 348.103985 -274.902426) (xy 348.134009 -274.858389)
			(xy 348.170261 -274.819318) (xy 348.211932 -274.786087) (xy 348.25809 -274.759438) (xy 348.307704 -274.739966)
			(xy 348.359666 -274.728106) (xy 348.412816 -274.724123) (xy 348.465966 -274.728106) (xy 348.517928 -274.739966)
			(xy 348.567542 -274.759438) (xy 348.6137 -274.786087) (xy 348.655371 -274.819318) (xy 348.691623 -274.858389)
			(xy 348.721647 -274.902426) (xy 348.744773 -274.950447) (xy 348.760483 -275.001377) (xy 348.768426 -275.054081)
			(xy 348.768923 -275.0807) (xy 349.935798 -275.0807) (xy 349.939781 -275.02755) (xy 349.951642 -274.975587)
			(xy 349.971115 -274.925972) (xy 349.997765 -274.879814) (xy 350.030997 -274.838143) (xy 350.070069 -274.801892)
			(xy 350.114108 -274.771868) (xy 350.16213 -274.748744) (xy 350.213062 -274.733036) (xy 350.265766 -274.725094)
			(xy 350.292416 -274.724622) (xy 350.317442 -274.72502) (xy 350.367001 -274.732031) (xy 350.41509 -274.745912)
			(xy 350.460761 -274.766391) (xy 350.503115 -274.793063) (xy 350.541317 -274.825404) (xy 350.574613 -274.862775)
			(xy 350.588834 -274.883372) (xy 350.935798 -274.883372) (xy 350.950021 -274.862777) (xy 350.983318 -274.825409)
			(xy 351.02152 -274.793072) (xy 351.063874 -274.766404) (xy 351.109545 -274.745929) (xy 351.157633 -274.732052)
			(xy 351.207191 -274.725045) (xy 351.232216 -274.724622) (xy 351.258867 -274.725061) (xy 351.311573 -274.733007)
			(xy 351.362506 -274.74872) (xy 351.410528 -274.771848) (xy 351.454567 -274.801875) (xy 351.493639 -274.83813)
			(xy 351.526871 -274.879804) (xy 351.553521 -274.925965) (xy 351.572994 -274.975582) (xy 351.584854 -275.027547)
			(xy 351.588838 -275.0807) (xy 351.584854 -275.133853) (xy 351.572994 -275.185818) (xy 351.553521 -275.235435)
			(xy 351.526871 -275.281596) (xy 351.493639 -275.32327) (xy 351.454567 -275.359525) (xy 351.410528 -275.389552)
			(xy 351.362506 -275.41268) (xy 351.311573 -275.428393) (xy 351.258867 -275.436339) (xy 351.232216 -275.436838)
			(xy 351.207192 -275.43639) (xy 351.157636 -275.429384) (xy 351.10955 -275.415509) (xy 351.063879 -275.395038)
			(xy 351.021525 -275.368375) (xy 350.983322 -275.336043) (xy 350.950022 -275.298681) (xy 350.935798 -275.278088)
			(xy 350.588834 -275.278088) (xy 350.57461 -275.298682) (xy 350.541311 -275.336047) (xy 350.503108 -275.368382)
			(xy 350.460754 -275.395049) (xy 350.415084 -275.415524) (xy 350.366997 -275.429403) (xy 350.317441 -275.436413)
			(xy 350.292416 -275.436838) (xy 350.265766 -275.436306) (xy 350.213062 -275.428364) (xy 350.16213 -275.412656)
			(xy 350.114108 -275.389532) (xy 350.070069 -275.359508) (xy 350.030997 -275.323257) (xy 349.997765 -275.281586)
			(xy 349.971115 -275.235428) (xy 349.951642 -275.185813) (xy 349.939781 -275.13385) (xy 349.935798 -275.0807)
			(xy 348.768923 -275.0807) (xy 348.768924 -275.08073) (xy 348.768426 -275.107379) (xy 348.760483 -275.160083)
			(xy 348.744773 -275.211013) (xy 348.721647 -275.259034) (xy 348.691623 -275.303071) (xy 348.655371 -275.342142)
			(xy 348.6137 -275.375373) (xy 348.567542 -275.402022) (xy 348.517928 -275.421494) (xy 348.465966 -275.433354)
			(xy 348.412816 -275.437338) (xy 348.359666 -275.433354) (xy 348.307704 -275.421494) (xy 348.25809 -275.402022)
			(xy 348.211932 -275.375373) (xy 348.170261 -275.342142) (xy 348.134009 -275.303071) (xy 348.103985 -275.259034)
			(xy 348.080859 -275.211013) (xy 348.065149 -275.160083) (xy 348.057206 -275.107379) (xy 347.828626 -275.107379)
			(xy 347.820683 -275.160083) (xy 347.804973 -275.211013) (xy 347.781847 -275.259034) (xy 347.751823 -275.303071)
			(xy 347.715571 -275.342142) (xy 347.6739 -275.375373) (xy 347.627742 -275.402022) (xy 347.578128 -275.421494)
			(xy 347.526166 -275.433354) (xy 347.473016 -275.437338) (xy 347.419866 -275.433354) (xy 347.367904 -275.421494)
			(xy 347.31829 -275.402022) (xy 347.272132 -275.375373) (xy 347.230461 -275.342142) (xy 347.194209 -275.303071)
			(xy 347.164185 -275.259034) (xy 347.141059 -275.211013) (xy 347.125349 -275.160083) (xy 347.117406 -275.107379)
			(xy 346.888572 -275.107379) (xy 346.880629 -275.160083) (xy 346.864919 -275.211013) (xy 346.841793 -275.259034)
			(xy 346.811769 -275.303071) (xy 346.775517 -275.342142) (xy 346.733846 -275.375373) (xy 346.687688 -275.402022)
			(xy 346.638074 -275.421494) (xy 346.586112 -275.433354) (xy 346.532962 -275.437338) (xy 346.479812 -275.433354)
			(xy 346.42785 -275.421494) (xy 346.378236 -275.402022) (xy 346.332078 -275.375373) (xy 346.290407 -275.342142)
			(xy 346.254155 -275.303071) (xy 346.224131 -275.259034) (xy 346.201005 -275.211013) (xy 346.185295 -275.160083)
			(xy 346.177352 -275.107379) (xy 345.949026 -275.107379) (xy 345.941083 -275.160083) (xy 345.925373 -275.211013)
			(xy 345.902247 -275.259034) (xy 345.872223 -275.303071) (xy 345.835971 -275.342142) (xy 345.7943 -275.375373)
			(xy 345.748142 -275.402022) (xy 345.698528 -275.421494) (xy 345.646566 -275.433354) (xy 345.593416 -275.437338)
			(xy 345.540266 -275.433354) (xy 345.488304 -275.421494) (xy 345.43869 -275.402022) (xy 345.392532 -275.375373)
			(xy 345.350861 -275.342142) (xy 345.314609 -275.303071) (xy 345.284585 -275.259034) (xy 345.261459 -275.211013)
			(xy 345.245749 -275.160083) (xy 345.237806 -275.107379) (xy 345.009226 -275.107379) (xy 345.001283 -275.160083)
			(xy 344.985573 -275.211013) (xy 344.962447 -275.259034) (xy 344.932423 -275.303071) (xy 344.896171 -275.342142)
			(xy 344.8545 -275.375373) (xy 344.808342 -275.402022) (xy 344.758728 -275.421494) (xy 344.706766 -275.433354)
			(xy 344.653616 -275.437338) (xy 344.600466 -275.433354) (xy 344.548504 -275.421494) (xy 344.49889 -275.402022)
			(xy 344.452732 -275.375373) (xy 344.411061 -275.342142) (xy 344.374809 -275.303071) (xy 344.344785 -275.259034)
			(xy 344.321659 -275.211013) (xy 344.305949 -275.160083) (xy 344.298006 -275.107379) (xy 344.069426 -275.107379)
			(xy 344.061483 -275.160083) (xy 344.045773 -275.211013) (xy 344.022647 -275.259034) (xy 343.992623 -275.303071)
			(xy 343.956371 -275.342142) (xy 343.9147 -275.375373) (xy 343.868542 -275.402022) (xy 343.818928 -275.421494)
			(xy 343.766966 -275.433354) (xy 343.713816 -275.437338) (xy 343.660666 -275.433354) (xy 343.608704 -275.421494)
			(xy 343.55909 -275.402022) (xy 343.512932 -275.375373) (xy 343.471261 -275.342142) (xy 343.435009 -275.303071)
			(xy 343.404985 -275.259034) (xy 343.381859 -275.211013) (xy 343.366149 -275.160083) (xy 343.358206 -275.107379)
			(xy 343.129626 -275.107379) (xy 343.121683 -275.160083) (xy 343.105973 -275.211013) (xy 343.082847 -275.259034)
			(xy 343.052823 -275.303071) (xy 343.016571 -275.342142) (xy 342.9749 -275.375373) (xy 342.928742 -275.402022)
			(xy 342.879128 -275.421494) (xy 342.827166 -275.433354) (xy 342.774016 -275.437338) (xy 342.720866 -275.433354)
			(xy 342.668904 -275.421494) (xy 342.61929 -275.402022) (xy 342.573132 -275.375373) (xy 342.531461 -275.342142)
			(xy 342.495209 -275.303071) (xy 342.465185 -275.259034) (xy 342.442059 -275.211013) (xy 342.426349 -275.160083)
			(xy 342.418406 -275.107379) (xy 342.189826 -275.107379) (xy 342.181883 -275.160083) (xy 342.166173 -275.211013)
			(xy 342.143047 -275.259034) (xy 342.113023 -275.303071) (xy 342.076771 -275.342142) (xy 342.0351 -275.375373)
			(xy 341.988942 -275.402022) (xy 341.939328 -275.421494) (xy 341.887366 -275.433354) (xy 341.834216 -275.437338)
			(xy 341.781066 -275.433354) (xy 341.729104 -275.421494) (xy 341.67949 -275.402022) (xy 341.633332 -275.375373)
			(xy 341.591661 -275.342142) (xy 341.555409 -275.303071) (xy 341.525385 -275.259034) (xy 341.502259 -275.211013)
			(xy 341.486549 -275.160083) (xy 341.478606 -275.107379) (xy 341.250026 -275.107379) (xy 341.242083 -275.160083)
			(xy 341.226373 -275.211013) (xy 341.203247 -275.259034) (xy 341.173223 -275.303071) (xy 341.136971 -275.342142)
			(xy 341.0953 -275.375373) (xy 341.049142 -275.402022) (xy 340.999528 -275.421494) (xy 340.947566 -275.433354)
			(xy 340.894416 -275.437338) (xy 340.841266 -275.433354) (xy 340.789304 -275.421494) (xy 340.73969 -275.402022)
			(xy 340.693532 -275.375373) (xy 340.651861 -275.342142) (xy 340.615609 -275.303071) (xy 340.585585 -275.259034)
			(xy 340.562459 -275.211013) (xy 340.546749 -275.160083) (xy 340.538806 -275.107379) (xy 340.309972 -275.107379)
			(xy 340.302029 -275.160083) (xy 340.286319 -275.211013) (xy 340.263193 -275.259034) (xy 340.233169 -275.303071)
			(xy 340.196917 -275.342142) (xy 340.155246 -275.375373) (xy 340.109088 -275.402022) (xy 340.059474 -275.421494)
			(xy 340.007512 -275.433354) (xy 339.954362 -275.437338) (xy 339.901212 -275.433354) (xy 339.84925 -275.421494)
			(xy 339.799636 -275.402022) (xy 339.753478 -275.375373) (xy 339.711807 -275.342142) (xy 339.675555 -275.303071)
			(xy 339.645531 -275.259034) (xy 339.622405 -275.211013) (xy 339.606695 -275.160083) (xy 339.598752 -275.107379)
			(xy 339.370426 -275.107379) (xy 339.362483 -275.160083) (xy 339.346773 -275.211013) (xy 339.323647 -275.259034)
			(xy 339.293623 -275.303071) (xy 339.257371 -275.342142) (xy 339.2157 -275.375373) (xy 339.169542 -275.402022)
			(xy 339.119928 -275.421494) (xy 339.067966 -275.433354) (xy 339.014816 -275.437338) (xy 338.961666 -275.433354)
			(xy 338.909704 -275.421494) (xy 338.86009 -275.402022) (xy 338.813932 -275.375373) (xy 338.772261 -275.342142)
			(xy 338.736009 -275.303071) (xy 338.705985 -275.259034) (xy 338.682859 -275.211013) (xy 338.667149 -275.160083)
			(xy 338.659206 -275.107379) (xy 338.430372 -275.107379) (xy 338.422429 -275.160083) (xy 338.406719 -275.211013)
			(xy 338.383593 -275.259034) (xy 338.353569 -275.303071) (xy 338.317317 -275.342142) (xy 338.275646 -275.375373)
			(xy 338.229488 -275.402022) (xy 338.179874 -275.421494) (xy 338.127912 -275.433354) (xy 338.074762 -275.437338)
			(xy 338.021612 -275.433354) (xy 337.96965 -275.421494) (xy 337.920036 -275.402022) (xy 337.873878 -275.375373)
			(xy 337.832207 -275.342142) (xy 337.795955 -275.303071) (xy 337.765931 -275.259034) (xy 337.742805 -275.211013)
			(xy 337.727095 -275.160083) (xy 337.719152 -275.107379) (xy 337.490572 -275.107379) (xy 337.482629 -275.160083)
			(xy 337.466919 -275.211013) (xy 337.443793 -275.259034) (xy 337.413769 -275.303071) (xy 337.377517 -275.342142)
			(xy 337.335846 -275.375373) (xy 337.289688 -275.402022) (xy 337.240074 -275.421494) (xy 337.188112 -275.433354)
			(xy 337.134962 -275.437338) (xy 337.081812 -275.433354) (xy 337.02985 -275.421494) (xy 336.980236 -275.402022)
			(xy 336.934078 -275.375373) (xy 336.892407 -275.342142) (xy 336.856155 -275.303071) (xy 336.826131 -275.259034)
			(xy 336.803005 -275.211013) (xy 336.787295 -275.160083) (xy 336.779352 -275.107379) (xy 336.550772 -275.107379)
			(xy 336.542829 -275.160083) (xy 336.527119 -275.211013) (xy 336.503993 -275.259034) (xy 336.473969 -275.303071)
			(xy 336.437717 -275.342142) (xy 336.396046 -275.375373) (xy 336.349888 -275.402022) (xy 336.300274 -275.421494)
			(xy 336.248312 -275.433354) (xy 336.195162 -275.437338) (xy 336.142012 -275.433354) (xy 336.09005 -275.421494)
			(xy 336.040436 -275.402022) (xy 335.994278 -275.375373) (xy 335.952607 -275.342142) (xy 335.916355 -275.303071)
			(xy 335.886331 -275.259034) (xy 335.863205 -275.211013) (xy 335.847495 -275.160083) (xy 335.839552 -275.107379)
			(xy 335.609793 -275.107379) (xy 335.60611 -275.143606) (xy 335.592537 -275.196032) (xy 335.571182 -275.245798)
			(xy 335.542537 -275.291757) (xy 335.507263 -275.332848) (xy 335.466174 -275.368124) (xy 335.420217 -275.396772)
			(xy 335.370453 -275.41813) (xy 335.318027 -275.431706) (xy 335.264151 -275.437187) (xy 335.210066 -275.434447)
			(xy 335.157019 -275.423549) (xy 335.106234 -275.404743) (xy 335.058883 -275.378465) (xy 335.016057 -275.345319)
			(xy 334.978743 -275.306071) (xy 334.947803 -275.261625) (xy 334.92395 -275.213006) (xy 334.907735 -275.161337)
			(xy 334.89953 -275.107807) (xy 334.899 -275.08073) (xy 334.899 -275.073618) (xy 334.898765 -275.058501)
			(xy 334.890524 -275.029428) (xy 334.874133 -275.00404) (xy 334.85103 -274.984563) (xy 334.823236 -274.972701)
			(xy 334.793189 -274.969495) (xy 334.763518 -274.975226) (xy 334.736825 -274.98939) (xy 334.725772 -274.999704)
			(xy 334.65897 -275.066506) (xy 334.658716 -275.086826) (xy 334.657764 -275.113193) (xy 334.648767 -275.165179)
			(xy 334.631927 -275.215178) (xy 334.607639 -275.262014) (xy 334.576475 -275.304585) (xy 334.539168 -275.34189)
			(xy 334.496595 -275.373051) (xy 334.449757 -275.397336) (xy 334.399757 -275.414173) (xy 334.34777 -275.423166)
			(xy 334.321404 -275.424138) (xy 334.301084 -275.424392) (xy 333.804027 -275.921449) (xy 335.369398 -275.921449)
			(xy 335.369398 -275.868151) (xy 335.377341 -275.815447) (xy 335.393051 -275.764517) (xy 335.416177 -275.716496)
			(xy 335.446201 -275.672459) (xy 335.482453 -275.633388) (xy 335.524124 -275.600157) (xy 335.570282 -275.573508)
			(xy 335.619896 -275.554036) (xy 335.671858 -275.542176) (xy 335.725008 -275.538193) (xy 335.778158 -275.542176)
			(xy 335.83012 -275.554036) (xy 335.879734 -275.573508) (xy 335.925892 -275.600157) (xy 335.967563 -275.633388)
			(xy 336.003815 -275.672459) (xy 336.033839 -275.716496) (xy 336.056965 -275.764517) (xy 336.072675 -275.815447)
			(xy 336.080618 -275.868151) (xy 336.081116 -275.8948) (xy 336.080618 -275.921449) (xy 336.309452 -275.921449)
			(xy 336.309452 -275.868151) (xy 336.317395 -275.815447) (xy 336.333105 -275.764517) (xy 336.356231 -275.716496)
			(xy 336.386255 -275.672459) (xy 336.422507 -275.633388) (xy 336.464178 -275.600157) (xy 336.510336 -275.573508)
			(xy 336.55995 -275.554036) (xy 336.611912 -275.542176) (xy 336.665062 -275.538193) (xy 336.718212 -275.542176)
			(xy 336.770174 -275.554036) (xy 336.819788 -275.573508) (xy 336.865946 -275.600157) (xy 336.907617 -275.633388)
			(xy 336.943869 -275.672459) (xy 336.973893 -275.716496) (xy 336.997019 -275.764517) (xy 337.012729 -275.815447)
			(xy 337.020672 -275.868151) (xy 337.02117 -275.8948) (xy 337.020672 -275.921449) (xy 337.249252 -275.921449)
			(xy 337.249252 -275.868151) (xy 337.257195 -275.815447) (xy 337.272905 -275.764517) (xy 337.296031 -275.716496)
			(xy 337.326055 -275.672459) (xy 337.362307 -275.633388) (xy 337.403978 -275.600157) (xy 337.450136 -275.573508)
			(xy 337.49975 -275.554036) (xy 337.551712 -275.542176) (xy 337.604862 -275.538193) (xy 337.658012 -275.542176)
			(xy 337.709974 -275.554036) (xy 337.759588 -275.573508) (xy 337.805746 -275.600157) (xy 337.847417 -275.633388)
			(xy 337.883669 -275.672459) (xy 337.913693 -275.716496) (xy 337.936819 -275.764517) (xy 337.952529 -275.815447)
			(xy 337.960472 -275.868151) (xy 337.96097 -275.8948) (xy 337.960472 -275.921449) (xy 338.189052 -275.921449)
			(xy 338.189052 -275.868151) (xy 338.196995 -275.815447) (xy 338.212705 -275.764517) (xy 338.235831 -275.716496)
			(xy 338.265855 -275.672459) (xy 338.302107 -275.633388) (xy 338.343778 -275.600157) (xy 338.389936 -275.573508)
			(xy 338.43955 -275.554036) (xy 338.491512 -275.542176) (xy 338.544662 -275.538193) (xy 338.597812 -275.542176)
			(xy 338.649774 -275.554036) (xy 338.699388 -275.573508) (xy 338.745546 -275.600157) (xy 338.787217 -275.633388)
			(xy 338.823469 -275.672459) (xy 338.853493 -275.716496) (xy 338.876619 -275.764517) (xy 338.892329 -275.815447)
			(xy 338.900272 -275.868151) (xy 338.90077 -275.8948) (xy 338.900272 -275.921449) (xy 339.128852 -275.921449)
			(xy 339.128852 -275.868151) (xy 339.136795 -275.815447) (xy 339.152505 -275.764517) (xy 339.175631 -275.716496)
			(xy 339.205655 -275.672459) (xy 339.241907 -275.633388) (xy 339.283578 -275.600157) (xy 339.329736 -275.573508)
			(xy 339.37935 -275.554036) (xy 339.431312 -275.542176) (xy 339.484462 -275.538193) (xy 339.537612 -275.542176)
			(xy 339.589574 -275.554036) (xy 339.639188 -275.573508) (xy 339.685346 -275.600157) (xy 339.727017 -275.633388)
			(xy 339.763269 -275.672459) (xy 339.793293 -275.716496) (xy 339.816419 -275.764517) (xy 339.832129 -275.815447)
			(xy 339.840072 -275.868151) (xy 339.84057 -275.8948) (xy 339.840072 -275.921449) (xy 340.068652 -275.921449)
			(xy 340.068652 -275.868151) (xy 340.076595 -275.815447) (xy 340.092305 -275.764517) (xy 340.115431 -275.716496)
			(xy 340.145455 -275.672459) (xy 340.181707 -275.633388) (xy 340.223378 -275.600157) (xy 340.269536 -275.573508)
			(xy 340.31915 -275.554036) (xy 340.371112 -275.542176) (xy 340.424262 -275.538193) (xy 340.477412 -275.542176)
			(xy 340.529374 -275.554036) (xy 340.578988 -275.573508) (xy 340.625146 -275.600157) (xy 340.666817 -275.633388)
			(xy 340.703069 -275.672459) (xy 340.733093 -275.716496) (xy 340.756219 -275.764517) (xy 340.771929 -275.815447)
			(xy 340.779872 -275.868151) (xy 340.78037 -275.8948) (xy 340.779872 -275.921449) (xy 341.008452 -275.921449)
			(xy 341.008452 -275.868151) (xy 341.016395 -275.815447) (xy 341.032105 -275.764517) (xy 341.055231 -275.716496)
			(xy 341.085255 -275.672459) (xy 341.121507 -275.633388) (xy 341.163178 -275.600157) (xy 341.209336 -275.573508)
			(xy 341.25895 -275.554036) (xy 341.310912 -275.542176) (xy 341.364062 -275.538193) (xy 341.417212 -275.542176)
			(xy 341.469174 -275.554036) (xy 341.518788 -275.573508) (xy 341.564946 -275.600157) (xy 341.606617 -275.633388)
			(xy 341.642869 -275.672459) (xy 341.672893 -275.716496) (xy 341.696019 -275.764517) (xy 341.711729 -275.815447)
			(xy 341.719672 -275.868151) (xy 341.72017 -275.8948) (xy 341.719672 -275.921449) (xy 341.948506 -275.921449)
			(xy 341.948506 -275.868151) (xy 341.956449 -275.815447) (xy 341.972159 -275.764517) (xy 341.995285 -275.716496)
			(xy 342.025309 -275.672459) (xy 342.061561 -275.633388) (xy 342.103232 -275.600157) (xy 342.14939 -275.573508)
			(xy 342.199004 -275.554036) (xy 342.250966 -275.542176) (xy 342.304116 -275.538193) (xy 342.357266 -275.542176)
			(xy 342.409228 -275.554036) (xy 342.458842 -275.573508) (xy 342.505 -275.600157) (xy 342.546671 -275.633388)
			(xy 342.582923 -275.672459) (xy 342.612947 -275.716496) (xy 342.636073 -275.764517) (xy 342.651783 -275.815447)
			(xy 342.659726 -275.868151) (xy 342.660224 -275.8948) (xy 342.659726 -275.921449) (xy 342.888052 -275.921449)
			(xy 342.888052 -275.868151) (xy 342.895995 -275.815447) (xy 342.911705 -275.764517) (xy 342.934831 -275.716496)
			(xy 342.964855 -275.672459) (xy 343.001107 -275.633388) (xy 343.042778 -275.600157) (xy 343.088936 -275.573508)
			(xy 343.13855 -275.554036) (xy 343.190512 -275.542176) (xy 343.243662 -275.538193) (xy 343.296812 -275.542176)
			(xy 343.348774 -275.554036) (xy 343.398388 -275.573508) (xy 343.444546 -275.600157) (xy 343.486217 -275.633388)
			(xy 343.522469 -275.672459) (xy 343.552493 -275.716496) (xy 343.575619 -275.764517) (xy 343.591329 -275.815447)
			(xy 343.599272 -275.868151) (xy 343.59977 -275.8948) (xy 343.599272 -275.921449) (xy 343.827852 -275.921449)
			(xy 343.827852 -275.868151) (xy 343.835795 -275.815447) (xy 343.851505 -275.764517) (xy 343.874631 -275.716496)
			(xy 343.904655 -275.672459) (xy 343.940907 -275.633388) (xy 343.982578 -275.600157) (xy 344.028736 -275.573508)
			(xy 344.07835 -275.554036) (xy 344.130312 -275.542176) (xy 344.183462 -275.538193) (xy 344.236612 -275.542176)
			(xy 344.288574 -275.554036) (xy 344.338188 -275.573508) (xy 344.384346 -275.600157) (xy 344.426017 -275.633388)
			(xy 344.462269 -275.672459) (xy 344.492293 -275.716496) (xy 344.515419 -275.764517) (xy 344.531129 -275.815447)
			(xy 344.539072 -275.868151) (xy 344.53957 -275.8948) (xy 344.539072 -275.921449) (xy 344.767652 -275.921449)
			(xy 344.767652 -275.868151) (xy 344.775595 -275.815447) (xy 344.791305 -275.764517) (xy 344.814431 -275.716496)
			(xy 344.844455 -275.672459) (xy 344.880707 -275.633388) (xy 344.922378 -275.600157) (xy 344.968536 -275.573508)
			(xy 345.01815 -275.554036) (xy 345.070112 -275.542176) (xy 345.123262 -275.538193) (xy 345.176412 -275.542176)
			(xy 345.228374 -275.554036) (xy 345.277988 -275.573508) (xy 345.324146 -275.600157) (xy 345.365817 -275.633388)
			(xy 345.402069 -275.672459) (xy 345.432093 -275.716496) (xy 345.455219 -275.764517) (xy 345.470929 -275.815447)
			(xy 345.478872 -275.868151) (xy 345.47937 -275.8948) (xy 345.478872 -275.921449) (xy 345.707452 -275.921449)
			(xy 345.707452 -275.868151) (xy 345.715395 -275.815447) (xy 345.731105 -275.764517) (xy 345.754231 -275.716496)
			(xy 345.784255 -275.672459) (xy 345.820507 -275.633388) (xy 345.862178 -275.600157) (xy 345.908336 -275.573508)
			(xy 345.95795 -275.554036) (xy 346.009912 -275.542176) (xy 346.063062 -275.538193) (xy 346.116212 -275.542176)
			(xy 346.168174 -275.554036) (xy 346.217788 -275.573508) (xy 346.263946 -275.600157) (xy 346.305617 -275.633388)
			(xy 346.341869 -275.672459) (xy 346.371893 -275.716496) (xy 346.395019 -275.764517) (xy 346.410729 -275.815447)
			(xy 346.418672 -275.868151) (xy 346.41917 -275.8948) (xy 346.418672 -275.921449) (xy 346.647252 -275.921449)
			(xy 346.647252 -275.868151) (xy 346.655195 -275.815447) (xy 346.670905 -275.764517) (xy 346.694031 -275.716496)
			(xy 346.724055 -275.672459) (xy 346.760307 -275.633388) (xy 346.801978 -275.600157) (xy 346.848136 -275.573508)
			(xy 346.89775 -275.554036) (xy 346.949712 -275.542176) (xy 347.002862 -275.538193) (xy 347.056012 -275.542176)
			(xy 347.107974 -275.554036) (xy 347.157588 -275.573508) (xy 347.203746 -275.600157) (xy 347.245417 -275.633388)
			(xy 347.281669 -275.672459) (xy 347.311693 -275.716496) (xy 347.334819 -275.764517) (xy 347.350529 -275.815447)
			(xy 347.358472 -275.868151) (xy 347.35897 -275.8948) (xy 347.358472 -275.921449) (xy 347.587052 -275.921449)
			(xy 347.587052 -275.868151) (xy 347.594995 -275.815447) (xy 347.610705 -275.764517) (xy 347.633831 -275.716496)
			(xy 347.663855 -275.672459) (xy 347.700107 -275.633388) (xy 347.741778 -275.600157) (xy 347.787936 -275.573508)
			(xy 347.83755 -275.554036) (xy 347.889512 -275.542176) (xy 347.942662 -275.538193) (xy 347.995812 -275.542176)
			(xy 348.047774 -275.554036) (xy 348.097388 -275.573508) (xy 348.143546 -275.600157) (xy 348.185217 -275.633388)
			(xy 348.221469 -275.672459) (xy 348.251493 -275.716496) (xy 348.274619 -275.764517) (xy 348.290329 -275.815447)
			(xy 348.298272 -275.868151) (xy 348.29877 -275.8948) (xy 348.298272 -275.921449) (xy 348.527106 -275.921449)
			(xy 348.527106 -275.868151) (xy 348.535049 -275.815447) (xy 348.550759 -275.764517) (xy 348.573885 -275.716496)
			(xy 348.603909 -275.672459) (xy 348.640161 -275.633388) (xy 348.681832 -275.600157) (xy 348.72799 -275.573508)
			(xy 348.777604 -275.554036) (xy 348.829566 -275.542176) (xy 348.882716 -275.538193) (xy 348.935866 -275.542176)
			(xy 348.987828 -275.554036) (xy 349.037442 -275.573508) (xy 349.0836 -275.600157) (xy 349.125271 -275.633388)
			(xy 349.161523 -275.672459) (xy 349.191547 -275.716496) (xy 349.214673 -275.764517) (xy 349.230383 -275.815447)
			(xy 349.238326 -275.868151) (xy 349.238824 -275.8948) (xy 349.238326 -275.921449) (xy 349.466652 -275.921449)
			(xy 349.466652 -275.868151) (xy 349.474595 -275.815447) (xy 349.490305 -275.764517) (xy 349.513431 -275.716496)
			(xy 349.543455 -275.672459) (xy 349.579707 -275.633388) (xy 349.621378 -275.600157) (xy 349.667536 -275.573508)
			(xy 349.71715 -275.554036) (xy 349.769112 -275.542176) (xy 349.822262 -275.538193) (xy 349.875412 -275.542176)
			(xy 349.927374 -275.554036) (xy 349.976988 -275.573508) (xy 350.023146 -275.600157) (xy 350.064817 -275.633388)
			(xy 350.101069 -275.672459) (xy 350.131093 -275.716496) (xy 350.154219 -275.764517) (xy 350.169929 -275.815447)
			(xy 350.177872 -275.868151) (xy 350.17837 -275.8948) (xy 350.177872 -275.921449) (xy 350.169929 -275.974153)
			(xy 350.154219 -276.025083) (xy 350.131093 -276.073104) (xy 350.101069 -276.117141) (xy 350.064817 -276.156212)
			(xy 350.023146 -276.189443) (xy 349.976988 -276.216092) (xy 349.927374 -276.235564) (xy 349.875412 -276.247424)
			(xy 349.822262 -276.251408) (xy 349.769112 -276.247424) (xy 349.71715 -276.235564) (xy 349.667536 -276.216092)
			(xy 349.621378 -276.189443) (xy 349.579707 -276.156212) (xy 349.543455 -276.117141) (xy 349.513431 -276.073104)
			(xy 349.490305 -276.025083) (xy 349.474595 -275.974153) (xy 349.466652 -275.921449) (xy 349.238326 -275.921449)
			(xy 349.230383 -275.974153) (xy 349.214673 -276.025083) (xy 349.191547 -276.073104) (xy 349.161523 -276.117141)
			(xy 349.125271 -276.156212) (xy 349.0836 -276.189443) (xy 349.037442 -276.216092) (xy 348.987828 -276.235564)
			(xy 348.935866 -276.247424) (xy 348.882716 -276.251408) (xy 348.829566 -276.247424) (xy 348.777604 -276.235564)
			(xy 348.72799 -276.216092) (xy 348.681832 -276.189443) (xy 348.640161 -276.156212) (xy 348.603909 -276.117141)
			(xy 348.573885 -276.073104) (xy 348.550759 -276.025083) (xy 348.535049 -275.974153) (xy 348.527106 -275.921449)
			(xy 348.298272 -275.921449) (xy 348.290329 -275.974153) (xy 348.274619 -276.025083) (xy 348.251493 -276.073104)
			(xy 348.221469 -276.117141) (xy 348.185217 -276.156212) (xy 348.143546 -276.189443) (xy 348.097388 -276.216092)
			(xy 348.047774 -276.235564) (xy 347.995812 -276.247424) (xy 347.942662 -276.251408) (xy 347.889512 -276.247424)
			(xy 347.83755 -276.235564) (xy 347.787936 -276.216092) (xy 347.741778 -276.189443) (xy 347.700107 -276.156212)
			(xy 347.663855 -276.117141) (xy 347.633831 -276.073104) (xy 347.610705 -276.025083) (xy 347.594995 -275.974153)
			(xy 347.587052 -275.921449) (xy 347.358472 -275.921449) (xy 347.350529 -275.974153) (xy 347.334819 -276.025083)
			(xy 347.311693 -276.073104) (xy 347.281669 -276.117141) (xy 347.245417 -276.156212) (xy 347.203746 -276.189443)
			(xy 347.157588 -276.216092) (xy 347.107974 -276.235564) (xy 347.056012 -276.247424) (xy 347.002862 -276.251408)
			(xy 346.949712 -276.247424) (xy 346.89775 -276.235564) (xy 346.848136 -276.216092) (xy 346.801978 -276.189443)
			(xy 346.760307 -276.156212) (xy 346.724055 -276.117141) (xy 346.694031 -276.073104) (xy 346.670905 -276.025083)
			(xy 346.655195 -275.974153) (xy 346.647252 -275.921449) (xy 346.418672 -275.921449) (xy 346.410729 -275.974153)
			(xy 346.395019 -276.025083) (xy 346.371893 -276.073104) (xy 346.341869 -276.117141) (xy 346.305617 -276.156212)
			(xy 346.263946 -276.189443) (xy 346.217788 -276.216092) (xy 346.168174 -276.235564) (xy 346.116212 -276.247424)
			(xy 346.063062 -276.251408) (xy 346.009912 -276.247424) (xy 345.95795 -276.235564) (xy 345.908336 -276.216092)
			(xy 345.862178 -276.189443) (xy 345.820507 -276.156212) (xy 345.784255 -276.117141) (xy 345.754231 -276.073104)
			(xy 345.731105 -276.025083) (xy 345.715395 -275.974153) (xy 345.707452 -275.921449) (xy 345.478872 -275.921449)
			(xy 345.470929 -275.974153) (xy 345.455219 -276.025083) (xy 345.432093 -276.073104) (xy 345.402069 -276.117141)
			(xy 345.365817 -276.156212) (xy 345.324146 -276.189443) (xy 345.277988 -276.216092) (xy 345.228374 -276.235564)
			(xy 345.176412 -276.247424) (xy 345.123262 -276.251408) (xy 345.070112 -276.247424) (xy 345.01815 -276.235564)
			(xy 344.968536 -276.216092) (xy 344.922378 -276.189443) (xy 344.880707 -276.156212) (xy 344.844455 -276.117141)
			(xy 344.814431 -276.073104) (xy 344.791305 -276.025083) (xy 344.775595 -275.974153) (xy 344.767652 -275.921449)
			(xy 344.539072 -275.921449) (xy 344.531129 -275.974153) (xy 344.515419 -276.025083) (xy 344.492293 -276.073104)
			(xy 344.462269 -276.117141) (xy 344.426017 -276.156212) (xy 344.384346 -276.189443) (xy 344.338188 -276.216092)
			(xy 344.288574 -276.235564) (xy 344.236612 -276.247424) (xy 344.183462 -276.251408) (xy 344.130312 -276.247424)
			(xy 344.07835 -276.235564) (xy 344.028736 -276.216092) (xy 343.982578 -276.189443) (xy 343.940907 -276.156212)
			(xy 343.904655 -276.117141) (xy 343.874631 -276.073104) (xy 343.851505 -276.025083) (xy 343.835795 -275.974153)
			(xy 343.827852 -275.921449) (xy 343.599272 -275.921449) (xy 343.591329 -275.974153) (xy 343.575619 -276.025083)
			(xy 343.552493 -276.073104) (xy 343.522469 -276.117141) (xy 343.486217 -276.156212) (xy 343.444546 -276.189443)
			(xy 343.398388 -276.216092) (xy 343.348774 -276.235564) (xy 343.296812 -276.247424) (xy 343.243662 -276.251408)
			(xy 343.190512 -276.247424) (xy 343.13855 -276.235564) (xy 343.088936 -276.216092) (xy 343.042778 -276.189443)
			(xy 343.001107 -276.156212) (xy 342.964855 -276.117141) (xy 342.934831 -276.073104) (xy 342.911705 -276.025083)
			(xy 342.895995 -275.974153) (xy 342.888052 -275.921449) (xy 342.659726 -275.921449) (xy 342.651783 -275.974153)
			(xy 342.636073 -276.025083) (xy 342.612947 -276.073104) (xy 342.582923 -276.117141) (xy 342.546671 -276.156212)
			(xy 342.505 -276.189443) (xy 342.458842 -276.216092) (xy 342.409228 -276.235564) (xy 342.357266 -276.247424)
			(xy 342.304116 -276.251408) (xy 342.250966 -276.247424) (xy 342.199004 -276.235564) (xy 342.14939 -276.216092)
			(xy 342.103232 -276.189443) (xy 342.061561 -276.156212) (xy 342.025309 -276.117141) (xy 341.995285 -276.073104)
			(xy 341.972159 -276.025083) (xy 341.956449 -275.974153) (xy 341.948506 -275.921449) (xy 341.719672 -275.921449)
			(xy 341.711729 -275.974153) (xy 341.696019 -276.025083) (xy 341.672893 -276.073104) (xy 341.642869 -276.117141)
			(xy 341.606617 -276.156212) (xy 341.564946 -276.189443) (xy 341.518788 -276.216092) (xy 341.469174 -276.235564)
			(xy 341.417212 -276.247424) (xy 341.364062 -276.251408) (xy 341.310912 -276.247424) (xy 341.25895 -276.235564)
			(xy 341.209336 -276.216092) (xy 341.163178 -276.189443) (xy 341.121507 -276.156212) (xy 341.085255 -276.117141)
			(xy 341.055231 -276.073104) (xy 341.032105 -276.025083) (xy 341.016395 -275.974153) (xy 341.008452 -275.921449)
			(xy 340.779872 -275.921449) (xy 340.771929 -275.974153) (xy 340.756219 -276.025083) (xy 340.733093 -276.073104)
			(xy 340.703069 -276.117141) (xy 340.666817 -276.156212) (xy 340.625146 -276.189443) (xy 340.578988 -276.216092)
			(xy 340.529374 -276.235564) (xy 340.477412 -276.247424) (xy 340.424262 -276.251408) (xy 340.371112 -276.247424)
			(xy 340.31915 -276.235564) (xy 340.269536 -276.216092) (xy 340.223378 -276.189443) (xy 340.181707 -276.156212)
			(xy 340.145455 -276.117141) (xy 340.115431 -276.073104) (xy 340.092305 -276.025083) (xy 340.076595 -275.974153)
			(xy 340.068652 -275.921449) (xy 339.840072 -275.921449) (xy 339.832129 -275.974153) (xy 339.816419 -276.025083)
			(xy 339.793293 -276.073104) (xy 339.763269 -276.117141) (xy 339.727017 -276.156212) (xy 339.685346 -276.189443)
			(xy 339.639188 -276.216092) (xy 339.589574 -276.235564) (xy 339.537612 -276.247424) (xy 339.484462 -276.251408)
			(xy 339.431312 -276.247424) (xy 339.37935 -276.235564) (xy 339.329736 -276.216092) (xy 339.283578 -276.189443)
			(xy 339.241907 -276.156212) (xy 339.205655 -276.117141) (xy 339.175631 -276.073104) (xy 339.152505 -276.025083)
			(xy 339.136795 -275.974153) (xy 339.128852 -275.921449) (xy 338.900272 -275.921449) (xy 338.892329 -275.974153)
			(xy 338.876619 -276.025083) (xy 338.853493 -276.073104) (xy 338.823469 -276.117141) (xy 338.787217 -276.156212)
			(xy 338.745546 -276.189443) (xy 338.699388 -276.216092) (xy 338.649774 -276.235564) (xy 338.597812 -276.247424)
			(xy 338.544662 -276.251408) (xy 338.491512 -276.247424) (xy 338.43955 -276.235564) (xy 338.389936 -276.216092)
			(xy 338.343778 -276.189443) (xy 338.302107 -276.156212) (xy 338.265855 -276.117141) (xy 338.235831 -276.073104)
			(xy 338.212705 -276.025083) (xy 338.196995 -275.974153) (xy 338.189052 -275.921449) (xy 337.960472 -275.921449)
			(xy 337.952529 -275.974153) (xy 337.936819 -276.025083) (xy 337.913693 -276.073104) (xy 337.883669 -276.117141)
			(xy 337.847417 -276.156212) (xy 337.805746 -276.189443) (xy 337.759588 -276.216092) (xy 337.709974 -276.235564)
			(xy 337.658012 -276.247424) (xy 337.604862 -276.251408) (xy 337.551712 -276.247424) (xy 337.49975 -276.235564)
			(xy 337.450136 -276.216092) (xy 337.403978 -276.189443) (xy 337.362307 -276.156212) (xy 337.326055 -276.117141)
			(xy 337.296031 -276.073104) (xy 337.272905 -276.025083) (xy 337.257195 -275.974153) (xy 337.249252 -275.921449)
			(xy 337.020672 -275.921449) (xy 337.012729 -275.974153) (xy 336.997019 -276.025083) (xy 336.973893 -276.073104)
			(xy 336.943869 -276.117141) (xy 336.907617 -276.156212) (xy 336.865946 -276.189443) (xy 336.819788 -276.216092)
			(xy 336.770174 -276.235564) (xy 336.718212 -276.247424) (xy 336.665062 -276.251408) (xy 336.611912 -276.247424)
			(xy 336.55995 -276.235564) (xy 336.510336 -276.216092) (xy 336.464178 -276.189443) (xy 336.422507 -276.156212)
			(xy 336.386255 -276.117141) (xy 336.356231 -276.073104) (xy 336.333105 -276.025083) (xy 336.317395 -275.974153)
			(xy 336.309452 -275.921449) (xy 336.080618 -275.921449) (xy 336.072675 -275.974153) (xy 336.056965 -276.025083)
			(xy 336.033839 -276.073104) (xy 336.003815 -276.117141) (xy 335.967563 -276.156212) (xy 335.925892 -276.189443)
			(xy 335.879734 -276.216092) (xy 335.83012 -276.235564) (xy 335.778158 -276.247424) (xy 335.725008 -276.251408)
			(xy 335.671858 -276.247424) (xy 335.619896 -276.235564) (xy 335.570282 -276.216092) (xy 335.524124 -276.189443)
			(xy 335.482453 -276.156212) (xy 335.446201 -276.117141) (xy 335.416177 -276.073104) (xy 335.393051 -276.025083)
			(xy 335.377341 -275.974153) (xy 335.369398 -275.921449) (xy 333.804027 -275.921449) (xy 333.466948 -276.258528)
			(xy 333.466948 -276.735265) (xy 335.839552 -276.735265) (xy 335.839552 -276.681967) (xy 335.847495 -276.629263)
			(xy 335.863205 -276.578333) (xy 335.886331 -276.530312) (xy 335.916355 -276.486275) (xy 335.952607 -276.447204)
			(xy 335.994278 -276.413973) (xy 336.040436 -276.387324) (xy 336.09005 -276.367852) (xy 336.142012 -276.355992)
			(xy 336.195162 -276.352009) (xy 336.248312 -276.355992) (xy 336.300274 -276.367852) (xy 336.349888 -276.387324)
			(xy 336.396046 -276.413973) (xy 336.437717 -276.447204) (xy 336.473969 -276.486275) (xy 336.503993 -276.530312)
			(xy 336.527119 -276.578333) (xy 336.542829 -276.629263) (xy 336.550772 -276.681967) (xy 336.55127 -276.708616)
			(xy 336.550772 -276.735265) (xy 336.779352 -276.735265) (xy 336.779352 -276.681967) (xy 336.787295 -276.629263)
			(xy 336.803005 -276.578333) (xy 336.826131 -276.530312) (xy 336.856155 -276.486275) (xy 336.892407 -276.447204)
			(xy 336.934078 -276.413973) (xy 336.980236 -276.387324) (xy 337.02985 -276.367852) (xy 337.081812 -276.355992)
			(xy 337.134962 -276.352009) (xy 337.188112 -276.355992) (xy 337.240074 -276.367852) (xy 337.289688 -276.387324)
			(xy 337.335846 -276.413973) (xy 337.377517 -276.447204) (xy 337.413769 -276.486275) (xy 337.443793 -276.530312)
			(xy 337.466919 -276.578333) (xy 337.482629 -276.629263) (xy 337.490572 -276.681967) (xy 337.49107 -276.708616)
			(xy 337.490572 -276.735265) (xy 337.719152 -276.735265) (xy 337.719152 -276.681967) (xy 337.727095 -276.629263)
			(xy 337.742805 -276.578333) (xy 337.765931 -276.530312) (xy 337.795955 -276.486275) (xy 337.832207 -276.447204)
			(xy 337.873878 -276.413973) (xy 337.920036 -276.387324) (xy 337.96965 -276.367852) (xy 338.021612 -276.355992)
			(xy 338.074762 -276.352009) (xy 338.127912 -276.355992) (xy 338.179874 -276.367852) (xy 338.229488 -276.387324)
			(xy 338.275646 -276.413973) (xy 338.317317 -276.447204) (xy 338.353569 -276.486275) (xy 338.383593 -276.530312)
			(xy 338.406719 -276.578333) (xy 338.422429 -276.629263) (xy 338.430372 -276.681967) (xy 338.43087 -276.708616)
			(xy 338.430372 -276.735265) (xy 338.658952 -276.735265) (xy 338.658952 -276.681967) (xy 338.666895 -276.629263)
			(xy 338.682605 -276.578333) (xy 338.705731 -276.530312) (xy 338.735755 -276.486275) (xy 338.772007 -276.447204)
			(xy 338.813678 -276.413973) (xy 338.859836 -276.387324) (xy 338.90945 -276.367852) (xy 338.961412 -276.355992)
			(xy 339.014562 -276.352009) (xy 339.067712 -276.355992) (xy 339.119674 -276.367852) (xy 339.169288 -276.387324)
			(xy 339.215446 -276.413973) (xy 339.257117 -276.447204) (xy 339.293369 -276.486275) (xy 339.323393 -276.530312)
			(xy 339.346519 -276.578333) (xy 339.362229 -276.629263) (xy 339.370172 -276.681967) (xy 339.37067 -276.708616)
			(xy 339.370172 -276.735265) (xy 339.599006 -276.735265) (xy 339.599006 -276.681967) (xy 339.606949 -276.629263)
			(xy 339.622659 -276.578333) (xy 339.645785 -276.530312) (xy 339.675809 -276.486275) (xy 339.712061 -276.447204)
			(xy 339.753732 -276.413973) (xy 339.79989 -276.387324) (xy 339.849504 -276.367852) (xy 339.901466 -276.355992)
			(xy 339.954616 -276.352009) (xy 340.007766 -276.355992) (xy 340.059728 -276.367852) (xy 340.109342 -276.387324)
			(xy 340.1555 -276.413973) (xy 340.197171 -276.447204) (xy 340.233423 -276.486275) (xy 340.263447 -276.530312)
			(xy 340.286573 -276.578333) (xy 340.302283 -276.629263) (xy 340.310226 -276.681967) (xy 340.310724 -276.708616)
			(xy 340.310226 -276.735265) (xy 340.538806 -276.735265) (xy 340.538806 -276.681967) (xy 340.546749 -276.629263)
			(xy 340.562459 -276.578333) (xy 340.585585 -276.530312) (xy 340.615609 -276.486275) (xy 340.651861 -276.447204)
			(xy 340.693532 -276.413973) (xy 340.73969 -276.387324) (xy 340.789304 -276.367852) (xy 340.841266 -276.355992)
			(xy 340.894416 -276.352009) (xy 340.947566 -276.355992) (xy 340.999528 -276.367852) (xy 341.049142 -276.387324)
			(xy 341.0953 -276.413973) (xy 341.136971 -276.447204) (xy 341.173223 -276.486275) (xy 341.203247 -276.530312)
			(xy 341.226373 -276.578333) (xy 341.242083 -276.629263) (xy 341.250026 -276.681967) (xy 341.250524 -276.708616)
			(xy 341.250026 -276.735265) (xy 341.478606 -276.735265) (xy 341.478606 -276.681967) (xy 341.486549 -276.629263)
			(xy 341.502259 -276.578333) (xy 341.525385 -276.530312) (xy 341.555409 -276.486275) (xy 341.591661 -276.447204)
			(xy 341.633332 -276.413973) (xy 341.67949 -276.387324) (xy 341.729104 -276.367852) (xy 341.781066 -276.355992)
			(xy 341.834216 -276.352009) (xy 341.887366 -276.355992) (xy 341.939328 -276.367852) (xy 341.988942 -276.387324)
			(xy 342.0351 -276.413973) (xy 342.076771 -276.447204) (xy 342.113023 -276.486275) (xy 342.143047 -276.530312)
			(xy 342.166173 -276.578333) (xy 342.181883 -276.629263) (xy 342.189826 -276.681967) (xy 342.190324 -276.708616)
			(xy 342.189826 -276.735265) (xy 342.418406 -276.735265) (xy 342.418406 -276.681967) (xy 342.426349 -276.629263)
			(xy 342.442059 -276.578333) (xy 342.465185 -276.530312) (xy 342.495209 -276.486275) (xy 342.531461 -276.447204)
			(xy 342.573132 -276.413973) (xy 342.61929 -276.387324) (xy 342.668904 -276.367852) (xy 342.720866 -276.355992)
			(xy 342.774016 -276.352009) (xy 342.827166 -276.355992) (xy 342.879128 -276.367852) (xy 342.928742 -276.387324)
			(xy 342.9749 -276.413973) (xy 343.016571 -276.447204) (xy 343.052823 -276.486275) (xy 343.082847 -276.530312)
			(xy 343.105973 -276.578333) (xy 343.121683 -276.629263) (xy 343.129626 -276.681967) (xy 343.130124 -276.708616)
			(xy 343.129626 -276.735265) (xy 343.358206 -276.735265) (xy 343.358206 -276.681967) (xy 343.366149 -276.629263)
			(xy 343.381859 -276.578333) (xy 343.404985 -276.530312) (xy 343.435009 -276.486275) (xy 343.471261 -276.447204)
			(xy 343.512932 -276.413973) (xy 343.55909 -276.387324) (xy 343.608704 -276.367852) (xy 343.660666 -276.355992)
			(xy 343.713816 -276.352009) (xy 343.766966 -276.355992) (xy 343.818928 -276.367852) (xy 343.868542 -276.387324)
			(xy 343.9147 -276.413973) (xy 343.956371 -276.447204) (xy 343.992623 -276.486275) (xy 344.022647 -276.530312)
			(xy 344.045773 -276.578333) (xy 344.061483 -276.629263) (xy 344.069426 -276.681967) (xy 344.069924 -276.708616)
			(xy 344.069426 -276.735265) (xy 344.298006 -276.735265) (xy 344.298006 -276.681967) (xy 344.305949 -276.629263)
			(xy 344.321659 -276.578333) (xy 344.344785 -276.530312) (xy 344.374809 -276.486275) (xy 344.411061 -276.447204)
			(xy 344.452732 -276.413973) (xy 344.49889 -276.387324) (xy 344.548504 -276.367852) (xy 344.600466 -276.355992)
			(xy 344.653616 -276.352009) (xy 344.706766 -276.355992) (xy 344.758728 -276.367852) (xy 344.808342 -276.387324)
			(xy 344.8545 -276.413973) (xy 344.896171 -276.447204) (xy 344.932423 -276.486275) (xy 344.962447 -276.530312)
			(xy 344.985573 -276.578333) (xy 345.001283 -276.629263) (xy 345.009226 -276.681967) (xy 345.009724 -276.708616)
			(xy 345.009226 -276.735265) (xy 345.237552 -276.735265) (xy 345.237552 -276.681967) (xy 345.245495 -276.629263)
			(xy 345.261205 -276.578333) (xy 345.284331 -276.530312) (xy 345.314355 -276.486275) (xy 345.350607 -276.447204)
			(xy 345.392278 -276.413973) (xy 345.438436 -276.387324) (xy 345.48805 -276.367852) (xy 345.540012 -276.355992)
			(xy 345.593162 -276.352009) (xy 345.646312 -276.355992) (xy 345.698274 -276.367852) (xy 345.747888 -276.387324)
			(xy 345.794046 -276.413973) (xy 345.835717 -276.447204) (xy 345.871969 -276.486275) (xy 345.901993 -276.530312)
			(xy 345.925119 -276.578333) (xy 345.940829 -276.629263) (xy 345.948772 -276.681967) (xy 345.94927 -276.708616)
			(xy 345.948772 -276.735265) (xy 346.177606 -276.735265) (xy 346.177606 -276.681967) (xy 346.185549 -276.629263)
			(xy 346.201259 -276.578333) (xy 346.224385 -276.530312) (xy 346.254409 -276.486275) (xy 346.290661 -276.447204)
			(xy 346.332332 -276.413973) (xy 346.37849 -276.387324) (xy 346.428104 -276.367852) (xy 346.480066 -276.355992)
			(xy 346.533216 -276.352009) (xy 346.586366 -276.355992) (xy 346.638328 -276.367852) (xy 346.687942 -276.387324)
			(xy 346.7341 -276.413973) (xy 346.775771 -276.447204) (xy 346.812023 -276.486275) (xy 346.842047 -276.530312)
			(xy 346.865173 -276.578333) (xy 346.880883 -276.629263) (xy 346.888826 -276.681967) (xy 346.889324 -276.708616)
			(xy 346.888826 -276.735265) (xy 347.117406 -276.735265) (xy 347.117406 -276.681967) (xy 347.125349 -276.629263)
			(xy 347.141059 -276.578333) (xy 347.164185 -276.530312) (xy 347.194209 -276.486275) (xy 347.230461 -276.447204)
			(xy 347.272132 -276.413973) (xy 347.31829 -276.387324) (xy 347.367904 -276.367852) (xy 347.419866 -276.355992)
			(xy 347.473016 -276.352009) (xy 347.526166 -276.355992) (xy 347.578128 -276.367852) (xy 347.627742 -276.387324)
			(xy 347.6739 -276.413973) (xy 347.715571 -276.447204) (xy 347.751823 -276.486275) (xy 347.781847 -276.530312)
			(xy 347.804973 -276.578333) (xy 347.820683 -276.629263) (xy 347.828626 -276.681967) (xy 347.829124 -276.708616)
			(xy 347.828626 -276.735265) (xy 348.057206 -276.735265) (xy 348.057206 -276.681967) (xy 348.065149 -276.629263)
			(xy 348.080859 -276.578333) (xy 348.103985 -276.530312) (xy 348.134009 -276.486275) (xy 348.170261 -276.447204)
			(xy 348.211932 -276.413973) (xy 348.25809 -276.387324) (xy 348.307704 -276.367852) (xy 348.359666 -276.355992)
			(xy 348.412816 -276.352009) (xy 348.465966 -276.355992) (xy 348.517928 -276.367852) (xy 348.567542 -276.387324)
			(xy 348.6137 -276.413973) (xy 348.655371 -276.447204) (xy 348.691623 -276.486275) (xy 348.721647 -276.530312)
			(xy 348.744773 -276.578333) (xy 348.760483 -276.629263) (xy 348.768426 -276.681967) (xy 348.768924 -276.708616)
			(xy 348.768426 -276.735265) (xy 348.997006 -276.735265) (xy 348.997006 -276.681967) (xy 349.004949 -276.629263)
			(xy 349.020659 -276.578333) (xy 349.043785 -276.530312) (xy 349.073809 -276.486275) (xy 349.110061 -276.447204)
			(xy 349.151732 -276.413973) (xy 349.19789 -276.387324) (xy 349.247504 -276.367852) (xy 349.299466 -276.355992)
			(xy 349.352616 -276.352009) (xy 349.405766 -276.355992) (xy 349.457728 -276.367852) (xy 349.507342 -276.387324)
			(xy 349.5535 -276.413973) (xy 349.595171 -276.447204) (xy 349.631423 -276.486275) (xy 349.661447 -276.530312)
			(xy 349.684573 -276.578333) (xy 349.700283 -276.629263) (xy 349.708226 -276.681967) (xy 349.708724 -276.708616)
			(xy 349.936054 -276.708616) (xy 349.936488 -276.682987) (xy 349.943822 -276.632257) (xy 349.958354 -276.583103)
			(xy 349.979785 -276.53654) (xy 350.007671 -276.493532) (xy 350.041437 -276.454967) (xy 350.080383 -276.421643)
			(xy 350.123706 -276.394248) (xy 350.170509 -276.373348) (xy 350.219826 -276.359376) (xy 350.245172 -276.355556)
			(xy 350.26981 -276.352254) (xy 350.442276 -276.05355) (xy 350.432878 -276.030436) (xy 350.424372 -276.008846)
			(xy 350.412401 -275.964011) (xy 350.406346 -275.918002) (xy 350.405954 -275.8948) (xy 350.406452 -275.868151)
			(xy 350.414395 -275.815447) (xy 350.430105 -275.764517) (xy 350.453231 -275.716496) (xy 350.483255 -275.672459)
			(xy 350.519507 -275.633388) (xy 350.561178 -275.600157) (xy 350.607336 -275.573508) (xy 350.65695 -275.554036)
			(xy 350.708912 -275.542176) (xy 350.762062 -275.538193) (xy 350.815212 -275.542176) (xy 350.867174 -275.554036)
			(xy 350.916788 -275.573508) (xy 350.962946 -275.600157) (xy 351.004617 -275.633388) (xy 351.040869 -275.672459)
			(xy 351.070893 -275.716496) (xy 351.094019 -275.764517) (xy 351.109729 -275.815447) (xy 351.117672 -275.868151)
			(xy 351.11817 -275.8948) (xy 351.11773 -275.920428) (xy 351.117582 -275.921449) (xy 351.346252 -275.921449)
			(xy 351.346252 -275.868151) (xy 351.354195 -275.815447) (xy 351.369905 -275.764517) (xy 351.393031 -275.716496)
			(xy 351.423055 -275.672459) (xy 351.459307 -275.633388) (xy 351.500978 -275.600157) (xy 351.547136 -275.573508)
			(xy 351.59675 -275.554036) (xy 351.648712 -275.542176) (xy 351.701862 -275.538193) (xy 351.755012 -275.542176)
			(xy 351.806974 -275.554036) (xy 351.856588 -275.573508) (xy 351.902746 -275.600157) (xy 351.944417 -275.633388)
			(xy 351.980669 -275.672459) (xy 352.010693 -275.716496) (xy 352.033819 -275.764517) (xy 352.049529 -275.815447)
			(xy 352.057472 -275.868151) (xy 352.05797 -275.8948) (xy 352.285554 -275.8948) (xy 352.285973 -275.869171)
			(xy 352.293309 -275.81844) (xy 352.307844 -275.769285) (xy 352.329276 -275.722723) (xy 352.357165 -275.679715)
			(xy 352.390931 -275.64115) (xy 352.429879 -275.607826) (xy 352.473203 -275.580431) (xy 352.520008 -275.559532)
			(xy 352.569325 -275.54556) (xy 352.594672 -275.54174) (xy 352.61931 -275.538438) (xy 352.79203 -275.23948)
			(xy 352.782632 -275.216366) (xy 352.774138 -275.194771) (xy 352.762162 -275.149939) (xy 352.756102 -275.103932)
			(xy 352.755708 -275.08073) (xy 352.756206 -275.054081) (xy 352.764149 -275.001377) (xy 352.779859 -274.950447)
			(xy 352.802985 -274.902426) (xy 352.833009 -274.858389) (xy 352.869261 -274.819318) (xy 352.910932 -274.786087)
			(xy 352.95709 -274.759438) (xy 353.006704 -274.739966) (xy 353.058666 -274.728106) (xy 353.111816 -274.724123)
			(xy 353.164966 -274.728106) (xy 353.216928 -274.739966) (xy 353.266542 -274.759438) (xy 353.3127 -274.786087)
			(xy 353.354371 -274.819318) (xy 353.390623 -274.858389) (xy 353.420647 -274.902426) (xy 353.443773 -274.950447)
			(xy 353.459483 -275.001377) (xy 353.467426 -275.054081) (xy 353.467924 -275.08073) (xy 353.467431 -275.106367)
			(xy 353.467285 -275.107379) (xy 353.695752 -275.107379) (xy 353.695752 -275.054081) (xy 353.703695 -275.001377)
			(xy 353.719405 -274.950447) (xy 353.742531 -274.902426) (xy 353.772555 -274.858389) (xy 353.808807 -274.819318)
			(xy 353.850478 -274.786087) (xy 353.896636 -274.759438) (xy 353.94625 -274.739966) (xy 353.998212 -274.728106)
			(xy 354.051362 -274.724123) (xy 354.104512 -274.728106) (xy 354.156474 -274.739966) (xy 354.206088 -274.759438)
			(xy 354.252246 -274.786087) (xy 354.293917 -274.819318) (xy 354.330169 -274.858389) (xy 354.360193 -274.902426)
			(xy 354.383319 -274.950447) (xy 354.399029 -275.001377) (xy 354.406972 -275.054081) (xy 354.40747 -275.08073)
			(xy 354.406972 -275.107379) (xy 354.635806 -275.107379) (xy 354.635806 -275.054081) (xy 354.643749 -275.001377)
			(xy 354.659459 -274.950447) (xy 354.682585 -274.902426) (xy 354.712609 -274.858389) (xy 354.748861 -274.819318)
			(xy 354.790532 -274.786087) (xy 354.83669 -274.759438) (xy 354.886304 -274.739966) (xy 354.938266 -274.728106)
			(xy 354.991416 -274.724123) (xy 355.044566 -274.728106) (xy 355.096528 -274.739966) (xy 355.146142 -274.759438)
			(xy 355.1923 -274.786087) (xy 355.233971 -274.819318) (xy 355.270223 -274.858389) (xy 355.300247 -274.902426)
			(xy 355.323373 -274.950447) (xy 355.339083 -275.001377) (xy 355.347026 -275.054081) (xy 355.347524 -275.08073)
			(xy 355.347026 -275.107379) (xy 355.339083 -275.160083) (xy 355.323373 -275.211013) (xy 355.300247 -275.259034)
			(xy 355.270223 -275.303071) (xy 355.233971 -275.342142) (xy 355.1923 -275.375373) (xy 355.146142 -275.402022)
			(xy 355.096528 -275.421494) (xy 355.044566 -275.433354) (xy 354.991416 -275.437338) (xy 354.938266 -275.433354)
			(xy 354.886304 -275.421494) (xy 354.83669 -275.402022) (xy 354.790532 -275.375373) (xy 354.748861 -275.342142)
			(xy 354.712609 -275.303071) (xy 354.682585 -275.259034) (xy 354.659459 -275.211013) (xy 354.643749 -275.160083)
			(xy 354.635806 -275.107379) (xy 354.406972 -275.107379) (xy 354.399029 -275.160083) (xy 354.383319 -275.211013)
			(xy 354.360193 -275.259034) (xy 354.330169 -275.303071) (xy 354.293917 -275.342142) (xy 354.252246 -275.375373)
			(xy 354.206088 -275.402022) (xy 354.156474 -275.421494) (xy 354.104512 -275.433354) (xy 354.051362 -275.437338)
			(xy 353.998212 -275.433354) (xy 353.94625 -275.421494) (xy 353.896636 -275.402022) (xy 353.850478 -275.375373)
			(xy 353.808807 -275.342142) (xy 353.772555 -275.303071) (xy 353.742531 -275.259034) (xy 353.719405 -275.211013)
			(xy 353.703695 -275.160083) (xy 353.695752 -275.107379) (xy 353.467285 -275.107379) (xy 353.460086 -275.157113)
			(xy 353.445539 -275.20628) (xy 353.42409 -275.252852) (xy 353.396182 -275.295867) (xy 353.362394 -275.334433)
			(xy 353.323423 -275.367754) (xy 353.280075 -275.395141) (xy 353.233248 -275.416027) (xy 353.183908 -275.429981)
			(xy 353.158552 -275.43379) (xy 353.133914 -275.437092) (xy 352.961194 -275.735796) (xy 352.970846 -275.75891)
			(xy 352.979361 -275.780542) (xy 352.991349 -275.82546) (xy 352.997394 -275.871555) (xy 352.99777 -275.8948)
			(xy 352.997272 -275.921449) (xy 353.226106 -275.921449) (xy 353.226106 -275.868151) (xy 353.234049 -275.815447)
			(xy 353.249759 -275.764517) (xy 353.272885 -275.716496) (xy 353.302909 -275.672459) (xy 353.339161 -275.633388)
			(xy 353.380832 -275.600157) (xy 353.42699 -275.573508) (xy 353.476604 -275.554036) (xy 353.528566 -275.542176)
			(xy 353.581716 -275.538193) (xy 353.634866 -275.542176) (xy 353.686828 -275.554036) (xy 353.736442 -275.573508)
			(xy 353.7826 -275.600157) (xy 353.824271 -275.633388) (xy 353.860523 -275.672459) (xy 353.890547 -275.716496)
			(xy 353.913673 -275.764517) (xy 353.929383 -275.815447) (xy 353.937326 -275.868151) (xy 353.937824 -275.8948)
			(xy 353.937326 -275.921449) (xy 353.929383 -275.974153) (xy 353.913673 -276.025083) (xy 353.890547 -276.073104)
			(xy 353.860523 -276.117141) (xy 353.824271 -276.156212) (xy 353.7826 -276.189443) (xy 353.736442 -276.216092)
			(xy 353.686828 -276.235564) (xy 353.634866 -276.247424) (xy 353.581716 -276.251408) (xy 353.528566 -276.247424)
			(xy 353.476604 -276.235564) (xy 353.42699 -276.216092) (xy 353.380832 -276.189443) (xy 353.339161 -276.156212)
			(xy 353.302909 -276.117141) (xy 353.272885 -276.073104) (xy 353.249759 -276.025083) (xy 353.234049 -275.974153)
			(xy 353.226106 -275.921449) (xy 352.997272 -275.921449) (xy 352.989329 -275.974153) (xy 352.973619 -276.025083)
			(xy 352.950493 -276.073104) (xy 352.920469 -276.117141) (xy 352.884217 -276.156212) (xy 352.842546 -276.189443)
			(xy 352.796388 -276.216092) (xy 352.746774 -276.235564) (xy 352.694812 -276.247424) (xy 352.641662 -276.251408)
			(xy 352.588512 -276.247424) (xy 352.53655 -276.235564) (xy 352.486936 -276.216092) (xy 352.440778 -276.189443)
			(xy 352.399107 -276.156212) (xy 352.362855 -276.117141) (xy 352.332831 -276.073104) (xy 352.309705 -276.025083)
			(xy 352.293995 -275.974153) (xy 352.286052 -275.921449) (xy 352.285554 -275.8948) (xy 352.05797 -275.8948)
			(xy 352.057472 -275.921449) (xy 352.049529 -275.974153) (xy 352.033819 -276.025083) (xy 352.010693 -276.073104)
			(xy 351.980669 -276.117141) (xy 351.944417 -276.156212) (xy 351.902746 -276.189443) (xy 351.856588 -276.216092)
			(xy 351.806974 -276.235564) (xy 351.755012 -276.247424) (xy 351.701862 -276.251408) (xy 351.648712 -276.247424)
			(xy 351.59675 -276.235564) (xy 351.547136 -276.216092) (xy 351.500978 -276.189443) (xy 351.459307 -276.156212)
			(xy 351.423055 -276.117141) (xy 351.393031 -276.073104) (xy 351.369905 -276.025083) (xy 351.354195 -275.974153)
			(xy 351.346252 -275.921449) (xy 351.117582 -275.921449) (xy 351.110395 -275.971157) (xy 351.095861 -276.02031)
			(xy 351.07443 -276.066872) (xy 351.046544 -276.109879) (xy 351.01278 -276.148443) (xy 350.973835 -276.181767)
			(xy 350.930514 -276.209163) (xy 350.883712 -276.230064) (xy 350.834398 -276.244038) (xy 350.809052 -276.24786)
			(xy 350.78416 -276.251162) (xy 350.611694 -276.549612) (xy 350.621346 -276.572726) (xy 350.629866 -276.594357)
			(xy 350.641852 -276.639275) (xy 350.647895 -276.685371) (xy 350.64827 -276.708616) (xy 350.876108 -276.708616)
			(xy 350.876606 -276.681967) (xy 350.884549 -276.629263) (xy 350.900259 -276.578333) (xy 350.923385 -276.530312)
			(xy 350.953409 -276.486275) (xy 350.989661 -276.447204) (xy 351.031332 -276.413973) (xy 351.07749 -276.387324)
			(xy 351.127104 -276.367852) (xy 351.179066 -276.355992) (xy 351.232216 -276.352009) (xy 351.285366 -276.355992)
			(xy 351.337328 -276.367852) (xy 351.386942 -276.387324) (xy 351.4331 -276.413973) (xy 351.474771 -276.447204)
			(xy 351.511023 -276.486275) (xy 351.541047 -276.530312) (xy 351.564173 -276.578333) (xy 351.579883 -276.629263)
			(xy 351.587826 -276.681967) (xy 351.588324 -276.7086) (xy 351.815384 -276.7086) (xy 351.819367 -276.655448)
			(xy 351.831228 -276.603483) (xy 351.850702 -276.553866) (xy 351.877353 -276.507706) (xy 351.910587 -276.466034)
			(xy 351.949661 -276.429781) (xy 351.993701 -276.399756) (xy 352.041725 -276.376631) (xy 352.092659 -276.360922)
			(xy 352.145365 -276.35298) (xy 352.172016 -276.352508) (xy 352.19703 -276.352935) (xy 352.246568 -276.359922)
			(xy 352.294641 -276.37377) (xy 352.340304 -276.394207) (xy 352.382659 -276.420831) (xy 352.420874 -276.453118)
			(xy 352.454195 -276.490434) (xy 352.468434 -276.511004) (xy 352.815398 -276.511004) (xy 352.829609 -276.490414)
			(xy 352.862942 -276.453107) (xy 352.901164 -276.420827) (xy 352.943524 -276.394207) (xy 352.989189 -276.373772)
			(xy 353.037263 -276.359922) (xy 353.086801 -276.352929) (xy 353.111816 -276.352508) (xy 353.138466 -276.352975)
			(xy 353.19117 -276.360921) (xy 353.242101 -276.376633) (xy 353.290121 -276.39976) (xy 353.334158 -276.429786)
			(xy 353.373229 -276.46604) (xy 353.40646 -276.507712) (xy 353.433109 -276.553871) (xy 353.452581 -276.603486)
			(xy 353.464441 -276.65545) (xy 353.468424 -276.7086) (xy 353.466426 -276.735265) (xy 353.695752 -276.735265)
			(xy 353.695752 -276.681967) (xy 353.703695 -276.629263) (xy 353.719405 -276.578333) (xy 353.742531 -276.530312)
			(xy 353.772555 -276.486275) (xy 353.808807 -276.447204) (xy 353.850478 -276.413973) (xy 353.896636 -276.387324)
			(xy 353.94625 -276.367852) (xy 353.998212 -276.355992) (xy 354.051362 -276.352009) (xy 354.104512 -276.355992)
			(xy 354.156474 -276.367852) (xy 354.206088 -276.387324) (xy 354.252246 -276.413973) (xy 354.293917 -276.447204)
			(xy 354.330169 -276.486275) (xy 354.360193 -276.530312) (xy 354.383319 -276.578333) (xy 354.399029 -276.629263)
			(xy 354.406972 -276.681967) (xy 354.40747 -276.708616) (xy 354.406972 -276.735265) (xy 354.399029 -276.787969)
			(xy 354.383319 -276.838899) (xy 354.360193 -276.88692) (xy 354.330169 -276.930957) (xy 354.293917 -276.970028)
			(xy 354.252246 -277.003259) (xy 354.206088 -277.029908) (xy 354.156474 -277.04938) (xy 354.104512 -277.06124)
			(xy 354.051362 -277.065224) (xy 353.998212 -277.06124) (xy 353.94625 -277.04938) (xy 353.896636 -277.029908)
			(xy 353.850478 -277.003259) (xy 353.808807 -276.970028) (xy 353.772555 -276.930957) (xy 353.742531 -276.88692)
			(xy 353.719405 -276.838899) (xy 353.703695 -276.787969) (xy 353.695752 -276.735265) (xy 353.466426 -276.735265)
			(xy 353.464441 -276.76175) (xy 353.452581 -276.813714) (xy 353.433109 -276.863329) (xy 353.40646 -276.909488)
			(xy 353.373229 -276.95116) (xy 353.334158 -276.987414) (xy 353.290121 -277.01744) (xy 353.242101 -277.040567)
			(xy 353.19117 -277.056279) (xy 353.138466 -277.064225) (xy 353.111816 -277.064724) (xy 353.086801 -277.064303)
			(xy 353.037262 -277.057319) (xy 352.989188 -277.043472) (xy 352.943523 -277.023035) (xy 352.901168 -276.996409)
			(xy 352.862954 -276.964119) (xy 352.829635 -276.9268) (xy 352.815398 -276.906228) (xy 352.468434 -276.906228)
			(xy 352.454213 -276.92681) (xy 352.42088 -276.964116) (xy 352.38266 -276.996396) (xy 352.340302 -277.023016)
			(xy 352.294638 -277.043452) (xy 352.246566 -277.057305) (xy 352.19703 -277.064301) (xy 352.172016 -277.064724)
			(xy 352.145365 -277.06422) (xy 352.092659 -277.056278) (xy 352.041725 -277.040569) (xy 351.993701 -277.017444)
			(xy 351.949661 -276.987419) (xy 351.910587 -276.951166) (xy 351.877353 -276.909494) (xy 351.850702 -276.863334)
			(xy 351.831228 -276.813717) (xy 351.819367 -276.761752) (xy 351.815384 -276.7086) (xy 351.588324 -276.7086)
			(xy 351.588324 -276.708616) (xy 351.587959 -276.731861) (xy 351.58191 -276.777957) (xy 351.569918 -276.822874)
			(xy 351.5614 -276.844506) (xy 351.551748 -276.86762) (xy 351.724214 -277.16607) (xy 351.748852 -277.169372)
			(xy 351.774194 -277.173197) (xy 351.823498 -277.187189) (xy 351.870289 -277.208102) (xy 351.913599 -277.235504)
			(xy 351.952537 -277.268829) (xy 351.986297 -277.307389) (xy 352.014184 -277.35039) (xy 352.035621 -277.396942)
			(xy 352.050167 -277.446086) (xy 352.05752 -277.496807) (xy 352.05797 -277.522432) (xy 352.057472 -277.549081)
			(xy 352.286052 -277.549081) (xy 352.286052 -277.495783) (xy 352.293995 -277.443079) (xy 352.309705 -277.392149)
			(xy 352.332831 -277.344128) (xy 352.362855 -277.300091) (xy 352.399107 -277.26102) (xy 352.440778 -277.227789)
			(xy 352.486936 -277.20114) (xy 352.53655 -277.181668) (xy 352.588512 -277.169808) (xy 352.641662 -277.165825)
			(xy 352.694812 -277.169808) (xy 352.746774 -277.181668) (xy 352.796388 -277.20114) (xy 352.842546 -277.227789)
			(xy 352.884217 -277.26102) (xy 352.920469 -277.300091) (xy 352.950493 -277.344128) (xy 352.973619 -277.392149)
			(xy 352.989329 -277.443079) (xy 352.997272 -277.495783) (xy 352.99777 -277.522432) (xy 352.997272 -277.549081)
			(xy 353.225852 -277.549081) (xy 353.225852 -277.495783) (xy 353.233795 -277.443079) (xy 353.249505 -277.392149)
			(xy 353.272631 -277.344128) (xy 353.302655 -277.300091) (xy 353.338907 -277.26102) (xy 353.380578 -277.227789)
			(xy 353.426736 -277.20114) (xy 353.47635 -277.181668) (xy 353.528312 -277.169808) (xy 353.581462 -277.165825)
			(xy 353.634612 -277.169808) (xy 353.686574 -277.181668) (xy 353.736188 -277.20114) (xy 353.782346 -277.227789)
			(xy 353.824017 -277.26102) (xy 353.860269 -277.300091) (xy 353.890293 -277.344128) (xy 353.913419 -277.392149)
			(xy 353.929129 -277.443079) (xy 353.937072 -277.495783) (xy 353.93757 -277.522432) (xy 354.165154 -277.522432)
			(xy 354.165603 -277.496803) (xy 354.172934 -277.446074) (xy 354.187464 -277.39692) (xy 354.208893 -277.350358)
			(xy 354.236778 -277.307349) (xy 354.270542 -277.268785) (xy 354.309487 -277.23546) (xy 354.352808 -277.208065)
			(xy 354.399611 -277.187165) (xy 354.448926 -277.173192) (xy 354.474272 -277.169372) (xy 354.49891 -277.16607)
			(xy 354.67163 -276.867112) (xy 354.661978 -276.843998) (xy 354.653505 -276.822448) (xy 354.641623 -276.777691)
			(xy 354.635656 -276.73177) (xy 354.635308 -276.708616) (xy 354.635806 -276.681967) (xy 354.643749 -276.629263)
			(xy 354.659459 -276.578333) (xy 354.682585 -276.530312) (xy 354.712609 -276.486275) (xy 354.748861 -276.447204)
			(xy 354.790532 -276.413973) (xy 354.83669 -276.387324) (xy 354.886304 -276.367852) (xy 354.938266 -276.355992)
			(xy 354.991416 -276.352009) (xy 355.044566 -276.355992) (xy 355.096528 -276.367852) (xy 355.146142 -276.387324)
			(xy 355.1923 -276.413973) (xy 355.233971 -276.447204) (xy 355.270223 -276.486275) (xy 355.300247 -276.530312)
			(xy 355.323373 -276.578333) (xy 355.339083 -276.629263) (xy 355.347026 -276.681967) (xy 355.347524 -276.708616)
			(xy 355.347018 -276.734253) (xy 355.339675 -276.784998) (xy 355.32513 -276.834165) (xy 355.303682 -276.880737)
			(xy 355.275776 -276.923751) (xy 355.241989 -276.962318) (xy 355.203019 -276.99564) (xy 355.159673 -277.023027)
			(xy 355.112846 -277.043913) (xy 355.063508 -277.057867) (xy 355.038152 -277.061676) (xy 355.01326 -277.064978)
			(xy 354.840794 -277.363428) (xy 354.850446 -277.386542) (xy 354.858971 -277.408171) (xy 354.870955 -277.45309)
			(xy 354.876996 -277.499187) (xy 354.87737 -277.522432) (xy 354.876872 -277.549081) (xy 354.868929 -277.601785)
			(xy 354.853219 -277.652715) (xy 354.830093 -277.700736) (xy 354.800069 -277.744773) (xy 354.763817 -277.783844)
			(xy 354.722146 -277.817075) (xy 354.675988 -277.843724) (xy 354.626374 -277.863196) (xy 354.574412 -277.875056)
			(xy 354.521262 -277.87904) (xy 354.468112 -277.875056) (xy 354.41615 -277.863196) (xy 354.366536 -277.843724)
			(xy 354.320378 -277.817075) (xy 354.278707 -277.783844) (xy 354.242455 -277.744773) (xy 354.212431 -277.700736)
			(xy 354.189305 -277.652715) (xy 354.173595 -277.601785) (xy 354.165652 -277.549081) (xy 354.165154 -277.522432)
			(xy 353.93757 -277.522432) (xy 353.937072 -277.549081) (xy 353.929129 -277.601785) (xy 353.913419 -277.652715)
			(xy 353.890293 -277.700736) (xy 353.860269 -277.744773) (xy 353.824017 -277.783844) (xy 353.782346 -277.817075)
			(xy 353.736188 -277.843724) (xy 353.686574 -277.863196) (xy 353.634612 -277.875056) (xy 353.581462 -277.87904)
			(xy 353.528312 -277.875056) (xy 353.47635 -277.863196) (xy 353.426736 -277.843724) (xy 353.380578 -277.817075)
			(xy 353.338907 -277.783844) (xy 353.302655 -277.744773) (xy 353.272631 -277.700736) (xy 353.249505 -277.652715)
			(xy 353.233795 -277.601785) (xy 353.225852 -277.549081) (xy 352.997272 -277.549081) (xy 352.989329 -277.601785)
			(xy 352.973619 -277.652715) (xy 352.950493 -277.700736) (xy 352.920469 -277.744773) (xy 352.884217 -277.783844)
			(xy 352.842546 -277.817075) (xy 352.796388 -277.843724) (xy 352.746774 -277.863196) (xy 352.694812 -277.875056)
			(xy 352.641662 -277.87904) (xy 352.588512 -277.875056) (xy 352.53655 -277.863196) (xy 352.486936 -277.843724)
			(xy 352.440778 -277.817075) (xy 352.399107 -277.783844) (xy 352.362855 -277.744773) (xy 352.332831 -277.700736)
			(xy 352.309705 -277.652715) (xy 352.293995 -277.601785) (xy 352.286052 -277.549081) (xy 352.057472 -277.549081)
			(xy 352.049529 -277.601785) (xy 352.033819 -277.652715) (xy 352.010693 -277.700736) (xy 351.980669 -277.744773)
			(xy 351.944417 -277.783844) (xy 351.902746 -277.817075) (xy 351.856588 -277.843724) (xy 351.806974 -277.863196)
			(xy 351.755012 -277.875056) (xy 351.701862 -277.87904) (xy 351.648712 -277.875056) (xy 351.59675 -277.863196)
			(xy 351.547136 -277.843724) (xy 351.500978 -277.817075) (xy 351.459307 -277.783844) (xy 351.423055 -277.744773)
			(xy 351.393031 -277.700736) (xy 351.369905 -277.652715) (xy 351.354195 -277.601785) (xy 351.346252 -277.549081)
			(xy 351.345754 -277.522432) (xy 351.346136 -277.499187) (xy 351.352178 -277.453092) (xy 351.364163 -277.408174)
			(xy 351.372678 -277.386542) (xy 351.38233 -277.363428) (xy 351.209864 -277.064978) (xy 351.184972 -277.061676)
			(xy 351.159655 -277.057773) (xy 351.110387 -277.043756) (xy 351.063635 -277.022828) (xy 351.020361 -276.99542)
			(xy 350.981459 -276.962098) (xy 350.947729 -276.923549) (xy 350.919867 -276.880566) (xy 350.898448 -276.834037)
			(xy 350.883912 -276.78492) (xy 350.87656 -276.734227) (xy 350.876108 -276.708616) (xy 350.64827 -276.708616)
			(xy 350.647772 -276.735265) (xy 350.639829 -276.787969) (xy 350.624119 -276.838899) (xy 350.600993 -276.88692)
			(xy 350.570969 -276.930957) (xy 350.534717 -276.970028) (xy 350.493046 -277.003259) (xy 350.446888 -277.029908)
			(xy 350.397274 -277.04938) (xy 350.345312 -277.06124) (xy 350.292162 -277.065224) (xy 350.239012 -277.06124)
			(xy 350.18705 -277.04938) (xy 350.137436 -277.029908) (xy 350.091278 -277.003259) (xy 350.049607 -276.970028)
			(xy 350.013355 -276.930957) (xy 349.983331 -276.88692) (xy 349.960205 -276.838899) (xy 349.944495 -276.787969)
			(xy 349.936552 -276.735265) (xy 349.936054 -276.708616) (xy 349.708724 -276.708616) (xy 349.708226 -276.735265)
			(xy 349.700283 -276.787969) (xy 349.684573 -276.838899) (xy 349.661447 -276.88692) (xy 349.631423 -276.930957)
			(xy 349.595171 -276.970028) (xy 349.5535 -277.003259) (xy 349.507342 -277.029908) (xy 349.457728 -277.04938)
			(xy 349.405766 -277.06124) (xy 349.352616 -277.065224) (xy 349.299466 -277.06124) (xy 349.247504 -277.04938)
			(xy 349.19789 -277.029908) (xy 349.151732 -277.003259) (xy 349.110061 -276.970028) (xy 349.073809 -276.930957)
			(xy 349.043785 -276.88692) (xy 349.020659 -276.838899) (xy 349.004949 -276.787969) (xy 348.997006 -276.735265)
			(xy 348.768426 -276.735265) (xy 348.760483 -276.787969) (xy 348.744773 -276.838899) (xy 348.721647 -276.88692)
			(xy 348.691623 -276.930957) (xy 348.655371 -276.970028) (xy 348.6137 -277.003259) (xy 348.567542 -277.029908)
			(xy 348.517928 -277.04938) (xy 348.465966 -277.06124) (xy 348.412816 -277.065224) (xy 348.359666 -277.06124)
			(xy 348.307704 -277.04938) (xy 348.25809 -277.029908) (xy 348.211932 -277.003259) (xy 348.170261 -276.970028)
			(xy 348.134009 -276.930957) (xy 348.103985 -276.88692) (xy 348.080859 -276.838899) (xy 348.065149 -276.787969)
			(xy 348.057206 -276.735265) (xy 347.828626 -276.735265) (xy 347.820683 -276.787969) (xy 347.804973 -276.838899)
			(xy 347.781847 -276.88692) (xy 347.751823 -276.930957) (xy 347.715571 -276.970028) (xy 347.6739 -277.003259)
			(xy 347.627742 -277.029908) (xy 347.578128 -277.04938) (xy 347.526166 -277.06124) (xy 347.473016 -277.065224)
			(xy 347.419866 -277.06124) (xy 347.367904 -277.04938) (xy 347.31829 -277.029908) (xy 347.272132 -277.003259)
			(xy 347.230461 -276.970028) (xy 347.194209 -276.930957) (xy 347.164185 -276.88692) (xy 347.141059 -276.838899)
			(xy 347.125349 -276.787969) (xy 347.117406 -276.735265) (xy 346.888826 -276.735265) (xy 346.880883 -276.787969)
			(xy 346.865173 -276.838899) (xy 346.842047 -276.88692) (xy 346.812023 -276.930957) (xy 346.775771 -276.970028)
			(xy 346.7341 -277.003259) (xy 346.687942 -277.029908) (xy 346.638328 -277.04938) (xy 346.586366 -277.06124)
			(xy 346.533216 -277.065224) (xy 346.480066 -277.06124) (xy 346.428104 -277.04938) (xy 346.37849 -277.029908)
			(xy 346.332332 -277.003259) (xy 346.290661 -276.970028) (xy 346.254409 -276.930957) (xy 346.224385 -276.88692)
			(xy 346.201259 -276.838899) (xy 346.185549 -276.787969) (xy 346.177606 -276.735265) (xy 345.948772 -276.735265)
			(xy 345.940829 -276.787969) (xy 345.925119 -276.838899) (xy 345.901993 -276.88692) (xy 345.871969 -276.930957)
			(xy 345.835717 -276.970028) (xy 345.794046 -277.003259) (xy 345.747888 -277.029908) (xy 345.698274 -277.04938)
			(xy 345.646312 -277.06124) (xy 345.593162 -277.065224) (xy 345.540012 -277.06124) (xy 345.48805 -277.04938)
			(xy 345.438436 -277.029908) (xy 345.392278 -277.003259) (xy 345.350607 -276.970028) (xy 345.314355 -276.930957)
			(xy 345.284331 -276.88692) (xy 345.261205 -276.838899) (xy 345.245495 -276.787969) (xy 345.237552 -276.735265)
			(xy 345.009226 -276.735265) (xy 345.001283 -276.787969) (xy 344.985573 -276.838899) (xy 344.962447 -276.88692)
			(xy 344.932423 -276.930957) (xy 344.896171 -276.970028) (xy 344.8545 -277.003259) (xy 344.808342 -277.029908)
			(xy 344.758728 -277.04938) (xy 344.706766 -277.06124) (xy 344.653616 -277.065224) (xy 344.600466 -277.06124)
			(xy 344.548504 -277.04938) (xy 344.49889 -277.029908) (xy 344.452732 -277.003259) (xy 344.411061 -276.970028)
			(xy 344.374809 -276.930957) (xy 344.344785 -276.88692) (xy 344.321659 -276.838899) (xy 344.305949 -276.787969)
			(xy 344.298006 -276.735265) (xy 344.069426 -276.735265) (xy 344.061483 -276.787969) (xy 344.045773 -276.838899)
			(xy 344.022647 -276.88692) (xy 343.992623 -276.930957) (xy 343.956371 -276.970028) (xy 343.9147 -277.003259)
			(xy 343.868542 -277.029908) (xy 343.818928 -277.04938) (xy 343.766966 -277.06124) (xy 343.713816 -277.065224)
			(xy 343.660666 -277.06124) (xy 343.608704 -277.04938) (xy 343.55909 -277.029908) (xy 343.512932 -277.003259)
			(xy 343.471261 -276.970028) (xy 343.435009 -276.930957) (xy 343.404985 -276.88692) (xy 343.381859 -276.838899)
			(xy 343.366149 -276.787969) (xy 343.358206 -276.735265) (xy 343.129626 -276.735265) (xy 343.121683 -276.787969)
			(xy 343.105973 -276.838899) (xy 343.082847 -276.88692) (xy 343.052823 -276.930957) (xy 343.016571 -276.970028)
			(xy 342.9749 -277.003259) (xy 342.928742 -277.029908) (xy 342.879128 -277.04938) (xy 342.827166 -277.06124)
			(xy 342.774016 -277.065224) (xy 342.720866 -277.06124) (xy 342.668904 -277.04938) (xy 342.61929 -277.029908)
			(xy 342.573132 -277.003259) (xy 342.531461 -276.970028) (xy 342.495209 -276.930957) (xy 342.465185 -276.88692)
			(xy 342.442059 -276.838899) (xy 342.426349 -276.787969) (xy 342.418406 -276.735265) (xy 342.189826 -276.735265)
			(xy 342.181883 -276.787969) (xy 342.166173 -276.838899) (xy 342.143047 -276.88692) (xy 342.113023 -276.930957)
			(xy 342.076771 -276.970028) (xy 342.0351 -277.003259) (xy 341.988942 -277.029908) (xy 341.939328 -277.04938)
			(xy 341.887366 -277.06124) (xy 341.834216 -277.065224) (xy 341.781066 -277.06124) (xy 341.729104 -277.04938)
			(xy 341.67949 -277.029908) (xy 341.633332 -277.003259) (xy 341.591661 -276.970028) (xy 341.555409 -276.930957)
			(xy 341.525385 -276.88692) (xy 341.502259 -276.838899) (xy 341.486549 -276.787969) (xy 341.478606 -276.735265)
			(xy 341.250026 -276.735265) (xy 341.242083 -276.787969) (xy 341.226373 -276.838899) (xy 341.203247 -276.88692)
			(xy 341.173223 -276.930957) (xy 341.136971 -276.970028) (xy 341.0953 -277.003259) (xy 341.049142 -277.029908)
			(xy 340.999528 -277.04938) (xy 340.947566 -277.06124) (xy 340.894416 -277.065224) (xy 340.841266 -277.06124)
			(xy 340.789304 -277.04938) (xy 340.73969 -277.029908) (xy 340.693532 -277.003259) (xy 340.651861 -276.970028)
			(xy 340.615609 -276.930957) (xy 340.585585 -276.88692) (xy 340.562459 -276.838899) (xy 340.546749 -276.787969)
			(xy 340.538806 -276.735265) (xy 340.310226 -276.735265) (xy 340.302283 -276.787969) (xy 340.286573 -276.838899)
			(xy 340.263447 -276.88692) (xy 340.233423 -276.930957) (xy 340.197171 -276.970028) (xy 340.1555 -277.003259)
			(xy 340.109342 -277.029908) (xy 340.059728 -277.04938) (xy 340.007766 -277.06124) (xy 339.954616 -277.065224)
			(xy 339.901466 -277.06124) (xy 339.849504 -277.04938) (xy 339.79989 -277.029908) (xy 339.753732 -277.003259)
			(xy 339.712061 -276.970028) (xy 339.675809 -276.930957) (xy 339.645785 -276.88692) (xy 339.622659 -276.838899)
			(xy 339.606949 -276.787969) (xy 339.599006 -276.735265) (xy 339.370172 -276.735265) (xy 339.362229 -276.787969)
			(xy 339.346519 -276.838899) (xy 339.323393 -276.88692) (xy 339.293369 -276.930957) (xy 339.257117 -276.970028)
			(xy 339.215446 -277.003259) (xy 339.169288 -277.029908) (xy 339.119674 -277.04938) (xy 339.067712 -277.06124)
			(xy 339.014562 -277.065224) (xy 338.961412 -277.06124) (xy 338.90945 -277.04938) (xy 338.859836 -277.029908)
			(xy 338.813678 -277.003259) (xy 338.772007 -276.970028) (xy 338.735755 -276.930957) (xy 338.705731 -276.88692)
			(xy 338.682605 -276.838899) (xy 338.666895 -276.787969) (xy 338.658952 -276.735265) (xy 338.430372 -276.735265)
			(xy 338.422429 -276.787969) (xy 338.406719 -276.838899) (xy 338.383593 -276.88692) (xy 338.353569 -276.930957)
			(xy 338.317317 -276.970028) (xy 338.275646 -277.003259) (xy 338.229488 -277.029908) (xy 338.179874 -277.04938)
			(xy 338.127912 -277.06124) (xy 338.074762 -277.065224) (xy 338.021612 -277.06124) (xy 337.96965 -277.04938)
			(xy 337.920036 -277.029908) (xy 337.873878 -277.003259) (xy 337.832207 -276.970028) (xy 337.795955 -276.930957)
			(xy 337.765931 -276.88692) (xy 337.742805 -276.838899) (xy 337.727095 -276.787969) (xy 337.719152 -276.735265)
			(xy 337.490572 -276.735265) (xy 337.482629 -276.787969) (xy 337.466919 -276.838899) (xy 337.443793 -276.88692)
			(xy 337.413769 -276.930957) (xy 337.377517 -276.970028) (xy 337.335846 -277.003259) (xy 337.289688 -277.029908)
			(xy 337.240074 -277.04938) (xy 337.188112 -277.06124) (xy 337.134962 -277.065224) (xy 337.081812 -277.06124)
			(xy 337.02985 -277.04938) (xy 336.980236 -277.029908) (xy 336.934078 -277.003259) (xy 336.892407 -276.970028)
			(xy 336.856155 -276.930957) (xy 336.826131 -276.88692) (xy 336.803005 -276.838899) (xy 336.787295 -276.787969)
			(xy 336.779352 -276.735265) (xy 336.550772 -276.735265) (xy 336.542829 -276.787969) (xy 336.527119 -276.838899)
			(xy 336.503993 -276.88692) (xy 336.473969 -276.930957) (xy 336.437717 -276.970028) (xy 336.396046 -277.003259)
			(xy 336.349888 -277.029908) (xy 336.300274 -277.04938) (xy 336.248312 -277.06124) (xy 336.195162 -277.065224)
			(xy 336.142012 -277.06124) (xy 336.09005 -277.04938) (xy 336.040436 -277.029908) (xy 335.994278 -277.003259)
			(xy 335.952607 -276.970028) (xy 335.916355 -276.930957) (xy 335.886331 -276.88692) (xy 335.863205 -276.838899)
			(xy 335.847495 -276.787969) (xy 335.839552 -276.735265) (xy 333.466948 -276.735265) (xy 333.466948 -277.270951)
			(xy 334.886036 -277.270951) (xy 334.886036 -277.217653) (xy 334.893979 -277.164949) (xy 334.909689 -277.114019)
			(xy 334.932815 -277.065998) (xy 334.962839 -277.021961) (xy 334.999091 -276.98289) (xy 335.040762 -276.949659)
			(xy 335.08692 -276.92301) (xy 335.136534 -276.903538) (xy 335.188496 -276.891678) (xy 335.241646 -276.887695)
			(xy 335.294796 -276.891678) (xy 335.346758 -276.903538) (xy 335.396372 -276.92301) (xy 335.44253 -276.949659)
			(xy 335.484201 -276.98289) (xy 335.520453 -277.021961) (xy 335.550477 -277.065998) (xy 335.573603 -277.114019)
			(xy 335.589313 -277.164949) (xy 335.597256 -277.217653) (xy 335.597754 -277.244302) (xy 335.597256 -277.270951)
			(xy 335.589313 -277.323655) (xy 335.573603 -277.374585) (xy 335.550477 -277.422606) (xy 335.520453 -277.466643)
			(xy 335.484201 -277.505714) (xy 335.44253 -277.538945) (xy 335.424534 -277.549335) (xy 336.309198 -277.549335)
			(xy 336.309198 -277.496037) (xy 336.317141 -277.443333) (xy 336.332851 -277.392403) (xy 336.355977 -277.344382)
			(xy 336.386001 -277.300345) (xy 336.422253 -277.261274) (xy 336.463924 -277.228043) (xy 336.510082 -277.201394)
			(xy 336.559696 -277.181922) (xy 336.611658 -277.170062) (xy 336.664808 -277.166079) (xy 336.717958 -277.170062)
			(xy 336.76992 -277.181922) (xy 336.819534 -277.201394) (xy 336.865692 -277.228043) (xy 336.907363 -277.261274)
			(xy 336.943615 -277.300345) (xy 336.973639 -277.344382) (xy 336.996765 -277.392403) (xy 337.012475 -277.443333)
			(xy 337.020418 -277.496037) (xy 337.020916 -277.522686) (xy 337.020423 -277.549081) (xy 337.249252 -277.549081)
			(xy 337.249252 -277.495783) (xy 337.257195 -277.443079) (xy 337.272905 -277.392149) (xy 337.296031 -277.344128)
			(xy 337.326055 -277.300091) (xy 337.362307 -277.26102) (xy 337.403978 -277.227789) (xy 337.450136 -277.20114)
			(xy 337.49975 -277.181668) (xy 337.551712 -277.169808) (xy 337.604862 -277.165825) (xy 337.658012 -277.169808)
			(xy 337.709974 -277.181668) (xy 337.759588 -277.20114) (xy 337.805746 -277.227789) (xy 337.847417 -277.26102)
			(xy 337.883669 -277.300091) (xy 337.913693 -277.344128) (xy 337.936819 -277.392149) (xy 337.952529 -277.443079)
			(xy 337.960472 -277.495783) (xy 337.96097 -277.522432) (xy 337.960472 -277.549081) (xy 338.189306 -277.549081)
			(xy 338.189306 -277.495783) (xy 338.197249 -277.443079) (xy 338.212959 -277.392149) (xy 338.236085 -277.344128)
			(xy 338.266109 -277.300091) (xy 338.302361 -277.26102) (xy 338.344032 -277.227789) (xy 338.39019 -277.20114)
			(xy 338.439804 -277.181668) (xy 338.491766 -277.169808) (xy 338.544916 -277.165825) (xy 338.598066 -277.169808)
			(xy 338.650028 -277.181668) (xy 338.699642 -277.20114) (xy 338.7458 -277.227789) (xy 338.787471 -277.26102)
			(xy 338.823723 -277.300091) (xy 338.853747 -277.344128) (xy 338.876873 -277.392149) (xy 338.892583 -277.443079)
			(xy 338.900526 -277.495783) (xy 338.901024 -277.522432) (xy 338.900526 -277.549081) (xy 339.128852 -277.549081)
			(xy 339.128852 -277.495783) (xy 339.136795 -277.443079) (xy 339.152505 -277.392149) (xy 339.175631 -277.344128)
			(xy 339.205655 -277.300091) (xy 339.241907 -277.26102) (xy 339.283578 -277.227789) (xy 339.329736 -277.20114)
			(xy 339.37935 -277.181668) (xy 339.431312 -277.169808) (xy 339.484462 -277.165825) (xy 339.537612 -277.169808)
			(xy 339.589574 -277.181668) (xy 339.639188 -277.20114) (xy 339.685346 -277.227789) (xy 339.727017 -277.26102)
			(xy 339.763269 -277.300091) (xy 339.793293 -277.344128) (xy 339.816419 -277.392149) (xy 339.832129 -277.443079)
			(xy 339.840072 -277.495783) (xy 339.84057 -277.522432) (xy 339.840072 -277.549081) (xy 340.068652 -277.549081)
			(xy 340.068652 -277.495783) (xy 340.076595 -277.443079) (xy 340.092305 -277.392149) (xy 340.115431 -277.344128)
			(xy 340.145455 -277.300091) (xy 340.181707 -277.26102) (xy 340.223378 -277.227789) (xy 340.269536 -277.20114)
			(xy 340.31915 -277.181668) (xy 340.371112 -277.169808) (xy 340.424262 -277.165825) (xy 340.477412 -277.169808)
			(xy 340.529374 -277.181668) (xy 340.578988 -277.20114) (xy 340.625146 -277.227789) (xy 340.666817 -277.26102)
			(xy 340.703069 -277.300091) (xy 340.733093 -277.344128) (xy 340.756219 -277.392149) (xy 340.771929 -277.443079)
			(xy 340.779872 -277.495783) (xy 340.78037 -277.522432) (xy 340.779872 -277.549081) (xy 341.008452 -277.549081)
			(xy 341.008452 -277.495783) (xy 341.016395 -277.443079) (xy 341.032105 -277.392149) (xy 341.055231 -277.344128)
			(xy 341.085255 -277.300091) (xy 341.121507 -277.26102) (xy 341.163178 -277.227789) (xy 341.209336 -277.20114)
			(xy 341.25895 -277.181668) (xy 341.310912 -277.169808) (xy 341.364062 -277.165825) (xy 341.417212 -277.169808)
			(xy 341.469174 -277.181668) (xy 341.518788 -277.20114) (xy 341.564946 -277.227789) (xy 341.606617 -277.26102)
			(xy 341.642869 -277.300091) (xy 341.672893 -277.344128) (xy 341.696019 -277.392149) (xy 341.711729 -277.443079)
			(xy 341.719672 -277.495783) (xy 341.72017 -277.522432) (xy 341.719672 -277.549081) (xy 341.948252 -277.549081)
			(xy 341.948252 -277.495783) (xy 341.956195 -277.443079) (xy 341.971905 -277.392149) (xy 341.995031 -277.344128)
			(xy 342.025055 -277.300091) (xy 342.061307 -277.26102) (xy 342.102978 -277.227789) (xy 342.149136 -277.20114)
			(xy 342.19875 -277.181668) (xy 342.250712 -277.169808) (xy 342.303862 -277.165825) (xy 342.357012 -277.169808)
			(xy 342.408974 -277.181668) (xy 342.458588 -277.20114) (xy 342.504746 -277.227789) (xy 342.546417 -277.26102)
			(xy 342.582669 -277.300091) (xy 342.612693 -277.344128) (xy 342.635819 -277.392149) (xy 342.651529 -277.443079)
			(xy 342.659472 -277.495783) (xy 342.65997 -277.522432) (xy 342.659472 -277.549081) (xy 342.888052 -277.549081)
			(xy 342.888052 -277.495783) (xy 342.895995 -277.443079) (xy 342.911705 -277.392149) (xy 342.934831 -277.344128)
			(xy 342.964855 -277.300091) (xy 343.001107 -277.26102) (xy 343.042778 -277.227789) (xy 343.088936 -277.20114)
			(xy 343.13855 -277.181668) (xy 343.190512 -277.169808) (xy 343.243662 -277.165825) (xy 343.296812 -277.169808)
			(xy 343.348774 -277.181668) (xy 343.398388 -277.20114) (xy 343.444546 -277.227789) (xy 343.486217 -277.26102)
			(xy 343.522469 -277.300091) (xy 343.552493 -277.344128) (xy 343.575619 -277.392149) (xy 343.591329 -277.443079)
			(xy 343.599272 -277.495783) (xy 343.59977 -277.522432) (xy 343.599272 -277.549081) (xy 343.827852 -277.549081)
			(xy 343.827852 -277.495783) (xy 343.835795 -277.443079) (xy 343.851505 -277.392149) (xy 343.874631 -277.344128)
			(xy 343.904655 -277.300091) (xy 343.940907 -277.26102) (xy 343.982578 -277.227789) (xy 344.028736 -277.20114)
			(xy 344.07835 -277.181668) (xy 344.130312 -277.169808) (xy 344.183462 -277.165825) (xy 344.236612 -277.169808)
			(xy 344.288574 -277.181668) (xy 344.338188 -277.20114) (xy 344.384346 -277.227789) (xy 344.426017 -277.26102)
			(xy 344.462269 -277.300091) (xy 344.492293 -277.344128) (xy 344.515419 -277.392149) (xy 344.531129 -277.443079)
			(xy 344.539072 -277.495783) (xy 344.53957 -277.522432) (xy 344.539072 -277.549081) (xy 344.767652 -277.549081)
			(xy 344.767652 -277.495783) (xy 344.775595 -277.443079) (xy 344.791305 -277.392149) (xy 344.814431 -277.344128)
			(xy 344.844455 -277.300091) (xy 344.880707 -277.26102) (xy 344.922378 -277.227789) (xy 344.968536 -277.20114)
			(xy 345.01815 -277.181668) (xy 345.070112 -277.169808) (xy 345.123262 -277.165825) (xy 345.176412 -277.169808)
			(xy 345.228374 -277.181668) (xy 345.277988 -277.20114) (xy 345.324146 -277.227789) (xy 345.365817 -277.26102)
			(xy 345.402069 -277.300091) (xy 345.432093 -277.344128) (xy 345.455219 -277.392149) (xy 345.470929 -277.443079)
			(xy 345.478872 -277.495783) (xy 345.47937 -277.522432) (xy 345.478872 -277.549081) (xy 345.707452 -277.549081)
			(xy 345.707452 -277.495783) (xy 345.715395 -277.443079) (xy 345.731105 -277.392149) (xy 345.754231 -277.344128)
			(xy 345.784255 -277.300091) (xy 345.820507 -277.26102) (xy 345.862178 -277.227789) (xy 345.908336 -277.20114)
			(xy 345.95795 -277.181668) (xy 346.009912 -277.169808) (xy 346.063062 -277.165825) (xy 346.116212 -277.169808)
			(xy 346.168174 -277.181668) (xy 346.217788 -277.20114) (xy 346.263946 -277.227789) (xy 346.305617 -277.26102)
			(xy 346.341869 -277.300091) (xy 346.371893 -277.344128) (xy 346.395019 -277.392149) (xy 346.410729 -277.443079)
			(xy 346.418672 -277.495783) (xy 346.41917 -277.522432) (xy 346.418672 -277.549081) (xy 346.647252 -277.549081)
			(xy 346.647252 -277.495783) (xy 346.655195 -277.443079) (xy 346.670905 -277.392149) (xy 346.694031 -277.344128)
			(xy 346.724055 -277.300091) (xy 346.760307 -277.26102) (xy 346.801978 -277.227789) (xy 346.848136 -277.20114)
			(xy 346.89775 -277.181668) (xy 346.949712 -277.169808) (xy 347.002862 -277.165825) (xy 347.056012 -277.169808)
			(xy 347.107974 -277.181668) (xy 347.157588 -277.20114) (xy 347.203746 -277.227789) (xy 347.245417 -277.26102)
			(xy 347.281669 -277.300091) (xy 347.311693 -277.344128) (xy 347.334819 -277.392149) (xy 347.350529 -277.443079)
			(xy 347.358472 -277.495783) (xy 347.35897 -277.522432) (xy 347.358472 -277.549081) (xy 347.587052 -277.549081)
			(xy 347.587052 -277.495783) (xy 347.594995 -277.443079) (xy 347.610705 -277.392149) (xy 347.633831 -277.344128)
			(xy 347.663855 -277.300091) (xy 347.700107 -277.26102) (xy 347.741778 -277.227789) (xy 347.787936 -277.20114)
			(xy 347.83755 -277.181668) (xy 347.889512 -277.169808) (xy 347.942662 -277.165825) (xy 347.995812 -277.169808)
			(xy 348.047774 -277.181668) (xy 348.097388 -277.20114) (xy 348.143546 -277.227789) (xy 348.185217 -277.26102)
			(xy 348.221469 -277.300091) (xy 348.251493 -277.344128) (xy 348.274619 -277.392149) (xy 348.290329 -277.443079)
			(xy 348.298272 -277.495783) (xy 348.29877 -277.522432) (xy 348.298272 -277.549081) (xy 348.526852 -277.549081)
			(xy 348.526852 -277.495783) (xy 348.534795 -277.443079) (xy 348.550505 -277.392149) (xy 348.573631 -277.344128)
			(xy 348.603655 -277.300091) (xy 348.639907 -277.26102) (xy 348.681578 -277.227789) (xy 348.727736 -277.20114)
			(xy 348.77735 -277.181668) (xy 348.829312 -277.169808) (xy 348.882462 -277.165825) (xy 348.935612 -277.169808)
			(xy 348.987574 -277.181668) (xy 349.037188 -277.20114) (xy 349.083346 -277.227789) (xy 349.125017 -277.26102)
			(xy 349.161269 -277.300091) (xy 349.191293 -277.344128) (xy 349.214419 -277.392149) (xy 349.230129 -277.443079)
			(xy 349.238072 -277.495783) (xy 349.23857 -277.522432) (xy 349.238072 -277.549081) (xy 349.466906 -277.549081)
			(xy 349.466906 -277.495783) (xy 349.474849 -277.443079) (xy 349.490559 -277.392149) (xy 349.513685 -277.344128)
			(xy 349.543709 -277.300091) (xy 349.579961 -277.26102) (xy 349.621632 -277.227789) (xy 349.66779 -277.20114)
			(xy 349.717404 -277.181668) (xy 349.769366 -277.169808) (xy 349.822516 -277.165825) (xy 349.875666 -277.169808)
			(xy 349.927628 -277.181668) (xy 349.977242 -277.20114) (xy 350.0234 -277.227789) (xy 350.065071 -277.26102)
			(xy 350.101323 -277.300091) (xy 350.131347 -277.344128) (xy 350.154473 -277.392149) (xy 350.170183 -277.443079)
			(xy 350.178126 -277.495783) (xy 350.178624 -277.522432) (xy 350.178126 -277.549081) (xy 350.170183 -277.601785)
			(xy 350.154473 -277.652715) (xy 350.131347 -277.700736) (xy 350.101323 -277.744773) (xy 350.065071 -277.783844)
			(xy 350.0234 -277.817075) (xy 349.977242 -277.843724) (xy 349.927628 -277.863196) (xy 349.875666 -277.875056)
			(xy 349.822516 -277.87904) (xy 349.769366 -277.875056) (xy 349.717404 -277.863196) (xy 349.66779 -277.843724)
			(xy 349.621632 -277.817075) (xy 349.579961 -277.783844) (xy 349.543709 -277.744773) (xy 349.513685 -277.700736)
			(xy 349.490559 -277.652715) (xy 349.474849 -277.601785) (xy 349.466906 -277.549081) (xy 349.238072 -277.549081)
			(xy 349.230129 -277.601785) (xy 349.214419 -277.652715) (xy 349.191293 -277.700736) (xy 349.161269 -277.744773)
			(xy 349.125017 -277.783844) (xy 349.083346 -277.817075) (xy 349.037188 -277.843724) (xy 348.987574 -277.863196)
			(xy 348.935612 -277.875056) (xy 348.882462 -277.87904) (xy 348.829312 -277.875056) (xy 348.77735 -277.863196)
			(xy 348.727736 -277.843724) (xy 348.681578 -277.817075) (xy 348.639907 -277.783844) (xy 348.603655 -277.744773)
			(xy 348.573631 -277.700736) (xy 348.550505 -277.652715) (xy 348.534795 -277.601785) (xy 348.526852 -277.549081)
			(xy 348.298272 -277.549081) (xy 348.290329 -277.601785) (xy 348.274619 -277.652715) (xy 348.251493 -277.700736)
			(xy 348.221469 -277.744773) (xy 348.185217 -277.783844) (xy 348.143546 -277.817075) (xy 348.097388 -277.843724)
			(xy 348.047774 -277.863196) (xy 347.995812 -277.875056) (xy 347.942662 -277.87904) (xy 347.889512 -277.875056)
			(xy 347.83755 -277.863196) (xy 347.787936 -277.843724) (xy 347.741778 -277.817075) (xy 347.700107 -277.783844)
			(xy 347.663855 -277.744773) (xy 347.633831 -277.700736) (xy 347.610705 -277.652715) (xy 347.594995 -277.601785)
			(xy 347.587052 -277.549081) (xy 347.358472 -277.549081) (xy 347.350529 -277.601785) (xy 347.334819 -277.652715)
			(xy 347.311693 -277.700736) (xy 347.281669 -277.744773) (xy 347.245417 -277.783844) (xy 347.203746 -277.817075)
			(xy 347.157588 -277.843724) (xy 347.107974 -277.863196) (xy 347.056012 -277.875056) (xy 347.002862 -277.87904)
			(xy 346.949712 -277.875056) (xy 346.89775 -277.863196) (xy 346.848136 -277.843724) (xy 346.801978 -277.817075)
			(xy 346.760307 -277.783844) (xy 346.724055 -277.744773) (xy 346.694031 -277.700736) (xy 346.670905 -277.652715)
			(xy 346.655195 -277.601785) (xy 346.647252 -277.549081) (xy 346.418672 -277.549081) (xy 346.410729 -277.601785)
			(xy 346.395019 -277.652715) (xy 346.371893 -277.700736) (xy 346.341869 -277.744773) (xy 346.305617 -277.783844)
			(xy 346.263946 -277.817075) (xy 346.217788 -277.843724) (xy 346.168174 -277.863196) (xy 346.116212 -277.875056)
			(xy 346.063062 -277.87904) (xy 346.009912 -277.875056) (xy 345.95795 -277.863196) (xy 345.908336 -277.843724)
			(xy 345.862178 -277.817075) (xy 345.820507 -277.783844) (xy 345.784255 -277.744773) (xy 345.754231 -277.700736)
			(xy 345.731105 -277.652715) (xy 345.715395 -277.601785) (xy 345.707452 -277.549081) (xy 345.478872 -277.549081)
			(xy 345.470929 -277.601785) (xy 345.455219 -277.652715) (xy 345.432093 -277.700736) (xy 345.402069 -277.744773)
			(xy 345.365817 -277.783844) (xy 345.324146 -277.817075) (xy 345.277988 -277.843724) (xy 345.228374 -277.863196)
			(xy 345.176412 -277.875056) (xy 345.123262 -277.87904) (xy 345.070112 -277.875056) (xy 345.01815 -277.863196)
			(xy 344.968536 -277.843724) (xy 344.922378 -277.817075) (xy 344.880707 -277.783844) (xy 344.844455 -277.744773)
			(xy 344.814431 -277.700736) (xy 344.791305 -277.652715) (xy 344.775595 -277.601785) (xy 344.767652 -277.549081)
			(xy 344.539072 -277.549081) (xy 344.531129 -277.601785) (xy 344.515419 -277.652715) (xy 344.492293 -277.700736)
			(xy 344.462269 -277.744773) (xy 344.426017 -277.783844) (xy 344.384346 -277.817075) (xy 344.338188 -277.843724)
			(xy 344.288574 -277.863196) (xy 344.236612 -277.875056) (xy 344.183462 -277.87904) (xy 344.130312 -277.875056)
			(xy 344.07835 -277.863196) (xy 344.028736 -277.843724) (xy 343.982578 -277.817075) (xy 343.940907 -277.783844)
			(xy 343.904655 -277.744773) (xy 343.874631 -277.700736) (xy 343.851505 -277.652715) (xy 343.835795 -277.601785)
			(xy 343.827852 -277.549081) (xy 343.599272 -277.549081) (xy 343.591329 -277.601785) (xy 343.575619 -277.652715)
			(xy 343.552493 -277.700736) (xy 343.522469 -277.744773) (xy 343.486217 -277.783844) (xy 343.444546 -277.817075)
			(xy 343.398388 -277.843724) (xy 343.348774 -277.863196) (xy 343.296812 -277.875056) (xy 343.243662 -277.87904)
			(xy 343.190512 -277.875056) (xy 343.13855 -277.863196) (xy 343.088936 -277.843724) (xy 343.042778 -277.817075)
			(xy 343.001107 -277.783844) (xy 342.964855 -277.744773) (xy 342.934831 -277.700736) (xy 342.911705 -277.652715)
			(xy 342.895995 -277.601785) (xy 342.888052 -277.549081) (xy 342.659472 -277.549081) (xy 342.651529 -277.601785)
			(xy 342.635819 -277.652715) (xy 342.612693 -277.700736) (xy 342.582669 -277.744773) (xy 342.546417 -277.783844)
			(xy 342.504746 -277.817075) (xy 342.458588 -277.843724) (xy 342.408974 -277.863196) (xy 342.357012 -277.875056)
			(xy 342.303862 -277.87904) (xy 342.250712 -277.875056) (xy 342.19875 -277.863196) (xy 342.149136 -277.843724)
			(xy 342.102978 -277.817075) (xy 342.061307 -277.783844) (xy 342.025055 -277.744773) (xy 341.995031 -277.700736)
			(xy 341.971905 -277.652715) (xy 341.956195 -277.601785) (xy 341.948252 -277.549081) (xy 341.719672 -277.549081)
			(xy 341.711729 -277.601785) (xy 341.696019 -277.652715) (xy 341.672893 -277.700736) (xy 341.642869 -277.744773)
			(xy 341.606617 -277.783844) (xy 341.564946 -277.817075) (xy 341.518788 -277.843724) (xy 341.469174 -277.863196)
			(xy 341.417212 -277.875056) (xy 341.364062 -277.87904) (xy 341.310912 -277.875056) (xy 341.25895 -277.863196)
			(xy 341.209336 -277.843724) (xy 341.163178 -277.817075) (xy 341.121507 -277.783844) (xy 341.085255 -277.744773)
			(xy 341.055231 -277.700736) (xy 341.032105 -277.652715) (xy 341.016395 -277.601785) (xy 341.008452 -277.549081)
			(xy 340.779872 -277.549081) (xy 340.771929 -277.601785) (xy 340.756219 -277.652715) (xy 340.733093 -277.700736)
			(xy 340.703069 -277.744773) (xy 340.666817 -277.783844) (xy 340.625146 -277.817075) (xy 340.578988 -277.843724)
			(xy 340.529374 -277.863196) (xy 340.477412 -277.875056) (xy 340.424262 -277.87904) (xy 340.371112 -277.875056)
			(xy 340.31915 -277.863196) (xy 340.269536 -277.843724) (xy 340.223378 -277.817075) (xy 340.181707 -277.783844)
			(xy 340.145455 -277.744773) (xy 340.115431 -277.700736) (xy 340.092305 -277.652715) (xy 340.076595 -277.601785)
			(xy 340.068652 -277.549081) (xy 339.840072 -277.549081) (xy 339.832129 -277.601785) (xy 339.816419 -277.652715)
			(xy 339.793293 -277.700736) (xy 339.763269 -277.744773) (xy 339.727017 -277.783844) (xy 339.685346 -277.817075)
			(xy 339.639188 -277.843724) (xy 339.589574 -277.863196) (xy 339.537612 -277.875056) (xy 339.484462 -277.87904)
			(xy 339.431312 -277.875056) (xy 339.37935 -277.863196) (xy 339.329736 -277.843724) (xy 339.283578 -277.817075)
			(xy 339.241907 -277.783844) (xy 339.205655 -277.744773) (xy 339.175631 -277.700736) (xy 339.152505 -277.652715)
			(xy 339.136795 -277.601785) (xy 339.128852 -277.549081) (xy 338.900526 -277.549081) (xy 338.892583 -277.601785)
			(xy 338.876873 -277.652715) (xy 338.853747 -277.700736) (xy 338.823723 -277.744773) (xy 338.787471 -277.783844)
			(xy 338.7458 -277.817075) (xy 338.699642 -277.843724) (xy 338.650028 -277.863196) (xy 338.598066 -277.875056)
			(xy 338.544916 -277.87904) (xy 338.491766 -277.875056) (xy 338.439804 -277.863196) (xy 338.39019 -277.843724)
			(xy 338.344032 -277.817075) (xy 338.302361 -277.783844) (xy 338.266109 -277.744773) (xy 338.236085 -277.700736)
			(xy 338.212959 -277.652715) (xy 338.197249 -277.601785) (xy 338.189306 -277.549081) (xy 337.960472 -277.549081)
			(xy 337.952529 -277.601785) (xy 337.936819 -277.652715) (xy 337.913693 -277.700736) (xy 337.883669 -277.744773)
			(xy 337.847417 -277.783844) (xy 337.805746 -277.817075) (xy 337.759588 -277.843724) (xy 337.709974 -277.863196)
			(xy 337.658012 -277.875056) (xy 337.604862 -277.87904) (xy 337.551712 -277.875056) (xy 337.49975 -277.863196)
			(xy 337.450136 -277.843724) (xy 337.403978 -277.817075) (xy 337.362307 -277.783844) (xy 337.326055 -277.744773)
			(xy 337.296031 -277.700736) (xy 337.272905 -277.652715) (xy 337.257195 -277.601785) (xy 337.249252 -277.549081)
			(xy 337.020423 -277.549081) (xy 337.020418 -277.549335) (xy 337.012475 -277.602039) (xy 336.996765 -277.652969)
			(xy 336.973639 -277.70099) (xy 336.943615 -277.745027) (xy 336.907363 -277.784098) (xy 336.865692 -277.817329)
			(xy 336.819534 -277.843978) (xy 336.76992 -277.86345) (xy 336.717958 -277.87531) (xy 336.664808 -277.879294)
			(xy 336.611658 -277.87531) (xy 336.559696 -277.86345) (xy 336.510082 -277.843978) (xy 336.463924 -277.817329)
			(xy 336.422253 -277.784098) (xy 336.386001 -277.745027) (xy 336.355977 -277.70099) (xy 336.332851 -277.652969)
			(xy 336.317141 -277.602039) (xy 336.309198 -277.549335) (xy 335.424534 -277.549335) (xy 335.396372 -277.565594)
			(xy 335.346758 -277.585066) (xy 335.294796 -277.596926) (xy 335.241646 -277.60091) (xy 335.188496 -277.596926)
			(xy 335.136534 -277.585066) (xy 335.08692 -277.565594) (xy 335.040762 -277.538945) (xy 334.999091 -277.505714)
			(xy 334.962839 -277.466643) (xy 334.932815 -277.422606) (xy 334.909689 -277.374585) (xy 334.893979 -277.323655)
			(xy 334.886036 -277.270951) (xy 333.466948 -277.270951) (xy 333.466948 -278.336502) (xy 333.971649 -278.336502)
			(xy 333.975679 -278.284004) (xy 333.987676 -278.232736) (xy 334.007359 -278.183901) (xy 334.034265 -278.138642)
			(xy 334.067765 -278.098021) (xy 334.107073 -278.06299) (xy 334.151268 -278.03437) (xy 334.199313 -278.012831)
			(xy 334.250084 -277.998879) (xy 334.302389 -277.992841) (xy 334.355003 -277.994858) (xy 334.406693 -278.004882)
			(xy 334.456246 -278.02268) (xy 334.502502 -278.047833) (xy 334.544376 -278.079752) (xy 334.580888 -278.11769)
			(xy 334.61118 -278.160756) (xy 334.634543 -278.207941) (xy 334.650429 -278.25814) (xy 334.658466 -278.310176)
			(xy 334.65897 -278.336502) (xy 334.658466 -278.362828) (xy 334.658416 -278.363151) (xy 338.658952 -278.363151)
			(xy 338.658952 -278.309853) (xy 338.666895 -278.257149) (xy 338.682605 -278.206219) (xy 338.705731 -278.158198)
			(xy 338.735755 -278.114161) (xy 338.772007 -278.07509) (xy 338.813678 -278.041859) (xy 338.859836 -278.01521)
			(xy 338.90945 -277.995738) (xy 338.961412 -277.983878) (xy 339.014562 -277.979895) (xy 339.067712 -277.983878)
			(xy 339.119674 -277.995738) (xy 339.169288 -278.01521) (xy 339.215446 -278.041859) (xy 339.257117 -278.07509)
			(xy 339.293369 -278.114161) (xy 339.323393 -278.158198) (xy 339.346519 -278.206219) (xy 339.362229 -278.257149)
			(xy 339.370172 -278.309853) (xy 339.37067 -278.336502) (xy 339.370172 -278.363151) (xy 339.599006 -278.363151)
			(xy 339.599006 -278.309853) (xy 339.606949 -278.257149) (xy 339.622659 -278.206219) (xy 339.645785 -278.158198)
			(xy 339.675809 -278.114161) (xy 339.712061 -278.07509) (xy 339.753732 -278.041859) (xy 339.79989 -278.01521)
			(xy 339.849504 -277.995738) (xy 339.901466 -277.983878) (xy 339.954616 -277.979895) (xy 340.007766 -277.983878)
			(xy 340.059728 -277.995738) (xy 340.109342 -278.01521) (xy 340.1555 -278.041859) (xy 340.197171 -278.07509)
			(xy 340.233423 -278.114161) (xy 340.263447 -278.158198) (xy 340.286573 -278.206219) (xy 340.302283 -278.257149)
			(xy 340.310226 -278.309853) (xy 340.310724 -278.336502) (xy 340.310226 -278.363151) (xy 340.538806 -278.363151)
			(xy 340.538806 -278.309853) (xy 340.546749 -278.257149) (xy 340.562459 -278.206219) (xy 340.585585 -278.158198)
			(xy 340.615609 -278.114161) (xy 340.651861 -278.07509) (xy 340.693532 -278.041859) (xy 340.73969 -278.01521)
			(xy 340.789304 -277.995738) (xy 340.841266 -277.983878) (xy 340.894416 -277.979895) (xy 340.947566 -277.983878)
			(xy 340.999528 -277.995738) (xy 341.049142 -278.01521) (xy 341.0953 -278.041859) (xy 341.136971 -278.07509)
			(xy 341.173223 -278.114161) (xy 341.203247 -278.158198) (xy 341.226373 -278.206219) (xy 341.242083 -278.257149)
			(xy 341.250026 -278.309853) (xy 341.250524 -278.336502) (xy 341.250026 -278.363151) (xy 341.478606 -278.363151)
			(xy 341.478606 -278.309853) (xy 341.486549 -278.257149) (xy 341.502259 -278.206219) (xy 341.525385 -278.158198)
			(xy 341.555409 -278.114161) (xy 341.591661 -278.07509) (xy 341.633332 -278.041859) (xy 341.67949 -278.01521)
			(xy 341.729104 -277.995738) (xy 341.781066 -277.983878) (xy 341.834216 -277.979895) (xy 341.887366 -277.983878)
			(xy 341.939328 -277.995738) (xy 341.988942 -278.01521) (xy 342.0351 -278.041859) (xy 342.076771 -278.07509)
			(xy 342.113023 -278.114161) (xy 342.143047 -278.158198) (xy 342.166173 -278.206219) (xy 342.181883 -278.257149)
			(xy 342.189826 -278.309853) (xy 342.190324 -278.336502) (xy 342.189826 -278.363151) (xy 342.418406 -278.363151)
			(xy 342.418406 -278.309853) (xy 342.426349 -278.257149) (xy 342.442059 -278.206219) (xy 342.465185 -278.158198)
			(xy 342.495209 -278.114161) (xy 342.531461 -278.07509) (xy 342.573132 -278.041859) (xy 342.61929 -278.01521)
			(xy 342.668904 -277.995738) (xy 342.720866 -277.983878) (xy 342.774016 -277.979895) (xy 342.827166 -277.983878)
			(xy 342.879128 -277.995738) (xy 342.928742 -278.01521) (xy 342.9749 -278.041859) (xy 343.016571 -278.07509)
			(xy 343.052823 -278.114161) (xy 343.082847 -278.158198) (xy 343.105973 -278.206219) (xy 343.121683 -278.257149)
			(xy 343.129626 -278.309853) (xy 343.130124 -278.336502) (xy 343.129626 -278.363151) (xy 345.237806 -278.363151)
			(xy 345.237806 -278.309853) (xy 345.245749 -278.257149) (xy 345.261459 -278.206219) (xy 345.284585 -278.158198)
			(xy 345.314609 -278.114161) (xy 345.350861 -278.07509) (xy 345.392532 -278.041859) (xy 345.43869 -278.01521)
			(xy 345.488304 -277.995738) (xy 345.540266 -277.983878) (xy 345.593416 -277.979895) (xy 345.646566 -277.983878)
			(xy 345.698528 -277.995738) (xy 345.748142 -278.01521) (xy 345.7943 -278.041859) (xy 345.835971 -278.07509)
			(xy 345.872223 -278.114161) (xy 345.902247 -278.158198) (xy 345.925373 -278.206219) (xy 345.941083 -278.257149)
			(xy 345.949026 -278.309853) (xy 345.949524 -278.336502) (xy 345.949026 -278.363151) (xy 346.177606 -278.363151)
			(xy 346.177606 -278.309853) (xy 346.185549 -278.257149) (xy 346.201259 -278.206219) (xy 346.224385 -278.158198)
			(xy 346.254409 -278.114161) (xy 346.290661 -278.07509) (xy 346.332332 -278.041859) (xy 346.37849 -278.01521)
			(xy 346.428104 -277.995738) (xy 346.480066 -277.983878) (xy 346.533216 -277.979895) (xy 346.586366 -277.983878)
			(xy 346.638328 -277.995738) (xy 346.687942 -278.01521) (xy 346.7341 -278.041859) (xy 346.775771 -278.07509)
			(xy 346.812023 -278.114161) (xy 346.842047 -278.158198) (xy 346.865173 -278.206219) (xy 346.880883 -278.257149)
			(xy 346.888826 -278.309853) (xy 346.889324 -278.336502) (xy 346.888826 -278.363151) (xy 347.117406 -278.363151)
			(xy 347.117406 -278.309853) (xy 347.125349 -278.257149) (xy 347.141059 -278.206219) (xy 347.164185 -278.158198)
			(xy 347.194209 -278.114161) (xy 347.230461 -278.07509) (xy 347.272132 -278.041859) (xy 347.31829 -278.01521)
			(xy 347.367904 -277.995738) (xy 347.419866 -277.983878) (xy 347.473016 -277.979895) (xy 347.526166 -277.983878)
			(xy 347.578128 -277.995738) (xy 347.627742 -278.01521) (xy 347.6739 -278.041859) (xy 347.715571 -278.07509)
			(xy 347.751823 -278.114161) (xy 347.781847 -278.158198) (xy 347.804973 -278.206219) (xy 347.820683 -278.257149)
			(xy 347.828626 -278.309853) (xy 347.829124 -278.336502) (xy 347.828626 -278.363151) (xy 348.057206 -278.363151)
			(xy 348.057206 -278.309853) (xy 348.065149 -278.257149) (xy 348.080859 -278.206219) (xy 348.103985 -278.158198)
			(xy 348.134009 -278.114161) (xy 348.170261 -278.07509) (xy 348.211932 -278.041859) (xy 348.25809 -278.01521)
			(xy 348.307704 -277.995738) (xy 348.359666 -277.983878) (xy 348.412816 -277.979895) (xy 348.465966 -277.983878)
			(xy 348.517928 -277.995738) (xy 348.567542 -278.01521) (xy 348.6137 -278.041859) (xy 348.655371 -278.07509)
			(xy 348.691623 -278.114161) (xy 348.721647 -278.158198) (xy 348.744773 -278.206219) (xy 348.760483 -278.257149)
			(xy 348.768426 -278.309853) (xy 348.768924 -278.336502) (xy 348.768426 -278.363151) (xy 348.996752 -278.363151)
			(xy 348.996752 -278.309853) (xy 349.004695 -278.257149) (xy 349.020405 -278.206219) (xy 349.043531 -278.158198)
			(xy 349.073555 -278.114161) (xy 349.109807 -278.07509) (xy 349.151478 -278.041859) (xy 349.197636 -278.01521)
			(xy 349.24725 -277.995738) (xy 349.299212 -277.983878) (xy 349.352362 -277.979895) (xy 349.405512 -277.983878)
			(xy 349.457474 -277.995738) (xy 349.507088 -278.01521) (xy 349.553246 -278.041859) (xy 349.594917 -278.07509)
			(xy 349.631169 -278.114161) (xy 349.661193 -278.158198) (xy 349.684319 -278.206219) (xy 349.700029 -278.257149)
			(xy 349.707972 -278.309853) (xy 349.70847 -278.336502) (xy 349.707972 -278.363151) (xy 349.936806 -278.363151)
			(xy 349.936806 -278.309853) (xy 349.944749 -278.257149) (xy 349.960459 -278.206219) (xy 349.983585 -278.158198)
			(xy 350.013609 -278.114161) (xy 350.049861 -278.07509) (xy 350.091532 -278.041859) (xy 350.13769 -278.01521)
			(xy 350.187304 -277.995738) (xy 350.239266 -277.983878) (xy 350.292416 -277.979895) (xy 350.345566 -277.983878)
			(xy 350.397528 -277.995738) (xy 350.447142 -278.01521) (xy 350.4933 -278.041859) (xy 350.534971 -278.07509)
			(xy 350.571223 -278.114161) (xy 350.601247 -278.158198) (xy 350.624373 -278.206219) (xy 350.640083 -278.257149)
			(xy 350.648026 -278.309853) (xy 350.648524 -278.336502) (xy 350.648026 -278.363151) (xy 350.876606 -278.363151)
			(xy 350.876606 -278.309853) (xy 350.884549 -278.257149) (xy 350.900259 -278.206219) (xy 350.923385 -278.158198)
			(xy 350.953409 -278.114161) (xy 350.989661 -278.07509) (xy 351.031332 -278.041859) (xy 351.07749 -278.01521)
			(xy 351.127104 -277.995738) (xy 351.179066 -277.983878) (xy 351.232216 -277.979895) (xy 351.285366 -277.983878)
			(xy 351.337328 -277.995738) (xy 351.386942 -278.01521) (xy 351.4331 -278.041859) (xy 351.474771 -278.07509)
			(xy 351.511023 -278.114161) (xy 351.541047 -278.158198) (xy 351.564173 -278.206219) (xy 351.579883 -278.257149)
			(xy 351.587826 -278.309853) (xy 351.588324 -278.336502) (xy 351.587826 -278.363151) (xy 351.816406 -278.363151)
			(xy 351.816406 -278.309853) (xy 351.824349 -278.257149) (xy 351.840059 -278.206219) (xy 351.863185 -278.158198)
			(xy 351.893209 -278.114161) (xy 351.929461 -278.07509) (xy 351.971132 -278.041859) (xy 352.01729 -278.01521)
			(xy 352.066904 -277.995738) (xy 352.118866 -277.983878) (xy 352.172016 -277.979895) (xy 352.225166 -277.983878)
			(xy 352.277128 -277.995738) (xy 352.326742 -278.01521) (xy 352.3729 -278.041859) (xy 352.414571 -278.07509)
			(xy 352.450823 -278.114161) (xy 352.480847 -278.158198) (xy 352.503973 -278.206219) (xy 352.519683 -278.257149)
			(xy 352.527626 -278.309853) (xy 352.528124 -278.336502) (xy 352.527626 -278.363151) (xy 352.755952 -278.363151)
			(xy 352.755952 -278.309853) (xy 352.763895 -278.257149) (xy 352.779605 -278.206219) (xy 352.802731 -278.158198)
			(xy 352.832755 -278.114161) (xy 352.869007 -278.07509) (xy 352.910678 -278.041859) (xy 352.956836 -278.01521)
			(xy 353.00645 -277.995738) (xy 353.058412 -277.983878) (xy 353.111562 -277.979895) (xy 353.164712 -277.983878)
			(xy 353.216674 -277.995738) (xy 353.266288 -278.01521) (xy 353.312446 -278.041859) (xy 353.354117 -278.07509)
			(xy 353.390369 -278.114161) (xy 353.420393 -278.158198) (xy 353.443519 -278.206219) (xy 353.459229 -278.257149)
			(xy 353.467172 -278.309853) (xy 353.46767 -278.336502) (xy 353.467172 -278.363151) (xy 354.635806 -278.363151)
			(xy 354.635806 -278.309853) (xy 354.643749 -278.257149) (xy 354.659459 -278.206219) (xy 354.682585 -278.158198)
			(xy 354.712609 -278.114161) (xy 354.748861 -278.07509) (xy 354.790532 -278.041859) (xy 354.83669 -278.01521)
			(xy 354.886304 -277.995738) (xy 354.938266 -277.983878) (xy 354.991416 -277.979895) (xy 355.044566 -277.983878)
			(xy 355.096528 -277.995738) (xy 355.146142 -278.01521) (xy 355.1923 -278.041859) (xy 355.233971 -278.07509)
			(xy 355.270223 -278.114161) (xy 355.300247 -278.158198) (xy 355.323373 -278.206219) (xy 355.339083 -278.257149)
			(xy 355.347026 -278.309853) (xy 355.347524 -278.336502) (xy 355.347026 -278.363151) (xy 355.339083 -278.415855)
			(xy 355.323373 -278.466785) (xy 355.300247 -278.514806) (xy 355.270223 -278.558843) (xy 355.233971 -278.597914)
			(xy 355.1923 -278.631145) (xy 355.146142 -278.657794) (xy 355.096528 -278.677266) (xy 355.044566 -278.689126)
			(xy 354.991416 -278.69311) (xy 354.938266 -278.689126) (xy 354.886304 -278.677266) (xy 354.83669 -278.657794)
			(xy 354.790532 -278.631145) (xy 354.748861 -278.597914) (xy 354.712609 -278.558843) (xy 354.682585 -278.514806)
			(xy 354.659459 -278.466785) (xy 354.643749 -278.415855) (xy 354.635806 -278.363151) (xy 353.467172 -278.363151)
			(xy 353.459229 -278.415855) (xy 353.443519 -278.466785) (xy 353.420393 -278.514806) (xy 353.390369 -278.558843)
			(xy 353.354117 -278.597914) (xy 353.312446 -278.631145) (xy 353.266288 -278.657794) (xy 353.216674 -278.677266)
			(xy 353.164712 -278.689126) (xy 353.111562 -278.69311) (xy 353.058412 -278.689126) (xy 353.00645 -278.677266)
			(xy 352.956836 -278.657794) (xy 352.910678 -278.631145) (xy 352.869007 -278.597914) (xy 352.832755 -278.558843)
			(xy 352.802731 -278.514806) (xy 352.779605 -278.466785) (xy 352.763895 -278.415855) (xy 352.755952 -278.363151)
			(xy 352.527626 -278.363151) (xy 352.519683 -278.415855) (xy 352.503973 -278.466785) (xy 352.480847 -278.514806)
			(xy 352.450823 -278.558843) (xy 352.414571 -278.597914) (xy 352.3729 -278.631145) (xy 352.326742 -278.657794)
			(xy 352.277128 -278.677266) (xy 352.225166 -278.689126) (xy 352.172016 -278.69311) (xy 352.118866 -278.689126)
			(xy 352.066904 -278.677266) (xy 352.01729 -278.657794) (xy 351.971132 -278.631145) (xy 351.929461 -278.597914)
			(xy 351.893209 -278.558843) (xy 351.863185 -278.514806) (xy 351.840059 -278.466785) (xy 351.824349 -278.415855)
			(xy 351.816406 -278.363151) (xy 351.587826 -278.363151) (xy 351.579883 -278.415855) (xy 351.564173 -278.466785)
			(xy 351.541047 -278.514806) (xy 351.511023 -278.558843) (xy 351.474771 -278.597914) (xy 351.4331 -278.631145)
			(xy 351.386942 -278.657794) (xy 351.337328 -278.677266) (xy 351.285366 -278.689126) (xy 351.232216 -278.69311)
			(xy 351.179066 -278.689126) (xy 351.127104 -278.677266) (xy 351.07749 -278.657794) (xy 351.031332 -278.631145)
			(xy 350.989661 -278.597914) (xy 350.953409 -278.558843) (xy 350.923385 -278.514806) (xy 350.900259 -278.466785)
			(xy 350.884549 -278.415855) (xy 350.876606 -278.363151) (xy 350.648026 -278.363151) (xy 350.640083 -278.415855)
			(xy 350.624373 -278.466785) (xy 350.601247 -278.514806) (xy 350.571223 -278.558843) (xy 350.534971 -278.597914)
			(xy 350.4933 -278.631145) (xy 350.447142 -278.657794) (xy 350.397528 -278.677266) (xy 350.345566 -278.689126)
			(xy 350.292416 -278.69311) (xy 350.239266 -278.689126) (xy 350.187304 -278.677266) (xy 350.13769 -278.657794)
			(xy 350.091532 -278.631145) (xy 350.049861 -278.597914) (xy 350.013609 -278.558843) (xy 349.983585 -278.514806)
			(xy 349.960459 -278.466785) (xy 349.944749 -278.415855) (xy 349.936806 -278.363151) (xy 349.707972 -278.363151)
			(xy 349.700029 -278.415855) (xy 349.684319 -278.466785) (xy 349.661193 -278.514806) (xy 349.631169 -278.558843)
			(xy 349.594917 -278.597914) (xy 349.553246 -278.631145) (xy 349.507088 -278.657794) (xy 349.457474 -278.677266)
			(xy 349.405512 -278.689126) (xy 349.352362 -278.69311) (xy 349.299212 -278.689126) (xy 349.24725 -278.677266)
			(xy 349.197636 -278.657794) (xy 349.151478 -278.631145) (xy 349.109807 -278.597914) (xy 349.073555 -278.558843)
			(xy 349.043531 -278.514806) (xy 349.020405 -278.466785) (xy 349.004695 -278.415855) (xy 348.996752 -278.363151)
			(xy 348.768426 -278.363151) (xy 348.760483 -278.415855) (xy 348.744773 -278.466785) (xy 348.721647 -278.514806)
			(xy 348.691623 -278.558843) (xy 348.655371 -278.597914) (xy 348.6137 -278.631145) (xy 348.567542 -278.657794)
			(xy 348.517928 -278.677266) (xy 348.465966 -278.689126) (xy 348.412816 -278.69311) (xy 348.359666 -278.689126)
			(xy 348.307704 -278.677266) (xy 348.25809 -278.657794) (xy 348.211932 -278.631145) (xy 348.170261 -278.597914)
			(xy 348.134009 -278.558843) (xy 348.103985 -278.514806) (xy 348.080859 -278.466785) (xy 348.065149 -278.415855)
			(xy 348.057206 -278.363151) (xy 347.828626 -278.363151) (xy 347.820683 -278.415855) (xy 347.804973 -278.466785)
			(xy 347.781847 -278.514806) (xy 347.751823 -278.558843) (xy 347.715571 -278.597914) (xy 347.6739 -278.631145)
			(xy 347.627742 -278.657794) (xy 347.578128 -278.677266) (xy 347.526166 -278.689126) (xy 347.473016 -278.69311)
			(xy 347.419866 -278.689126) (xy 347.367904 -278.677266) (xy 347.31829 -278.657794) (xy 347.272132 -278.631145)
			(xy 347.230461 -278.597914) (xy 347.194209 -278.558843) (xy 347.164185 -278.514806) (xy 347.141059 -278.466785)
			(xy 347.125349 -278.415855) (xy 347.117406 -278.363151) (xy 346.888826 -278.363151) (xy 346.880883 -278.415855)
			(xy 346.865173 -278.466785) (xy 346.842047 -278.514806) (xy 346.812023 -278.558843) (xy 346.775771 -278.597914)
			(xy 346.7341 -278.631145) (xy 346.687942 -278.657794) (xy 346.638328 -278.677266) (xy 346.586366 -278.689126)
			(xy 346.533216 -278.69311) (xy 346.480066 -278.689126) (xy 346.428104 -278.677266) (xy 346.37849 -278.657794)
			(xy 346.332332 -278.631145) (xy 346.290661 -278.597914) (xy 346.254409 -278.558843) (xy 346.224385 -278.514806)
			(xy 346.201259 -278.466785) (xy 346.185549 -278.415855) (xy 346.177606 -278.363151) (xy 345.949026 -278.363151)
			(xy 345.941083 -278.415855) (xy 345.925373 -278.466785) (xy 345.902247 -278.514806) (xy 345.872223 -278.558843)
			(xy 345.835971 -278.597914) (xy 345.7943 -278.631145) (xy 345.748142 -278.657794) (xy 345.698528 -278.677266)
			(xy 345.646566 -278.689126) (xy 345.593416 -278.69311) (xy 345.540266 -278.689126) (xy 345.488304 -278.677266)
			(xy 345.43869 -278.657794) (xy 345.392532 -278.631145) (xy 345.350861 -278.597914) (xy 345.314609 -278.558843)
			(xy 345.284585 -278.514806) (xy 345.261459 -278.466785) (xy 345.245749 -278.415855) (xy 345.237806 -278.363151)
			(xy 343.129626 -278.363151) (xy 343.121683 -278.415855) (xy 343.105973 -278.466785) (xy 343.082847 -278.514806)
			(xy 343.052823 -278.558843) (xy 343.016571 -278.597914) (xy 342.9749 -278.631145) (xy 342.928742 -278.657794)
			(xy 342.879128 -278.677266) (xy 342.827166 -278.689126) (xy 342.774016 -278.69311) (xy 342.720866 -278.689126)
			(xy 342.668904 -278.677266) (xy 342.61929 -278.657794) (xy 342.573132 -278.631145) (xy 342.531461 -278.597914)
			(xy 342.495209 -278.558843) (xy 342.465185 -278.514806) (xy 342.442059 -278.466785) (xy 342.426349 -278.415855)
			(xy 342.418406 -278.363151) (xy 342.189826 -278.363151) (xy 342.181883 -278.415855) (xy 342.166173 -278.466785)
			(xy 342.143047 -278.514806) (xy 342.113023 -278.558843) (xy 342.076771 -278.597914) (xy 342.0351 -278.631145)
			(xy 341.988942 -278.657794) (xy 341.939328 -278.677266) (xy 341.887366 -278.689126) (xy 341.834216 -278.69311)
			(xy 341.781066 -278.689126) (xy 341.729104 -278.677266) (xy 341.67949 -278.657794) (xy 341.633332 -278.631145)
			(xy 341.591661 -278.597914) (xy 341.555409 -278.558843) (xy 341.525385 -278.514806) (xy 341.502259 -278.466785)
			(xy 341.486549 -278.415855) (xy 341.478606 -278.363151) (xy 341.250026 -278.363151) (xy 341.242083 -278.415855)
			(xy 341.226373 -278.466785) (xy 341.203247 -278.514806) (xy 341.173223 -278.558843) (xy 341.136971 -278.597914)
			(xy 341.0953 -278.631145) (xy 341.049142 -278.657794) (xy 340.999528 -278.677266) (xy 340.947566 -278.689126)
			(xy 340.894416 -278.69311) (xy 340.841266 -278.689126) (xy 340.789304 -278.677266) (xy 340.73969 -278.657794)
			(xy 340.693532 -278.631145) (xy 340.651861 -278.597914) (xy 340.615609 -278.558843) (xy 340.585585 -278.514806)
			(xy 340.562459 -278.466785) (xy 340.546749 -278.415855) (xy 340.538806 -278.363151) (xy 340.310226 -278.363151)
			(xy 340.302283 -278.415855) (xy 340.286573 -278.466785) (xy 340.263447 -278.514806) (xy 340.233423 -278.558843)
			(xy 340.197171 -278.597914) (xy 340.1555 -278.631145) (xy 340.109342 -278.657794) (xy 340.059728 -278.677266)
			(xy 340.007766 -278.689126) (xy 339.954616 -278.69311) (xy 339.901466 -278.689126) (xy 339.849504 -278.677266)
			(xy 339.79989 -278.657794) (xy 339.753732 -278.631145) (xy 339.712061 -278.597914) (xy 339.675809 -278.558843)
			(xy 339.645785 -278.514806) (xy 339.622659 -278.466785) (xy 339.606949 -278.415855) (xy 339.599006 -278.363151)
			(xy 339.370172 -278.363151) (xy 339.362229 -278.415855) (xy 339.346519 -278.466785) (xy 339.323393 -278.514806)
			(xy 339.293369 -278.558843) (xy 339.257117 -278.597914) (xy 339.215446 -278.631145) (xy 339.169288 -278.657794)
			(xy 339.119674 -278.677266) (xy 339.067712 -278.689126) (xy 339.014562 -278.69311) (xy 338.961412 -278.689126)
			(xy 338.90945 -278.677266) (xy 338.859836 -278.657794) (xy 338.813678 -278.631145) (xy 338.772007 -278.597914)
			(xy 338.735755 -278.558843) (xy 338.705731 -278.514806) (xy 338.682605 -278.466785) (xy 338.666895 -278.415855)
			(xy 338.658952 -278.363151) (xy 334.658416 -278.363151) (xy 334.650429 -278.414864) (xy 334.634543 -278.465063)
			(xy 334.61118 -278.512248) (xy 334.580888 -278.555314) (xy 334.544376 -278.593252) (xy 334.502502 -278.625171)
			(xy 334.456246 -278.650324) (xy 334.406693 -278.668122) (xy 334.355003 -278.678146) (xy 334.302389 -278.680163)
			(xy 334.250084 -278.674125) (xy 334.199313 -278.660173) (xy 334.151268 -278.638634) (xy 334.107073 -278.610014)
			(xy 334.067765 -278.574983) (xy 334.034265 -278.534362) (xy 334.007359 -278.489103) (xy 333.987676 -278.440268)
			(xy 333.975679 -278.389) (xy 333.971649 -278.336502) (xy 333.466948 -278.336502) (xy 333.466948 -278.64308)
			(xy 333.46771 -278.647398) (xy 333.470438 -278.663259) (xy 333.473364 -278.695313) (xy 333.473552 -278.711406)
			(xy 333.47336 -278.727499) (xy 333.470432 -278.759552) (xy 333.46771 -278.775414) (xy 333.466948 -278.779732)
			(xy 333.466948 -279.176967) (xy 336.309452 -279.176967) (xy 336.309452 -279.123669) (xy 336.317395 -279.070965)
			(xy 336.333105 -279.020035) (xy 336.356231 -278.972014) (xy 336.386255 -278.927977) (xy 336.422507 -278.888906)
			(xy 336.464178 -278.855675) (xy 336.510336 -278.829026) (xy 336.55995 -278.809554) (xy 336.611912 -278.797694)
			(xy 336.665062 -278.793711) (xy 336.718212 -278.797694) (xy 336.770174 -278.809554) (xy 336.819788 -278.829026)
			(xy 336.865946 -278.855675) (xy 336.907617 -278.888906) (xy 336.943869 -278.927977) (xy 336.973893 -278.972014)
			(xy 336.997019 -279.020035) (xy 337.012729 -279.070965) (xy 337.020672 -279.123669) (xy 337.02117 -279.150318)
			(xy 337.020672 -279.176967) (xy 337.249252 -279.176967) (xy 337.249252 -279.123669) (xy 337.257195 -279.070965)
			(xy 337.272905 -279.020035) (xy 337.296031 -278.972014) (xy 337.326055 -278.927977) (xy 337.362307 -278.888906)
			(xy 337.403978 -278.855675) (xy 337.450136 -278.829026) (xy 337.49975 -278.809554) (xy 337.551712 -278.797694)
			(xy 337.604862 -278.793711) (xy 337.658012 -278.797694) (xy 337.709974 -278.809554) (xy 337.759588 -278.829026)
			(xy 337.805746 -278.855675) (xy 337.847417 -278.888906) (xy 337.883669 -278.927977) (xy 337.913693 -278.972014)
			(xy 337.936819 -279.020035) (xy 337.952529 -279.070965) (xy 337.960472 -279.123669) (xy 337.96097 -279.150318)
			(xy 337.960472 -279.176967) (xy 338.189052 -279.176967) (xy 338.189052 -279.123669) (xy 338.196995 -279.070965)
			(xy 338.212705 -279.020035) (xy 338.235831 -278.972014) (xy 338.265855 -278.927977) (xy 338.302107 -278.888906)
			(xy 338.343778 -278.855675) (xy 338.389936 -278.829026) (xy 338.43955 -278.809554) (xy 338.491512 -278.797694)
			(xy 338.544662 -278.793711) (xy 338.597812 -278.797694) (xy 338.649774 -278.809554) (xy 338.699388 -278.829026)
			(xy 338.745546 -278.855675) (xy 338.787217 -278.888906) (xy 338.823469 -278.927977) (xy 338.853493 -278.972014)
			(xy 338.876619 -279.020035) (xy 338.892329 -279.070965) (xy 338.900272 -279.123669) (xy 338.90077 -279.150318)
			(xy 338.900272 -279.176967) (xy 339.128852 -279.176967) (xy 339.128852 -279.123669) (xy 339.136795 -279.070965)
			(xy 339.152505 -279.020035) (xy 339.175631 -278.972014) (xy 339.205655 -278.927977) (xy 339.241907 -278.888906)
			(xy 339.283578 -278.855675) (xy 339.329736 -278.829026) (xy 339.37935 -278.809554) (xy 339.431312 -278.797694)
			(xy 339.484462 -278.793711) (xy 339.537612 -278.797694) (xy 339.589574 -278.809554) (xy 339.639188 -278.829026)
			(xy 339.685346 -278.855675) (xy 339.727017 -278.888906) (xy 339.763269 -278.927977) (xy 339.793293 -278.972014)
			(xy 339.816419 -279.020035) (xy 339.832129 -279.070965) (xy 339.840072 -279.123669) (xy 339.84057 -279.150318)
			(xy 339.840072 -279.176967) (xy 340.068652 -279.176967) (xy 340.068652 -279.123669) (xy 340.076595 -279.070965)
			(xy 340.092305 -279.020035) (xy 340.115431 -278.972014) (xy 340.145455 -278.927977) (xy 340.181707 -278.888906)
			(xy 340.223378 -278.855675) (xy 340.269536 -278.829026) (xy 340.31915 -278.809554) (xy 340.371112 -278.797694)
			(xy 340.424262 -278.793711) (xy 340.477412 -278.797694) (xy 340.529374 -278.809554) (xy 340.578988 -278.829026)
			(xy 340.625146 -278.855675) (xy 340.666817 -278.888906) (xy 340.703069 -278.927977) (xy 340.733093 -278.972014)
			(xy 340.756219 -279.020035) (xy 340.771929 -279.070965) (xy 340.779872 -279.123669) (xy 340.78037 -279.150318)
			(xy 340.779872 -279.176967) (xy 341.008452 -279.176967) (xy 341.008452 -279.123669) (xy 341.016395 -279.070965)
			(xy 341.032105 -279.020035) (xy 341.055231 -278.972014) (xy 341.085255 -278.927977) (xy 341.121507 -278.888906)
			(xy 341.163178 -278.855675) (xy 341.209336 -278.829026) (xy 341.25895 -278.809554) (xy 341.310912 -278.797694)
			(xy 341.364062 -278.793711) (xy 341.417212 -278.797694) (xy 341.469174 -278.809554) (xy 341.518788 -278.829026)
			(xy 341.564946 -278.855675) (xy 341.606617 -278.888906) (xy 341.642869 -278.927977) (xy 341.672893 -278.972014)
			(xy 341.696019 -279.020035) (xy 341.711729 -279.070965) (xy 341.719672 -279.123669) (xy 341.72017 -279.150318)
			(xy 341.719672 -279.176967) (xy 341.948506 -279.176967) (xy 341.948506 -279.123669) (xy 341.956449 -279.070965)
			(xy 341.972159 -279.020035) (xy 341.995285 -278.972014) (xy 342.025309 -278.927977) (xy 342.061561 -278.888906)
			(xy 342.103232 -278.855675) (xy 342.14939 -278.829026) (xy 342.199004 -278.809554) (xy 342.250966 -278.797694)
			(xy 342.304116 -278.793711) (xy 342.357266 -278.797694) (xy 342.409228 -278.809554) (xy 342.458842 -278.829026)
			(xy 342.505 -278.855675) (xy 342.546671 -278.888906) (xy 342.582923 -278.927977) (xy 342.612947 -278.972014)
			(xy 342.636073 -279.020035) (xy 342.651783 -279.070965) (xy 342.659726 -279.123669) (xy 342.660224 -279.150318)
			(xy 342.659726 -279.176967) (xy 342.888306 -279.176967) (xy 342.888306 -279.123669) (xy 342.896249 -279.070965)
			(xy 342.911959 -279.020035) (xy 342.935085 -278.972014) (xy 342.965109 -278.927977) (xy 343.001361 -278.888906)
			(xy 343.043032 -278.855675) (xy 343.08919 -278.829026) (xy 343.138804 -278.809554) (xy 343.190766 -278.797694)
			(xy 343.243916 -278.793711) (xy 343.297066 -278.797694) (xy 343.349028 -278.809554) (xy 343.398642 -278.829026)
			(xy 343.4448 -278.855675) (xy 343.486471 -278.888906) (xy 343.522723 -278.927977) (xy 343.552747 -278.972014)
			(xy 343.575873 -279.020035) (xy 343.591583 -279.070965) (xy 343.599526 -279.123669) (xy 343.600024 -279.150318)
			(xy 343.599526 -279.176967) (xy 343.827852 -279.176967) (xy 343.827852 -279.123669) (xy 343.835795 -279.070965)
			(xy 343.851505 -279.020035) (xy 343.874631 -278.972014) (xy 343.904655 -278.927977) (xy 343.940907 -278.888906)
			(xy 343.982578 -278.855675) (xy 344.028736 -278.829026) (xy 344.07835 -278.809554) (xy 344.130312 -278.797694)
			(xy 344.183462 -278.793711) (xy 344.236612 -278.797694) (xy 344.288574 -278.809554) (xy 344.338188 -278.829026)
			(xy 344.384346 -278.855675) (xy 344.426017 -278.888906) (xy 344.462269 -278.927977) (xy 344.492293 -278.972014)
			(xy 344.515419 -279.020035) (xy 344.531129 -279.070965) (xy 344.539072 -279.123669) (xy 344.53957 -279.150318)
			(xy 344.539072 -279.176967) (xy 345.707706 -279.176967) (xy 345.707706 -279.123669) (xy 345.715649 -279.070965)
			(xy 345.731359 -279.020035) (xy 345.754485 -278.972014) (xy 345.784509 -278.927977) (xy 345.820761 -278.888906)
			(xy 345.862432 -278.855675) (xy 345.90859 -278.829026) (xy 345.958204 -278.809554) (xy 346.010166 -278.797694)
			(xy 346.063316 -278.793711) (xy 346.116466 -278.797694) (xy 346.168428 -278.809554) (xy 346.218042 -278.829026)
			(xy 346.2642 -278.855675) (xy 346.305871 -278.888906) (xy 346.342123 -278.927977) (xy 346.372147 -278.972014)
			(xy 346.395273 -279.020035) (xy 346.410983 -279.070965) (xy 346.418926 -279.123669) (xy 346.419424 -279.150318)
			(xy 346.418926 -279.176967) (xy 346.647252 -279.176967) (xy 346.647252 -279.123669) (xy 346.655195 -279.070965)
			(xy 346.670905 -279.020035) (xy 346.694031 -278.972014) (xy 346.724055 -278.927977) (xy 346.760307 -278.888906)
			(xy 346.801978 -278.855675) (xy 346.848136 -278.829026) (xy 346.89775 -278.809554) (xy 346.949712 -278.797694)
			(xy 347.002862 -278.793711) (xy 347.056012 -278.797694) (xy 347.107974 -278.809554) (xy 347.157588 -278.829026)
			(xy 347.203746 -278.855675) (xy 347.245417 -278.888906) (xy 347.281669 -278.927977) (xy 347.311693 -278.972014)
			(xy 347.334819 -279.020035) (xy 347.350529 -279.070965) (xy 347.358472 -279.123669) (xy 347.35897 -279.150318)
			(xy 347.358472 -279.176967) (xy 347.587052 -279.176967) (xy 347.587052 -279.123669) (xy 347.594995 -279.070965)
			(xy 347.610705 -279.020035) (xy 347.633831 -278.972014) (xy 347.663855 -278.927977) (xy 347.700107 -278.888906)
			(xy 347.741778 -278.855675) (xy 347.787936 -278.829026) (xy 347.83755 -278.809554) (xy 347.889512 -278.797694)
			(xy 347.942662 -278.793711) (xy 347.995812 -278.797694) (xy 348.047774 -278.809554) (xy 348.097388 -278.829026)
			(xy 348.143546 -278.855675) (xy 348.185217 -278.888906) (xy 348.221469 -278.927977) (xy 348.251493 -278.972014)
			(xy 348.274619 -279.020035) (xy 348.290329 -279.070965) (xy 348.298272 -279.123669) (xy 348.29877 -279.150318)
			(xy 348.298272 -279.176967) (xy 348.527106 -279.176967) (xy 348.527106 -279.123669) (xy 348.535049 -279.070965)
			(xy 348.550759 -279.020035) (xy 348.573885 -278.972014) (xy 348.603909 -278.927977) (xy 348.640161 -278.888906)
			(xy 348.681832 -278.855675) (xy 348.72799 -278.829026) (xy 348.777604 -278.809554) (xy 348.829566 -278.797694)
			(xy 348.882716 -278.793711) (xy 348.935866 -278.797694) (xy 348.987828 -278.809554) (xy 349.037442 -278.829026)
			(xy 349.0836 -278.855675) (xy 349.125271 -278.888906) (xy 349.161523 -278.927977) (xy 349.191547 -278.972014)
			(xy 349.214673 -279.020035) (xy 349.230383 -279.070965) (xy 349.238326 -279.123669) (xy 349.238824 -279.150318)
			(xy 349.466154 -279.150318) (xy 349.466652 -279.123669) (xy 349.474595 -279.070965) (xy 349.490305 -279.020035)
			(xy 349.513431 -278.972014) (xy 349.543455 -278.927977) (xy 349.579707 -278.888906) (xy 349.621378 -278.855675)
			(xy 349.667536 -278.829026) (xy 349.71715 -278.809554) (xy 349.769112 -278.797694) (xy 349.822262 -278.793711)
			(xy 349.875412 -278.797694) (xy 349.927374 -278.809554) (xy 349.976988 -278.829026) (xy 350.023146 -278.855675)
			(xy 350.064817 -278.888906) (xy 350.101069 -278.927977) (xy 350.131093 -278.972014) (xy 350.154219 -279.020035)
			(xy 350.169929 -279.070965) (xy 350.177872 -279.123669) (xy 350.17837 -279.1503) (xy 350.405511 -279.1503)
			(xy 350.409493 -279.097157) (xy 350.421351 -279.0452) (xy 350.44082 -278.995592) (xy 350.467464 -278.949438)
			(xy 350.500689 -278.907771) (xy 350.539753 -278.871521) (xy 350.583784 -278.841498) (xy 350.631796 -278.818371)
			(xy 350.68272 -278.802659) (xy 350.735416 -278.794711) (xy 350.762062 -278.79421) (xy 350.787087 -278.794654)
			(xy 350.836643 -278.801657) (xy 350.884731 -278.815531) (xy 350.930402 -278.836003) (xy 350.972756 -278.862668)
			(xy 351.010959 -278.895001) (xy 351.044258 -278.932366) (xy 351.05848 -278.95296) (xy 351.405444 -278.95296)
			(xy 351.419697 -278.932387) (xy 351.45299 -278.895019) (xy 351.491187 -278.862682) (xy 351.533535 -278.836011)
			(xy 351.579201 -278.815532) (xy 351.627285 -278.80165) (xy 351.676838 -278.794637) (xy 351.701862 -278.79421)
			(xy 351.728516 -278.794645) (xy 351.78123 -278.802585) (xy 351.832172 -278.818293) (xy 351.880203 -278.841419)
			(xy 351.924251 -278.871446) (xy 351.963331 -278.907703) (xy 351.99657 -278.94938) (xy 352.023226 -278.995546)
			(xy 352.042703 -279.045169) (xy 352.054566 -279.09714) (xy 352.05855 -279.1503) (xy 352.056551 -279.176967)
			(xy 352.286052 -279.176967) (xy 352.286052 -279.123669) (xy 352.293995 -279.070965) (xy 352.309705 -279.020035)
			(xy 352.332831 -278.972014) (xy 352.362855 -278.927977) (xy 352.399107 -278.888906) (xy 352.440778 -278.855675)
			(xy 352.486936 -278.829026) (xy 352.53655 -278.809554) (xy 352.588512 -278.797694) (xy 352.641662 -278.793711)
			(xy 352.694812 -278.797694) (xy 352.746774 -278.809554) (xy 352.796388 -278.829026) (xy 352.842546 -278.855675)
			(xy 352.884217 -278.888906) (xy 352.920469 -278.927977) (xy 352.950493 -278.972014) (xy 352.973619 -279.020035)
			(xy 352.989329 -279.070965) (xy 352.997272 -279.123669) (xy 352.99777 -279.150318) (xy 352.997272 -279.176967)
			(xy 353.226106 -279.176967) (xy 353.226106 -279.123669) (xy 353.234049 -279.070965) (xy 353.249759 -279.020035)
			(xy 353.272885 -278.972014) (xy 353.302909 -278.927977) (xy 353.339161 -278.888906) (xy 353.380832 -278.855675)
			(xy 353.42699 -278.829026) (xy 353.476604 -278.809554) (xy 353.528566 -278.797694) (xy 353.581716 -278.793711)
			(xy 353.634866 -278.797694) (xy 353.686828 -278.809554) (xy 353.736442 -278.829026) (xy 353.7826 -278.855675)
			(xy 353.824271 -278.888906) (xy 353.860523 -278.927977) (xy 353.890547 -278.972014) (xy 353.913673 -279.020035)
			(xy 353.929383 -279.070965) (xy 353.937326 -279.123669) (xy 353.937824 -279.150318) (xy 353.937326 -279.176967)
			(xy 354.165906 -279.176967) (xy 354.165906 -279.123669) (xy 354.173849 -279.070965) (xy 354.189559 -279.020035)
			(xy 354.212685 -278.972014) (xy 354.242709 -278.927977) (xy 354.278961 -278.888906) (xy 354.320632 -278.855675)
			(xy 354.36679 -278.829026) (xy 354.416404 -278.809554) (xy 354.468366 -278.797694) (xy 354.521516 -278.793711)
			(xy 354.574666 -278.797694) (xy 354.626628 -278.809554) (xy 354.676242 -278.829026) (xy 354.7224 -278.855675)
			(xy 354.764071 -278.888906) (xy 354.800323 -278.927977) (xy 354.830347 -278.972014) (xy 354.853473 -279.020035)
			(xy 354.869183 -279.070965) (xy 354.877126 -279.123669) (xy 354.877624 -279.150318) (xy 354.877126 -279.176967)
			(xy 354.869183 -279.229671) (xy 354.853473 -279.280601) (xy 354.830347 -279.328622) (xy 354.800323 -279.372659)
			(xy 354.764071 -279.41173) (xy 354.7224 -279.444961) (xy 354.676242 -279.47161) (xy 354.626628 -279.491082)
			(xy 354.574666 -279.502942) (xy 354.521516 -279.506926) (xy 354.468366 -279.502942) (xy 354.416404 -279.491082)
			(xy 354.36679 -279.47161) (xy 354.320632 -279.444961) (xy 354.278961 -279.41173) (xy 354.242709 -279.372659)
			(xy 354.212685 -279.328622) (xy 354.189559 -279.280601) (xy 354.173849 -279.229671) (xy 354.165906 -279.176967)
			(xy 353.937326 -279.176967) (xy 353.929383 -279.229671) (xy 353.913673 -279.280601) (xy 353.890547 -279.328622)
			(xy 353.860523 -279.372659) (xy 353.824271 -279.41173) (xy 353.7826 -279.444961) (xy 353.736442 -279.47161)
			(xy 353.686828 -279.491082) (xy 353.634866 -279.502942) (xy 353.581716 -279.506926) (xy 353.528566 -279.502942)
			(xy 353.476604 -279.491082) (xy 353.42699 -279.47161) (xy 353.380832 -279.444961) (xy 353.339161 -279.41173)
			(xy 353.302909 -279.372659) (xy 353.272885 -279.328622) (xy 353.249759 -279.280601) (xy 353.234049 -279.229671)
			(xy 353.226106 -279.176967) (xy 352.997272 -279.176967) (xy 352.989329 -279.229671) (xy 352.973619 -279.280601)
			(xy 352.950493 -279.328622) (xy 352.920469 -279.372659) (xy 352.884217 -279.41173) (xy 352.842546 -279.444961)
			(xy 352.796388 -279.47161) (xy 352.746774 -279.491082) (xy 352.694812 -279.502942) (xy 352.641662 -279.506926)
			(xy 352.588512 -279.502942) (xy 352.53655 -279.491082) (xy 352.486936 -279.47161) (xy 352.440778 -279.444961)
			(xy 352.399107 -279.41173) (xy 352.362855 -279.372659) (xy 352.332831 -279.328622) (xy 352.309705 -279.280601)
			(xy 352.293995 -279.229671) (xy 352.286052 -279.176967) (xy 352.056551 -279.176967) (xy 352.054566 -279.20346)
			(xy 352.042703 -279.255431) (xy 352.023226 -279.305054) (xy 351.99657 -279.35122) (xy 351.963331 -279.392897)
			(xy 351.924251 -279.429154) (xy 351.880203 -279.459181) (xy 351.832172 -279.482307) (xy 351.78123 -279.498015)
			(xy 351.728516 -279.505955) (xy 351.701862 -279.506426) (xy 351.676836 -279.506024) (xy 351.627278 -279.499011)
			(xy 351.57919 -279.485128) (xy 351.53352 -279.46465) (xy 351.491166 -279.437979) (xy 351.452964 -279.405641)
			(xy 351.419666 -279.368272) (xy 351.405444 -279.347676) (xy 351.05848 -279.347676) (xy 351.044287 -279.368292)
			(xy 351.010983 -279.405657) (xy 350.972775 -279.437991) (xy 350.930416 -279.464656) (xy 350.884741 -279.485127)
			(xy 350.836649 -279.499001) (xy 350.787089 -279.506004) (xy 350.762062 -279.506426) (xy 350.735416 -279.505889)
			(xy 350.68272 -279.497941) (xy 350.631796 -279.482229) (xy 350.583784 -279.459102) (xy 350.539753 -279.429079)
			(xy 350.500689 -279.392829) (xy 350.467464 -279.351162) (xy 350.44082 -279.305008) (xy 350.421351 -279.2554)
			(xy 350.409493 -279.203443) (xy 350.405511 -279.1503) (xy 350.17837 -279.1503) (xy 350.17837 -279.150318)
			(xy 350.178006 -279.17347) (xy 350.172017 -279.219384) (xy 350.160141 -279.264139) (xy 350.1517 -279.2857)
			(xy 350.142048 -279.308814) (xy 350.314768 -279.607772) (xy 350.339406 -279.611074) (xy 350.364743 -279.614933)
			(xy 350.414047 -279.62892) (xy 350.460837 -279.649827) (xy 350.504149 -279.677224) (xy 350.543087 -279.710545)
			(xy 350.576849 -279.749102) (xy 350.604736 -279.792099) (xy 350.626175 -279.838649) (xy 350.640721 -279.887791)
			(xy 350.648074 -279.938509) (xy 350.648524 -279.964134) (xy 350.648026 -279.990783) (xy 350.876352 -279.990783)
			(xy 350.876352 -279.937485) (xy 350.884295 -279.884781) (xy 350.900005 -279.833851) (xy 350.923131 -279.78583)
			(xy 350.953155 -279.741793) (xy 350.989407 -279.702722) (xy 351.031078 -279.669491) (xy 351.077236 -279.642842)
			(xy 351.12685 -279.62337) (xy 351.178812 -279.61151) (xy 351.231962 -279.607527) (xy 351.285112 -279.61151)
			(xy 351.337074 -279.62337) (xy 351.386688 -279.642842) (xy 351.432846 -279.669491) (xy 351.474517 -279.702722)
			(xy 351.510769 -279.741793) (xy 351.540793 -279.78583) (xy 351.563919 -279.833851) (xy 351.579629 -279.884781)
			(xy 351.587572 -279.937485) (xy 351.58807 -279.964134) (xy 351.587572 -279.990783) (xy 351.816406 -279.990783)
			(xy 351.816406 -279.937485) (xy 351.824349 -279.884781) (xy 351.840059 -279.833851) (xy 351.863185 -279.78583)
			(xy 351.893209 -279.741793) (xy 351.929461 -279.702722) (xy 351.971132 -279.669491) (xy 352.01729 -279.642842)
			(xy 352.066904 -279.62337) (xy 352.118866 -279.61151) (xy 352.172016 -279.607527) (xy 352.225166 -279.61151)
			(xy 352.277128 -279.62337) (xy 352.326742 -279.642842) (xy 352.3729 -279.669491) (xy 352.414571 -279.702722)
			(xy 352.450823 -279.741793) (xy 352.480847 -279.78583) (xy 352.503973 -279.833851) (xy 352.519683 -279.884781)
			(xy 352.527626 -279.937485) (xy 352.528124 -279.964134) (xy 352.527626 -279.990783) (xy 352.519683 -280.043487)
			(xy 352.503973 -280.094417) (xy 352.480847 -280.142438) (xy 352.450823 -280.186475) (xy 352.414571 -280.225546)
			(xy 352.3729 -280.258777) (xy 352.326742 -280.285426) (xy 352.277128 -280.304898) (xy 352.225166 -280.316758)
			(xy 352.172016 -280.320742) (xy 352.118866 -280.316758) (xy 352.066904 -280.304898) (xy 352.01729 -280.285426)
			(xy 351.971132 -280.258777) (xy 351.929461 -280.225546) (xy 351.893209 -280.186475) (xy 351.863185 -280.142438)
			(xy 351.840059 -280.094417) (xy 351.824349 -280.043487) (xy 351.816406 -279.990783) (xy 351.587572 -279.990783)
			(xy 351.579629 -280.043487) (xy 351.563919 -280.094417) (xy 351.540793 -280.142438) (xy 351.510769 -280.186475)
			(xy 351.474517 -280.225546) (xy 351.432846 -280.258777) (xy 351.386688 -280.285426) (xy 351.337074 -280.304898)
			(xy 351.285112 -280.316758) (xy 351.231962 -280.320742) (xy 351.178812 -280.316758) (xy 351.12685 -280.304898)
			(xy 351.077236 -280.285426) (xy 351.031078 -280.258777) (xy 350.989407 -280.225546) (xy 350.953155 -280.186475)
			(xy 350.923131 -280.142438) (xy 350.900005 -280.094417) (xy 350.884295 -280.043487) (xy 350.876352 -279.990783)
			(xy 350.648026 -279.990783) (xy 350.640083 -280.043487) (xy 350.624373 -280.094417) (xy 350.601247 -280.142438)
			(xy 350.571223 -280.186475) (xy 350.534971 -280.225546) (xy 350.4933 -280.258777) (xy 350.447142 -280.285426)
			(xy 350.397528 -280.304898) (xy 350.345566 -280.316758) (xy 350.292416 -280.320742) (xy 350.239266 -280.316758)
			(xy 350.187304 -280.304898) (xy 350.13769 -280.285426) (xy 350.091532 -280.258777) (xy 350.049861 -280.225546)
			(xy 350.013609 -280.186475) (xy 349.983585 -280.142438) (xy 349.960459 -280.094417) (xy 349.944749 -280.043487)
			(xy 349.936806 -279.990783) (xy 349.936308 -279.964134) (xy 349.936687 -279.940889) (xy 349.94273 -279.894794)
			(xy 349.954716 -279.849876) (xy 349.963232 -279.828244) (xy 349.972884 -279.80513) (xy 349.800418 -279.50668)
			(xy 349.775526 -279.503378) (xy 349.750171 -279.499552) (xy 349.700831 -279.485598) (xy 349.654003 -279.464713)
			(xy 349.610653 -279.437328) (xy 349.571679 -279.40401) (xy 349.537885 -279.365446) (xy 349.509971 -279.322435)
			(xy 349.488514 -279.275865) (xy 349.473957 -279.2267) (xy 349.466602 -279.175956) (xy 349.466154 -279.150318)
			(xy 349.238824 -279.150318) (xy 349.238326 -279.176967) (xy 349.230383 -279.229671) (xy 349.214673 -279.280601)
			(xy 349.191547 -279.328622) (xy 349.161523 -279.372659) (xy 349.125271 -279.41173) (xy 349.0836 -279.444961)
			(xy 349.037442 -279.47161) (xy 348.987828 -279.491082) (xy 348.935866 -279.502942) (xy 348.882716 -279.506926)
			(xy 348.829566 -279.502942) (xy 348.777604 -279.491082) (xy 348.72799 -279.47161) (xy 348.681832 -279.444961)
			(xy 348.640161 -279.41173) (xy 348.603909 -279.372659) (xy 348.573885 -279.328622) (xy 348.550759 -279.280601)
			(xy 348.535049 -279.229671) (xy 348.527106 -279.176967) (xy 348.298272 -279.176967) (xy 348.290329 -279.229671)
			(xy 348.274619 -279.280601) (xy 348.251493 -279.328622) (xy 348.221469 -279.372659) (xy 348.185217 -279.41173)
			(xy 348.143546 -279.444961) (xy 348.097388 -279.47161) (xy 348.047774 -279.491082) (xy 347.995812 -279.502942)
			(xy 347.942662 -279.506926) (xy 347.889512 -279.502942) (xy 347.83755 -279.491082) (xy 347.787936 -279.47161)
			(xy 347.741778 -279.444961) (xy 347.700107 -279.41173) (xy 347.663855 -279.372659) (xy 347.633831 -279.328622)
			(xy 347.610705 -279.280601) (xy 347.594995 -279.229671) (xy 347.587052 -279.176967) (xy 347.358472 -279.176967)
			(xy 347.350529 -279.229671) (xy 347.334819 -279.280601) (xy 347.311693 -279.328622) (xy 347.281669 -279.372659)
			(xy 347.245417 -279.41173) (xy 347.203746 -279.444961) (xy 347.157588 -279.47161) (xy 347.107974 -279.491082)
			(xy 347.056012 -279.502942) (xy 347.002862 -279.506926) (xy 346.949712 -279.502942) (xy 346.89775 -279.491082)
			(xy 346.848136 -279.47161) (xy 346.801978 -279.444961) (xy 346.760307 -279.41173) (xy 346.724055 -279.372659)
			(xy 346.694031 -279.328622) (xy 346.670905 -279.280601) (xy 346.655195 -279.229671) (xy 346.647252 -279.176967)
			(xy 346.418926 -279.176967) (xy 346.410983 -279.229671) (xy 346.395273 -279.280601) (xy 346.372147 -279.328622)
			(xy 346.342123 -279.372659) (xy 346.305871 -279.41173) (xy 346.2642 -279.444961) (xy 346.218042 -279.47161)
			(xy 346.168428 -279.491082) (xy 346.116466 -279.502942) (xy 346.063316 -279.506926) (xy 346.010166 -279.502942)
			(xy 345.958204 -279.491082) (xy 345.90859 -279.47161) (xy 345.862432 -279.444961) (xy 345.820761 -279.41173)
			(xy 345.784509 -279.372659) (xy 345.754485 -279.328622) (xy 345.731359 -279.280601) (xy 345.715649 -279.229671)
			(xy 345.707706 -279.176967) (xy 344.539072 -279.176967) (xy 344.531129 -279.229671) (xy 344.515419 -279.280601)
			(xy 344.492293 -279.328622) (xy 344.462269 -279.372659) (xy 344.426017 -279.41173) (xy 344.384346 -279.444961)
			(xy 344.338188 -279.47161) (xy 344.288574 -279.491082) (xy 344.236612 -279.502942) (xy 344.183462 -279.506926)
			(xy 344.130312 -279.502942) (xy 344.07835 -279.491082) (xy 344.028736 -279.47161) (xy 343.982578 -279.444961)
			(xy 343.940907 -279.41173) (xy 343.904655 -279.372659) (xy 343.874631 -279.328622) (xy 343.851505 -279.280601)
			(xy 343.835795 -279.229671) (xy 343.827852 -279.176967) (xy 343.599526 -279.176967) (xy 343.591583 -279.229671)
			(xy 343.575873 -279.280601) (xy 343.552747 -279.328622) (xy 343.522723 -279.372659) (xy 343.486471 -279.41173)
			(xy 343.4448 -279.444961) (xy 343.398642 -279.47161) (xy 343.349028 -279.491082) (xy 343.297066 -279.502942)
			(xy 343.243916 -279.506926) (xy 343.190766 -279.502942) (xy 343.138804 -279.491082) (xy 343.08919 -279.47161)
			(xy 343.043032 -279.444961) (xy 343.001361 -279.41173) (xy 342.965109 -279.372659) (xy 342.935085 -279.328622)
			(xy 342.911959 -279.280601) (xy 342.896249 -279.229671) (xy 342.888306 -279.176967) (xy 342.659726 -279.176967)
			(xy 342.651783 -279.229671) (xy 342.636073 -279.280601) (xy 342.612947 -279.328622) (xy 342.582923 -279.372659)
			(xy 342.546671 -279.41173) (xy 342.505 -279.444961) (xy 342.458842 -279.47161) (xy 342.409228 -279.491082)
			(xy 342.357266 -279.502942) (xy 342.304116 -279.506926) (xy 342.250966 -279.502942) (xy 342.199004 -279.491082)
			(xy 342.14939 -279.47161) (xy 342.103232 -279.444961) (xy 342.061561 -279.41173) (xy 342.025309 -279.372659)
			(xy 341.995285 -279.328622) (xy 341.972159 -279.280601) (xy 341.956449 -279.229671) (xy 341.948506 -279.176967)
			(xy 341.719672 -279.176967) (xy 341.711729 -279.229671) (xy 341.696019 -279.280601) (xy 341.672893 -279.328622)
			(xy 341.642869 -279.372659) (xy 341.606617 -279.41173) (xy 341.564946 -279.444961) (xy 341.518788 -279.47161)
			(xy 341.469174 -279.491082) (xy 341.417212 -279.502942) (xy 341.364062 -279.506926) (xy 341.310912 -279.502942)
			(xy 341.25895 -279.491082) (xy 341.209336 -279.47161) (xy 341.163178 -279.444961) (xy 341.121507 -279.41173)
			(xy 341.085255 -279.372659) (xy 341.055231 -279.328622) (xy 341.032105 -279.280601) (xy 341.016395 -279.229671)
			(xy 341.008452 -279.176967) (xy 340.779872 -279.176967) (xy 340.771929 -279.229671) (xy 340.756219 -279.280601)
			(xy 340.733093 -279.328622) (xy 340.703069 -279.372659) (xy 340.666817 -279.41173) (xy 340.625146 -279.444961)
			(xy 340.578988 -279.47161) (xy 340.529374 -279.491082) (xy 340.477412 -279.502942) (xy 340.424262 -279.506926)
			(xy 340.371112 -279.502942) (xy 340.31915 -279.491082) (xy 340.269536 -279.47161) (xy 340.223378 -279.444961)
			(xy 340.181707 -279.41173) (xy 340.145455 -279.372659) (xy 340.115431 -279.328622) (xy 340.092305 -279.280601)
			(xy 340.076595 -279.229671) (xy 340.068652 -279.176967) (xy 339.840072 -279.176967) (xy 339.832129 -279.229671)
			(xy 339.816419 -279.280601) (xy 339.793293 -279.328622) (xy 339.763269 -279.372659) (xy 339.727017 -279.41173)
			(xy 339.685346 -279.444961) (xy 339.639188 -279.47161) (xy 339.589574 -279.491082) (xy 339.537612 -279.502942)
			(xy 339.484462 -279.506926) (xy 339.431312 -279.502942) (xy 339.37935 -279.491082) (xy 339.329736 -279.47161)
			(xy 339.283578 -279.444961) (xy 339.241907 -279.41173) (xy 339.205655 -279.372659) (xy 339.175631 -279.328622)
			(xy 339.152505 -279.280601) (xy 339.136795 -279.229671) (xy 339.128852 -279.176967) (xy 338.900272 -279.176967)
			(xy 338.892329 -279.229671) (xy 338.876619 -279.280601) (xy 338.853493 -279.328622) (xy 338.823469 -279.372659)
			(xy 338.787217 -279.41173) (xy 338.745546 -279.444961) (xy 338.699388 -279.47161) (xy 338.649774 -279.491082)
			(xy 338.597812 -279.502942) (xy 338.544662 -279.506926) (xy 338.491512 -279.502942) (xy 338.43955 -279.491082)
			(xy 338.389936 -279.47161) (xy 338.343778 -279.444961) (xy 338.302107 -279.41173) (xy 338.265855 -279.372659)
			(xy 338.235831 -279.328622) (xy 338.212705 -279.280601) (xy 338.196995 -279.229671) (xy 338.189052 -279.176967)
			(xy 337.960472 -279.176967) (xy 337.952529 -279.229671) (xy 337.936819 -279.280601) (xy 337.913693 -279.328622)
			(xy 337.883669 -279.372659) (xy 337.847417 -279.41173) (xy 337.805746 -279.444961) (xy 337.759588 -279.47161)
			(xy 337.709974 -279.491082) (xy 337.658012 -279.502942) (xy 337.604862 -279.506926) (xy 337.551712 -279.502942)
			(xy 337.49975 -279.491082) (xy 337.450136 -279.47161) (xy 337.403978 -279.444961) (xy 337.362307 -279.41173)
			(xy 337.326055 -279.372659) (xy 337.296031 -279.328622) (xy 337.272905 -279.280601) (xy 337.257195 -279.229671)
			(xy 337.249252 -279.176967) (xy 337.020672 -279.176967) (xy 337.012729 -279.229671) (xy 336.997019 -279.280601)
			(xy 336.973893 -279.328622) (xy 336.943869 -279.372659) (xy 336.907617 -279.41173) (xy 336.865946 -279.444961)
			(xy 336.819788 -279.47161) (xy 336.770174 -279.491082) (xy 336.718212 -279.502942) (xy 336.665062 -279.506926)
			(xy 336.611912 -279.502942) (xy 336.55995 -279.491082) (xy 336.510336 -279.47161) (xy 336.464178 -279.444961)
			(xy 336.422507 -279.41173) (xy 336.386255 -279.372659) (xy 336.356231 -279.328622) (xy 336.333105 -279.280601)
			(xy 336.317395 -279.229671) (xy 336.309452 -279.176967) (xy 333.466948 -279.176967) (xy 333.466948 -279.990783)
			(xy 333.959952 -279.990783) (xy 333.959952 -279.937485) (xy 333.967895 -279.884781) (xy 333.983605 -279.833851)
			(xy 334.006731 -279.78583) (xy 334.036755 -279.741793) (xy 334.073007 -279.702722) (xy 334.114678 -279.669491)
			(xy 334.160836 -279.642842) (xy 334.21045 -279.62337) (xy 334.262412 -279.61151) (xy 334.315562 -279.607527)
			(xy 334.368712 -279.61151) (xy 334.420674 -279.62337) (xy 334.470288 -279.642842) (xy 334.516446 -279.669491)
			(xy 334.558117 -279.702722) (xy 334.594369 -279.741793) (xy 334.624393 -279.78583) (xy 334.647519 -279.833851)
			(xy 334.663229 -279.884781) (xy 334.671172 -279.937485) (xy 334.67167 -279.964134) (xy 334.671172 -279.990783)
			(xy 334.899752 -279.990783) (xy 334.899752 -279.937485) (xy 334.907695 -279.884781) (xy 334.923405 -279.833851)
			(xy 334.946531 -279.78583) (xy 334.976555 -279.741793) (xy 335.012807 -279.702722) (xy 335.054478 -279.669491)
			(xy 335.100636 -279.642842) (xy 335.15025 -279.62337) (xy 335.202212 -279.61151) (xy 335.255362 -279.607527)
			(xy 335.308512 -279.61151) (xy 335.360474 -279.62337) (xy 335.410088 -279.642842) (xy 335.456246 -279.669491)
			(xy 335.497917 -279.702722) (xy 335.534169 -279.741793) (xy 335.564193 -279.78583) (xy 335.587319 -279.833851)
			(xy 335.603029 -279.884781) (xy 335.610972 -279.937485) (xy 335.61147 -279.964134) (xy 335.610972 -279.990783)
			(xy 335.839552 -279.990783) (xy 335.839552 -279.937485) (xy 335.847495 -279.884781) (xy 335.863205 -279.833851)
			(xy 335.886331 -279.78583) (xy 335.916355 -279.741793) (xy 335.952607 -279.702722) (xy 335.994278 -279.669491)
			(xy 336.040436 -279.642842) (xy 336.09005 -279.62337) (xy 336.142012 -279.61151) (xy 336.195162 -279.607527)
			(xy 336.248312 -279.61151) (xy 336.300274 -279.62337) (xy 336.349888 -279.642842) (xy 336.396046 -279.669491)
			(xy 336.437717 -279.702722) (xy 336.473969 -279.741793) (xy 336.503993 -279.78583) (xy 336.527119 -279.833851)
			(xy 336.542829 -279.884781) (xy 336.550772 -279.937485) (xy 336.551269 -279.9641) (xy 336.778427 -279.9641)
			(xy 336.782409 -279.910959) (xy 336.794266 -279.859005) (xy 336.813734 -279.809399) (xy 336.840377 -279.763247)
			(xy 336.873601 -279.721582) (xy 336.912663 -279.685334) (xy 336.956692 -279.655311) (xy 337.004702 -279.632186)
			(xy 337.055623 -279.616474) (xy 337.108317 -279.608527) (xy 337.134962 -279.608026) (xy 337.159987 -279.608463)
			(xy 337.209544 -279.615467) (xy 337.257632 -279.629341) (xy 337.303304 -279.649814) (xy 337.345658 -279.67648)
			(xy 337.38386 -279.708815) (xy 337.417158 -279.746181) (xy 337.43138 -279.766776) (xy 337.778344 -279.766776)
			(xy 337.792602 -279.746207) (xy 337.825894 -279.708838) (xy 337.864089 -279.6765) (xy 337.906437 -279.649828)
			(xy 337.952102 -279.629349) (xy 338.000185 -279.615466) (xy 338.049739 -279.608453) (xy 338.074762 -279.608026)
			(xy 338.101418 -279.608429) (xy 338.154134 -279.616369) (xy 338.205078 -279.632078) (xy 338.253111 -279.655205)
			(xy 338.297161 -279.685234) (xy 338.336242 -279.721492) (xy 338.369483 -279.763171) (xy 338.39614 -279.809339)
			(xy 338.415618 -279.858964) (xy 338.427482 -279.910938) (xy 338.431466 -279.9641) (xy 338.429466 -279.990783)
			(xy 339.599006 -279.990783) (xy 339.599006 -279.937485) (xy 339.606949 -279.884781) (xy 339.622659 -279.833851)
			(xy 339.645785 -279.78583) (xy 339.675809 -279.741793) (xy 339.712061 -279.702722) (xy 339.753732 -279.669491)
			(xy 339.79989 -279.642842) (xy 339.849504 -279.62337) (xy 339.901466 -279.61151) (xy 339.954616 -279.607527)
			(xy 340.007766 -279.61151) (xy 340.059728 -279.62337) (xy 340.109342 -279.642842) (xy 340.1555 -279.669491)
			(xy 340.197171 -279.702722) (xy 340.233423 -279.741793) (xy 340.263447 -279.78583) (xy 340.286573 -279.833851)
			(xy 340.302283 -279.884781) (xy 340.310226 -279.937485) (xy 340.310724 -279.964134) (xy 340.310226 -279.990783)
			(xy 340.538806 -279.990783) (xy 340.538806 -279.937485) (xy 340.546749 -279.884781) (xy 340.562459 -279.833851)
			(xy 340.585585 -279.78583) (xy 340.615609 -279.741793) (xy 340.651861 -279.702722) (xy 340.693532 -279.669491)
			(xy 340.73969 -279.642842) (xy 340.789304 -279.62337) (xy 340.841266 -279.61151) (xy 340.894416 -279.607527)
			(xy 340.947566 -279.61151) (xy 340.999528 -279.62337) (xy 341.049142 -279.642842) (xy 341.0953 -279.669491)
			(xy 341.136971 -279.702722) (xy 341.173223 -279.741793) (xy 341.203247 -279.78583) (xy 341.226373 -279.833851)
			(xy 341.242083 -279.884781) (xy 341.250026 -279.937485) (xy 341.250524 -279.964134) (xy 341.250026 -279.990783)
			(xy 342.418152 -279.990783) (xy 342.418152 -279.937485) (xy 342.426095 -279.884781) (xy 342.441805 -279.833851)
			(xy 342.464931 -279.78583) (xy 342.494955 -279.741793) (xy 342.531207 -279.702722) (xy 342.572878 -279.669491)
			(xy 342.619036 -279.642842) (xy 342.66865 -279.62337) (xy 342.720612 -279.61151) (xy 342.773762 -279.607527)
			(xy 342.826912 -279.61151) (xy 342.878874 -279.62337) (xy 342.928488 -279.642842) (xy 342.974646 -279.669491)
			(xy 343.016317 -279.702722) (xy 343.052569 -279.741793) (xy 343.082593 -279.78583) (xy 343.105719 -279.833851)
			(xy 343.121429 -279.884781) (xy 343.129372 -279.937485) (xy 343.12987 -279.964134) (xy 343.129372 -279.990783)
			(xy 343.358206 -279.990783) (xy 343.358206 -279.937485) (xy 343.366149 -279.884781) (xy 343.381859 -279.833851)
			(xy 343.404985 -279.78583) (xy 343.435009 -279.741793) (xy 343.471261 -279.702722) (xy 343.512932 -279.669491)
			(xy 343.55909 -279.642842) (xy 343.608704 -279.62337) (xy 343.660666 -279.61151) (xy 343.713816 -279.607527)
			(xy 343.766966 -279.61151) (xy 343.818928 -279.62337) (xy 343.868542 -279.642842) (xy 343.9147 -279.669491)
			(xy 343.956371 -279.702722) (xy 343.992623 -279.741793) (xy 344.022647 -279.78583) (xy 344.045773 -279.833851)
			(xy 344.061483 -279.884781) (xy 344.069426 -279.937485) (xy 344.069924 -279.964134) (xy 344.297508 -279.964134)
			(xy 344.298006 -279.937485) (xy 344.305949 -279.884781) (xy 344.321659 -279.833851) (xy 344.344785 -279.78583)
			(xy 344.374809 -279.741793) (xy 344.411061 -279.702722) (xy 344.452732 -279.669491) (xy 344.49889 -279.642842)
			(xy 344.548504 -279.62337) (xy 344.600466 -279.61151) (xy 344.653616 -279.607527) (xy 344.706766 -279.61151)
			(xy 344.758728 -279.62337) (xy 344.808342 -279.642842) (xy 344.8545 -279.669491) (xy 344.896171 -279.702722)
			(xy 344.932423 -279.741793) (xy 344.962447 -279.78583) (xy 344.985573 -279.833851) (xy 345.001283 -279.884781)
			(xy 345.009226 -279.937485) (xy 345.009724 -279.964134) (xy 345.009374 -279.987423) (xy 345.008936 -279.990783)
			(xy 345.237806 -279.990783) (xy 345.237806 -279.937485) (xy 345.245749 -279.884781) (xy 345.261459 -279.833851)
			(xy 345.284585 -279.78583) (xy 345.314609 -279.741793) (xy 345.350861 -279.702722) (xy 345.392532 -279.669491)
			(xy 345.43869 -279.642842) (xy 345.488304 -279.62337) (xy 345.540266 -279.61151) (xy 345.593416 -279.607527)
			(xy 345.646566 -279.61151) (xy 345.698528 -279.62337) (xy 345.748142 -279.642842) (xy 345.7943 -279.669491)
			(xy 345.835971 -279.702722) (xy 345.872223 -279.741793) (xy 345.902247 -279.78583) (xy 345.925373 -279.833851)
			(xy 345.941083 -279.884781) (xy 345.949026 -279.937485) (xy 345.949524 -279.964134) (xy 345.949026 -279.990783)
			(xy 346.177606 -279.990783) (xy 346.177606 -279.937485) (xy 346.185549 -279.884781) (xy 346.201259 -279.833851)
			(xy 346.224385 -279.78583) (xy 346.254409 -279.741793) (xy 346.290661 -279.702722) (xy 346.332332 -279.669491)
			(xy 346.37849 -279.642842) (xy 346.428104 -279.62337) (xy 346.480066 -279.61151) (xy 346.533216 -279.607527)
			(xy 346.586366 -279.61151) (xy 346.638328 -279.62337) (xy 346.687942 -279.642842) (xy 346.7341 -279.669491)
			(xy 346.775771 -279.702722) (xy 346.812023 -279.741793) (xy 346.842047 -279.78583) (xy 346.865173 -279.833851)
			(xy 346.880883 -279.884781) (xy 346.888826 -279.937485) (xy 346.889324 -279.964134) (xy 346.888826 -279.990783)
			(xy 348.057206 -279.990783) (xy 348.057206 -279.937485) (xy 348.065149 -279.884781) (xy 348.080859 -279.833851)
			(xy 348.103985 -279.78583) (xy 348.134009 -279.741793) (xy 348.170261 -279.702722) (xy 348.211932 -279.669491)
			(xy 348.25809 -279.642842) (xy 348.307704 -279.62337) (xy 348.359666 -279.61151) (xy 348.412816 -279.607527)
			(xy 348.465966 -279.61151) (xy 348.517928 -279.62337) (xy 348.567542 -279.642842) (xy 348.6137 -279.669491)
			(xy 348.655371 -279.702722) (xy 348.691623 -279.741793) (xy 348.721647 -279.78583) (xy 348.744773 -279.833851)
			(xy 348.760483 -279.884781) (xy 348.768426 -279.937485) (xy 348.768924 -279.964134) (xy 348.768426 -279.990783)
			(xy 348.997006 -279.990783) (xy 348.997006 -279.937485) (xy 349.004949 -279.884781) (xy 349.020659 -279.833851)
			(xy 349.043785 -279.78583) (xy 349.073809 -279.741793) (xy 349.110061 -279.702722) (xy 349.151732 -279.669491)
			(xy 349.19789 -279.642842) (xy 349.247504 -279.62337) (xy 349.299466 -279.61151) (xy 349.352616 -279.607527)
			(xy 349.405766 -279.61151) (xy 349.457728 -279.62337) (xy 349.507342 -279.642842) (xy 349.5535 -279.669491)
			(xy 349.595171 -279.702722) (xy 349.631423 -279.741793) (xy 349.661447 -279.78583) (xy 349.684573 -279.833851)
			(xy 349.700283 -279.884781) (xy 349.708226 -279.937485) (xy 349.708724 -279.964134) (xy 349.708226 -279.990783)
			(xy 349.700283 -280.043487) (xy 349.684573 -280.094417) (xy 349.661447 -280.142438) (xy 349.631423 -280.186475)
			(xy 349.595171 -280.225546) (xy 349.5535 -280.258777) (xy 349.507342 -280.285426) (xy 349.457728 -280.304898)
			(xy 349.405766 -280.316758) (xy 349.352616 -280.320742) (xy 349.299466 -280.316758) (xy 349.247504 -280.304898)
			(xy 349.19789 -280.285426) (xy 349.151732 -280.258777) (xy 349.110061 -280.225546) (xy 349.073809 -280.186475)
			(xy 349.043785 -280.142438) (xy 349.020659 -280.094417) (xy 349.004949 -280.043487) (xy 348.997006 -279.990783)
			(xy 348.768426 -279.990783) (xy 348.760483 -280.043487) (xy 348.744773 -280.094417) (xy 348.721647 -280.142438)
			(xy 348.691623 -280.186475) (xy 348.655371 -280.225546) (xy 348.6137 -280.258777) (xy 348.567542 -280.285426)
			(xy 348.517928 -280.304898) (xy 348.465966 -280.316758) (xy 348.412816 -280.320742) (xy 348.359666 -280.316758)
			(xy 348.307704 -280.304898) (xy 348.25809 -280.285426) (xy 348.211932 -280.258777) (xy 348.170261 -280.225546)
			(xy 348.134009 -280.186475) (xy 348.103985 -280.142438) (xy 348.080859 -280.094417) (xy 348.065149 -280.043487)
			(xy 348.057206 -279.990783) (xy 346.888826 -279.990783) (xy 346.880883 -280.043487) (xy 346.865173 -280.094417)
			(xy 346.842047 -280.142438) (xy 346.812023 -280.186475) (xy 346.775771 -280.225546) (xy 346.7341 -280.258777)
			(xy 346.687942 -280.285426) (xy 346.638328 -280.304898) (xy 346.586366 -280.316758) (xy 346.533216 -280.320742)
			(xy 346.480066 -280.316758) (xy 346.428104 -280.304898) (xy 346.37849 -280.285426) (xy 346.332332 -280.258777)
			(xy 346.290661 -280.225546) (xy 346.254409 -280.186475) (xy 346.224385 -280.142438) (xy 346.201259 -280.094417)
			(xy 346.185549 -280.043487) (xy 346.177606 -279.990783) (xy 345.949026 -279.990783) (xy 345.941083 -280.043487)
			(xy 345.925373 -280.094417) (xy 345.902247 -280.142438) (xy 345.872223 -280.186475) (xy 345.835971 -280.225546)
			(xy 345.7943 -280.258777) (xy 345.748142 -280.285426) (xy 345.698528 -280.304898) (xy 345.646566 -280.316758)
			(xy 345.593416 -280.320742) (xy 345.540266 -280.316758) (xy 345.488304 -280.304898) (xy 345.43869 -280.285426)
			(xy 345.392532 -280.258777) (xy 345.350861 -280.225546) (xy 345.314609 -280.186475) (xy 345.284585 -280.142438)
			(xy 345.261459 -280.094417) (xy 345.245749 -280.043487) (xy 345.237806 -279.990783) (xy 345.008936 -279.990783)
			(xy 345.003352 -280.033609) (xy 344.991351 -280.078613) (xy 344.9828 -280.100278) (xy 344.973148 -280.123392)
			(xy 345.145614 -280.421842) (xy 345.170252 -280.425144) (xy 345.195589 -280.428996) (xy 345.244891 -280.442987)
			(xy 345.29168 -280.463898) (xy 345.33499 -280.491297) (xy 345.373926 -280.524619) (xy 345.407687 -280.563176)
			(xy 345.435574 -280.606173) (xy 345.457013 -280.652721) (xy 345.471561 -280.701862) (xy 345.478918 -280.75258)
			(xy 345.47937 -280.778204) (xy 345.478872 -280.804853) (xy 345.470929 -280.857557) (xy 345.455219 -280.908487)
			(xy 345.432093 -280.956508) (xy 345.402069 -281.000545) (xy 345.365817 -281.039616) (xy 345.324146 -281.072847)
			(xy 345.277988 -281.099496) (xy 345.228374 -281.118968) (xy 345.176412 -281.130828) (xy 345.123262 -281.134812)
			(xy 345.070112 -281.130828) (xy 345.01815 -281.118968) (xy 344.968536 -281.099496) (xy 344.922378 -281.072847)
			(xy 344.880707 -281.039616) (xy 344.844455 -281.000545) (xy 344.814431 -280.956508) (xy 344.791305 -280.908487)
			(xy 344.775595 -280.857557) (xy 344.767652 -280.804853) (xy 344.767154 -280.778204) (xy 344.767527 -280.754959)
			(xy 344.773573 -280.708864) (xy 344.785561 -280.663946) (xy 344.794078 -280.642314) (xy 344.80373 -280.6192)
			(xy 344.63101 -280.320496) (xy 344.606372 -280.317194) (xy 344.581041 -280.31337) (xy 344.531767 -280.299349)
			(xy 344.48501 -280.278414) (xy 344.441732 -280.250999) (xy 344.402828 -280.217668) (xy 344.369098 -280.179109)
			(xy 344.341239 -280.136116) (xy 344.319825 -280.089577) (xy 344.305297 -280.04045) (xy 344.297955 -279.989749)
			(xy 344.297508 -279.964134) (xy 344.069924 -279.964134) (xy 344.069426 -279.990783) (xy 344.061483 -280.043487)
			(xy 344.045773 -280.094417) (xy 344.022647 -280.142438) (xy 343.992623 -280.186475) (xy 343.956371 -280.225546)
			(xy 343.9147 -280.258777) (xy 343.868542 -280.285426) (xy 343.818928 -280.304898) (xy 343.766966 -280.316758)
			(xy 343.713816 -280.320742) (xy 343.660666 -280.316758) (xy 343.608704 -280.304898) (xy 343.55909 -280.285426)
			(xy 343.512932 -280.258777) (xy 343.471261 -280.225546) (xy 343.435009 -280.186475) (xy 343.404985 -280.142438)
			(xy 343.381859 -280.094417) (xy 343.366149 -280.043487) (xy 343.358206 -279.990783) (xy 343.129372 -279.990783)
			(xy 343.121429 -280.043487) (xy 343.105719 -280.094417) (xy 343.082593 -280.142438) (xy 343.052569 -280.186475)
			(xy 343.016317 -280.225546) (xy 342.974646 -280.258777) (xy 342.928488 -280.285426) (xy 342.878874 -280.304898)
			(xy 342.826912 -280.316758) (xy 342.773762 -280.320742) (xy 342.720612 -280.316758) (xy 342.66865 -280.304898)
			(xy 342.619036 -280.285426) (xy 342.572878 -280.258777) (xy 342.531207 -280.225546) (xy 342.494955 -280.186475)
			(xy 342.464931 -280.142438) (xy 342.441805 -280.094417) (xy 342.426095 -280.043487) (xy 342.418152 -279.990783)
			(xy 341.250026 -279.990783) (xy 341.242083 -280.043487) (xy 341.226373 -280.094417) (xy 341.203247 -280.142438)
			(xy 341.173223 -280.186475) (xy 341.136971 -280.225546) (xy 341.0953 -280.258777) (xy 341.049142 -280.285426)
			(xy 340.999528 -280.304898) (xy 340.947566 -280.316758) (xy 340.894416 -280.320742) (xy 340.841266 -280.316758)
			(xy 340.789304 -280.304898) (xy 340.73969 -280.285426) (xy 340.693532 -280.258777) (xy 340.651861 -280.225546)
			(xy 340.615609 -280.186475) (xy 340.585585 -280.142438) (xy 340.562459 -280.094417) (xy 340.546749 -280.043487)
			(xy 340.538806 -279.990783) (xy 340.310226 -279.990783) (xy 340.302283 -280.043487) (xy 340.286573 -280.094417)
			(xy 340.263447 -280.142438) (xy 340.233423 -280.186475) (xy 340.197171 -280.225546) (xy 340.1555 -280.258777)
			(xy 340.109342 -280.285426) (xy 340.059728 -280.304898) (xy 340.007766 -280.316758) (xy 339.954616 -280.320742)
			(xy 339.901466 -280.316758) (xy 339.849504 -280.304898) (xy 339.79989 -280.285426) (xy 339.753732 -280.258777)
			(xy 339.712061 -280.225546) (xy 339.675809 -280.186475) (xy 339.645785 -280.142438) (xy 339.622659 -280.094417)
			(xy 339.606949 -280.043487) (xy 339.599006 -279.990783) (xy 338.429466 -279.990783) (xy 338.427482 -280.017262)
			(xy 338.415618 -280.069236) (xy 338.39614 -280.118861) (xy 338.369483 -280.165029) (xy 338.336242 -280.206708)
			(xy 338.297161 -280.242966) (xy 338.253111 -280.272995) (xy 338.205078 -280.296122) (xy 338.154134 -280.311831)
			(xy 338.101418 -280.319771) (xy 338.074762 -280.320242) (xy 338.049737 -280.319833) (xy 338.000179 -280.31282)
			(xy 337.952092 -280.298938) (xy 337.906422 -280.278461) (xy 337.864068 -280.251791) (xy 337.825866 -280.219454)
			(xy 337.792567 -280.182087) (xy 337.778344 -280.161492) (xy 337.43138 -280.161492) (xy 337.417192 -280.182112)
			(xy 337.383887 -280.219476) (xy 337.345678 -280.251809) (xy 337.303318 -280.278473) (xy 337.257642 -280.298944)
			(xy 337.20955 -280.312817) (xy 337.159989 -280.31982) (xy 337.134962 -280.320242) (xy 337.108317 -280.319673)
			(xy 337.055623 -280.311726) (xy 337.004702 -280.296014) (xy 336.956692 -280.272889) (xy 336.912663 -280.242866)
			(xy 336.873601 -280.206618) (xy 336.840377 -280.164953) (xy 336.813734 -280.118801) (xy 336.794266 -280.069195)
			(xy 336.782409 -280.017241) (xy 336.778427 -279.9641) (xy 336.551269 -279.9641) (xy 336.55127 -279.964134)
			(xy 336.550772 -279.990783) (xy 336.542829 -280.043487) (xy 336.527119 -280.094417) (xy 336.503993 -280.142438)
			(xy 336.473969 -280.186475) (xy 336.437717 -280.225546) (xy 336.396046 -280.258777) (xy 336.349888 -280.285426)
			(xy 336.300274 -280.304898) (xy 336.248312 -280.316758) (xy 336.195162 -280.320742) (xy 336.142012 -280.316758)
			(xy 336.09005 -280.304898) (xy 336.040436 -280.285426) (xy 335.994278 -280.258777) (xy 335.952607 -280.225546)
			(xy 335.916355 -280.186475) (xy 335.886331 -280.142438) (xy 335.863205 -280.094417) (xy 335.847495 -280.043487)
			(xy 335.839552 -279.990783) (xy 335.610972 -279.990783) (xy 335.603029 -280.043487) (xy 335.587319 -280.094417)
			(xy 335.564193 -280.142438) (xy 335.534169 -280.186475) (xy 335.497917 -280.225546) (xy 335.456246 -280.258777)
			(xy 335.410088 -280.285426) (xy 335.360474 -280.304898) (xy 335.308512 -280.316758) (xy 335.255362 -280.320742)
			(xy 335.202212 -280.316758) (xy 335.15025 -280.304898) (xy 335.100636 -280.285426) (xy 335.054478 -280.258777)
			(xy 335.012807 -280.225546) (xy 334.976555 -280.186475) (xy 334.946531 -280.142438) (xy 334.923405 -280.094417)
			(xy 334.907695 -280.043487) (xy 334.899752 -279.990783) (xy 334.671172 -279.990783) (xy 334.663229 -280.043487)
			(xy 334.647519 -280.094417) (xy 334.624393 -280.142438) (xy 334.594369 -280.186475) (xy 334.558117 -280.225546)
			(xy 334.516446 -280.258777) (xy 334.470288 -280.285426) (xy 334.420674 -280.304898) (xy 334.368712 -280.316758)
			(xy 334.315562 -280.320742) (xy 334.262412 -280.316758) (xy 334.21045 -280.304898) (xy 334.160836 -280.285426)
			(xy 334.114678 -280.258777) (xy 334.073007 -280.225546) (xy 334.036755 -280.186475) (xy 334.006731 -280.142438)
			(xy 333.983605 -280.094417) (xy 333.967895 -280.043487) (xy 333.959952 -279.990783) (xy 333.466948 -279.990783)
			(xy 333.466948 -280.42997) (xy 333.467424 -280.444237) (xy 333.475314 -280.471658) (xy 333.490485 -280.495824)
			(xy 333.511753 -280.514846) (xy 333.537455 -280.527238) (xy 333.565583 -280.532032) (xy 333.593939 -280.528853)
			(xy 333.620307 -280.51795) (xy 333.631794 -280.509472) (xy 333.654764 -280.49197) (xy 333.705338 -280.464098)
			(xy 333.759857 -280.445067) (xy 333.816789 -280.435413) (xy 333.845662 -280.434796) (xy 333.871364 -280.435249)
			(xy 333.922195 -280.442906) (xy 333.971317 -280.458053) (xy 334.017633 -280.480353) (xy 334.060107 -280.509307)
			(xy 334.097791 -280.544269) (xy 334.129843 -280.584457) (xy 334.155547 -280.628973) (xy 334.174328 -280.676824)
			(xy 334.185768 -280.726939) (xy 334.18961 -280.7782) (xy 334.428896 -280.7782) (xy 334.432879 -280.725055)
			(xy 334.444737 -280.673096) (xy 334.464207 -280.623485) (xy 334.490852 -280.57733) (xy 334.524079 -280.535661)
			(xy 334.563144 -280.49941) (xy 334.607176 -280.469385) (xy 334.655191 -280.446258) (xy 334.706116 -280.430545)
			(xy 334.758815 -280.422596) (xy 334.785462 -280.422096) (xy 334.810477 -280.422493) (xy 334.860016 -280.429486)
			(xy 334.908089 -280.44334) (xy 334.953752 -280.463782) (xy 334.996107 -280.49041) (xy 335.034321 -280.522701)
			(xy 335.067642 -280.56002) (xy 335.08188 -280.580592) (xy 335.428844 -280.580592) (xy 335.443086 -280.560025)
			(xy 335.476414 -280.522717) (xy 335.514631 -280.490436) (xy 335.556985 -280.463814) (xy 335.602645 -280.443375)
			(xy 335.650715 -280.42952) (xy 335.700249 -280.422521) (xy 335.725262 -280.422096) (xy 335.751915 -280.422559)
			(xy 335.804627 -280.430498) (xy 335.855567 -280.446206) (xy 335.903596 -280.469331) (xy 335.947642 -280.499357)
			(xy 335.98672 -280.535613) (xy 336.019958 -280.577288) (xy 336.046613 -280.623452) (xy 336.06609 -280.673073)
			(xy 336.077952 -280.725043) (xy 336.081936 -280.7782) (xy 336.077952 -280.831357) (xy 336.06609 -280.883327)
			(xy 336.046613 -280.932948) (xy 336.019958 -280.979112) (xy 335.98672 -281.020787) (xy 335.947642 -281.057043)
			(xy 335.903596 -281.087069) (xy 335.855567 -281.110194) (xy 335.804627 -281.125902) (xy 335.751915 -281.133841)
			(xy 335.725262 -281.134312) (xy 335.700248 -281.133893) (xy 335.65071 -281.126904) (xy 335.602637 -281.113054)
			(xy 335.556974 -281.092615) (xy 335.514619 -281.06599) (xy 335.476405 -281.033702) (xy 335.443083 -280.996386)
			(xy 335.428844 -280.975816) (xy 335.08188 -280.975816) (xy 335.067626 -280.996374) (xy 335.034299 -281.033681)
			(xy 334.996084 -281.065963) (xy 334.953732 -281.092586) (xy 334.908074 -281.113027) (xy 334.860007 -281.126884)
			(xy 334.810474 -281.133886) (xy 334.785462 -281.134312) (xy 334.758815 -281.133804) (xy 334.706116 -281.125855)
			(xy 334.655191 -281.110142) (xy 334.607176 -281.087015) (xy 334.563144 -281.05699) (xy 334.524079 -281.020739)
			(xy 334.490852 -280.97907) (xy 334.464207 -280.932915) (xy 334.444737 -280.883304) (xy 334.432879 -280.831345)
			(xy 334.428896 -280.7782) (xy 334.18961 -280.7782) (xy 334.185768 -280.829461) (xy 334.174328 -280.879576)
			(xy 334.155547 -280.927427) (xy 334.129843 -280.971943) (xy 334.097791 -281.012131) (xy 334.060107 -281.047093)
			(xy 334.017633 -281.076047) (xy 333.971317 -281.098347) (xy 333.922195 -281.113494) (xy 333.871364 -281.121151)
			(xy 333.845662 -281.121612) (xy 333.816787 -281.121025) (xy 333.759847 -281.111378) (xy 333.705323 -281.092345)
			(xy 333.654749 -281.064462) (xy 333.631794 -281.046936) (xy 333.620331 -281.038419) (xy 333.593951 -281.02751)
			(xy 333.565583 -281.024329) (xy 333.537443 -281.029124) (xy 333.511729 -281.041523) (xy 333.490453 -281.060554)
			(xy 333.475276 -281.084731) (xy 333.467384 -281.112165) (xy 333.466948 -281.126438) (xy 333.466948 -281.618669)
			(xy 333.959952 -281.618669) (xy 333.959952 -281.565371) (xy 333.967895 -281.512667) (xy 333.983605 -281.461737)
			(xy 334.006731 -281.413716) (xy 334.036755 -281.369679) (xy 334.073007 -281.330608) (xy 334.114678 -281.297377)
			(xy 334.160836 -281.270728) (xy 334.21045 -281.251256) (xy 334.262412 -281.239396) (xy 334.315562 -281.235413)
			(xy 334.368712 -281.239396) (xy 334.420674 -281.251256) (xy 334.470288 -281.270728) (xy 334.516446 -281.297377)
			(xy 334.558117 -281.330608) (xy 334.594369 -281.369679) (xy 334.624393 -281.413716) (xy 334.647519 -281.461737)
			(xy 334.663229 -281.512667) (xy 334.671172 -281.565371) (xy 334.67167 -281.59202) (xy 334.671172 -281.618669)
			(xy 334.663229 -281.671373) (xy 334.647519 -281.722303) (xy 334.624393 -281.770324) (xy 334.594369 -281.814361)
			(xy 334.558117 -281.853432) (xy 334.516446 -281.886663) (xy 334.470288 -281.913312) (xy 334.420674 -281.932784)
			(xy 334.368712 -281.944644) (xy 334.315562 -281.948628) (xy 334.262412 -281.944644) (xy 334.21045 -281.932784)
			(xy 334.160836 -281.913312) (xy 334.114678 -281.886663) (xy 334.073007 -281.853432) (xy 334.036755 -281.814361)
			(xy 334.006731 -281.770324) (xy 333.983605 -281.722303) (xy 333.967895 -281.671373) (xy 333.959952 -281.618669)
			(xy 333.466948 -281.618669) (xy 333.466948 -282.0416) (xy 333.467396 -282.055738) (xy 333.475127 -282.082937)
			(xy 333.490022 -282.106971) (xy 333.51094 -282.125997) (xy 333.536275 -282.138554) (xy 333.564083 -282.143678)
			(xy 333.592229 -282.140978) (xy 333.618555 -282.130658) (xy 333.630016 -282.122372) (xy 333.653422 -282.105294)
			(xy 333.704612 -282.07816) (xy 333.759518 -282.059667) (xy 333.816693 -282.050302) (xy 333.845662 -282.049728)
			(xy 333.872312 -282.050198) (xy 333.925018 -282.058137) (xy 333.975952 -282.073844) (xy 334.023976 -282.096966)
			(xy 334.068017 -282.126988) (xy 334.107091 -282.16324) (xy 334.140325 -282.20491) (xy 334.166977 -282.251069)
			(xy 334.186451 -282.300685) (xy 334.198313 -282.352649) (xy 334.202296 -282.4058) (xy 334.202293 -282.405836)
			(xy 334.429608 -282.405836) (xy 334.4301 -282.380209) (xy 334.43743 -282.329483) (xy 334.451957 -282.280333)
			(xy 334.473383 -282.233773) (xy 334.501263 -282.190767) (xy 334.535021 -282.152202) (xy 334.57396 -282.118877)
			(xy 334.617276 -282.09148) (xy 334.664072 -282.070576) (xy 334.713383 -282.056599) (xy 334.738726 -282.052776)
			(xy 334.763364 -282.049474) (xy 334.93583 -281.75077) (xy 334.926432 -281.727656) (xy 334.917935 -281.706062)
			(xy 334.90596 -281.661229) (xy 334.899901 -281.615222) (xy 334.899508 -281.59202) (xy 334.900006 -281.565371)
			(xy 334.907949 -281.512667) (xy 334.923659 -281.461737) (xy 334.946785 -281.413716) (xy 334.976809 -281.369679)
			(xy 335.013061 -281.330608) (xy 335.054732 -281.297377) (xy 335.10089 -281.270728) (xy 335.150504 -281.251256)
			(xy 335.202466 -281.239396) (xy 335.255616 -281.235413) (xy 335.308766 -281.239396) (xy 335.360728 -281.251256)
			(xy 335.410342 -281.270728) (xy 335.4565 -281.297377) (xy 335.498171 -281.330608) (xy 335.534423 -281.369679)
			(xy 335.564447 -281.413716) (xy 335.587573 -281.461737) (xy 335.603283 -281.512667) (xy 335.611226 -281.565371)
			(xy 335.611724 -281.59202) (xy 335.611342 -281.617651) (xy 335.611195 -281.618669) (xy 335.839552 -281.618669)
			(xy 335.839552 -281.565371) (xy 335.847495 -281.512667) (xy 335.863205 -281.461737) (xy 335.886331 -281.413716)
			(xy 335.916355 -281.369679) (xy 335.952607 -281.330608) (xy 335.994278 -281.297377) (xy 336.040436 -281.270728)
			(xy 336.09005 -281.251256) (xy 336.142012 -281.239396) (xy 336.195162 -281.235413) (xy 336.248312 -281.239396)
			(xy 336.300274 -281.251256) (xy 336.349888 -281.270728) (xy 336.396046 -281.297377) (xy 336.437717 -281.330608)
			(xy 336.473969 -281.369679) (xy 336.503993 -281.413716) (xy 336.527119 -281.461737) (xy 336.542829 -281.512667)
			(xy 336.550772 -281.565371) (xy 336.55127 -281.59202) (xy 336.779108 -281.59202) (xy 336.779585 -281.566393)
			(xy 336.786917 -281.515666) (xy 336.801447 -281.466515) (xy 336.822874 -281.419956) (xy 336.850756 -281.376949)
			(xy 336.884516 -281.338385) (xy 336.923457 -281.30506) (xy 336.966773 -281.277663) (xy 337.013571 -281.25676)
			(xy 337.062882 -281.242783) (xy 337.088226 -281.23896) (xy 337.113118 -281.235658) (xy 337.28533 -280.937462)
			(xy 337.275678 -280.914348) (xy 337.267153 -280.892674) (xy 337.255156 -280.847672) (xy 337.249119 -280.801491)
			(xy 337.248754 -280.778204) (xy 337.249252 -280.751555) (xy 337.257195 -280.698851) (xy 337.272905 -280.647921)
			(xy 337.296031 -280.5999) (xy 337.326055 -280.555863) (xy 337.362307 -280.516792) (xy 337.403978 -280.483561)
			(xy 337.450136 -280.456912) (xy 337.49975 -280.43744) (xy 337.551712 -280.42558) (xy 337.604862 -280.421597)
			(xy 337.658012 -280.42558) (xy 337.709974 -280.43744) (xy 337.759588 -280.456912) (xy 337.805746 -280.483561)
			(xy 337.847417 -280.516792) (xy 337.883669 -280.555863) (xy 337.913693 -280.5999) (xy 337.936819 -280.647921)
			(xy 337.952529 -280.698851) (xy 337.960472 -280.751555) (xy 337.96097 -280.778204) (xy 337.960563 -280.803824)
			(xy 337.960414 -280.804853) (xy 338.189052 -280.804853) (xy 338.189052 -280.751555) (xy 338.196995 -280.698851)
			(xy 338.212705 -280.647921) (xy 338.235831 -280.5999) (xy 338.265855 -280.555863) (xy 338.302107 -280.516792)
			(xy 338.343778 -280.483561) (xy 338.389936 -280.456912) (xy 338.43955 -280.43744) (xy 338.491512 -280.42558)
			(xy 338.544662 -280.421597) (xy 338.597812 -280.42558) (xy 338.649774 -280.43744) (xy 338.699388 -280.456912)
			(xy 338.745546 -280.483561) (xy 338.787217 -280.516792) (xy 338.823469 -280.555863) (xy 338.853493 -280.5999)
			(xy 338.876619 -280.647921) (xy 338.892329 -280.698851) (xy 338.900272 -280.751555) (xy 338.90077 -280.778204)
			(xy 340.068408 -280.778204) (xy 340.068906 -280.751555) (xy 340.076849 -280.698851) (xy 340.092559 -280.647921)
			(xy 340.115685 -280.5999) (xy 340.145709 -280.555863) (xy 340.181961 -280.516792) (xy 340.223632 -280.483561)
			(xy 340.26979 -280.456912) (xy 340.319404 -280.43744) (xy 340.371366 -280.42558) (xy 340.424516 -280.421597)
			(xy 340.477666 -280.42558) (xy 340.529628 -280.43744) (xy 340.579242 -280.456912) (xy 340.6254 -280.483561)
			(xy 340.667071 -280.516792) (xy 340.703323 -280.555863) (xy 340.733347 -280.5999) (xy 340.756473 -280.647921)
			(xy 340.772183 -280.698851) (xy 340.780126 -280.751555) (xy 340.780624 -280.778204) (xy 340.780296 -280.801494)
			(xy 340.779857 -280.804853) (xy 341.948506 -280.804853) (xy 341.948506 -280.751555) (xy 341.956449 -280.698851)
			(xy 341.972159 -280.647921) (xy 341.995285 -280.5999) (xy 342.025309 -280.555863) (xy 342.061561 -280.516792)
			(xy 342.103232 -280.483561) (xy 342.14939 -280.456912) (xy 342.199004 -280.43744) (xy 342.250966 -280.42558)
			(xy 342.304116 -280.421597) (xy 342.357266 -280.42558) (xy 342.409228 -280.43744) (xy 342.458842 -280.456912)
			(xy 342.505 -280.483561) (xy 342.546671 -280.516792) (xy 342.582923 -280.555863) (xy 342.612947 -280.5999)
			(xy 342.636073 -280.647921) (xy 342.651783 -280.698851) (xy 342.659726 -280.751555) (xy 342.660224 -280.7782)
			(xy 342.887096 -280.7782) (xy 342.891079 -280.725055) (xy 342.902937 -280.673096) (xy 342.922407 -280.623485)
			(xy 342.949052 -280.57733) (xy 342.982279 -280.535661) (xy 343.021344 -280.49941) (xy 343.065376 -280.469385)
			(xy 343.113391 -280.446258) (xy 343.164316 -280.430545) (xy 343.217015 -280.422596) (xy 343.243662 -280.422096)
			(xy 343.268677 -280.422493) (xy 343.318216 -280.429486) (xy 343.366289 -280.44334) (xy 343.411952 -280.463782)
			(xy 343.454307 -280.49041) (xy 343.492521 -280.522701) (xy 343.525842 -280.56002) (xy 343.54008 -280.580592)
			(xy 343.887298 -280.580592) (xy 343.901505 -280.56) (xy 343.934839 -280.522693) (xy 343.973062 -280.490413)
			(xy 344.015422 -280.463794) (xy 344.061088 -280.443359) (xy 344.109163 -280.429509) (xy 344.158701 -280.422517)
			(xy 344.183716 -280.422096) (xy 344.210365 -280.422587) (xy 344.263067 -280.430533) (xy 344.313996 -280.446244)
			(xy 344.362015 -280.469371) (xy 344.406051 -280.499396) (xy 344.44512 -280.535648) (xy 344.47835 -280.577319)
			(xy 344.504998 -280.623476) (xy 344.524469 -280.67309) (xy 344.536329 -280.725051) (xy 344.540312 -280.7782)
			(xy 344.536329 -280.831349) (xy 344.524469 -280.88331) (xy 344.504998 -280.932924) (xy 344.47835 -280.979081)
			(xy 344.44512 -281.020752) (xy 344.406051 -281.057004) (xy 344.362015 -281.087029) (xy 344.313996 -281.110156)
			(xy 344.263067 -281.125867) (xy 344.210365 -281.133813) (xy 344.183716 -281.134312) (xy 344.158703 -281.133852)
			(xy 344.109167 -281.12687) (xy 344.061095 -281.113027) (xy 344.015433 -281.092595) (xy 343.973077 -281.065977)
			(xy 343.934862 -281.033694) (xy 343.901538 -280.996384) (xy 343.887298 -280.975816) (xy 343.54008 -280.975816)
			(xy 343.525826 -280.996374) (xy 343.492499 -281.033681) (xy 343.454284 -281.065963) (xy 343.411932 -281.092586)
			(xy 343.366274 -281.113027) (xy 343.318207 -281.126884) (xy 343.268674 -281.133886) (xy 343.243662 -281.134312)
			(xy 343.217015 -281.133804) (xy 343.164316 -281.125855) (xy 343.113391 -281.110142) (xy 343.065376 -281.087015)
			(xy 343.021344 -281.05699) (xy 342.982279 -281.020739) (xy 342.949052 -280.97907) (xy 342.922407 -280.932915)
			(xy 342.902937 -280.883304) (xy 342.891079 -280.831345) (xy 342.887096 -280.7782) (xy 342.660224 -280.7782)
			(xy 342.660224 -280.778204) (xy 342.659726 -280.804853) (xy 342.651783 -280.857557) (xy 342.636073 -280.908487)
			(xy 342.612947 -280.956508) (xy 342.582923 -281.000545) (xy 342.546671 -281.039616) (xy 342.505 -281.072847)
			(xy 342.458842 -281.099496) (xy 342.409228 -281.118968) (xy 342.357266 -281.130828) (xy 342.304116 -281.134812)
			(xy 342.250966 -281.130828) (xy 342.199004 -281.118968) (xy 342.14939 -281.099496) (xy 342.103232 -281.072847)
			(xy 342.061561 -281.039616) (xy 342.025309 -281.000545) (xy 341.995285 -280.956508) (xy 341.972159 -280.908487)
			(xy 341.956449 -280.857557) (xy 341.948506 -280.804853) (xy 340.779857 -280.804853) (xy 340.774266 -280.84768)
			(xy 340.762255 -280.892684) (xy 340.7537 -280.914348) (xy 340.744048 -280.937462) (xy 340.91626 -281.235658)
			(xy 340.941152 -281.23896) (xy 340.966492 -281.242796) (xy 341.015795 -281.256788) (xy 341.062585 -281.2777)
			(xy 341.105895 -281.305101) (xy 341.144832 -281.338425) (xy 341.178593 -281.376984) (xy 341.20648 -281.419982)
			(xy 341.227918 -281.466533) (xy 341.242464 -281.515675) (xy 341.249819 -281.566395) (xy 341.25027 -281.59202)
			(xy 341.249772 -281.618669) (xy 341.241829 -281.671373) (xy 341.226119 -281.722303) (xy 341.202993 -281.770324)
			(xy 341.172969 -281.814361) (xy 341.136717 -281.853432) (xy 341.095046 -281.886663) (xy 341.048888 -281.913312)
			(xy 340.999274 -281.932784) (xy 340.947312 -281.944644) (xy 340.894162 -281.948628) (xy 340.841012 -281.944644)
			(xy 340.78905 -281.932784) (xy 340.739436 -281.913312) (xy 340.693278 -281.886663) (xy 340.651607 -281.853432)
			(xy 340.615355 -281.814361) (xy 340.585331 -281.770324) (xy 340.562205 -281.722303) (xy 340.546495 -281.671373)
			(xy 340.538552 -281.618669) (xy 340.538054 -281.59202) (xy 340.538437 -281.568817) (xy 340.544485 -281.522806)
			(xy 340.556468 -281.477974) (xy 340.564978 -281.456384) (xy 340.574376 -281.43327) (xy 340.40191 -281.134566)
			(xy 340.377272 -281.131264) (xy 340.351953 -281.127373) (xy 340.302684 -281.113355) (xy 340.255931 -281.092426)
			(xy 340.212657 -281.065017) (xy 340.173754 -281.031694) (xy 340.140024 -280.993143) (xy 340.112163 -280.950159)
			(xy 340.090744 -280.903628) (xy 340.07621 -280.85451) (xy 340.068859 -280.803816) (xy 340.068408 -280.778204)
			(xy 338.90077 -280.778204) (xy 338.900272 -280.804853) (xy 338.892329 -280.857557) (xy 338.876619 -280.908487)
			(xy 338.853493 -280.956508) (xy 338.823469 -281.000545) (xy 338.787217 -281.039616) (xy 338.745546 -281.072847)
			(xy 338.699388 -281.099496) (xy 338.649774 -281.118968) (xy 338.597812 -281.130828) (xy 338.544662 -281.134812)
			(xy 338.491512 -281.130828) (xy 338.43955 -281.118968) (xy 338.389936 -281.099496) (xy 338.343778 -281.072847)
			(xy 338.302107 -281.039616) (xy 338.265855 -281.000545) (xy 338.235831 -280.956508) (xy 338.212705 -280.908487)
			(xy 338.196995 -280.857557) (xy 338.189052 -280.804853) (xy 337.960414 -280.804853) (xy 337.953244 -280.854537)
			(xy 337.938731 -280.903678) (xy 337.917323 -280.95023) (xy 337.889462 -280.993232) (xy 337.855723 -281.031795)
			(xy 337.816804 -281.065123) (xy 337.773509 -281.092527) (xy 337.726733 -281.113441) (xy 337.677441 -281.127432)
			(xy 337.652106 -281.131264) (xy 337.627468 -281.134566) (xy 337.455002 -281.433016) (xy 337.4644 -281.45613)
			(xy 337.472924 -281.477759) (xy 337.484908 -281.522679) (xy 337.49095 -281.568775) (xy 337.491324 -281.59202)
			(xy 337.490826 -281.618669) (xy 337.719152 -281.618669) (xy 337.719152 -281.565371) (xy 337.727095 -281.512667)
			(xy 337.742805 -281.461737) (xy 337.765931 -281.413716) (xy 337.795955 -281.369679) (xy 337.832207 -281.330608)
			(xy 337.873878 -281.297377) (xy 337.920036 -281.270728) (xy 337.96965 -281.251256) (xy 338.021612 -281.239396)
			(xy 338.074762 -281.235413) (xy 338.127912 -281.239396) (xy 338.179874 -281.251256) (xy 338.229488 -281.270728)
			(xy 338.275646 -281.297377) (xy 338.317317 -281.330608) (xy 338.353569 -281.369679) (xy 338.383593 -281.413716)
			(xy 338.406719 -281.461737) (xy 338.422429 -281.512667) (xy 338.430372 -281.565371) (xy 338.43087 -281.592)
			(xy 338.658013 -281.592) (xy 338.661995 -281.538857) (xy 338.673853 -281.486901) (xy 338.693321 -281.437292)
			(xy 338.719966 -281.391139) (xy 338.753191 -281.349473) (xy 338.792255 -281.313223) (xy 338.836285 -281.283199)
			(xy 338.884297 -281.260073) (xy 338.93522 -281.244361) (xy 338.987916 -281.236413) (xy 339.014562 -281.235912)
			(xy 339.039577 -281.236302) (xy 339.089117 -281.243295) (xy 339.137191 -281.25715) (xy 339.182854 -281.277593)
			(xy 339.225209 -281.304222) (xy 339.263422 -281.336515) (xy 339.296742 -281.373836) (xy 339.31098 -281.394408)
			(xy 339.657944 -281.394408) (xy 339.672191 -281.373844) (xy 339.705518 -281.336536) (xy 339.743733 -281.304254)
			(xy 339.786087 -281.277631) (xy 339.831746 -281.257191) (xy 339.879815 -281.243336) (xy 339.929349 -281.236337)
			(xy 339.954362 -281.235912) (xy 339.981016 -281.236343) (xy 340.033731 -281.244283) (xy 340.084673 -281.259991)
			(xy 340.132704 -281.283118) (xy 340.176752 -281.313145) (xy 340.215832 -281.349402) (xy 340.249072 -281.391079)
			(xy 340.275728 -281.437245) (xy 340.295205 -281.486868) (xy 340.307068 -281.53884) (xy 340.311052 -281.592)
			(xy 340.307068 -281.64516) (xy 340.295205 -281.697132) (xy 340.275728 -281.746755) (xy 340.249072 -281.792921)
			(xy 340.215832 -281.834598) (xy 340.176752 -281.870855) (xy 340.132704 -281.900882) (xy 340.084673 -281.924009)
			(xy 340.033731 -281.939717) (xy 339.981016 -281.947657) (xy 339.954362 -281.948128) (xy 339.929346 -281.947746)
			(xy 339.879805 -281.940755) (xy 339.83173 -281.926901) (xy 339.786065 -281.906457) (xy 339.743711 -281.879826)
			(xy 339.705498 -281.84753) (xy 339.67218 -281.810206) (xy 339.657944 -281.789632) (xy 339.31098 -281.789632)
			(xy 339.296731 -281.810193) (xy 339.263403 -281.8475) (xy 339.225187 -281.879781) (xy 339.182834 -281.906403)
			(xy 339.137175 -281.926843) (xy 339.089107 -281.9407) (xy 339.039575 -281.947702) (xy 339.014562 -281.948128)
			(xy 338.987916 -281.947587) (xy 338.93522 -281.939639) (xy 338.884297 -281.923927) (xy 338.836285 -281.900801)
			(xy 338.792255 -281.870777) (xy 338.753191 -281.834527) (xy 338.719966 -281.792861) (xy 338.693321 -281.746708)
			(xy 338.673853 -281.697099) (xy 338.661995 -281.645143) (xy 338.658013 -281.592) (xy 338.43087 -281.592)
			(xy 338.43087 -281.59202) (xy 338.430372 -281.618669) (xy 338.422429 -281.671373) (xy 338.406719 -281.722303)
			(xy 338.383593 -281.770324) (xy 338.353569 -281.814361) (xy 338.317317 -281.853432) (xy 338.275646 -281.886663)
			(xy 338.229488 -281.913312) (xy 338.179874 -281.932784) (xy 338.127912 -281.944644) (xy 338.074762 -281.948628)
			(xy 338.021612 -281.944644) (xy 337.96965 -281.932784) (xy 337.920036 -281.913312) (xy 337.873878 -281.886663)
			(xy 337.832207 -281.853432) (xy 337.795955 -281.814361) (xy 337.765931 -281.770324) (xy 337.742805 -281.722303)
			(xy 337.727095 -281.671373) (xy 337.719152 -281.618669) (xy 337.490826 -281.618669) (xy 337.482883 -281.671373)
			(xy 337.467173 -281.722303) (xy 337.444047 -281.770324) (xy 337.414023 -281.814361) (xy 337.377771 -281.853432)
			(xy 337.3361 -281.886663) (xy 337.289942 -281.913312) (xy 337.240328 -281.932784) (xy 337.188366 -281.944644)
			(xy 337.135216 -281.948628) (xy 337.082066 -281.944644) (xy 337.030104 -281.932784) (xy 336.98049 -281.913312)
			(xy 336.934332 -281.886663) (xy 336.892661 -281.853432) (xy 336.856409 -281.814361) (xy 336.826385 -281.770324)
			(xy 336.803259 -281.722303) (xy 336.787549 -281.671373) (xy 336.779606 -281.618669) (xy 336.779108 -281.59202)
			(xy 336.55127 -281.59202) (xy 336.550772 -281.618669) (xy 336.542829 -281.671373) (xy 336.527119 -281.722303)
			(xy 336.503993 -281.770324) (xy 336.473969 -281.814361) (xy 336.437717 -281.853432) (xy 336.396046 -281.886663)
			(xy 336.349888 -281.913312) (xy 336.300274 -281.932784) (xy 336.248312 -281.944644) (xy 336.195162 -281.948628)
			(xy 336.142012 -281.944644) (xy 336.09005 -281.932784) (xy 336.040436 -281.913312) (xy 335.994278 -281.886663)
			(xy 335.952607 -281.853432) (xy 335.916355 -281.814361) (xy 335.886331 -281.770324) (xy 335.863205 -281.722303)
			(xy 335.847495 -281.671373) (xy 335.839552 -281.618669) (xy 335.611195 -281.618669) (xy 335.604003 -281.668384)
			(xy 335.589465 -281.717541) (xy 335.568028 -281.764104) (xy 335.540136 -281.807113) (xy 335.506364 -281.845678)
			(xy 335.467412 -281.879001) (xy 335.424084 -281.906395) (xy 335.377276 -281.927292) (xy 335.327955 -281.941261)
			(xy 335.302606 -281.94508) (xy 335.277968 -281.948382) (xy 335.105502 -282.247086) (xy 335.1149 -282.2702)
			(xy 335.123386 -282.291798) (xy 335.135364 -282.336629) (xy 335.141428 -282.382635) (xy 335.141824 -282.405836)
			(xy 335.369154 -282.405836) (xy 335.369652 -282.379187) (xy 335.377595 -282.326483) (xy 335.393305 -282.275553)
			(xy 335.416431 -282.227532) (xy 335.446455 -282.183495) (xy 335.482707 -282.144424) (xy 335.524378 -282.111193)
			(xy 335.570536 -282.084544) (xy 335.62015 -282.065072) (xy 335.672112 -282.053212) (xy 335.725262 -282.049229)
			(xy 335.778412 -282.053212) (xy 335.830374 -282.065072) (xy 335.879988 -282.084544) (xy 335.926146 -282.111193)
			(xy 335.967817 -282.144424) (xy 336.004069 -282.183495) (xy 336.034093 -282.227532) (xy 336.057219 -282.275553)
			(xy 336.072929 -282.326483) (xy 336.080872 -282.379187) (xy 336.081369 -282.4058) (xy 336.308704 -282.4058)
			(xy 336.312687 -282.352651) (xy 336.324547 -282.300689) (xy 336.34402 -282.251075) (xy 336.37067 -282.204917)
			(xy 336.403902 -282.163248) (xy 336.442973 -282.126996) (xy 336.487011 -282.096973) (xy 336.535032 -282.07385)
			(xy 336.585963 -282.058142) (xy 336.638667 -282.0502) (xy 336.665316 -282.049728) (xy 336.69033 -282.050146)
			(xy 336.739869 -282.057133) (xy 336.787943 -282.070982) (xy 336.833606 -282.09142) (xy 336.875961 -282.118046)
			(xy 336.914175 -282.150335) (xy 336.947496 -282.187653) (xy 336.961734 -282.208224) (xy 337.308698 -282.208224)
			(xy 337.322915 -282.187639) (xy 337.356247 -282.150331) (xy 337.394467 -282.118049) (xy 337.436826 -282.091429)
			(xy 337.48249 -282.070992) (xy 337.530564 -282.057142) (xy 337.580102 -282.050149) (xy 337.605116 -282.049728)
			(xy 337.631767 -282.050155) (xy 337.684474 -282.058101) (xy 337.735408 -282.073814) (xy 337.783431 -282.096943)
			(xy 337.827471 -282.126971) (xy 337.866543 -282.163226) (xy 337.899776 -282.204901) (xy 337.926427 -282.251062)
			(xy 337.9459 -282.30068) (xy 337.95776 -282.352647) (xy 337.961744 -282.4058) (xy 337.959744 -282.432485)
			(xy 338.189306 -282.432485) (xy 338.189306 -282.379187) (xy 338.197249 -282.326483) (xy 338.212959 -282.275553)
			(xy 338.236085 -282.227532) (xy 338.266109 -282.183495) (xy 338.302361 -282.144424) (xy 338.344032 -282.111193)
			(xy 338.39019 -282.084544) (xy 338.439804 -282.065072) (xy 338.491766 -282.053212) (xy 338.544916 -282.049229)
			(xy 338.598066 -282.053212) (xy 338.650028 -282.065072) (xy 338.699642 -282.084544) (xy 338.7458 -282.111193)
			(xy 338.787471 -282.144424) (xy 338.823723 -282.183495) (xy 338.853747 -282.227532) (xy 338.876873 -282.275553)
			(xy 338.892583 -282.326483) (xy 338.900526 -282.379187) (xy 338.901024 -282.405836) (xy 338.900526 -282.432485)
			(xy 338.892583 -282.485189) (xy 338.876873 -282.536119) (xy 338.853747 -282.58414) (xy 338.823723 -282.628177)
			(xy 338.787471 -282.667248) (xy 338.7458 -282.700479) (xy 338.699642 -282.727128) (xy 338.650028 -282.7466)
			(xy 338.598066 -282.75846) (xy 338.544916 -282.762444) (xy 338.491766 -282.75846) (xy 338.439804 -282.7466)
			(xy 338.39019 -282.727128) (xy 338.344032 -282.700479) (xy 338.302361 -282.667248) (xy 338.266109 -282.628177)
			(xy 338.236085 -282.58414) (xy 338.212959 -282.536119) (xy 338.197249 -282.485189) (xy 338.189306 -282.432485)
			(xy 337.959744 -282.432485) (xy 337.95776 -282.458953) (xy 337.9459 -282.51092) (xy 337.926427 -282.560538)
			(xy 337.899776 -282.606699) (xy 337.866543 -282.648374) (xy 337.827471 -282.684629) (xy 337.783431 -282.714657)
			(xy 337.735408 -282.737786) (xy 337.684474 -282.753499) (xy 337.631767 -282.761445) (xy 337.605116 -282.761944)
			(xy 337.580102 -282.761514) (xy 337.530563 -282.75453) (xy 337.482489 -282.740685) (xy 337.436825 -282.720249)
			(xy 337.39447 -282.693625) (xy 337.356256 -282.661336) (xy 337.322936 -282.624019) (xy 337.308698 -282.603448)
			(xy 336.961734 -282.603448) (xy 336.947487 -282.624012) (xy 336.914162 -282.661322) (xy 336.875947 -282.693606)
			(xy 336.833593 -282.720229) (xy 336.787933 -282.740669) (xy 336.739864 -282.754523) (xy 336.690329 -282.76152)
			(xy 336.665316 -282.761944) (xy 336.638667 -282.7614) (xy 336.585963 -282.753458) (xy 336.535032 -282.73775)
			(xy 336.487011 -282.714627) (xy 336.442973 -282.684604) (xy 336.403902 -282.648352) (xy 336.37067 -282.606683)
			(xy 336.34402 -282.560525) (xy 336.324547 -282.510911) (xy 336.312687 -282.458949) (xy 336.308704 -282.4058)
			(xy 336.081369 -282.4058) (xy 336.08137 -282.405836) (xy 336.080983 -282.429081) (xy 336.074944 -282.475176)
			(xy 336.06296 -282.520094) (xy 336.054446 -282.541726) (xy 336.044794 -282.56484) (xy 336.217514 -282.863544)
			(xy 336.242152 -282.866846) (xy 336.26749 -282.870696) (xy 336.316792 -282.884687) (xy 336.363581 -282.905598)
			(xy 336.40689 -282.932997) (xy 336.445827 -282.966319) (xy 336.479588 -283.004877) (xy 336.507475 -283.047874)
			(xy 336.528914 -283.094423) (xy 336.543462 -283.143564) (xy 336.550818 -283.194282) (xy 336.55127 -283.219906)
			(xy 336.550772 -283.246555) (xy 336.779352 -283.246555) (xy 336.779352 -283.193257) (xy 336.787295 -283.140553)
			(xy 336.803005 -283.089623) (xy 336.826131 -283.041602) (xy 336.856155 -282.997565) (xy 336.892407 -282.958494)
			(xy 336.934078 -282.925263) (xy 336.980236 -282.898614) (xy 337.02985 -282.879142) (xy 337.081812 -282.867282)
			(xy 337.134962 -282.863299) (xy 337.188112 -282.867282) (xy 337.240074 -282.879142) (xy 337.289688 -282.898614)
			(xy 337.335846 -282.925263) (xy 337.377517 -282.958494) (xy 337.413769 -282.997565) (xy 337.443793 -283.041602)
			(xy 337.466919 -283.089623) (xy 337.482629 -283.140553) (xy 337.490572 -283.193257) (xy 337.49107 -283.219906)
			(xy 337.490572 -283.246555) (xy 337.719152 -283.246555) (xy 337.719152 -283.193257) (xy 337.727095 -283.140553)
			(xy 337.742805 -283.089623) (xy 337.765931 -283.041602) (xy 337.795955 -282.997565) (xy 337.832207 -282.958494)
			(xy 337.873878 -282.925263) (xy 337.920036 -282.898614) (xy 337.96965 -282.879142) (xy 338.021612 -282.867282)
			(xy 338.074762 -282.863299) (xy 338.127912 -282.867282) (xy 338.179874 -282.879142) (xy 338.229488 -282.898614)
			(xy 338.275646 -282.925263) (xy 338.317317 -282.958494) (xy 338.353569 -282.997565) (xy 338.383593 -283.041602)
			(xy 338.406719 -283.089623) (xy 338.422429 -283.140553) (xy 338.430372 -283.193257) (xy 338.43087 -283.219906)
			(xy 338.658454 -283.219906) (xy 338.658879 -283.194277) (xy 338.666214 -283.143546) (xy 338.680748 -283.094392)
			(xy 338.70218 -283.047829) (xy 338.730067 -283.004821) (xy 338.763833 -282.966257) (xy 338.802781 -282.932933)
			(xy 338.846104 -282.905538) (xy 338.892908 -282.884638) (xy 338.942225 -282.870666) (xy 338.967572 -282.866846)
			(xy 338.992464 -282.863544) (xy 339.16493 -282.564586) (xy 339.155532 -282.541472) (xy 339.147039 -282.519877)
			(xy 339.135063 -282.475044) (xy 339.129002 -282.429038) (xy 339.128608 -282.405836) (xy 339.129106 -282.379187)
			(xy 339.137049 -282.326483) (xy 339.152759 -282.275553) (xy 339.175885 -282.227532) (xy 339.205909 -282.183495)
			(xy 339.242161 -282.144424) (xy 339.283832 -282.111193) (xy 339.32999 -282.084544) (xy 339.379604 -282.065072)
			(xy 339.431566 -282.053212) (xy 339.484716 -282.049229) (xy 339.537866 -282.053212) (xy 339.589828 -282.065072)
			(xy 339.639442 -282.084544) (xy 339.6856 -282.111193) (xy 339.727271 -282.144424) (xy 339.763523 -282.183495)
			(xy 339.793547 -282.227532) (xy 339.816673 -282.275553) (xy 339.832383 -282.326483) (xy 339.840326 -282.379187)
			(xy 339.840824 -282.405836) (xy 339.840336 -282.431473) (xy 339.84019 -282.432485) (xy 340.068906 -282.432485)
			(xy 340.068906 -282.379187) (xy 340.076849 -282.326483) (xy 340.092559 -282.275553) (xy 340.115685 -282.227532)
			(xy 340.145709 -282.183495) (xy 340.181961 -282.144424) (xy 340.223632 -282.111193) (xy 340.26979 -282.084544)
			(xy 340.319404 -282.065072) (xy 340.371366 -282.053212) (xy 340.424516 -282.049229) (xy 340.477666 -282.053212)
			(xy 340.529628 -282.065072) (xy 340.579242 -282.084544) (xy 340.6254 -282.111193) (xy 340.667071 -282.144424)
			(xy 340.703323 -282.183495) (xy 340.733347 -282.227532) (xy 340.756473 -282.275553) (xy 340.772183 -282.326483)
			(xy 340.780126 -282.379187) (xy 340.780624 -282.405836) (xy 341.008208 -282.405836) (xy 341.0087 -282.380209)
			(xy 341.01603 -282.329483) (xy 341.030557 -282.280333) (xy 341.051983 -282.233773) (xy 341.079863 -282.190767)
			(xy 341.113621 -282.152202) (xy 341.15256 -282.118877) (xy 341.195876 -282.09148) (xy 341.242672 -282.070576)
			(xy 341.291983 -282.056599) (xy 341.317326 -282.052776) (xy 341.341964 -282.049474) (xy 341.51443 -281.751024)
			(xy 341.504778 -281.72791) (xy 341.496265 -281.706277) (xy 341.484277 -281.661359) (xy 341.478231 -281.615265)
			(xy 341.477854 -281.59202) (xy 341.478352 -281.565371) (xy 341.486295 -281.512667) (xy 341.502005 -281.461737)
			(xy 341.525131 -281.413716) (xy 341.555155 -281.369679) (xy 341.591407 -281.330608) (xy 341.633078 -281.297377)
			(xy 341.679236 -281.270728) (xy 341.72885 -281.251256) (xy 341.780812 -281.239396) (xy 341.833962 -281.235413)
			(xy 341.887112 -281.239396) (xy 341.939074 -281.251256) (xy 341.988688 -281.270728) (xy 342.034846 -281.297377)
			(xy 342.076517 -281.330608) (xy 342.112769 -281.369679) (xy 342.142793 -281.413716) (xy 342.165919 -281.461737)
			(xy 342.181629 -281.512667) (xy 342.189572 -281.565371) (xy 342.19007 -281.59202) (xy 342.189677 -281.61764)
			(xy 342.189528 -281.618669) (xy 342.418152 -281.618669) (xy 342.418152 -281.565371) (xy 342.426095 -281.512667)
			(xy 342.441805 -281.461737) (xy 342.464931 -281.413716) (xy 342.494955 -281.369679) (xy 342.531207 -281.330608)
			(xy 342.572878 -281.297377) (xy 342.619036 -281.270728) (xy 342.66865 -281.251256) (xy 342.720612 -281.239396)
			(xy 342.773762 -281.235413) (xy 342.826912 -281.239396) (xy 342.878874 -281.251256) (xy 342.928488 -281.270728)
			(xy 342.974646 -281.297377) (xy 343.016317 -281.330608) (xy 343.052569 -281.369679) (xy 343.082593 -281.413716)
			(xy 343.105719 -281.461737) (xy 343.121429 -281.512667) (xy 343.129372 -281.565371) (xy 343.12987 -281.59202)
			(xy 343.129372 -281.618669) (xy 343.121429 -281.671373) (xy 343.105719 -281.722303) (xy 343.082593 -281.770324)
			(xy 343.052569 -281.814361) (xy 343.016317 -281.853432) (xy 342.974646 -281.886663) (xy 342.928488 -281.913312)
			(xy 342.878874 -281.932784) (xy 342.826912 -281.944644) (xy 342.773762 -281.948628) (xy 342.720612 -281.944644)
			(xy 342.66865 -281.932784) (xy 342.619036 -281.913312) (xy 342.572878 -281.886663) (xy 342.531207 -281.853432)
			(xy 342.494955 -281.814361) (xy 342.464931 -281.770324) (xy 342.441805 -281.722303) (xy 342.426095 -281.671373)
			(xy 342.418152 -281.618669) (xy 342.189528 -281.618669) (xy 342.182357 -281.668354) (xy 342.167842 -281.717495)
			(xy 342.146431 -281.764047) (xy 342.118568 -281.807049) (xy 342.084828 -281.845612) (xy 342.045908 -281.87894)
			(xy 342.002612 -281.906344) (xy 341.955834 -281.927257) (xy 341.906542 -281.941248) (xy 341.881206 -281.94508)
			(xy 341.856314 -281.948382) (xy 341.683848 -282.246832) (xy 341.6935 -282.269946) (xy 341.702028 -282.291573)
			(xy 341.714011 -282.336494) (xy 341.720051 -282.382591) (xy 341.720424 -282.405836) (xy 341.719926 -282.432485)
			(xy 341.948506 -282.432485) (xy 341.948506 -282.379187) (xy 341.956449 -282.326483) (xy 341.972159 -282.275553)
			(xy 341.995285 -282.227532) (xy 342.025309 -282.183495) (xy 342.061561 -282.144424) (xy 342.103232 -282.111193)
			(xy 342.14939 -282.084544) (xy 342.199004 -282.065072) (xy 342.250966 -282.053212) (xy 342.304116 -282.049229)
			(xy 342.357266 -282.053212) (xy 342.409228 -282.065072) (xy 342.458842 -282.084544) (xy 342.505 -282.111193)
			(xy 342.546671 -282.144424) (xy 342.582923 -282.183495) (xy 342.612947 -282.227532) (xy 342.636073 -282.275553)
			(xy 342.651783 -282.326483) (xy 342.659726 -282.379187) (xy 342.660224 -282.405836) (xy 342.887554 -282.405836)
			(xy 342.888006 -282.380208) (xy 342.895337 -282.329478) (xy 342.909867 -282.280324) (xy 342.931296 -282.233762)
			(xy 342.95918 -282.190754) (xy 342.992943 -282.152189) (xy 343.031888 -282.118864) (xy 343.075209 -282.091469)
			(xy 343.122011 -282.070569) (xy 343.171326 -282.056597) (xy 343.196672 -282.052776) (xy 343.22131 -282.049474)
			(xy 343.39403 -281.750516) (xy 343.384378 -281.727402) (xy 343.375906 -281.705851) (xy 343.364024 -281.661095)
			(xy 343.358057 -281.615174) (xy 343.357708 -281.59202) (xy 343.358206 -281.565371) (xy 343.366149 -281.512667)
			(xy 343.381859 -281.461737) (xy 343.404985 -281.413716) (xy 343.435009 -281.369679) (xy 343.471261 -281.330608)
			(xy 343.512932 -281.297377) (xy 343.55909 -281.270728) (xy 343.608704 -281.251256) (xy 343.660666 -281.239396)
			(xy 343.713816 -281.235413) (xy 343.766966 -281.239396) (xy 343.818928 -281.251256) (xy 343.868542 -281.270728)
			(xy 343.9147 -281.297377) (xy 343.956371 -281.330608) (xy 343.992623 -281.369679) (xy 344.022647 -281.413716)
			(xy 344.045773 -281.461737) (xy 344.061483 -281.512667) (xy 344.069426 -281.565371) (xy 344.069924 -281.59202)
			(xy 344.069422 -281.617657) (xy 344.069276 -281.618669) (xy 344.298006 -281.618669) (xy 344.298006 -281.565371)
			(xy 344.305949 -281.512667) (xy 344.321659 -281.461737) (xy 344.344785 -281.413716) (xy 344.374809 -281.369679)
			(xy 344.411061 -281.330608) (xy 344.452732 -281.297377) (xy 344.49889 -281.270728) (xy 344.548504 -281.251256)
			(xy 344.600466 -281.239396) (xy 344.653616 -281.235413) (xy 344.706766 -281.239396) (xy 344.758728 -281.251256)
			(xy 344.808342 -281.270728) (xy 344.8545 -281.297377) (xy 344.896171 -281.330608) (xy 344.932423 -281.369679)
			(xy 344.962447 -281.413716) (xy 344.985573 -281.461737) (xy 345.001283 -281.512667) (xy 345.009226 -281.565371)
			(xy 345.009724 -281.59202) (xy 345.237308 -281.59202) (xy 345.237785 -281.566393) (xy 345.245117 -281.515666)
			(xy 345.259647 -281.466515) (xy 345.281074 -281.419956) (xy 345.308956 -281.376949) (xy 345.342716 -281.338385)
			(xy 345.381657 -281.30506) (xy 345.424973 -281.277663) (xy 345.471771 -281.25676) (xy 345.521082 -281.242783)
			(xy 345.546426 -281.23896) (xy 345.571064 -281.235658) (xy 345.74353 -280.937208) (xy 345.733878 -280.914094)
			(xy 345.725361 -280.892463) (xy 345.713374 -280.847544) (xy 345.70733 -280.801449) (xy 345.706954 -280.778204)
			(xy 345.707452 -280.751555) (xy 345.715395 -280.698851) (xy 345.731105 -280.647921) (xy 345.754231 -280.5999)
			(xy 345.784255 -280.555863) (xy 345.820507 -280.516792) (xy 345.862178 -280.483561) (xy 345.908336 -280.456912)
			(xy 345.95795 -280.43744) (xy 346.009912 -280.42558) (xy 346.063062 -280.421597) (xy 346.116212 -280.42558)
			(xy 346.168174 -280.43744) (xy 346.217788 -280.456912) (xy 346.263946 -280.483561) (xy 346.305617 -280.516792)
			(xy 346.341869 -280.555863) (xy 346.371893 -280.5999) (xy 346.395019 -280.647921) (xy 346.410729 -280.698851)
			(xy 346.418672 -280.751555) (xy 346.41917 -280.778204) (xy 346.418763 -280.803824) (xy 346.418614 -280.804853)
			(xy 346.647252 -280.804853) (xy 346.647252 -280.751555) (xy 346.655195 -280.698851) (xy 346.670905 -280.647921)
			(xy 346.694031 -280.5999) (xy 346.724055 -280.555863) (xy 346.760307 -280.516792) (xy 346.801978 -280.483561)
			(xy 346.848136 -280.456912) (xy 346.89775 -280.43744) (xy 346.949712 -280.42558) (xy 347.002862 -280.421597)
			(xy 347.056012 -280.42558) (xy 347.107974 -280.43744) (xy 347.157588 -280.456912) (xy 347.203746 -280.483561)
			(xy 347.245417 -280.516792) (xy 347.281669 -280.555863) (xy 347.311693 -280.5999) (xy 347.334819 -280.647921)
			(xy 347.350529 -280.698851) (xy 347.358472 -280.751555) (xy 347.35897 -280.778204) (xy 348.526354 -280.778204)
			(xy 348.526852 -280.751555) (xy 348.534795 -280.698851) (xy 348.550505 -280.647921) (xy 348.573631 -280.5999)
			(xy 348.603655 -280.555863) (xy 348.639907 -280.516792) (xy 348.681578 -280.483561) (xy 348.727736 -280.456912)
			(xy 348.77735 -280.43744) (xy 348.829312 -280.42558) (xy 348.882462 -280.421597) (xy 348.935612 -280.42558)
			(xy 348.987574 -280.43744) (xy 349.037188 -280.456912) (xy 349.083346 -280.483561) (xy 349.125017 -280.516792)
			(xy 349.161269 -280.555863) (xy 349.191293 -280.5999) (xy 349.214419 -280.647921) (xy 349.230129 -280.698851)
			(xy 349.238072 -280.751555) (xy 349.23857 -280.778204) (xy 349.238202 -280.801356) (xy 349.237746 -280.804853)
			(xy 349.466652 -280.804853) (xy 349.466652 -280.751555) (xy 349.474595 -280.698851) (xy 349.490305 -280.647921)
			(xy 349.513431 -280.5999) (xy 349.543455 -280.555863) (xy 349.579707 -280.516792) (xy 349.621378 -280.483561)
			(xy 349.667536 -280.456912) (xy 349.71715 -280.43744) (xy 349.769112 -280.42558) (xy 349.822262 -280.421597)
			(xy 349.875412 -280.42558) (xy 349.927374 -280.43744) (xy 349.976988 -280.456912) (xy 350.023146 -280.483561)
			(xy 350.064817 -280.516792) (xy 350.101069 -280.555863) (xy 350.131093 -280.5999) (xy 350.154219 -280.647921)
			(xy 350.169929 -280.698851) (xy 350.177872 -280.751555) (xy 350.17837 -280.778204) (xy 350.177872 -280.804853)
			(xy 350.406706 -280.804853) (xy 350.406706 -280.751555) (xy 350.414649 -280.698851) (xy 350.430359 -280.647921)
			(xy 350.453485 -280.5999) (xy 350.483509 -280.555863) (xy 350.519761 -280.516792) (xy 350.561432 -280.483561)
			(xy 350.60759 -280.456912) (xy 350.657204 -280.43744) (xy 350.709166 -280.42558) (xy 350.762316 -280.421597)
			(xy 350.815466 -280.42558) (xy 350.867428 -280.43744) (xy 350.917042 -280.456912) (xy 350.9632 -280.483561)
			(xy 351.004871 -280.516792) (xy 351.041123 -280.555863) (xy 351.071147 -280.5999) (xy 351.094273 -280.647921)
			(xy 351.109983 -280.698851) (xy 351.117926 -280.751555) (xy 351.118424 -280.778204) (xy 351.345754 -280.778204)
			(xy 351.346252 -280.751555) (xy 351.354195 -280.698851) (xy 351.369905 -280.647921) (xy 351.393031 -280.5999)
			(xy 351.423055 -280.555863) (xy 351.459307 -280.516792) (xy 351.500978 -280.483561) (xy 351.547136 -280.456912)
			(xy 351.59675 -280.43744) (xy 351.648712 -280.42558) (xy 351.701862 -280.421597) (xy 351.755012 -280.42558)
			(xy 351.806974 -280.43744) (xy 351.856588 -280.456912) (xy 351.902746 -280.483561) (xy 351.944417 -280.516792)
			(xy 351.980669 -280.555863) (xy 352.010693 -280.5999) (xy 352.033819 -280.647921) (xy 352.049529 -280.698851)
			(xy 352.057472 -280.751555) (xy 352.05797 -280.778204) (xy 352.285554 -280.778204) (xy 352.285977 -280.752575)
			(xy 352.293312 -280.701844) (xy 352.307846 -280.65269) (xy 352.329279 -280.606127) (xy 352.357166 -280.563119)
			(xy 352.390933 -280.524555) (xy 352.42988 -280.49123) (xy 352.473204 -280.463836) (xy 352.520008 -280.442936)
			(xy 352.569325 -280.428964) (xy 352.594672 -280.425144) (xy 352.61931 -280.421842) (xy 352.79203 -280.122884)
			(xy 352.782632 -280.09977) (xy 352.774139 -280.078175) (xy 352.762163 -280.033343) (xy 352.756102 -279.987336)
			(xy 352.755708 -279.964134) (xy 352.756206 -279.937485) (xy 352.764149 -279.884781) (xy 352.779859 -279.833851)
			(xy 352.802985 -279.78583) (xy 352.833009 -279.741793) (xy 352.869261 -279.702722) (xy 352.910932 -279.669491)
			(xy 352.95709 -279.642842) (xy 353.006704 -279.62337) (xy 353.058666 -279.61151) (xy 353.111816 -279.607527)
			(xy 353.164966 -279.61151) (xy 353.216928 -279.62337) (xy 353.266542 -279.642842) (xy 353.3127 -279.669491)
			(xy 353.354371 -279.702722) (xy 353.390623 -279.741793) (xy 353.420647 -279.78583) (xy 353.443773 -279.833851)
			(xy 353.459483 -279.884781) (xy 353.467426 -279.937485) (xy 353.467924 -279.964134) (xy 353.467434 -279.989771)
			(xy 353.467288 -279.990783) (xy 353.696006 -279.990783) (xy 353.696006 -279.937485) (xy 353.703949 -279.884781)
			(xy 353.719659 -279.833851) (xy 353.742785 -279.78583) (xy 353.772809 -279.741793) (xy 353.809061 -279.702722)
			(xy 353.850732 -279.669491) (xy 353.89689 -279.642842) (xy 353.946504 -279.62337) (xy 353.998466 -279.61151)
			(xy 354.051616 -279.607527) (xy 354.104766 -279.61151) (xy 354.156728 -279.62337) (xy 354.206342 -279.642842)
			(xy 354.2525 -279.669491) (xy 354.294171 -279.702722) (xy 354.330423 -279.741793) (xy 354.360447 -279.78583)
			(xy 354.383573 -279.833851) (xy 354.399283 -279.884781) (xy 354.407226 -279.937485) (xy 354.407724 -279.964134)
			(xy 354.407226 -279.990783) (xy 354.399283 -280.043487) (xy 354.383573 -280.094417) (xy 354.360447 -280.142438)
			(xy 354.330423 -280.186475) (xy 354.294171 -280.225546) (xy 354.2525 -280.258777) (xy 354.206342 -280.285426)
			(xy 354.156728 -280.304898) (xy 354.104766 -280.316758) (xy 354.051616 -280.320742) (xy 353.998466 -280.316758)
			(xy 353.946504 -280.304898) (xy 353.89689 -280.285426) (xy 353.850732 -280.258777) (xy 353.809061 -280.225546)
			(xy 353.772809 -280.186475) (xy 353.742785 -280.142438) (xy 353.719659 -280.094417) (xy 353.703949 -280.043487)
			(xy 353.696006 -279.990783) (xy 353.467288 -279.990783) (xy 353.460089 -280.040517) (xy 353.445542 -280.089684)
			(xy 353.424092 -280.136257) (xy 353.396184 -280.179271) (xy 353.362395 -280.217837) (xy 353.323424 -280.251159)
			(xy 353.280076 -280.278545) (xy 353.233248 -280.299431) (xy 353.183909 -280.313385) (xy 353.158552 -280.317194)
			(xy 353.133914 -280.320496) (xy 352.961194 -280.6192) (xy 352.970846 -280.642314) (xy 352.979362 -280.663946)
			(xy 352.99135 -280.708864) (xy 352.997395 -280.754959) (xy 352.99777 -280.778204) (xy 352.997272 -280.804853)
			(xy 352.989329 -280.857557) (xy 352.973619 -280.908487) (xy 352.950493 -280.956508) (xy 352.920469 -281.000545)
			(xy 352.884217 -281.039616) (xy 352.842546 -281.072847) (xy 352.796388 -281.099496) (xy 352.746774 -281.118968)
			(xy 352.694812 -281.130828) (xy 352.641662 -281.134812) (xy 352.588512 -281.130828) (xy 352.53655 -281.118968)
			(xy 352.486936 -281.099496) (xy 352.440778 -281.072847) (xy 352.399107 -281.039616) (xy 352.362855 -281.000545)
			(xy 352.332831 -280.956508) (xy 352.309705 -280.908487) (xy 352.293995 -280.857557) (xy 352.286052 -280.804853)
			(xy 352.285554 -280.778204) (xy 352.05797 -280.778204) (xy 352.057602 -280.801356) (xy 352.051614 -280.84727)
			(xy 352.03974 -280.892025) (xy 352.0313 -280.913586) (xy 352.021648 -280.9367) (xy 352.194368 -281.235658)
			(xy 352.219006 -281.23896) (xy 352.24434 -281.242833) (xy 352.293643 -281.256818) (xy 352.340433 -281.277725)
			(xy 352.383744 -281.30512) (xy 352.422682 -281.33844) (xy 352.456444 -281.376995) (xy 352.484332 -281.41999)
			(xy 352.505771 -281.466539) (xy 352.520318 -281.515679) (xy 352.527673 -281.566396) (xy 352.528124 -281.59202)
			(xy 352.527626 -281.618669) (xy 352.756206 -281.618669) (xy 352.756206 -281.565371) (xy 352.764149 -281.512667)
			(xy 352.779859 -281.461737) (xy 352.802985 -281.413716) (xy 352.833009 -281.369679) (xy 352.869261 -281.330608)
			(xy 352.910932 -281.297377) (xy 352.95709 -281.270728) (xy 353.006704 -281.251256) (xy 353.058666 -281.239396)
			(xy 353.111816 -281.235413) (xy 353.164966 -281.239396) (xy 353.216928 -281.251256) (xy 353.266542 -281.270728)
			(xy 353.3127 -281.297377) (xy 353.354371 -281.330608) (xy 353.390623 -281.369679) (xy 353.420647 -281.413716)
			(xy 353.443773 -281.461737) (xy 353.459483 -281.512667) (xy 353.467426 -281.565371) (xy 353.467924 -281.59202)
			(xy 353.467426 -281.618669) (xy 353.459483 -281.671373) (xy 353.443773 -281.722303) (xy 353.420647 -281.770324)
			(xy 353.390623 -281.814361) (xy 353.354371 -281.853432) (xy 353.3127 -281.886663) (xy 353.266542 -281.913312)
			(xy 353.216928 -281.932784) (xy 353.164966 -281.944644) (xy 353.111816 -281.948628) (xy 353.058666 -281.944644)
			(xy 353.006704 -281.932784) (xy 352.95709 -281.913312) (xy 352.910932 -281.886663) (xy 352.869261 -281.853432)
			(xy 352.833009 -281.814361) (xy 352.802985 -281.770324) (xy 352.779859 -281.722303) (xy 352.764149 -281.671373)
			(xy 352.756206 -281.618669) (xy 352.527626 -281.618669) (xy 352.519683 -281.671373) (xy 352.503973 -281.722303)
			(xy 352.480847 -281.770324) (xy 352.450823 -281.814361) (xy 352.414571 -281.853432) (xy 352.3729 -281.886663)
			(xy 352.326742 -281.913312) (xy 352.277128 -281.932784) (xy 352.225166 -281.944644) (xy 352.172016 -281.948628)
			(xy 352.118866 -281.944644) (xy 352.066904 -281.932784) (xy 352.01729 -281.913312) (xy 351.971132 -281.886663)
			(xy 351.929461 -281.853432) (xy 351.893209 -281.814361) (xy 351.863185 -281.770324) (xy 351.840059 -281.722303)
			(xy 351.824349 -281.671373) (xy 351.816406 -281.618669) (xy 351.815908 -281.59202) (xy 351.816283 -281.568775)
			(xy 351.822327 -281.52268) (xy 351.834315 -281.477762) (xy 351.842832 -281.45613) (xy 351.852484 -281.433016)
			(xy 351.680018 -281.134566) (xy 351.655126 -281.131264) (xy 351.629769 -281.127452) (xy 351.580428 -281.113497)
			(xy 351.533598 -281.092611) (xy 351.490248 -281.065224) (xy 351.451273 -281.031904) (xy 351.41748 -280.993339)
			(xy 351.389567 -280.950326) (xy 351.36811 -280.903755) (xy 351.353555 -280.854588) (xy 351.346201 -280.803842)
			(xy 351.345754 -280.778204) (xy 351.118424 -280.778204) (xy 351.117926 -280.804853) (xy 351.109983 -280.857557)
			(xy 351.094273 -280.908487) (xy 351.071147 -280.956508) (xy 351.041123 -281.000545) (xy 351.004871 -281.039616)
			(xy 350.9632 -281.072847) (xy 350.917042 -281.099496) (xy 350.867428 -281.118968) (xy 350.815466 -281.130828)
			(xy 350.762316 -281.134812) (xy 350.709166 -281.130828) (xy 350.657204 -281.118968) (xy 350.60759 -281.099496)
			(xy 350.561432 -281.072847) (xy 350.519761 -281.039616) (xy 350.483509 -281.000545) (xy 350.453485 -280.956508)
			(xy 350.430359 -280.908487) (xy 350.414649 -280.857557) (xy 350.406706 -280.804853) (xy 350.177872 -280.804853)
			(xy 350.169929 -280.857557) (xy 350.154219 -280.908487) (xy 350.131093 -280.956508) (xy 350.101069 -281.000545)
			(xy 350.064817 -281.039616) (xy 350.023146 -281.072847) (xy 349.976988 -281.099496) (xy 349.927374 -281.118968)
			(xy 349.875412 -281.130828) (xy 349.822262 -281.134812) (xy 349.769112 -281.130828) (xy 349.71715 -281.118968)
			(xy 349.667536 -281.099496) (xy 349.621378 -281.072847) (xy 349.579707 -281.039616) (xy 349.543455 -281.000545)
			(xy 349.513431 -280.956508) (xy 349.490305 -280.908487) (xy 349.474595 -280.857557) (xy 349.466652 -280.804853)
			(xy 349.237746 -280.804853) (xy 349.232214 -280.84727) (xy 349.22034 -280.892025) (xy 349.2119 -280.913586)
			(xy 349.202248 -280.9367) (xy 349.374968 -281.235658) (xy 349.399606 -281.23896) (xy 349.42494 -281.242833)
			(xy 349.474243 -281.256818) (xy 349.521033 -281.277725) (xy 349.564344 -281.30512) (xy 349.603282 -281.33844)
			(xy 349.637044 -281.376995) (xy 349.664932 -281.41999) (xy 349.686371 -281.466539) (xy 349.700918 -281.515679)
			(xy 349.708273 -281.566396) (xy 349.708724 -281.59202) (xy 349.708226 -281.618669) (xy 349.700283 -281.671373)
			(xy 349.684573 -281.722303) (xy 349.661447 -281.770324) (xy 349.631423 -281.814361) (xy 349.595171 -281.853432)
			(xy 349.5535 -281.886663) (xy 349.507342 -281.913312) (xy 349.457728 -281.932784) (xy 349.405766 -281.944644)
			(xy 349.352616 -281.948628) (xy 349.299466 -281.944644) (xy 349.247504 -281.932784) (xy 349.19789 -281.913312)
			(xy 349.151732 -281.886663) (xy 349.110061 -281.853432) (xy 349.073809 -281.814361) (xy 349.043785 -281.770324)
			(xy 349.020659 -281.722303) (xy 349.004949 -281.671373) (xy 348.997006 -281.618669) (xy 348.996508 -281.59202)
			(xy 348.996883 -281.568775) (xy 349.002927 -281.52268) (xy 349.014915 -281.477762) (xy 349.023432 -281.45613)
			(xy 349.033084 -281.433016) (xy 348.860618 -281.134566) (xy 348.835726 -281.131264) (xy 348.810369 -281.127452)
			(xy 348.761028 -281.113497) (xy 348.714198 -281.092611) (xy 348.670848 -281.065224) (xy 348.631873 -281.031904)
			(xy 348.59808 -280.993339) (xy 348.570167 -280.950326) (xy 348.54871 -280.903755) (xy 348.534155 -280.854588)
			(xy 348.526801 -280.803842) (xy 348.526354 -280.778204) (xy 347.35897 -280.778204) (xy 347.358472 -280.804853)
			(xy 347.350529 -280.857557) (xy 347.334819 -280.908487) (xy 347.311693 -280.956508) (xy 347.281669 -281.000545)
			(xy 347.245417 -281.039616) (xy 347.203746 -281.072847) (xy 347.157588 -281.099496) (xy 347.107974 -281.118968)
			(xy 347.056012 -281.130828) (xy 347.002862 -281.134812) (xy 346.949712 -281.130828) (xy 346.89775 -281.118968)
			(xy 346.848136 -281.099496) (xy 346.801978 -281.072847) (xy 346.760307 -281.039616) (xy 346.724055 -281.000545)
			(xy 346.694031 -280.956508) (xy 346.670905 -280.908487) (xy 346.655195 -280.857557) (xy 346.647252 -280.804853)
			(xy 346.418614 -280.804853) (xy 346.411444 -280.854537) (xy 346.396931 -280.903678) (xy 346.375523 -280.95023)
			(xy 346.347662 -280.993232) (xy 346.313923 -281.031795) (xy 346.275004 -281.065123) (xy 346.231709 -281.092527)
			(xy 346.184933 -281.113441) (xy 346.135641 -281.127432) (xy 346.110306 -281.131264) (xy 346.085414 -281.134566)
			(xy 345.912948 -281.433016) (xy 345.9226 -281.45613) (xy 345.931124 -281.477759) (xy 345.943108 -281.522679)
			(xy 345.94915 -281.568775) (xy 345.949524 -281.59202) (xy 345.949026 -281.618669) (xy 346.177606 -281.618669)
			(xy 346.177606 -281.565371) (xy 346.185549 -281.512667) (xy 346.201259 -281.461737) (xy 346.224385 -281.413716)
			(xy 346.254409 -281.369679) (xy 346.290661 -281.330608) (xy 346.332332 -281.297377) (xy 346.37849 -281.270728)
			(xy 346.428104 -281.251256) (xy 346.480066 -281.239396) (xy 346.533216 -281.235413) (xy 346.586366 -281.239396)
			(xy 346.638328 -281.251256) (xy 346.687942 -281.270728) (xy 346.7341 -281.297377) (xy 346.775771 -281.330608)
			(xy 346.812023 -281.369679) (xy 346.842047 -281.413716) (xy 346.865173 -281.461737) (xy 346.880883 -281.512667)
			(xy 346.888826 -281.565371) (xy 346.889324 -281.592) (xy 347.116388 -281.592) (xy 347.120371 -281.538848)
			(xy 347.132232 -281.486884) (xy 347.151706 -281.437268) (xy 347.178357 -281.391108) (xy 347.21159 -281.349437)
			(xy 347.250663 -281.313184) (xy 347.294703 -281.28316) (xy 347.342726 -281.260035) (xy 347.39366 -281.244326)
			(xy 347.446366 -281.236384) (xy 347.473016 -281.235912) (xy 347.49803 -281.236337) (xy 347.547568 -281.243324)
			(xy 347.595641 -281.257172) (xy 347.641305 -281.27761) (xy 347.68366 -281.304234) (xy 347.721874 -281.336521)
			(xy 347.755195 -281.373838) (xy 347.769434 -281.394408) (xy 348.116398 -281.394408) (xy 348.13061 -281.373819)
			(xy 348.163943 -281.336512) (xy 348.202164 -281.304231) (xy 348.244524 -281.277611) (xy 348.290189 -281.257176)
			(xy 348.338263 -281.243326) (xy 348.387801 -281.236333) (xy 348.412816 -281.235912) (xy 348.439466 -281.236371)
			(xy 348.49217 -281.244317) (xy 348.543102 -281.260029) (xy 348.591123 -281.283157) (xy 348.635161 -281.313183)
			(xy 348.674232 -281.349437) (xy 348.707463 -281.39111) (xy 348.734112 -281.437269) (xy 348.753584 -281.486885)
			(xy 348.765444 -281.538849) (xy 348.769428 -281.592) (xy 348.765444 -281.645151) (xy 348.753584 -281.697115)
			(xy 348.734112 -281.746731) (xy 348.707463 -281.79289) (xy 348.674232 -281.834563) (xy 348.635161 -281.870817)
			(xy 348.591123 -281.900843) (xy 348.543102 -281.923971) (xy 348.49217 -281.939683) (xy 348.439466 -281.947629)
			(xy 348.412816 -281.948128) (xy 348.387801 -281.947705) (xy 348.338262 -281.940721) (xy 348.290188 -281.926875)
			(xy 348.244524 -281.906438) (xy 348.202168 -281.879812) (xy 348.163955 -281.847523) (xy 348.130635 -281.810204)
			(xy 348.116398 -281.789632) (xy 347.769434 -281.789632) (xy 347.755214 -281.810215) (xy 347.721881 -281.847521)
			(xy 347.68366 -281.8798) (xy 347.641302 -281.90642) (xy 347.595639 -281.926857) (xy 347.547567 -281.940709)
			(xy 347.49803 -281.947705) (xy 347.473016 -281.948128) (xy 347.446366 -281.947616) (xy 347.39366 -281.939674)
			(xy 347.342726 -281.923965) (xy 347.294703 -281.90084) (xy 347.250663 -281.870816) (xy 347.21159 -281.834563)
			(xy 347.178357 -281.792892) (xy 347.151706 -281.746732) (xy 347.132232 -281.697116) (xy 347.120371 -281.645152)
			(xy 347.116388 -281.592) (xy 346.889324 -281.592) (xy 346.889324 -281.59202) (xy 346.888826 -281.618669)
			(xy 346.880883 -281.671373) (xy 346.865173 -281.722303) (xy 346.842047 -281.770324) (xy 346.812023 -281.814361)
			(xy 346.775771 -281.853432) (xy 346.7341 -281.886663) (xy 346.687942 -281.913312) (xy 346.638328 -281.932784)
			(xy 346.586366 -281.944644) (xy 346.533216 -281.948628) (xy 346.480066 -281.944644) (xy 346.428104 -281.932784)
			(xy 346.37849 -281.913312) (xy 346.332332 -281.886663) (xy 346.290661 -281.853432) (xy 346.254409 -281.814361)
			(xy 346.224385 -281.770324) (xy 346.201259 -281.722303) (xy 346.185549 -281.671373) (xy 346.177606 -281.618669)
			(xy 345.949026 -281.618669) (xy 345.941083 -281.671373) (xy 345.925373 -281.722303) (xy 345.902247 -281.770324)
			(xy 345.872223 -281.814361) (xy 345.835971 -281.853432) (xy 345.7943 -281.886663) (xy 345.748142 -281.913312)
			(xy 345.698528 -281.932784) (xy 345.646566 -281.944644) (xy 345.593416 -281.948628) (xy 345.540266 -281.944644)
			(xy 345.488304 -281.932784) (xy 345.43869 -281.913312) (xy 345.392532 -281.886663) (xy 345.350861 -281.853432)
			(xy 345.314609 -281.814361) (xy 345.284585 -281.770324) (xy 345.261459 -281.722303) (xy 345.245749 -281.671373)
			(xy 345.237806 -281.618669) (xy 345.237308 -281.59202) (xy 345.009724 -281.59202) (xy 345.009226 -281.618669)
			(xy 345.001283 -281.671373) (xy 344.985573 -281.722303) (xy 344.962447 -281.770324) (xy 344.932423 -281.814361)
			(xy 344.896171 -281.853432) (xy 344.8545 -281.886663) (xy 344.808342 -281.913312) (xy 344.758728 -281.932784)
			(xy 344.706766 -281.944644) (xy 344.653616 -281.948628) (xy 344.600466 -281.944644) (xy 344.548504 -281.932784)
			(xy 344.49889 -281.913312) (xy 344.452732 -281.886663) (xy 344.411061 -281.853432) (xy 344.374809 -281.814361)
			(xy 344.344785 -281.770324) (xy 344.321659 -281.722303) (xy 344.305949 -281.671373) (xy 344.298006 -281.618669)
			(xy 344.069276 -281.618669) (xy 344.062078 -281.668402) (xy 344.047532 -281.717569) (xy 344.026084 -281.764141)
			(xy 343.998178 -281.807156) (xy 343.96439 -281.845722) (xy 343.92542 -281.879044) (xy 343.882074 -281.906431)
			(xy 343.835247 -281.927317) (xy 343.785908 -281.941271) (xy 343.760552 -281.94508) (xy 343.73566 -281.948382)
			(xy 343.563194 -282.246832) (xy 343.572846 -282.269946) (xy 343.581372 -282.291574) (xy 343.593356 -282.336494)
			(xy 343.599397 -282.382591) (xy 343.59977 -282.405836) (xy 343.827354 -282.405836) (xy 343.827852 -282.379187)
			(xy 343.835795 -282.326483) (xy 343.851505 -282.275553) (xy 343.874631 -282.227532) (xy 343.904655 -282.183495)
			(xy 343.940907 -282.144424) (xy 343.982578 -282.111193) (xy 344.028736 -282.084544) (xy 344.07835 -282.065072)
			(xy 344.130312 -282.053212) (xy 344.183462 -282.049229) (xy 344.236612 -282.053212) (xy 344.288574 -282.065072)
			(xy 344.338188 -282.084544) (xy 344.384346 -282.111193) (xy 344.426017 -282.144424) (xy 344.462269 -282.183495)
			(xy 344.492293 -282.227532) (xy 344.515419 -282.275553) (xy 344.531129 -282.326483) (xy 344.539072 -282.379187)
			(xy 344.539569 -282.4058) (xy 344.766729 -282.4058) (xy 344.770711 -282.352659) (xy 344.782568 -282.300706)
			(xy 344.802036 -282.251099) (xy 344.828679 -282.204948) (xy 344.861903 -282.163283) (xy 344.900965 -282.127035)
			(xy 344.944993 -282.097013) (xy 344.993003 -282.073888) (xy 345.043924 -282.058176) (xy 345.096617 -282.050229)
			(xy 345.123262 -282.049728) (xy 345.148278 -282.050111) (xy 345.197818 -282.057105) (xy 345.245892 -282.07096)
			(xy 345.291556 -282.091404) (xy 345.333911 -282.118035) (xy 345.372123 -282.150329) (xy 345.405443 -282.187651)
			(xy 345.41968 -282.208224) (xy 345.766644 -282.208224) (xy 345.780896 -282.187664) (xy 345.814221 -282.150355)
			(xy 345.852436 -282.118072) (xy 345.894789 -282.091449) (xy 345.940448 -282.071008) (xy 345.988516 -282.057152)
			(xy 346.038049 -282.050153) (xy 346.063062 -282.049728) (xy 346.089718 -282.050127) (xy 346.142434 -282.058067)
			(xy 346.193378 -282.073777) (xy 346.241412 -282.096904) (xy 346.285462 -282.126932) (xy 346.324544 -282.163191)
			(xy 346.357785 -282.20487) (xy 346.384442 -282.251038) (xy 346.40392 -282.300663) (xy 346.415784 -282.352638)
			(xy 346.419768 -282.4058) (xy 346.417768 -282.432485) (xy 346.647252 -282.432485) (xy 346.647252 -282.379187)
			(xy 346.655195 -282.326483) (xy 346.670905 -282.275553) (xy 346.694031 -282.227532) (xy 346.724055 -282.183495)
			(xy 346.760307 -282.144424) (xy 346.801978 -282.111193) (xy 346.848136 -282.084544) (xy 346.89775 -282.065072)
			(xy 346.949712 -282.053212) (xy 347.002862 -282.049229) (xy 347.056012 -282.053212) (xy 347.107974 -282.065072)
			(xy 347.157588 -282.084544) (xy 347.203746 -282.111193) (xy 347.245417 -282.144424) (xy 347.281669 -282.183495)
			(xy 347.311693 -282.227532) (xy 347.334819 -282.275553) (xy 347.350529 -282.326483) (xy 347.358472 -282.379187)
			(xy 347.35897 -282.405836) (xy 347.358472 -282.432485) (xy 347.350529 -282.485189) (xy 347.334819 -282.536119)
			(xy 347.311693 -282.58414) (xy 347.281669 -282.628177) (xy 347.245417 -282.667248) (xy 347.203746 -282.700479)
			(xy 347.157588 -282.727128) (xy 347.107974 -282.7466) (xy 347.056012 -282.75846) (xy 347.002862 -282.762444)
			(xy 346.949712 -282.75846) (xy 346.89775 -282.7466) (xy 346.848136 -282.727128) (xy 346.801978 -282.700479)
			(xy 346.760307 -282.667248) (xy 346.724055 -282.628177) (xy 346.694031 -282.58414) (xy 346.670905 -282.536119)
			(xy 346.655195 -282.485189) (xy 346.647252 -282.432485) (xy 346.417768 -282.432485) (xy 346.415784 -282.458962)
			(xy 346.40392 -282.510937) (xy 346.384442 -282.560562) (xy 346.357785 -282.60673) (xy 346.324544 -282.648409)
			(xy 346.285462 -282.684668) (xy 346.241412 -282.714696) (xy 346.193378 -282.737823) (xy 346.142434 -282.753533)
			(xy 346.089718 -282.761473) (xy 346.063062 -282.761944) (xy 346.038046 -282.761555) (xy 345.988506 -282.754564)
			(xy 345.940431 -282.740711) (xy 345.894767 -282.720268) (xy 345.852412 -282.693638) (xy 345.8142 -282.661344)
			(xy 345.780881 -282.624022) (xy 345.766644 -282.603448) (xy 345.41968 -282.603448) (xy 345.405404 -282.62399)
			(xy 345.372083 -282.661301) (xy 345.333873 -282.693586) (xy 345.291525 -282.720212) (xy 345.245869 -282.740655)
			(xy 345.197804 -282.754514) (xy 345.148274 -282.761517) (xy 345.123262 -282.761944) (xy 345.096617 -282.761371)
			(xy 345.043924 -282.753424) (xy 344.993003 -282.737712) (xy 344.944993 -282.714587) (xy 344.900965 -282.684565)
			(xy 344.861903 -282.648317) (xy 344.828679 -282.606652) (xy 344.802036 -282.560501) (xy 344.782568 -282.510894)
			(xy 344.770711 -282.458941) (xy 344.766729 -282.4058) (xy 344.539569 -282.4058) (xy 344.53957 -282.405836)
			(xy 344.539203 -282.42904) (xy 344.533148 -282.475051) (xy 344.521159 -282.519883) (xy 344.512646 -282.541472)
			(xy 344.503248 -282.564586) (xy 344.675968 -282.863544) (xy 344.700606 -282.866846) (xy 344.725938 -282.870732)
			(xy 344.77524 -282.884717) (xy 344.822029 -282.905622) (xy 344.865339 -282.933017) (xy 344.904277 -282.966334)
			(xy 344.938038 -283.004888) (xy 344.965927 -283.047882) (xy 344.987367 -283.094428) (xy 345.001915 -283.143567)
			(xy 345.009272 -283.194283) (xy 345.009724 -283.219906) (xy 345.009226 -283.246555) (xy 345.237552 -283.246555)
			(xy 345.237552 -283.193257) (xy 345.245495 -283.140553) (xy 345.261205 -283.089623) (xy 345.284331 -283.041602)
			(xy 345.314355 -282.997565) (xy 345.350607 -282.958494) (xy 345.392278 -282.925263) (xy 345.438436 -282.898614)
			(xy 345.48805 -282.879142) (xy 345.540012 -282.867282) (xy 345.593162 -282.863299) (xy 345.646312 -282.867282)
			(xy 345.698274 -282.879142) (xy 345.747888 -282.898614) (xy 345.794046 -282.925263) (xy 345.835717 -282.958494)
			(xy 345.871969 -282.997565) (xy 345.901993 -283.041602) (xy 345.925119 -283.089623) (xy 345.940829 -283.140553)
			(xy 345.948772 -283.193257) (xy 345.94927 -283.219906) (xy 345.948772 -283.246555) (xy 346.177352 -283.246555)
			(xy 346.177352 -283.193257) (xy 346.185295 -283.140553) (xy 346.201005 -283.089623) (xy 346.224131 -283.041602)
			(xy 346.254155 -282.997565) (xy 346.290407 -282.958494) (xy 346.332078 -282.925263) (xy 346.378236 -282.898614)
			(xy 346.42785 -282.879142) (xy 346.479812 -282.867282) (xy 346.532962 -282.863299) (xy 346.586112 -282.867282)
			(xy 346.638074 -282.879142) (xy 346.687688 -282.898614) (xy 346.733846 -282.925263) (xy 346.775517 -282.958494)
			(xy 346.811769 -282.997565) (xy 346.841793 -283.041602) (xy 346.864919 -283.089623) (xy 346.880629 -283.140553)
			(xy 346.888572 -283.193257) (xy 346.88907 -283.219906) (xy 347.116908 -283.219906) (xy 347.117372 -283.194279)
			(xy 347.124706 -283.143552) (xy 347.139238 -283.0944) (xy 347.160667 -283.04784) (xy 347.18855 -283.004834)
			(xy 347.222311 -282.96627) (xy 347.261253 -282.932945) (xy 347.304571 -282.905548) (xy 347.35137 -282.884646)
			(xy 347.400682 -282.870669) (xy 347.426026 -282.866846) (xy 347.450664 -282.863544) (xy 347.62313 -282.565094)
			(xy 347.613478 -282.54198) (xy 347.604963 -282.520303) (xy 347.592962 -282.475302) (xy 347.586921 -282.429123)
			(xy 347.586554 -282.405836) (xy 347.587052 -282.379187) (xy 347.594995 -282.326483) (xy 347.610705 -282.275553)
			(xy 347.633831 -282.227532) (xy 347.663855 -282.183495) (xy 347.700107 -282.144424) (xy 347.741778 -282.111193)
			(xy 347.787936 -282.084544) (xy 347.83755 -282.065072) (xy 347.889512 -282.053212) (xy 347.942662 -282.049229)
			(xy 347.995812 -282.053212) (xy 348.047774 -282.065072) (xy 348.097388 -282.084544) (xy 348.143546 -282.111193)
			(xy 348.185217 -282.144424) (xy 348.221469 -282.183495) (xy 348.251493 -282.227532) (xy 348.274619 -282.275553)
			(xy 348.290329 -282.326483) (xy 348.298272 -282.379187) (xy 348.29877 -282.405836) (xy 348.298392 -282.431457)
			(xy 348.298244 -282.432485) (xy 348.526852 -282.432485) (xy 348.526852 -282.379187) (xy 348.534795 -282.326483)
			(xy 348.550505 -282.275553) (xy 348.573631 -282.227532) (xy 348.603655 -282.183495) (xy 348.639907 -282.144424)
			(xy 348.681578 -282.111193) (xy 348.727736 -282.084544) (xy 348.77735 -282.065072) (xy 348.829312 -282.053212)
			(xy 348.882462 -282.049229) (xy 348.935612 -282.053212) (xy 348.987574 -282.065072) (xy 349.037188 -282.084544)
			(xy 349.083346 -282.111193) (xy 349.125017 -282.144424) (xy 349.161269 -282.183495) (xy 349.191293 -282.227532)
			(xy 349.214419 -282.275553) (xy 349.230129 -282.326483) (xy 349.238072 -282.379187) (xy 349.23857 -282.405836)
			(xy 349.466154 -282.405836) (xy 349.466606 -282.380208) (xy 349.473937 -282.329478) (xy 349.488467 -282.280324)
			(xy 349.509896 -282.233762) (xy 349.53778 -282.190754) (xy 349.571543 -282.152189) (xy 349.610488 -282.118864)
			(xy 349.653809 -282.091469) (xy 349.700611 -282.070569) (xy 349.749926 -282.056597) (xy 349.775272 -282.052776)
			(xy 349.79991 -282.049474) (xy 349.97263 -281.750516) (xy 349.962978 -281.727402) (xy 349.954506 -281.705851)
			(xy 349.942624 -281.661095) (xy 349.936657 -281.615174) (xy 349.936308 -281.59202) (xy 349.936806 -281.565371)
			(xy 349.944749 -281.512667) (xy 349.960459 -281.461737) (xy 349.983585 -281.413716) (xy 350.013609 -281.369679)
			(xy 350.049861 -281.330608) (xy 350.091532 -281.297377) (xy 350.13769 -281.270728) (xy 350.187304 -281.251256)
			(xy 350.239266 -281.239396) (xy 350.292416 -281.235413) (xy 350.345566 -281.239396) (xy 350.397528 -281.251256)
			(xy 350.447142 -281.270728) (xy 350.4933 -281.297377) (xy 350.534971 -281.330608) (xy 350.571223 -281.369679)
			(xy 350.601247 -281.413716) (xy 350.624373 -281.461737) (xy 350.640083 -281.512667) (xy 350.648026 -281.565371)
			(xy 350.648524 -281.59202) (xy 350.648022 -281.617657) (xy 350.647876 -281.618669) (xy 350.876352 -281.618669)
			(xy 350.876352 -281.565371) (xy 350.884295 -281.512667) (xy 350.900005 -281.461737) (xy 350.923131 -281.413716)
			(xy 350.953155 -281.369679) (xy 350.989407 -281.330608) (xy 351.031078 -281.297377) (xy 351.077236 -281.270728)
			(xy 351.12685 -281.251256) (xy 351.178812 -281.239396) (xy 351.231962 -281.235413) (xy 351.285112 -281.239396)
			(xy 351.337074 -281.251256) (xy 351.386688 -281.270728) (xy 351.432846 -281.297377) (xy 351.474517 -281.330608)
			(xy 351.510769 -281.369679) (xy 351.540793 -281.413716) (xy 351.563919 -281.461737) (xy 351.579629 -281.512667)
			(xy 351.587572 -281.565371) (xy 351.58807 -281.59202) (xy 351.587572 -281.618669) (xy 351.579629 -281.671373)
			(xy 351.563919 -281.722303) (xy 351.540793 -281.770324) (xy 351.510769 -281.814361) (xy 351.474517 -281.853432)
			(xy 351.432846 -281.886663) (xy 351.386688 -281.913312) (xy 351.337074 -281.932784) (xy 351.285112 -281.944644)
			(xy 351.231962 -281.948628) (xy 351.178812 -281.944644) (xy 351.12685 -281.932784) (xy 351.077236 -281.913312)
			(xy 351.031078 -281.886663) (xy 350.989407 -281.853432) (xy 350.953155 -281.814361) (xy 350.923131 -281.770324)
			(xy 350.900005 -281.722303) (xy 350.884295 -281.671373) (xy 350.876352 -281.618669) (xy 350.647876 -281.618669)
			(xy 350.640678 -281.668402) (xy 350.626132 -281.717569) (xy 350.604684 -281.764141) (xy 350.576778 -281.807156)
			(xy 350.54299 -281.845722) (xy 350.50402 -281.879044) (xy 350.460674 -281.906431) (xy 350.413847 -281.927317)
			(xy 350.364508 -281.941271) (xy 350.339152 -281.94508) (xy 350.31426 -281.948382) (xy 350.141794 -282.246832)
			(xy 350.151446 -282.269946) (xy 350.159972 -282.291574) (xy 350.171956 -282.336494) (xy 350.177997 -282.382591)
			(xy 350.17837 -282.405836) (xy 350.177872 -282.432485) (xy 350.406706 -282.432485) (xy 350.406706 -282.379187)
			(xy 350.414649 -282.326483) (xy 350.430359 -282.275553) (xy 350.453485 -282.227532) (xy 350.483509 -282.183495)
			(xy 350.519761 -282.144424) (xy 350.561432 -282.111193) (xy 350.60759 -282.084544) (xy 350.657204 -282.065072)
			(xy 350.709166 -282.053212) (xy 350.762316 -282.049229) (xy 350.815466 -282.053212) (xy 350.867428 -282.065072)
			(xy 350.917042 -282.084544) (xy 350.9632 -282.111193) (xy 351.004871 -282.144424) (xy 351.041123 -282.183495)
			(xy 351.071147 -282.227532) (xy 351.094273 -282.275553) (xy 351.109983 -282.326483) (xy 351.117926 -282.379187)
			(xy 351.118424 -282.405836) (xy 351.117926 -282.432485) (xy 351.109983 -282.485189) (xy 351.094273 -282.536119)
			(xy 351.071147 -282.58414) (xy 351.041123 -282.628177) (xy 351.004871 -282.667248) (xy 350.9632 -282.700479)
			(xy 350.917042 -282.727128) (xy 350.867428 -282.7466) (xy 350.815466 -282.75846) (xy 350.762316 -282.762444)
			(xy 350.709166 -282.75846) (xy 350.657204 -282.7466) (xy 350.60759 -282.727128) (xy 350.561432 -282.700479)
			(xy 350.519761 -282.667248) (xy 350.483509 -282.628177) (xy 350.453485 -282.58414) (xy 350.430359 -282.536119)
			(xy 350.414649 -282.485189) (xy 350.406706 -282.432485) (xy 350.177872 -282.432485) (xy 350.169929 -282.485189)
			(xy 350.154219 -282.536119) (xy 350.131093 -282.58414) (xy 350.101069 -282.628177) (xy 350.064817 -282.667248)
			(xy 350.023146 -282.700479) (xy 349.976988 -282.727128) (xy 349.927374 -282.7466) (xy 349.875412 -282.75846)
			(xy 349.822262 -282.762444) (xy 349.769112 -282.75846) (xy 349.71715 -282.7466) (xy 349.667536 -282.727128)
			(xy 349.621378 -282.700479) (xy 349.579707 -282.667248) (xy 349.543455 -282.628177) (xy 349.513431 -282.58414)
			(xy 349.490305 -282.536119) (xy 349.474595 -282.485189) (xy 349.466652 -282.432485) (xy 349.466154 -282.405836)
			(xy 349.23857 -282.405836) (xy 349.238072 -282.432485) (xy 349.230129 -282.485189) (xy 349.214419 -282.536119)
			(xy 349.191293 -282.58414) (xy 349.161269 -282.628177) (xy 349.125017 -282.667248) (xy 349.083346 -282.700479)
			(xy 349.037188 -282.727128) (xy 348.987574 -282.7466) (xy 348.935612 -282.75846) (xy 348.882462 -282.762444)
			(xy 348.829312 -282.75846) (xy 348.77735 -282.7466) (xy 348.727736 -282.727128) (xy 348.681578 -282.700479)
			(xy 348.639907 -282.667248) (xy 348.603655 -282.628177) (xy 348.573631 -282.58414) (xy 348.550505 -282.536119)
			(xy 348.534795 -282.485189) (xy 348.526852 -282.432485) (xy 348.298244 -282.432485) (xy 348.29107 -282.482171)
			(xy 348.276552 -282.531312) (xy 348.25514 -282.577865) (xy 348.227275 -282.620867) (xy 348.193533 -282.659429)
			(xy 348.154612 -282.692757) (xy 348.111314 -282.72016) (xy 348.064536 -282.741073) (xy 348.015242 -282.755064)
			(xy 347.989906 -282.758896) (xy 347.965268 -282.762198) (xy 347.792548 -283.060902) (xy 347.8022 -283.084016)
			(xy 347.810719 -283.105647) (xy 347.822705 -283.150565) (xy 347.828749 -283.196661) (xy 347.829124 -283.219906)
			(xy 347.828626 -283.246555) (xy 348.056952 -283.246555) (xy 348.056952 -283.193257) (xy 348.064895 -283.140553)
			(xy 348.080605 -283.089623) (xy 348.103731 -283.041602) (xy 348.133755 -282.997565) (xy 348.170007 -282.958494)
			(xy 348.211678 -282.925263) (xy 348.257836 -282.898614) (xy 348.30745 -282.879142) (xy 348.359412 -282.867282)
			(xy 348.412562 -282.863299) (xy 348.465712 -282.867282) (xy 348.517674 -282.879142) (xy 348.567288 -282.898614)
			(xy 348.613446 -282.925263) (xy 348.655117 -282.958494) (xy 348.691369 -282.997565) (xy 348.721393 -283.041602)
			(xy 348.744519 -283.089623) (xy 348.760229 -283.140553) (xy 348.768172 -283.193257) (xy 348.76867 -283.2199)
			(xy 348.995974 -283.2199) (xy 348.999957 -283.166746) (xy 349.011819 -283.11478) (xy 349.031293 -283.065162)
			(xy 349.057945 -283.019) (xy 349.09118 -282.977327) (xy 349.130254 -282.941073) (xy 349.174296 -282.911047)
			(xy 349.222321 -282.887922) (xy 349.273257 -282.872212) (xy 349.325965 -282.86427) (xy 349.352616 -282.863798)
			(xy 349.377642 -282.864206) (xy 349.4272 -282.871217) (xy 349.475288 -282.885097) (xy 349.520959 -282.905575)
			(xy 349.563313 -282.932245) (xy 349.601515 -282.964583) (xy 349.634812 -283.001952) (xy 349.649034 -283.022548)
			(xy 349.995998 -283.022548) (xy 350.010213 -283.001947) (xy 350.043512 -282.964581) (xy 350.081716 -282.932245)
			(xy 350.124071 -282.905578) (xy 350.169743 -282.885104) (xy 350.217832 -282.871227) (xy 350.26739 -282.864221)
			(xy 350.292416 -282.863798) (xy 350.319065 -282.864285) (xy 350.371767 -282.872231) (xy 350.422697 -282.887942)
			(xy 350.470716 -282.911069) (xy 350.514752 -282.941094) (xy 350.553821 -282.977347) (xy 350.587051 -283.019018)
			(xy 350.6137 -283.065175) (xy 350.633171 -283.114789) (xy 350.645031 -283.166751) (xy 350.649014 -283.2199)
			(xy 350.647016 -283.246555) (xy 350.876352 -283.246555) (xy 350.876352 -283.193257) (xy 350.884295 -283.140553)
			(xy 350.900005 -283.089623) (xy 350.923131 -283.041602) (xy 350.953155 -282.997565) (xy 350.989407 -282.958494)
			(xy 351.031078 -282.925263) (xy 351.077236 -282.898614) (xy 351.12685 -282.879142) (xy 351.178812 -282.867282)
			(xy 351.231962 -282.863299) (xy 351.285112 -282.867282) (xy 351.337074 -282.879142) (xy 351.386688 -282.898614)
			(xy 351.432846 -282.925263) (xy 351.474517 -282.958494) (xy 351.510769 -282.997565) (xy 351.540793 -283.041602)
			(xy 351.563919 -283.089623) (xy 351.579629 -283.140553) (xy 351.587572 -283.193257) (xy 351.58807 -283.219906)
			(xy 351.587572 -283.246555) (xy 351.579629 -283.299259) (xy 351.563919 -283.350189) (xy 351.540793 -283.39821)
			(xy 351.510769 -283.442247) (xy 351.474517 -283.481318) (xy 351.432846 -283.514549) (xy 351.386688 -283.541198)
			(xy 351.337074 -283.56067) (xy 351.285112 -283.57253) (xy 351.231962 -283.576514) (xy 351.178812 -283.57253)
			(xy 351.12685 -283.56067) (xy 351.077236 -283.541198) (xy 351.031078 -283.514549) (xy 350.989407 -283.481318)
			(xy 350.953155 -283.442247) (xy 350.923131 -283.39821) (xy 350.900005 -283.350189) (xy 350.884295 -283.299259)
			(xy 350.876352 -283.246555) (xy 350.647016 -283.246555) (xy 350.645031 -283.273049) (xy 350.633171 -283.325011)
			(xy 350.6137 -283.374625) (xy 350.587051 -283.420782) (xy 350.553821 -283.462453) (xy 350.514752 -283.498706)
			(xy 350.470716 -283.528731) (xy 350.422697 -283.551858) (xy 350.371767 -283.567569) (xy 350.319065 -283.575515)
			(xy 350.292416 -283.576014) (xy 350.267391 -283.575576) (xy 350.217835 -283.56857) (xy 350.169748 -283.554694)
			(xy 350.124077 -283.534222) (xy 350.081723 -283.507556) (xy 350.04352 -283.475223) (xy 350.010221 -283.437858)
			(xy 349.995998 -283.417264) (xy 349.649034 -283.417264) (xy 349.634802 -283.437852) (xy 349.601505 -283.475219)
			(xy 349.563304 -283.507555) (xy 349.520952 -283.534223) (xy 349.475283 -283.554699) (xy 349.427197 -283.568579)
			(xy 349.377641 -283.575589) (xy 349.352616 -283.576014) (xy 349.325965 -283.57553) (xy 349.273257 -283.567588)
			(xy 349.222321 -283.551878) (xy 349.174296 -283.528753) (xy 349.130254 -283.498727) (xy 349.09118 -283.462473)
			(xy 349.057945 -283.4208) (xy 349.031293 -283.374638) (xy 349.011819 -283.32502) (xy 348.999957 -283.273054)
			(xy 348.995974 -283.2199) (xy 348.76867 -283.2199) (xy 348.76867 -283.219906) (xy 348.768172 -283.246555)
			(xy 348.760229 -283.299259) (xy 348.744519 -283.350189) (xy 348.721393 -283.39821) (xy 348.691369 -283.442247)
			(xy 348.655117 -283.481318) (xy 348.613446 -283.514549) (xy 348.567288 -283.541198) (xy 348.517674 -283.56067)
			(xy 348.465712 -283.57253) (xy 348.412562 -283.576514) (xy 348.359412 -283.57253) (xy 348.30745 -283.56067)
			(xy 348.257836 -283.541198) (xy 348.211678 -283.514549) (xy 348.170007 -283.481318) (xy 348.133755 -283.442247)
			(xy 348.103731 -283.39821) (xy 348.080605 -283.350189) (xy 348.064895 -283.299259) (xy 348.056952 -283.246555)
			(xy 347.828626 -283.246555) (xy 347.820683 -283.299259) (xy 347.804973 -283.350189) (xy 347.781847 -283.39821)
			(xy 347.751823 -283.442247) (xy 347.715571 -283.481318) (xy 347.6739 -283.514549) (xy 347.627742 -283.541198)
			(xy 347.578128 -283.56067) (xy 347.526166 -283.57253) (xy 347.473016 -283.576514) (xy 347.419866 -283.57253)
			(xy 347.367904 -283.56067) (xy 347.31829 -283.541198) (xy 347.272132 -283.514549) (xy 347.230461 -283.481318)
			(xy 347.194209 -283.442247) (xy 347.164185 -283.39821) (xy 347.141059 -283.350189) (xy 347.125349 -283.299259)
			(xy 347.117406 -283.246555) (xy 347.116908 -283.219906) (xy 346.88907 -283.219906) (xy 346.888572 -283.246555)
			(xy 346.880629 -283.299259) (xy 346.864919 -283.350189) (xy 346.841793 -283.39821) (xy 346.811769 -283.442247)
			(xy 346.775517 -283.481318) (xy 346.733846 -283.514549) (xy 346.687688 -283.541198) (xy 346.638074 -283.56067)
			(xy 346.586112 -283.57253) (xy 346.532962 -283.576514) (xy 346.479812 -283.57253) (xy 346.42785 -283.56067)
			(xy 346.378236 -283.541198) (xy 346.332078 -283.514549) (xy 346.290407 -283.481318) (xy 346.254155 -283.442247)
			(xy 346.224131 -283.39821) (xy 346.201005 -283.350189) (xy 346.185295 -283.299259) (xy 346.177352 -283.246555)
			(xy 345.948772 -283.246555) (xy 345.940829 -283.299259) (xy 345.925119 -283.350189) (xy 345.901993 -283.39821)
			(xy 345.871969 -283.442247) (xy 345.835717 -283.481318) (xy 345.794046 -283.514549) (xy 345.747888 -283.541198)
			(xy 345.698274 -283.56067) (xy 345.646312 -283.57253) (xy 345.593162 -283.576514) (xy 345.540012 -283.57253)
			(xy 345.48805 -283.56067) (xy 345.438436 -283.541198) (xy 345.392278 -283.514549) (xy 345.350607 -283.481318)
			(xy 345.314355 -283.442247) (xy 345.284331 -283.39821) (xy 345.261205 -283.350189) (xy 345.245495 -283.299259)
			(xy 345.237552 -283.246555) (xy 345.009226 -283.246555) (xy 345.001283 -283.299259) (xy 344.985573 -283.350189)
			(xy 344.962447 -283.39821) (xy 344.932423 -283.442247) (xy 344.896171 -283.481318) (xy 344.8545 -283.514549)
			(xy 344.808342 -283.541198) (xy 344.758728 -283.56067) (xy 344.706766 -283.57253) (xy 344.653616 -283.576514)
			(xy 344.600466 -283.57253) (xy 344.548504 -283.56067) (xy 344.49889 -283.541198) (xy 344.452732 -283.514549)
			(xy 344.411061 -283.481318) (xy 344.374809 -283.442247) (xy 344.344785 -283.39821) (xy 344.321659 -283.350189)
			(xy 344.305949 -283.299259) (xy 344.298006 -283.246555) (xy 344.297508 -283.219906) (xy 344.297879 -283.196661)
			(xy 344.303925 -283.150565) (xy 344.315915 -283.105648) (xy 344.324432 -283.084016) (xy 344.334084 -283.060902)
			(xy 344.161364 -282.762198) (xy 344.136726 -282.758896) (xy 344.111374 -282.755053) (xy 344.062036 -282.7411)
			(xy 344.015208 -282.720216) (xy 343.971859 -282.692833) (xy 343.932885 -282.659516) (xy 343.899092 -282.620955)
			(xy 343.871177 -282.577946) (xy 343.849719 -282.531379) (xy 343.835161 -282.482216) (xy 343.827803 -282.431473)
			(xy 343.827354 -282.405836) (xy 343.59977 -282.405836) (xy 343.599272 -282.432485) (xy 343.591329 -282.485189)
			(xy 343.575619 -282.536119) (xy 343.552493 -282.58414) (xy 343.522469 -282.628177) (xy 343.486217 -282.667248)
			(xy 343.444546 -282.700479) (xy 343.398388 -282.727128) (xy 343.348774 -282.7466) (xy 343.296812 -282.75846)
			(xy 343.243662 -282.762444) (xy 343.190512 -282.75846) (xy 343.13855 -282.7466) (xy 343.088936 -282.727128)
			(xy 343.042778 -282.700479) (xy 343.001107 -282.667248) (xy 342.964855 -282.628177) (xy 342.934831 -282.58414)
			(xy 342.911705 -282.536119) (xy 342.895995 -282.485189) (xy 342.888052 -282.432485) (xy 342.887554 -282.405836)
			(xy 342.660224 -282.405836) (xy 342.659726 -282.432485) (xy 342.651783 -282.485189) (xy 342.636073 -282.536119)
			(xy 342.612947 -282.58414) (xy 342.582923 -282.628177) (xy 342.546671 -282.667248) (xy 342.505 -282.700479)
			(xy 342.458842 -282.727128) (xy 342.409228 -282.7466) (xy 342.357266 -282.75846) (xy 342.304116 -282.762444)
			(xy 342.250966 -282.75846) (xy 342.199004 -282.7466) (xy 342.14939 -282.727128) (xy 342.103232 -282.700479)
			(xy 342.061561 -282.667248) (xy 342.025309 -282.628177) (xy 341.995285 -282.58414) (xy 341.972159 -282.536119)
			(xy 341.956449 -282.485189) (xy 341.948506 -282.432485) (xy 341.719926 -282.432485) (xy 341.711983 -282.485189)
			(xy 341.696273 -282.536119) (xy 341.673147 -282.58414) (xy 341.643123 -282.628177) (xy 341.606871 -282.667248)
			(xy 341.5652 -282.700479) (xy 341.519042 -282.727128) (xy 341.469428 -282.7466) (xy 341.417466 -282.75846)
			(xy 341.364316 -282.762444) (xy 341.311166 -282.75846) (xy 341.259204 -282.7466) (xy 341.20959 -282.727128)
			(xy 341.163432 -282.700479) (xy 341.121761 -282.667248) (xy 341.085509 -282.628177) (xy 341.055485 -282.58414)
			(xy 341.032359 -282.536119) (xy 341.016649 -282.485189) (xy 341.008706 -282.432485) (xy 341.008208 -282.405836)
			(xy 340.780624 -282.405836) (xy 340.780126 -282.432485) (xy 340.772183 -282.485189) (xy 340.756473 -282.536119)
			(xy 340.733347 -282.58414) (xy 340.703323 -282.628177) (xy 340.667071 -282.667248) (xy 340.6254 -282.700479)
			(xy 340.579242 -282.727128) (xy 340.529628 -282.7466) (xy 340.477666 -282.75846) (xy 340.424516 -282.762444)
			(xy 340.371366 -282.75846) (xy 340.319404 -282.7466) (xy 340.26979 -282.727128) (xy 340.223632 -282.700479)
			(xy 340.181961 -282.667248) (xy 340.145709 -282.628177) (xy 340.115685 -282.58414) (xy 340.092559 -282.536119)
			(xy 340.076849 -282.485189) (xy 340.068906 -282.432485) (xy 339.84019 -282.432485) (xy 339.832991 -282.482219)
			(xy 339.818443 -282.531387) (xy 339.796993 -282.577959) (xy 339.769085 -282.620973) (xy 339.735296 -282.659539)
			(xy 339.696324 -282.692861) (xy 339.652976 -282.720247) (xy 339.606148 -282.741133) (xy 339.556809 -282.755087)
			(xy 339.531452 -282.758896) (xy 339.50656 -282.762198) (xy 339.334094 -283.060902) (xy 339.343746 -283.084016)
			(xy 339.352263 -283.105648) (xy 339.36425 -283.150566) (xy 339.370295 -283.196661) (xy 339.37067 -283.219906)
			(xy 339.370172 -283.246555) (xy 339.598752 -283.246555) (xy 339.598752 -283.193257) (xy 339.606695 -283.140553)
			(xy 339.622405 -283.089623) (xy 339.645531 -283.041602) (xy 339.675555 -282.997565) (xy 339.711807 -282.958494)
			(xy 339.753478 -282.925263) (xy 339.799636 -282.898614) (xy 339.84925 -282.879142) (xy 339.901212 -282.867282)
			(xy 339.954362 -282.863299) (xy 340.007512 -282.867282) (xy 340.059474 -282.879142) (xy 340.109088 -282.898614)
			(xy 340.155246 -282.925263) (xy 340.196917 -282.958494) (xy 340.233169 -282.997565) (xy 340.263193 -283.041602)
			(xy 340.286319 -283.089623) (xy 340.302029 -283.140553) (xy 340.309972 -283.193257) (xy 340.31047 -283.2199)
			(xy 340.537598 -283.2199) (xy 340.541581 -283.166755) (xy 340.553439 -283.114797) (xy 340.572908 -283.065186)
			(xy 340.599554 -283.019031) (xy 340.63278 -282.977363) (xy 340.671846 -282.941111) (xy 340.715877 -282.911087)
			(xy 340.763892 -282.88796) (xy 340.814817 -282.872247) (xy 340.867515 -282.864298) (xy 340.894162 -282.863798)
			(xy 340.919186 -282.864247) (xy 340.968743 -282.87125) (xy 341.01683 -282.885124) (xy 341.062501 -282.905594)
			(xy 341.104855 -282.932258) (xy 341.143058 -282.964591) (xy 341.176357 -283.001954) (xy 341.19058 -283.022548)
			(xy 341.537544 -283.022548) (xy 341.551794 -283.001972) (xy 341.585087 -282.964605) (xy 341.623285 -282.932268)
			(xy 341.665634 -282.905598) (xy 341.711301 -282.88512) (xy 341.759384 -282.871238) (xy 341.808938 -282.864225)
			(xy 341.833962 -282.863798) (xy 341.860615 -282.864257) (xy 341.913328 -282.872196) (xy 341.964268 -282.887904)
			(xy 342.012297 -282.91103) (xy 342.056343 -282.941056) (xy 342.095422 -282.977311) (xy 342.12866 -283.018987)
			(xy 342.155315 -283.065151) (xy 342.174791 -283.114772) (xy 342.186654 -283.166742) (xy 342.190638 -283.2199)
			(xy 342.18864 -283.246555) (xy 342.418152 -283.246555) (xy 342.418152 -283.193257) (xy 342.426095 -283.140553)
			(xy 342.441805 -283.089623) (xy 342.464931 -283.041602) (xy 342.494955 -282.997565) (xy 342.531207 -282.958494)
			(xy 342.572878 -282.925263) (xy 342.619036 -282.898614) (xy 342.66865 -282.879142) (xy 342.720612 -282.867282)
			(xy 342.773762 -282.863299) (xy 342.826912 -282.867282) (xy 342.878874 -282.879142) (xy 342.928488 -282.898614)
			(xy 342.974646 -282.925263) (xy 343.016317 -282.958494) (xy 343.052569 -282.997565) (xy 343.082593 -283.041602)
			(xy 343.105719 -283.089623) (xy 343.121429 -283.140553) (xy 343.129372 -283.193257) (xy 343.12987 -283.219906)
			(xy 343.129372 -283.246555) (xy 343.357952 -283.246555) (xy 343.357952 -283.193257) (xy 343.365895 -283.140553)
			(xy 343.381605 -283.089623) (xy 343.404731 -283.041602) (xy 343.434755 -282.997565) (xy 343.471007 -282.958494)
			(xy 343.512678 -282.925263) (xy 343.558836 -282.898614) (xy 343.60845 -282.879142) (xy 343.660412 -282.867282)
			(xy 343.713562 -282.863299) (xy 343.766712 -282.867282) (xy 343.818674 -282.879142) (xy 343.868288 -282.898614)
			(xy 343.914446 -282.925263) (xy 343.956117 -282.958494) (xy 343.992369 -282.997565) (xy 344.022393 -283.041602)
			(xy 344.045519 -283.089623) (xy 344.061229 -283.140553) (xy 344.069172 -283.193257) (xy 344.06967 -283.219906)
			(xy 344.069172 -283.246555) (xy 344.061229 -283.299259) (xy 344.045519 -283.350189) (xy 344.022393 -283.39821)
			(xy 343.992369 -283.442247) (xy 343.956117 -283.481318) (xy 343.914446 -283.514549) (xy 343.868288 -283.541198)
			(xy 343.818674 -283.56067) (xy 343.766712 -283.57253) (xy 343.713562 -283.576514) (xy 343.660412 -283.57253)
			(xy 343.60845 -283.56067) (xy 343.558836 -283.541198) (xy 343.512678 -283.514549) (xy 343.471007 -283.481318)
			(xy 343.434755 -283.442247) (xy 343.404731 -283.39821) (xy 343.381605 -283.350189) (xy 343.365895 -283.299259)
			(xy 343.357952 -283.246555) (xy 343.129372 -283.246555) (xy 343.121429 -283.299259) (xy 343.105719 -283.350189)
			(xy 343.082593 -283.39821) (xy 343.052569 -283.442247) (xy 343.016317 -283.481318) (xy 342.974646 -283.514549)
			(xy 342.928488 -283.541198) (xy 342.878874 -283.56067) (xy 342.826912 -283.57253) (xy 342.773762 -283.576514)
			(xy 342.720612 -283.57253) (xy 342.66865 -283.56067) (xy 342.619036 -283.541198) (xy 342.572878 -283.514549)
			(xy 342.531207 -283.481318) (xy 342.494955 -283.442247) (xy 342.464931 -283.39821) (xy 342.441805 -283.350189)
			(xy 342.426095 -283.299259) (xy 342.418152 -283.246555) (xy 342.18864 -283.246555) (xy 342.186654 -283.273058)
			(xy 342.174791 -283.325028) (xy 342.155315 -283.374649) (xy 342.12866 -283.420813) (xy 342.095422 -283.462489)
			(xy 342.056343 -283.498744) (xy 342.012297 -283.52877) (xy 341.964268 -283.551896) (xy 341.913328 -283.567604)
			(xy 341.860615 -283.575543) (xy 341.833962 -283.576014) (xy 341.808936 -283.575617) (xy 341.759378 -283.568604)
			(xy 341.711289 -283.554721) (xy 341.665619 -283.534242) (xy 341.623265 -283.50757) (xy 341.585063 -283.47523)
			(xy 341.551766 -283.437861) (xy 341.537544 -283.417264) (xy 341.19058 -283.417264) (xy 341.176383 -283.437878)
			(xy 341.14308 -283.475243) (xy 341.104873 -283.507577) (xy 341.062515 -283.534243) (xy 341.01684 -283.554715)
			(xy 340.968749 -283.568589) (xy 340.919188 -283.575592) (xy 340.894162 -283.576014) (xy 340.867515 -283.575502)
			(xy 340.814817 -283.567553) (xy 340.763892 -283.55184) (xy 340.715877 -283.528713) (xy 340.671846 -283.498689)
			(xy 340.63278 -283.462437) (xy 340.599554 -283.420769) (xy 340.572908 -283.374614) (xy 340.553439 -283.325003)
			(xy 340.541581 -283.273045) (xy 340.537598 -283.2199) (xy 340.31047 -283.2199) (xy 340.31047 -283.219906)
			(xy 340.309972 -283.246555) (xy 340.302029 -283.299259) (xy 340.286319 -283.350189) (xy 340.263193 -283.39821)
			(xy 340.233169 -283.442247) (xy 340.196917 -283.481318) (xy 340.155246 -283.514549) (xy 340.109088 -283.541198)
			(xy 340.059474 -283.56067) (xy 340.007512 -283.57253) (xy 339.954362 -283.576514) (xy 339.901212 -283.57253)
			(xy 339.84925 -283.56067) (xy 339.799636 -283.541198) (xy 339.753478 -283.514549) (xy 339.711807 -283.481318)
			(xy 339.675555 -283.442247) (xy 339.645531 -283.39821) (xy 339.622405 -283.350189) (xy 339.606695 -283.299259)
			(xy 339.598752 -283.246555) (xy 339.370172 -283.246555) (xy 339.362229 -283.299259) (xy 339.346519 -283.350189)
			(xy 339.323393 -283.39821) (xy 339.293369 -283.442247) (xy 339.257117 -283.481318) (xy 339.215446 -283.514549)
			(xy 339.169288 -283.541198) (xy 339.119674 -283.56067) (xy 339.067712 -283.57253) (xy 339.014562 -283.576514)
			(xy 338.961412 -283.57253) (xy 338.90945 -283.56067) (xy 338.859836 -283.541198) (xy 338.813678 -283.514549)
			(xy 338.772007 -283.481318) (xy 338.735755 -283.442247) (xy 338.705731 -283.39821) (xy 338.682605 -283.350189)
			(xy 338.666895 -283.299259) (xy 338.658952 -283.246555) (xy 338.658454 -283.219906) (xy 338.43087 -283.219906)
			(xy 338.430372 -283.246555) (xy 338.422429 -283.299259) (xy 338.406719 -283.350189) (xy 338.383593 -283.39821)
			(xy 338.353569 -283.442247) (xy 338.317317 -283.481318) (xy 338.275646 -283.514549) (xy 338.229488 -283.541198)
			(xy 338.179874 -283.56067) (xy 338.127912 -283.57253) (xy 338.074762 -283.576514) (xy 338.021612 -283.57253)
			(xy 337.96965 -283.56067) (xy 337.920036 -283.541198) (xy 337.873878 -283.514549) (xy 337.832207 -283.481318)
			(xy 337.795955 -283.442247) (xy 337.765931 -283.39821) (xy 337.742805 -283.350189) (xy 337.727095 -283.299259)
			(xy 337.719152 -283.246555) (xy 337.490572 -283.246555) (xy 337.482629 -283.299259) (xy 337.466919 -283.350189)
			(xy 337.443793 -283.39821) (xy 337.413769 -283.442247) (xy 337.377517 -283.481318) (xy 337.335846 -283.514549)
			(xy 337.289688 -283.541198) (xy 337.240074 -283.56067) (xy 337.188112 -283.57253) (xy 337.134962 -283.576514)
			(xy 337.081812 -283.57253) (xy 337.02985 -283.56067) (xy 336.980236 -283.541198) (xy 336.934078 -283.514549)
			(xy 336.892407 -283.481318) (xy 336.856155 -283.442247) (xy 336.826131 -283.39821) (xy 336.803005 -283.350189)
			(xy 336.787295 -283.299259) (xy 336.779352 -283.246555) (xy 336.550772 -283.246555) (xy 336.542829 -283.299259)
			(xy 336.527119 -283.350189) (xy 336.503993 -283.39821) (xy 336.473969 -283.442247) (xy 336.437717 -283.481318)
			(xy 336.396046 -283.514549) (xy 336.349888 -283.541198) (xy 336.300274 -283.56067) (xy 336.248312 -283.57253)
			(xy 336.195162 -283.576514) (xy 336.142012 -283.57253) (xy 336.09005 -283.56067) (xy 336.040436 -283.541198)
			(xy 335.994278 -283.514549) (xy 335.952607 -283.481318) (xy 335.916355 -283.442247) (xy 335.886331 -283.39821)
			(xy 335.863205 -283.350189) (xy 335.847495 -283.299259) (xy 335.839552 -283.246555) (xy 335.839054 -283.219906)
			(xy 335.839428 -283.196661) (xy 335.845473 -283.150566) (xy 335.857461 -283.105648) (xy 335.865978 -283.084016)
			(xy 335.87563 -283.060902) (xy 335.70291 -282.762198) (xy 335.678272 -282.758896) (xy 335.652927 -282.755083)
			(xy 335.603621 -282.741092) (xy 335.556829 -282.72018) (xy 335.513516 -282.692778) (xy 335.474578 -282.659451)
			(xy 335.440817 -282.620889) (xy 335.412931 -282.577887) (xy 335.391495 -282.531332) (xy 335.376952 -282.482185)
			(xy 335.369602 -282.431462) (xy 335.369154 -282.405836) (xy 335.141824 -282.405836) (xy 335.141326 -282.432485)
			(xy 335.133383 -282.485189) (xy 335.117673 -282.536119) (xy 335.094547 -282.58414) (xy 335.064523 -282.628177)
			(xy 335.028271 -282.667248) (xy 334.9866 -282.700479) (xy 334.940442 -282.727128) (xy 334.890828 -282.7466)
			(xy 334.838866 -282.75846) (xy 334.785716 -282.762444) (xy 334.732566 -282.75846) (xy 334.680604 -282.7466)
			(xy 334.63099 -282.727128) (xy 334.584832 -282.700479) (xy 334.543161 -282.667248) (xy 334.506909 -282.628177)
			(xy 334.476885 -282.58414) (xy 334.453759 -282.536119) (xy 334.438049 -282.485189) (xy 334.430106 -282.432485)
			(xy 334.429608 -282.405836) (xy 334.202293 -282.405836) (xy 334.198313 -282.458951) (xy 334.186451 -282.510915)
			(xy 334.166977 -282.560531) (xy 334.140325 -282.60669) (xy 334.107091 -282.64836) (xy 334.068017 -282.684612)
			(xy 334.023976 -282.714634) (xy 333.975952 -282.737756) (xy 333.925018 -282.753463) (xy 333.872312 -282.761402)
			(xy 333.845662 -282.761944) (xy 333.816694 -282.761375) (xy 333.759522 -282.751999) (xy 333.704619 -282.733501)
			(xy 333.65343 -282.706366) (xy 333.630016 -282.6893) (xy 333.618494 -282.681115) (xy 333.59218 -282.670828)
			(xy 333.564055 -282.668142) (xy 333.536271 -282.673263) (xy 333.510951 -282.685798) (xy 333.490034 -282.704789)
			(xy 333.475118 -282.728784) (xy 333.467345 -282.755946) (xy 333.466948 -282.770072) (xy 333.466948 -282.873958)
			(xy 333.499968 -282.88615) (xy 333.525142 -282.896052) (xy 333.572405 -282.922365) (xy 333.615144 -282.955524)
			(xy 333.652376 -282.994765) (xy 333.683245 -283.039186) (xy 333.707041 -283.087765) (xy 333.723215 -283.139384)
			(xy 333.731396 -283.192855) (xy 333.731396 -283.246555) (xy 333.959952 -283.246555) (xy 333.959952 -283.193257)
			(xy 333.967895 -283.140553) (xy 333.983605 -283.089623) (xy 334.006731 -283.041602) (xy 334.036755 -282.997565)
			(xy 334.073007 -282.958494) (xy 334.114678 -282.925263) (xy 334.160836 -282.898614) (xy 334.21045 -282.879142)
			(xy 334.262412 -282.867282) (xy 334.315562 -282.863299) (xy 334.368712 -282.867282) (xy 334.420674 -282.879142)
			(xy 334.470288 -282.898614) (xy 334.516446 -282.925263) (xy 334.558117 -282.958494) (xy 334.594369 -282.997565)
			(xy 334.624393 -283.041602) (xy 334.647519 -283.089623) (xy 334.663229 -283.140553) (xy 334.671172 -283.193257)
			(xy 334.67167 -283.219906) (xy 334.671172 -283.246555) (xy 334.899752 -283.246555) (xy 334.899752 -283.193257)
			(xy 334.907695 -283.140553) (xy 334.923405 -283.089623) (xy 334.946531 -283.041602) (xy 334.976555 -282.997565)
			(xy 335.012807 -282.958494) (xy 335.054478 -282.925263) (xy 335.100636 -282.898614) (xy 335.15025 -282.879142)
			(xy 335.202212 -282.867282) (xy 335.255362 -282.863299) (xy 335.308512 -282.867282) (xy 335.360474 -282.879142)
			(xy 335.410088 -282.898614) (xy 335.456246 -282.925263) (xy 335.497917 -282.958494) (xy 335.534169 -282.997565)
			(xy 335.564193 -283.041602) (xy 335.587319 -283.089623) (xy 335.603029 -283.140553) (xy 335.610972 -283.193257)
			(xy 335.61147 -283.219906) (xy 335.610972 -283.246555) (xy 335.603029 -283.299259) (xy 335.587319 -283.350189)
			(xy 335.564193 -283.39821) (xy 335.534169 -283.442247) (xy 335.497917 -283.481318) (xy 335.456246 -283.514549)
			(xy 335.410088 -283.541198) (xy 335.360474 -283.56067) (xy 335.308512 -283.57253) (xy 335.255362 -283.576514)
			(xy 335.202212 -283.57253) (xy 335.15025 -283.56067) (xy 335.100636 -283.541198) (xy 335.054478 -283.514549)
			(xy 335.012807 -283.481318) (xy 334.976555 -283.442247) (xy 334.946531 -283.39821) (xy 334.923405 -283.350189)
			(xy 334.907695 -283.299259) (xy 334.899752 -283.246555) (xy 334.671172 -283.246555) (xy 334.663229 -283.299259)
			(xy 334.647519 -283.350189) (xy 334.624393 -283.39821) (xy 334.594369 -283.442247) (xy 334.558117 -283.481318)
			(xy 334.516446 -283.514549) (xy 334.470288 -283.541198) (xy 334.420674 -283.56067) (xy 334.368712 -283.57253)
			(xy 334.315562 -283.576514) (xy 334.262412 -283.57253) (xy 334.21045 -283.56067) (xy 334.160836 -283.541198)
			(xy 334.114678 -283.514549) (xy 334.073007 -283.481318) (xy 334.036755 -283.442247) (xy 334.006731 -283.39821)
			(xy 333.983605 -283.350189) (xy 333.967895 -283.299259) (xy 333.959952 -283.246555) (xy 333.731396 -283.246555)
			(xy 333.731396 -283.246949) (xy 333.723214 -283.30042) (xy 333.707039 -283.352039) (xy 333.683243 -283.400618)
			(xy 333.652374 -283.445038) (xy 333.615141 -283.484279) (xy 333.572401 -283.517437) (xy 333.525138 -283.543749)
			(xy 333.499968 -283.553662) (xy 333.466948 -283.565854) (xy 333.466948 -284.033722) (xy 334.429608 -284.033722)
			(xy 334.430106 -284.007073) (xy 334.438049 -283.954369) (xy 334.453759 -283.903439) (xy 334.476885 -283.855418)
			(xy 334.506909 -283.811381) (xy 334.543161 -283.77231) (xy 334.584832 -283.739079) (xy 334.63099 -283.71243)
			(xy 334.680604 -283.692958) (xy 334.732566 -283.681098) (xy 334.785716 -283.677115) (xy 334.838866 -283.681098)
			(xy 334.890828 -283.692958) (xy 334.940442 -283.71243) (xy 334.9866 -283.739079) (xy 335.028271 -283.77231)
			(xy 335.064523 -283.811381) (xy 335.094547 -283.855418) (xy 335.117673 -283.903439) (xy 335.133383 -283.954369)
			(xy 335.141326 -284.007073) (xy 335.141824 -284.033722) (xy 335.14146 -284.056967) (xy 335.141013 -284.060371)
			(xy 335.369652 -284.060371) (xy 335.369652 -284.007073) (xy 335.377595 -283.954369) (xy 335.393305 -283.903439)
			(xy 335.416431 -283.855418) (xy 335.446455 -283.811381) (xy 335.482707 -283.77231) (xy 335.524378 -283.739079)
			(xy 335.570536 -283.71243) (xy 335.62015 -283.692958) (xy 335.672112 -283.681098) (xy 335.725262 -283.677115)
			(xy 335.778412 -283.681098) (xy 335.830374 -283.692958) (xy 335.879988 -283.71243) (xy 335.926146 -283.739079)
			(xy 335.967817 -283.77231) (xy 336.004069 -283.811381) (xy 336.034093 -283.855418) (xy 336.057219 -283.903439)
			(xy 336.072929 -283.954369) (xy 336.080872 -284.007073) (xy 336.08137 -284.033722) (xy 336.080872 -284.060371)
			(xy 336.309706 -284.060371) (xy 336.309706 -284.007073) (xy 336.317649 -283.954369) (xy 336.333359 -283.903439)
			(xy 336.356485 -283.855418) (xy 336.386509 -283.811381) (xy 336.422761 -283.77231) (xy 336.464432 -283.739079)
			(xy 336.51059 -283.71243) (xy 336.560204 -283.692958) (xy 336.612166 -283.681098) (xy 336.665316 -283.677115)
			(xy 336.718466 -283.681098) (xy 336.770428 -283.692958) (xy 336.820042 -283.71243) (xy 336.8662 -283.739079)
			(xy 336.907871 -283.77231) (xy 336.944123 -283.811381) (xy 336.974147 -283.855418) (xy 336.997273 -283.903439)
			(xy 337.012983 -283.954369) (xy 337.020926 -284.007073) (xy 337.021424 -284.033722) (xy 337.020926 -284.060371)
			(xy 338.189052 -284.060371) (xy 338.189052 -284.007073) (xy 338.196995 -283.954369) (xy 338.212705 -283.903439)
			(xy 338.235831 -283.855418) (xy 338.265855 -283.811381) (xy 338.302107 -283.77231) (xy 338.343778 -283.739079)
			(xy 338.389936 -283.71243) (xy 338.43955 -283.692958) (xy 338.491512 -283.681098) (xy 338.544662 -283.677115)
			(xy 338.597812 -283.681098) (xy 338.649774 -283.692958) (xy 338.699388 -283.71243) (xy 338.745546 -283.739079)
			(xy 338.787217 -283.77231) (xy 338.823469 -283.811381) (xy 338.853493 -283.855418) (xy 338.876619 -283.903439)
			(xy 338.892329 -283.954369) (xy 338.900272 -284.007073) (xy 338.90077 -284.033722) (xy 338.900272 -284.060371)
			(xy 339.128852 -284.060371) (xy 339.128852 -284.007073) (xy 339.136795 -283.954369) (xy 339.152505 -283.903439)
			(xy 339.175631 -283.855418) (xy 339.205655 -283.811381) (xy 339.241907 -283.77231) (xy 339.283578 -283.739079)
			(xy 339.329736 -283.71243) (xy 339.37935 -283.692958) (xy 339.431312 -283.681098) (xy 339.484462 -283.677115)
			(xy 339.537612 -283.681098) (xy 339.589574 -283.692958) (xy 339.639188 -283.71243) (xy 339.685346 -283.739079)
			(xy 339.727017 -283.77231) (xy 339.763269 -283.811381) (xy 339.793293 -283.855418) (xy 339.816419 -283.903439)
			(xy 339.832129 -283.954369) (xy 339.840072 -284.007073) (xy 339.84057 -284.033722) (xy 339.840072 -284.060371)
			(xy 340.068652 -284.060371) (xy 340.068652 -284.007073) (xy 340.076595 -283.954369) (xy 340.092305 -283.903439)
			(xy 340.115431 -283.855418) (xy 340.145455 -283.811381) (xy 340.181707 -283.77231) (xy 340.223378 -283.739079)
			(xy 340.269536 -283.71243) (xy 340.31915 -283.692958) (xy 340.371112 -283.681098) (xy 340.424262 -283.677115)
			(xy 340.477412 -283.681098) (xy 340.529374 -283.692958) (xy 340.578988 -283.71243) (xy 340.625146 -283.739079)
			(xy 340.666817 -283.77231) (xy 340.703069 -283.811381) (xy 340.733093 -283.855418) (xy 340.756219 -283.903439)
			(xy 340.771929 -283.954369) (xy 340.779872 -284.007073) (xy 340.78037 -284.033722) (xy 340.779872 -284.060371)
			(xy 341.008452 -284.060371) (xy 341.008452 -284.007073) (xy 341.016395 -283.954369) (xy 341.032105 -283.903439)
			(xy 341.055231 -283.855418) (xy 341.085255 -283.811381) (xy 341.121507 -283.77231) (xy 341.163178 -283.739079)
			(xy 341.209336 -283.71243) (xy 341.25895 -283.692958) (xy 341.310912 -283.681098) (xy 341.364062 -283.677115)
			(xy 341.417212 -283.681098) (xy 341.469174 -283.692958) (xy 341.518788 -283.71243) (xy 341.564946 -283.739079)
			(xy 341.606617 -283.77231) (xy 341.642869 -283.811381) (xy 341.672893 -283.855418) (xy 341.696019 -283.903439)
			(xy 341.711729 -283.954369) (xy 341.719672 -284.007073) (xy 341.72017 -284.033722) (xy 341.719672 -284.060371)
			(xy 341.948252 -284.060371) (xy 341.948252 -284.007073) (xy 341.956195 -283.954369) (xy 341.971905 -283.903439)
			(xy 341.995031 -283.855418) (xy 342.025055 -283.811381) (xy 342.061307 -283.77231) (xy 342.102978 -283.739079)
			(xy 342.149136 -283.71243) (xy 342.19875 -283.692958) (xy 342.250712 -283.681098) (xy 342.303862 -283.677115)
			(xy 342.357012 -283.681098) (xy 342.408974 -283.692958) (xy 342.458588 -283.71243) (xy 342.504746 -283.739079)
			(xy 342.546417 -283.77231) (xy 342.582669 -283.811381) (xy 342.612693 -283.855418) (xy 342.635819 -283.903439)
			(xy 342.651529 -283.954369) (xy 342.659472 -284.007073) (xy 342.65997 -284.033722) (xy 342.659472 -284.060371)
			(xy 342.888052 -284.060371) (xy 342.888052 -284.007073) (xy 342.895995 -283.954369) (xy 342.911705 -283.903439)
			(xy 342.934831 -283.855418) (xy 342.964855 -283.811381) (xy 343.001107 -283.77231) (xy 343.042778 -283.739079)
			(xy 343.088936 -283.71243) (xy 343.13855 -283.692958) (xy 343.190512 -283.681098) (xy 343.243662 -283.677115)
			(xy 343.296812 -283.681098) (xy 343.348774 -283.692958) (xy 343.398388 -283.71243) (xy 343.444546 -283.739079)
			(xy 343.486217 -283.77231) (xy 343.522469 -283.811381) (xy 343.552493 -283.855418) (xy 343.575619 -283.903439)
			(xy 343.591329 -283.954369) (xy 343.599272 -284.007073) (xy 343.59977 -284.033722) (xy 343.599272 -284.060371)
			(xy 343.827852 -284.060371) (xy 343.827852 -284.007073) (xy 343.835795 -283.954369) (xy 343.851505 -283.903439)
			(xy 343.874631 -283.855418) (xy 343.904655 -283.811381) (xy 343.940907 -283.77231) (xy 343.982578 -283.739079)
			(xy 344.028736 -283.71243) (xy 344.07835 -283.692958) (xy 344.130312 -283.681098) (xy 344.183462 -283.677115)
			(xy 344.236612 -283.681098) (xy 344.288574 -283.692958) (xy 344.338188 -283.71243) (xy 344.384346 -283.739079)
			(xy 344.426017 -283.77231) (xy 344.462269 -283.811381) (xy 344.492293 -283.855418) (xy 344.515419 -283.903439)
			(xy 344.531129 -283.954369) (xy 344.539072 -284.007073) (xy 344.53957 -284.033722) (xy 344.539072 -284.060371)
			(xy 344.767652 -284.060371) (xy 344.767652 -284.007073) (xy 344.775595 -283.954369) (xy 344.791305 -283.903439)
			(xy 344.814431 -283.855418) (xy 344.844455 -283.811381) (xy 344.880707 -283.77231) (xy 344.922378 -283.739079)
			(xy 344.968536 -283.71243) (xy 345.01815 -283.692958) (xy 345.070112 -283.681098) (xy 345.123262 -283.677115)
			(xy 345.176412 -283.681098) (xy 345.228374 -283.692958) (xy 345.277988 -283.71243) (xy 345.324146 -283.739079)
			(xy 345.365817 -283.77231) (xy 345.402069 -283.811381) (xy 345.432093 -283.855418) (xy 345.455219 -283.903439)
			(xy 345.470929 -283.954369) (xy 345.478872 -284.007073) (xy 345.47937 -284.033722) (xy 345.478872 -284.060371)
			(xy 345.707452 -284.060371) (xy 345.707452 -284.007073) (xy 345.715395 -283.954369) (xy 345.731105 -283.903439)
			(xy 345.754231 -283.855418) (xy 345.784255 -283.811381) (xy 345.820507 -283.77231) (xy 345.862178 -283.739079)
			(xy 345.908336 -283.71243) (xy 345.95795 -283.692958) (xy 346.009912 -283.681098) (xy 346.063062 -283.677115)
			(xy 346.116212 -283.681098) (xy 346.168174 -283.692958) (xy 346.217788 -283.71243) (xy 346.263946 -283.739079)
			(xy 346.305617 -283.77231) (xy 346.341869 -283.811381) (xy 346.371893 -283.855418) (xy 346.395019 -283.903439)
			(xy 346.410729 -283.954369) (xy 346.418672 -284.007073) (xy 346.41917 -284.033722) (xy 346.418672 -284.060371)
			(xy 346.647252 -284.060371) (xy 346.647252 -284.007073) (xy 346.655195 -283.954369) (xy 346.670905 -283.903439)
			(xy 346.694031 -283.855418) (xy 346.724055 -283.811381) (xy 346.760307 -283.77231) (xy 346.801978 -283.739079)
			(xy 346.848136 -283.71243) (xy 346.89775 -283.692958) (xy 346.949712 -283.681098) (xy 347.002862 -283.677115)
			(xy 347.056012 -283.681098) (xy 347.107974 -283.692958) (xy 347.157588 -283.71243) (xy 347.203746 -283.739079)
			(xy 347.245417 -283.77231) (xy 347.281669 -283.811381) (xy 347.311693 -283.855418) (xy 347.334819 -283.903439)
			(xy 347.350529 -283.954369) (xy 347.358472 -284.007073) (xy 347.35897 -284.033722) (xy 347.358472 -284.060371)
			(xy 347.587052 -284.060371) (xy 347.587052 -284.007073) (xy 347.594995 -283.954369) (xy 347.610705 -283.903439)
			(xy 347.633831 -283.855418) (xy 347.663855 -283.811381) (xy 347.700107 -283.77231) (xy 347.741778 -283.739079)
			(xy 347.787936 -283.71243) (xy 347.83755 -283.692958) (xy 347.889512 -283.681098) (xy 347.942662 -283.677115)
			(xy 347.995812 -283.681098) (xy 348.047774 -283.692958) (xy 348.097388 -283.71243) (xy 348.143546 -283.739079)
			(xy 348.185217 -283.77231) (xy 348.221469 -283.811381) (xy 348.251493 -283.855418) (xy 348.274619 -283.903439)
			(xy 348.290329 -283.954369) (xy 348.298272 -284.007073) (xy 348.29877 -284.033722) (xy 348.298272 -284.060371)
			(xy 348.526852 -284.060371) (xy 348.526852 -284.007073) (xy 348.534795 -283.954369) (xy 348.550505 -283.903439)
			(xy 348.573631 -283.855418) (xy 348.603655 -283.811381) (xy 348.639907 -283.77231) (xy 348.681578 -283.739079)
			(xy 348.727736 -283.71243) (xy 348.77735 -283.692958) (xy 348.829312 -283.681098) (xy 348.882462 -283.677115)
			(xy 348.935612 -283.681098) (xy 348.987574 -283.692958) (xy 349.037188 -283.71243) (xy 349.083346 -283.739079)
			(xy 349.125017 -283.77231) (xy 349.161269 -283.811381) (xy 349.191293 -283.855418) (xy 349.214419 -283.903439)
			(xy 349.230129 -283.954369) (xy 349.238072 -284.007073) (xy 349.23857 -284.033722) (xy 349.238072 -284.060371)
			(xy 349.466652 -284.060371) (xy 349.466652 -284.007073) (xy 349.474595 -283.954369) (xy 349.490305 -283.903439)
			(xy 349.513431 -283.855418) (xy 349.543455 -283.811381) (xy 349.579707 -283.77231) (xy 349.621378 -283.739079)
			(xy 349.667536 -283.71243) (xy 349.71715 -283.692958) (xy 349.769112 -283.681098) (xy 349.822262 -283.677115)
			(xy 349.875412 -283.681098) (xy 349.927374 -283.692958) (xy 349.976988 -283.71243) (xy 350.023146 -283.739079)
			(xy 350.064817 -283.77231) (xy 350.101069 -283.811381) (xy 350.131093 -283.855418) (xy 350.154219 -283.903439)
			(xy 350.169929 -283.954369) (xy 350.177872 -284.007073) (xy 350.17837 -284.033722) (xy 350.177872 -284.060371)
			(xy 350.406452 -284.060371) (xy 350.406452 -284.007073) (xy 350.414395 -283.954369) (xy 350.430105 -283.903439)
			(xy 350.453231 -283.855418) (xy 350.483255 -283.811381) (xy 350.519507 -283.77231) (xy 350.561178 -283.739079)
			(xy 350.607336 -283.71243) (xy 350.65695 -283.692958) (xy 350.708912 -283.681098) (xy 350.762062 -283.677115)
			(xy 350.815212 -283.681098) (xy 350.867174 -283.692958) (xy 350.916788 -283.71243) (xy 350.962946 -283.739079)
			(xy 351.004617 -283.77231) (xy 351.040869 -283.811381) (xy 351.070893 -283.855418) (xy 351.094019 -283.903439)
			(xy 351.109729 -283.954369) (xy 351.117672 -284.007073) (xy 351.11817 -284.033722) (xy 351.117672 -284.060371)
			(xy 351.109729 -284.113075) (xy 351.094019 -284.164005) (xy 351.070893 -284.212026) (xy 351.040869 -284.256063)
			(xy 351.004617 -284.295134) (xy 350.962946 -284.328365) (xy 350.916788 -284.355014) (xy 350.867174 -284.374486)
			(xy 350.815212 -284.386346) (xy 350.762062 -284.39033) (xy 350.708912 -284.386346) (xy 350.65695 -284.374486)
			(xy 350.607336 -284.355014) (xy 350.561178 -284.328365) (xy 350.519507 -284.295134) (xy 350.483255 -284.256063)
			(xy 350.453231 -284.212026) (xy 350.430105 -284.164005) (xy 350.414395 -284.113075) (xy 350.406452 -284.060371)
			(xy 350.177872 -284.060371) (xy 350.169929 -284.113075) (xy 350.154219 -284.164005) (xy 350.131093 -284.212026)
			(xy 350.101069 -284.256063) (xy 350.064817 -284.295134) (xy 350.023146 -284.328365) (xy 349.976988 -284.355014)
			(xy 349.927374 -284.374486) (xy 349.875412 -284.386346) (xy 349.822262 -284.39033) (xy 349.769112 -284.386346)
			(xy 349.71715 -284.374486) (xy 349.667536 -284.355014) (xy 349.621378 -284.328365) (xy 349.579707 -284.295134)
			(xy 349.543455 -284.256063) (xy 349.513431 -284.212026) (xy 349.490305 -284.164005) (xy 349.474595 -284.113075)
			(xy 349.466652 -284.060371) (xy 349.238072 -284.060371) (xy 349.230129 -284.113075) (xy 349.214419 -284.164005)
			(xy 349.191293 -284.212026) (xy 349.161269 -284.256063) (xy 349.125017 -284.295134) (xy 349.083346 -284.328365)
			(xy 349.037188 -284.355014) (xy 348.987574 -284.374486) (xy 348.935612 -284.386346) (xy 348.882462 -284.39033)
			(xy 348.829312 -284.386346) (xy 348.77735 -284.374486) (xy 348.727736 -284.355014) (xy 348.681578 -284.328365)
			(xy 348.639907 -284.295134) (xy 348.603655 -284.256063) (xy 348.573631 -284.212026) (xy 348.550505 -284.164005)
			(xy 348.534795 -284.113075) (xy 348.526852 -284.060371) (xy 348.298272 -284.060371) (xy 348.290329 -284.113075)
			(xy 348.274619 -284.164005) (xy 348.251493 -284.212026) (xy 348.221469 -284.256063) (xy 348.185217 -284.295134)
			(xy 348.143546 -284.328365) (xy 348.097388 -284.355014) (xy 348.047774 -284.374486) (xy 347.995812 -284.386346)
			(xy 347.942662 -284.39033) (xy 347.889512 -284.386346) (xy 347.83755 -284.374486) (xy 347.787936 -284.355014)
			(xy 347.741778 -284.328365) (xy 347.700107 -284.295134) (xy 347.663855 -284.256063) (xy 347.633831 -284.212026)
			(xy 347.610705 -284.164005) (xy 347.594995 -284.113075) (xy 347.587052 -284.060371) (xy 347.358472 -284.060371)
			(xy 347.350529 -284.113075) (xy 347.334819 -284.164005) (xy 347.311693 -284.212026) (xy 347.281669 -284.256063)
			(xy 347.245417 -284.295134) (xy 347.203746 -284.328365) (xy 347.157588 -284.355014) (xy 347.107974 -284.374486)
			(xy 347.056012 -284.386346) (xy 347.002862 -284.39033) (xy 346.949712 -284.386346) (xy 346.89775 -284.374486)
			(xy 346.848136 -284.355014) (xy 346.801978 -284.328365) (xy 346.760307 -284.295134) (xy 346.724055 -284.256063)
			(xy 346.694031 -284.212026) (xy 346.670905 -284.164005) (xy 346.655195 -284.113075) (xy 346.647252 -284.060371)
			(xy 346.418672 -284.060371) (xy 346.410729 -284.113075) (xy 346.395019 -284.164005) (xy 346.371893 -284.212026)
			(xy 346.341869 -284.256063) (xy 346.305617 -284.295134) (xy 346.263946 -284.328365) (xy 346.217788 -284.355014)
			(xy 346.168174 -284.374486) (xy 346.116212 -284.386346) (xy 346.063062 -284.39033) (xy 346.009912 -284.386346)
			(xy 345.95795 -284.374486) (xy 345.908336 -284.355014) (xy 345.862178 -284.328365) (xy 345.820507 -284.295134)
			(xy 345.784255 -284.256063) (xy 345.754231 -284.212026) (xy 345.731105 -284.164005) (xy 345.715395 -284.113075)
			(xy 345.707452 -284.060371) (xy 345.478872 -284.060371) (xy 345.470929 -284.113075) (xy 345.455219 -284.164005)
			(xy 345.432093 -284.212026) (xy 345.402069 -284.256063) (xy 345.365817 -284.295134) (xy 345.324146 -284.328365)
			(xy 345.277988 -284.355014) (xy 345.228374 -284.374486) (xy 345.176412 -284.386346) (xy 345.123262 -284.39033)
			(xy 345.070112 -284.386346) (xy 345.01815 -284.374486) (xy 344.968536 -284.355014) (xy 344.922378 -284.328365)
			(xy 344.880707 -284.295134) (xy 344.844455 -284.256063) (xy 344.814431 -284.212026) (xy 344.791305 -284.164005)
			(xy 344.775595 -284.113075) (xy 344.767652 -284.060371) (xy 344.539072 -284.060371) (xy 344.531129 -284.113075)
			(xy 344.515419 -284.164005) (xy 344.492293 -284.212026) (xy 344.462269 -284.256063) (xy 344.426017 -284.295134)
			(xy 344.384346 -284.328365) (xy 344.338188 -284.355014) (xy 344.288574 -284.374486) (xy 344.236612 -284.386346)
			(xy 344.183462 -284.39033) (xy 344.130312 -284.386346) (xy 344.07835 -284.374486) (xy 344.028736 -284.355014)
			(xy 343.982578 -284.328365) (xy 343.940907 -284.295134) (xy 343.904655 -284.256063) (xy 343.874631 -284.212026)
			(xy 343.851505 -284.164005) (xy 343.835795 -284.113075) (xy 343.827852 -284.060371) (xy 343.599272 -284.060371)
			(xy 343.591329 -284.113075) (xy 343.575619 -284.164005) (xy 343.552493 -284.212026) (xy 343.522469 -284.256063)
			(xy 343.486217 -284.295134) (xy 343.444546 -284.328365) (xy 343.398388 -284.355014) (xy 343.348774 -284.374486)
			(xy 343.296812 -284.386346) (xy 343.243662 -284.39033) (xy 343.190512 -284.386346) (xy 343.13855 -284.374486)
			(xy 343.088936 -284.355014) (xy 343.042778 -284.328365) (xy 343.001107 -284.295134) (xy 342.964855 -284.256063)
			(xy 342.934831 -284.212026) (xy 342.911705 -284.164005) (xy 342.895995 -284.113075) (xy 342.888052 -284.060371)
			(xy 342.659472 -284.060371) (xy 342.651529 -284.113075) (xy 342.635819 -284.164005) (xy 342.612693 -284.212026)
			(xy 342.582669 -284.256063) (xy 342.546417 -284.295134) (xy 342.504746 -284.328365) (xy 342.458588 -284.355014)
			(xy 342.408974 -284.374486) (xy 342.357012 -284.386346) (xy 342.303862 -284.39033) (xy 342.250712 -284.386346)
			(xy 342.19875 -284.374486) (xy 342.149136 -284.355014) (xy 342.102978 -284.328365) (xy 342.061307 -284.295134)
			(xy 342.025055 -284.256063) (xy 341.995031 -284.212026) (xy 341.971905 -284.164005) (xy 341.956195 -284.113075)
			(xy 341.948252 -284.060371) (xy 341.719672 -284.060371) (xy 341.711729 -284.113075) (xy 341.696019 -284.164005)
			(xy 341.672893 -284.212026) (xy 341.642869 -284.256063) (xy 341.606617 -284.295134) (xy 341.564946 -284.328365)
			(xy 341.518788 -284.355014) (xy 341.469174 -284.374486) (xy 341.417212 -284.386346) (xy 341.364062 -284.39033)
			(xy 341.310912 -284.386346) (xy 341.25895 -284.374486) (xy 341.209336 -284.355014) (xy 341.163178 -284.328365)
			(xy 341.121507 -284.295134) (xy 341.085255 -284.256063) (xy 341.055231 -284.212026) (xy 341.032105 -284.164005)
			(xy 341.016395 -284.113075) (xy 341.008452 -284.060371) (xy 340.779872 -284.060371) (xy 340.771929 -284.113075)
			(xy 340.756219 -284.164005) (xy 340.733093 -284.212026) (xy 340.703069 -284.256063) (xy 340.666817 -284.295134)
			(xy 340.625146 -284.328365) (xy 340.578988 -284.355014) (xy 340.529374 -284.374486) (xy 340.477412 -284.386346)
			(xy 340.424262 -284.39033) (xy 340.371112 -284.386346) (xy 340.31915 -284.374486) (xy 340.269536 -284.355014)
			(xy 340.223378 -284.328365) (xy 340.181707 -284.295134) (xy 340.145455 -284.256063) (xy 340.115431 -284.212026)
			(xy 340.092305 -284.164005) (xy 340.076595 -284.113075) (xy 340.068652 -284.060371) (xy 339.840072 -284.060371)
			(xy 339.832129 -284.113075) (xy 339.816419 -284.164005) (xy 339.793293 -284.212026) (xy 339.763269 -284.256063)
			(xy 339.727017 -284.295134) (xy 339.685346 -284.328365) (xy 339.639188 -284.355014) (xy 339.589574 -284.374486)
			(xy 339.537612 -284.386346) (xy 339.484462 -284.39033) (xy 339.431312 -284.386346) (xy 339.37935 -284.374486)
			(xy 339.329736 -284.355014) (xy 339.283578 -284.328365) (xy 339.241907 -284.295134) (xy 339.205655 -284.256063)
			(xy 339.175631 -284.212026) (xy 339.152505 -284.164005) (xy 339.136795 -284.113075) (xy 339.128852 -284.060371)
			(xy 338.900272 -284.060371) (xy 338.892329 -284.113075) (xy 338.876619 -284.164005) (xy 338.853493 -284.212026)
			(xy 338.823469 -284.256063) (xy 338.787217 -284.295134) (xy 338.745546 -284.328365) (xy 338.699388 -284.355014)
			(xy 338.649774 -284.374486) (xy 338.597812 -284.386346) (xy 338.544662 -284.39033) (xy 338.491512 -284.386346)
			(xy 338.43955 -284.374486) (xy 338.389936 -284.355014) (xy 338.343778 -284.328365) (xy 338.302107 -284.295134)
			(xy 338.265855 -284.256063) (xy 338.235831 -284.212026) (xy 338.212705 -284.164005) (xy 338.196995 -284.113075)
			(xy 338.189052 -284.060371) (xy 337.020926 -284.060371) (xy 337.012983 -284.113075) (xy 336.997273 -284.164005)
			(xy 336.974147 -284.212026) (xy 336.944123 -284.256063) (xy 336.907871 -284.295134) (xy 336.8662 -284.328365)
			(xy 336.820042 -284.355014) (xy 336.770428 -284.374486) (xy 336.718466 -284.386346) (xy 336.665316 -284.39033)
			(xy 336.612166 -284.386346) (xy 336.560204 -284.374486) (xy 336.51059 -284.355014) (xy 336.464432 -284.328365)
			(xy 336.422761 -284.295134) (xy 336.386509 -284.256063) (xy 336.356485 -284.212026) (xy 336.333359 -284.164005)
			(xy 336.317649 -284.113075) (xy 336.309706 -284.060371) (xy 336.080872 -284.060371) (xy 336.072929 -284.113075)
			(xy 336.057219 -284.164005) (xy 336.034093 -284.212026) (xy 336.004069 -284.256063) (xy 335.967817 -284.295134)
			(xy 335.926146 -284.328365) (xy 335.879988 -284.355014) (xy 335.830374 -284.374486) (xy 335.778412 -284.386346)
			(xy 335.725262 -284.39033) (xy 335.672112 -284.386346) (xy 335.62015 -284.374486) (xy 335.570536 -284.355014)
			(xy 335.524378 -284.328365) (xy 335.482707 -284.295134) (xy 335.446455 -284.256063) (xy 335.416431 -284.212026)
			(xy 335.393305 -284.164005) (xy 335.377595 -284.113075) (xy 335.369652 -284.060371) (xy 335.141013 -284.060371)
			(xy 335.135411 -284.103063) (xy 335.123419 -284.147981) (xy 335.1149 -284.169612) (xy 335.105248 -284.192726)
			(xy 335.277714 -284.491176) (xy 335.302352 -284.494478) (xy 335.327695 -284.498297) (xy 335.377 -284.51229)
			(xy 335.42379 -284.533203) (xy 335.467101 -284.560605) (xy 335.506039 -284.593931) (xy 335.539799 -284.632492)
			(xy 335.567686 -284.675493) (xy 335.589123 -284.722046) (xy 335.603668 -284.771191) (xy 335.61102 -284.821912)
			(xy 335.61147 -284.847538) (xy 335.610972 -284.874187) (xy 335.603029 -284.926891) (xy 335.587319 -284.977821)
			(xy 335.564193 -285.025842) (xy 335.534169 -285.069879) (xy 335.497917 -285.10895) (xy 335.456246 -285.142181)
			(xy 335.410088 -285.16883) (xy 335.360474 -285.188302) (xy 335.308512 -285.200162) (xy 335.255362 -285.204146)
			(xy 335.202212 -285.200162) (xy 335.15025 -285.188302) (xy 335.100636 -285.16883) (xy 335.054478 -285.142181)
			(xy 335.012807 -285.10895) (xy 334.976555 -285.069879) (xy 334.946531 -285.025842) (xy 334.923405 -284.977821)
			(xy 334.907695 -284.926891) (xy 334.899752 -284.874187) (xy 334.899254 -284.847538) (xy 334.899638 -284.824293)
			(xy 334.905679 -284.778198) (xy 334.917663 -284.73328) (xy 334.926178 -284.711648) (xy 334.93583 -284.688534)
			(xy 334.763364 -284.390084) (xy 334.738726 -284.386782) (xy 334.713386 -284.38294) (xy 334.664079 -284.368956)
			(xy 334.617285 -284.348049) (xy 334.573971 -284.320651) (xy 334.535031 -284.287329) (xy 334.501269 -284.248769)
			(xy 334.473382 -284.205768) (xy 334.451946 -284.159215) (xy 334.437404 -284.11007) (xy 334.430055 -284.059348)
			(xy 334.429608 -284.033722) (xy 333.466948 -284.033722) (xy 333.466948 -284.50159) (xy 333.499968 -284.513782)
			(xy 333.525956 -284.524033) (xy 333.574627 -284.55145) (xy 333.618419 -284.586131) (xy 333.656258 -284.627225)
			(xy 333.67218 -284.65018) (xy 334.019144 -284.65018) (xy 334.033364 -284.629581) (xy 334.06666 -284.592207)
			(xy 334.104861 -284.559864) (xy 334.147214 -284.533188) (xy 334.192885 -284.512706) (xy 334.240975 -284.498821)
			(xy 334.290535 -284.491807) (xy 334.315562 -284.49143) (xy 334.342212 -284.4919) (xy 334.394918 -284.499839)
			(xy 334.445851 -284.515545) (xy 334.493875 -284.538668) (xy 334.537916 -284.56869) (xy 334.57699 -284.604941)
			(xy 334.610224 -284.646611) (xy 334.636875 -284.69277) (xy 334.656349 -284.742385) (xy 334.668211 -284.794349)
			(xy 334.672194 -284.8475) (xy 334.668211 -284.900651) (xy 334.656349 -284.952615) (xy 334.636875 -285.00223)
			(xy 334.610224 -285.048389) (xy 334.57699 -285.090059) (xy 334.537916 -285.12631) (xy 334.493875 -285.156332)
			(xy 334.445851 -285.179455) (xy 334.394918 -285.195161) (xy 334.342212 -285.2031) (xy 334.315562 -285.203646)
			(xy 334.290538 -285.203219) (xy 334.240983 -285.196207) (xy 334.192898 -285.182326) (xy 334.14723 -285.16185)
			(xy 334.104878 -285.135181) (xy 334.066677 -285.102846) (xy 334.03338 -285.065481) (xy 334.019144 -285.044896)
			(xy 333.67218 -285.044896) (xy 333.656248 -285.067843) (xy 333.61841 -285.108938) (xy 333.574622 -285.143622)
			(xy 333.525956 -285.171045) (xy 333.499968 -285.181294) (xy 333.466948 -285.193486) (xy 333.466948 -285.297118)
			(xy 333.467398 -285.311255) (xy 333.475132 -285.338449) (xy 333.490028 -285.362478) (xy 333.510945 -285.3815)
			(xy 333.536277 -285.394054) (xy 333.564081 -285.399178) (xy 333.592224 -285.396479) (xy 333.618547 -285.386163)
			(xy 333.630016 -285.37789) (xy 333.653423 -285.360815) (xy 333.704615 -285.333688) (xy 333.759521 -285.315199)
			(xy 333.816694 -285.305836) (xy 333.845662 -285.305246) (xy 333.872318 -285.305717) (xy 333.925037 -285.313657)
			(xy 333.975982 -285.329367) (xy 334.024017 -285.352495) (xy 334.068068 -285.382524) (xy 334.107151 -285.418784)
			(xy 334.140393 -285.460464) (xy 334.167051 -285.506633) (xy 334.18653 -285.55626) (xy 334.198394 -285.608236)
			(xy 334.202378 -285.6614) (xy 334.200384 -285.688003) (xy 334.429852 -285.688003) (xy 334.429852 -285.634705)
			(xy 334.437795 -285.582001) (xy 334.453505 -285.531071) (xy 334.476631 -285.48305) (xy 334.506655 -285.439013)
			(xy 334.542907 -285.399942) (xy 334.584578 -285.366711) (xy 334.630736 -285.340062) (xy 334.68035 -285.32059)
			(xy 334.732312 -285.30873) (xy 334.785462 -285.304747) (xy 334.838612 -285.30873) (xy 334.890574 -285.32059)
			(xy 334.940188 -285.340062) (xy 334.986346 -285.366711) (xy 335.028017 -285.399942) (xy 335.064269 -285.439013)
			(xy 335.094293 -285.48305) (xy 335.117419 -285.531071) (xy 335.133129 -285.582001) (xy 335.141072 -285.634705)
			(xy 335.14157 -285.661354) (xy 335.369154 -285.661354) (xy 335.369623 -285.635726) (xy 335.376951 -285.584997)
			(xy 335.391479 -285.535844) (xy 335.412905 -285.489282) (xy 335.440787 -285.446273) (xy 335.474549 -285.407708)
			(xy 335.513492 -285.374383) (xy 335.556812 -285.346988) (xy 335.603613 -285.326087) (xy 335.652927 -285.312115)
			(xy 335.678272 -285.308294) (xy 335.70291 -285.304992) (xy 335.875376 -285.006288) (xy 335.865978 -284.983174)
			(xy 335.857483 -284.961579) (xy 335.845509 -284.916747) (xy 335.839448 -284.87074) (xy 335.839054 -284.847538)
			(xy 335.839552 -284.820889) (xy 335.847495 -284.768185) (xy 335.863205 -284.717255) (xy 335.886331 -284.669234)
			(xy 335.916355 -284.625197) (xy 335.952607 -284.586126) (xy 335.994278 -284.552895) (xy 336.040436 -284.526246)
			(xy 336.09005 -284.506774) (xy 336.142012 -284.494914) (xy 336.195162 -284.490931) (xy 336.248312 -284.494914)
			(xy 336.300274 -284.506774) (xy 336.349888 -284.526246) (xy 336.396046 -284.552895) (xy 336.437717 -284.586126)
			(xy 336.473969 -284.625197) (xy 336.503993 -284.669234) (xy 336.527119 -284.717255) (xy 336.542829 -284.768185)
			(xy 336.550772 -284.820889) (xy 336.55127 -284.847538) (xy 336.550773 -284.873165) (xy 336.550625 -284.874187)
			(xy 336.779352 -284.874187) (xy 336.779352 -284.820889) (xy 336.787295 -284.768185) (xy 336.803005 -284.717255)
			(xy 336.826131 -284.669234) (xy 336.856155 -284.625197) (xy 336.892407 -284.586126) (xy 336.934078 -284.552895)
			(xy 336.980236 -284.526246) (xy 337.02985 -284.506774) (xy 337.081812 -284.494914) (xy 337.134962 -284.490931)
			(xy 337.188112 -284.494914) (xy 337.240074 -284.506774) (xy 337.289688 -284.526246) (xy 337.335846 -284.552895)
			(xy 337.377517 -284.586126) (xy 337.413769 -284.625197) (xy 337.443793 -284.669234) (xy 337.466919 -284.717255)
			(xy 337.482629 -284.768185) (xy 337.490572 -284.820889) (xy 337.49107 -284.847538) (xy 337.490572 -284.874187)
			(xy 337.482629 -284.926891) (xy 337.466919 -284.977821) (xy 337.443793 -285.025842) (xy 337.413769 -285.069879)
			(xy 337.377517 -285.10895) (xy 337.335846 -285.142181) (xy 337.289688 -285.16883) (xy 337.240074 -285.188302)
			(xy 337.188112 -285.200162) (xy 337.134962 -285.204146) (xy 337.081812 -285.200162) (xy 337.02985 -285.188302)
			(xy 336.980236 -285.16883) (xy 336.934078 -285.142181) (xy 336.892407 -285.10895) (xy 336.856155 -285.069879)
			(xy 336.826131 -285.025842) (xy 336.803005 -284.977821) (xy 336.787295 -284.926891) (xy 336.779352 -284.874187)
			(xy 336.550625 -284.874187) (xy 336.543446 -284.923891) (xy 336.528921 -284.973043) (xy 336.507497 -285.019604)
			(xy 336.479618 -285.062611) (xy 336.44586 -285.101176) (xy 336.40692 -285.134502) (xy 336.363604 -285.161899)
			(xy 336.316807 -285.182801) (xy 336.267496 -285.196776) (xy 336.242152 -285.200598) (xy 336.217514 -285.2039)
			(xy 336.045048 -285.502604) (xy 336.054446 -285.525718) (xy 336.062935 -285.547315) (xy 336.074913 -285.592146)
			(xy 336.080975 -285.638152) (xy 336.08137 -285.661354) (xy 336.080872 -285.688003) (xy 336.309452 -285.688003)
			(xy 336.309452 -285.634705) (xy 336.317395 -285.582001) (xy 336.333105 -285.531071) (xy 336.356231 -285.48305)
			(xy 336.386255 -285.439013) (xy 336.422507 -285.399942) (xy 336.464178 -285.366711) (xy 336.510336 -285.340062)
			(xy 336.55995 -285.32059) (xy 336.611912 -285.30873) (xy 336.665062 -285.304747) (xy 336.718212 -285.30873)
			(xy 336.770174 -285.32059) (xy 336.819788 -285.340062) (xy 336.865946 -285.366711) (xy 336.907617 -285.399942)
			(xy 336.943869 -285.439013) (xy 336.973893 -285.48305) (xy 336.997019 -285.531071) (xy 337.012729 -285.582001)
			(xy 337.020672 -285.634705) (xy 337.02117 -285.661354) (xy 337.248754 -285.661354) (xy 337.249252 -285.634705)
			(xy 337.257195 -285.582001) (xy 337.272905 -285.531071) (xy 337.296031 -285.48305) (xy 337.326055 -285.439013)
			(xy 337.362307 -285.399942) (xy 337.403978 -285.366711) (xy 337.450136 -285.340062) (xy 337.49975 -285.32059)
			(xy 337.551712 -285.30873) (xy 337.604862 -285.304747) (xy 337.658012 -285.30873) (xy 337.709974 -285.32059)
			(xy 337.759588 -285.340062) (xy 337.805746 -285.366711) (xy 337.847417 -285.399942) (xy 337.883669 -285.439013)
			(xy 337.913693 -285.48305) (xy 337.936819 -285.531071) (xy 337.952529 -285.582001) (xy 337.960472 -285.634705)
			(xy 337.96097 -285.661354) (xy 338.188808 -285.661354) (xy 338.189317 -285.635728) (xy 338.196644 -285.585003)
			(xy 338.211169 -285.535852) (xy 338.232592 -285.489293) (xy 338.26047 -285.446286) (xy 338.294227 -285.407721)
			(xy 338.333165 -285.374396) (xy 338.376479 -285.346998) (xy 338.423274 -285.326095) (xy 338.472583 -285.312117)
			(xy 338.497926 -285.308294) (xy 338.522564 -285.304992) (xy 338.69503 -285.006542) (xy 338.685378 -284.983428)
			(xy 338.676871 -284.961793) (xy 338.664881 -284.916876) (xy 338.658832 -284.870783) (xy 338.658454 -284.847538)
			(xy 338.658952 -284.820889) (xy 338.666895 -284.768185) (xy 338.682605 -284.717255) (xy 338.705731 -284.669234)
			(xy 338.735755 -284.625197) (xy 338.772007 -284.586126) (xy 338.813678 -284.552895) (xy 338.859836 -284.526246)
			(xy 338.90945 -284.506774) (xy 338.961412 -284.494914) (xy 339.014562 -284.490931) (xy 339.067712 -284.494914)
			(xy 339.119674 -284.506774) (xy 339.169288 -284.526246) (xy 339.215446 -284.552895) (xy 339.257117 -284.586126)
			(xy 339.293369 -284.625197) (xy 339.323393 -284.669234) (xy 339.346519 -284.717255) (xy 339.362229 -284.768185)
			(xy 339.370172 -284.820889) (xy 339.37067 -284.847538) (xy 339.370294 -284.873159) (xy 339.362971 -284.923873)
			(xy 339.348453 -284.973015) (xy 339.327041 -285.019567) (xy 339.299176 -285.062569) (xy 339.265434 -285.101132)
			(xy 339.226512 -285.134459) (xy 339.183215 -285.161862) (xy 339.136436 -285.182775) (xy 339.087142 -285.196766)
			(xy 339.061806 -285.200598) (xy 339.036914 -285.2039) (xy 338.864448 -285.50235) (xy 338.8741 -285.525464)
			(xy 338.882604 -285.547101) (xy 338.894595 -285.592016) (xy 338.900646 -285.63811) (xy 338.901024 -285.661354)
			(xy 339.128608 -285.661354) (xy 339.129106 -285.634705) (xy 339.137049 -285.582001) (xy 339.152759 -285.531071)
			(xy 339.175885 -285.48305) (xy 339.205909 -285.439013) (xy 339.242161 -285.399942) (xy 339.283832 -285.366711)
			(xy 339.32999 -285.340062) (xy 339.379604 -285.32059) (xy 339.431566 -285.30873) (xy 339.484716 -285.304747)
			(xy 339.537866 -285.30873) (xy 339.589828 -285.32059) (xy 339.639442 -285.340062) (xy 339.6856 -285.366711)
			(xy 339.727271 -285.399942) (xy 339.763523 -285.439013) (xy 339.793547 -285.48305) (xy 339.816673 -285.531071)
			(xy 339.832383 -285.582001) (xy 339.840326 -285.634705) (xy 339.840824 -285.661354) (xy 340.068154 -285.661354)
			(xy 340.068623 -285.635726) (xy 340.075951 -285.584997) (xy 340.090479 -285.535844) (xy 340.111905 -285.489282)
			(xy 340.139787 -285.446273) (xy 340.173549 -285.407708) (xy 340.212492 -285.374383) (xy 340.255812 -285.346988)
			(xy 340.302613 -285.326087) (xy 340.351927 -285.312115) (xy 340.377272 -285.308294) (xy 340.40191 -285.304992)
			(xy 340.57463 -285.006034) (xy 340.564978 -284.98292) (xy 340.556512 -284.961367) (xy 340.544627 -284.916612)
			(xy 340.538658 -284.870692) (xy 340.538308 -284.847538) (xy 340.538806 -284.820889) (xy 340.546749 -284.768185)
			(xy 340.562459 -284.717255) (xy 340.585585 -284.669234) (xy 340.615609 -284.625197) (xy 340.651861 -284.586126)
			(xy 340.693532 -284.552895) (xy 340.73969 -284.526246) (xy 340.789304 -284.506774) (xy 340.841266 -284.494914)
			(xy 340.894416 -284.490931) (xy 340.947566 -284.494914) (xy 340.999528 -284.506774) (xy 341.049142 -284.526246)
			(xy 341.0953 -284.552895) (xy 341.136971 -284.586126) (xy 341.173223 -284.625197) (xy 341.203247 -284.669234)
			(xy 341.226373 -284.717255) (xy 341.242083 -284.768185) (xy 341.250026 -284.820889) (xy 341.250524 -284.847538)
			(xy 341.250038 -284.873175) (xy 341.242692 -284.923921) (xy 341.228144 -284.973089) (xy 341.206694 -285.019661)
			(xy 341.178786 -285.062675) (xy 341.144996 -285.101242) (xy 341.106025 -285.134563) (xy 341.062676 -285.161949)
			(xy 341.015848 -285.182836) (xy 340.966509 -285.196789) (xy 340.941152 -285.200598) (xy 340.91626 -285.2039)
			(xy 340.743794 -285.50235) (xy 340.753446 -285.525464) (xy 340.761947 -285.547102) (xy 340.77394 -285.592017)
			(xy 340.779991 -285.63811) (xy 340.78037 -285.661354) (xy 341.007954 -285.661354) (xy 341.008452 -285.634705)
			(xy 341.016395 -285.582001) (xy 341.032105 -285.531071) (xy 341.055231 -285.48305) (xy 341.085255 -285.439013)
			(xy 341.121507 -285.399942) (xy 341.163178 -285.366711) (xy 341.209336 -285.340062) (xy 341.25895 -285.32059)
			(xy 341.310912 -285.30873) (xy 341.364062 -285.304747) (xy 341.417212 -285.30873) (xy 341.469174 -285.32059)
			(xy 341.518788 -285.340062) (xy 341.564946 -285.366711) (xy 341.606617 -285.399942) (xy 341.642869 -285.439013)
			(xy 341.672893 -285.48305) (xy 341.696019 -285.531071) (xy 341.711729 -285.582001) (xy 341.719672 -285.634705)
			(xy 341.72017 -285.661354) (xy 341.947754 -285.661354) (xy 341.948223 -285.635726) (xy 341.955551 -285.584997)
			(xy 341.970079 -285.535844) (xy 341.991505 -285.489282) (xy 342.019387 -285.446273) (xy 342.053149 -285.407708)
			(xy 342.092092 -285.374383) (xy 342.135412 -285.346988) (xy 342.182213 -285.326087) (xy 342.231527 -285.312115)
			(xy 342.256872 -285.308294) (xy 342.28151 -285.304992) (xy 342.45423 -285.006034) (xy 342.444578 -284.98292)
			(xy 342.436112 -284.961367) (xy 342.424227 -284.916612) (xy 342.418258 -284.870692) (xy 342.417908 -284.847538)
			(xy 342.418406 -284.820889) (xy 342.426349 -284.768185) (xy 342.442059 -284.717255) (xy 342.465185 -284.669234)
			(xy 342.495209 -284.625197) (xy 342.531461 -284.586126) (xy 342.573132 -284.552895) (xy 342.61929 -284.526246)
			(xy 342.668904 -284.506774) (xy 342.720866 -284.494914) (xy 342.774016 -284.490931) (xy 342.827166 -284.494914)
			(xy 342.879128 -284.506774) (xy 342.928742 -284.526246) (xy 342.9749 -284.552895) (xy 343.016571 -284.586126)
			(xy 343.052823 -284.625197) (xy 343.082847 -284.669234) (xy 343.105973 -284.717255) (xy 343.121683 -284.768185)
			(xy 343.129626 -284.820889) (xy 343.130124 -284.847538) (xy 343.129638 -284.873175) (xy 343.122292 -284.923921)
			(xy 343.107744 -284.973089) (xy 343.086294 -285.019661) (xy 343.058386 -285.062675) (xy 343.024596 -285.101242)
			(xy 342.985625 -285.134563) (xy 342.942276 -285.161949) (xy 342.895448 -285.182836) (xy 342.846109 -285.196789)
			(xy 342.820752 -285.200598) (xy 342.79586 -285.2039) (xy 342.623394 -285.50235) (xy 342.633046 -285.525464)
			(xy 342.641547 -285.547102) (xy 342.65354 -285.592017) (xy 342.659591 -285.63811) (xy 342.65997 -285.661354)
			(xy 342.887554 -285.661354) (xy 342.888052 -285.634705) (xy 342.895995 -285.582001) (xy 342.911705 -285.531071)
			(xy 342.934831 -285.48305) (xy 342.964855 -285.439013) (xy 343.001107 -285.399942) (xy 343.042778 -285.366711)
			(xy 343.088936 -285.340062) (xy 343.13855 -285.32059) (xy 343.190512 -285.30873) (xy 343.243662 -285.304747)
			(xy 343.296812 -285.30873) (xy 343.348774 -285.32059) (xy 343.398388 -285.340062) (xy 343.444546 -285.366711)
			(xy 343.486217 -285.399942) (xy 343.522469 -285.439013) (xy 343.552493 -285.48305) (xy 343.575619 -285.531071)
			(xy 343.591329 -285.582001) (xy 343.599272 -285.634705) (xy 343.59977 -285.661354) (xy 343.827354 -285.661354)
			(xy 343.827823 -285.635726) (xy 343.835151 -285.584997) (xy 343.849679 -285.535844) (xy 343.871105 -285.489282)
			(xy 343.898987 -285.446273) (xy 343.932749 -285.407708) (xy 343.971692 -285.374383) (xy 344.015012 -285.346988)
			(xy 344.061813 -285.326087) (xy 344.111127 -285.312115) (xy 344.136472 -285.308294) (xy 344.16111 -285.304992)
			(xy 344.33383 -285.006034) (xy 344.324178 -284.98292) (xy 344.315712 -284.961367) (xy 344.303827 -284.916612)
			(xy 344.297858 -284.870692) (xy 344.297508 -284.847538) (xy 344.298006 -284.820889) (xy 344.305949 -284.768185)
			(xy 344.321659 -284.717255) (xy 344.344785 -284.669234) (xy 344.374809 -284.625197) (xy 344.411061 -284.586126)
			(xy 344.452732 -284.552895) (xy 344.49889 -284.526246) (xy 344.548504 -284.506774) (xy 344.600466 -284.494914)
			(xy 344.653616 -284.490931) (xy 344.706766 -284.494914) (xy 344.758728 -284.506774) (xy 344.808342 -284.526246)
			(xy 344.8545 -284.552895) (xy 344.896171 -284.586126) (xy 344.932423 -284.625197) (xy 344.962447 -284.669234)
			(xy 344.985573 -284.717255) (xy 345.001283 -284.768185) (xy 345.009226 -284.820889) (xy 345.009724 -284.847538)
			(xy 345.009238 -284.873175) (xy 345.001892 -284.923921) (xy 344.987344 -284.973089) (xy 344.965894 -285.019661)
			(xy 344.937986 -285.062675) (xy 344.904196 -285.101242) (xy 344.865225 -285.134563) (xy 344.821876 -285.161949)
			(xy 344.775048 -285.182836) (xy 344.725709 -285.196789) (xy 344.700352 -285.200598) (xy 344.67546 -285.2039)
			(xy 344.502994 -285.50235) (xy 344.512646 -285.525464) (xy 344.521147 -285.547102) (xy 344.53314 -285.592017)
			(xy 344.539191 -285.63811) (xy 344.53957 -285.661354) (xy 344.767154 -285.661354) (xy 344.767652 -285.634705)
			(xy 344.775595 -285.582001) (xy 344.791305 -285.531071) (xy 344.814431 -285.48305) (xy 344.844455 -285.439013)
			(xy 344.880707 -285.399942) (xy 344.922378 -285.366711) (xy 344.968536 -285.340062) (xy 345.01815 -285.32059)
			(xy 345.070112 -285.30873) (xy 345.123262 -285.304747) (xy 345.176412 -285.30873) (xy 345.228374 -285.32059)
			(xy 345.277988 -285.340062) (xy 345.324146 -285.366711) (xy 345.365817 -285.399942) (xy 345.402069 -285.439013)
			(xy 345.432093 -285.48305) (xy 345.455219 -285.531071) (xy 345.470929 -285.582001) (xy 345.478872 -285.634705)
			(xy 345.47937 -285.661354) (xy 345.706954 -285.661354) (xy 345.707423 -285.635726) (xy 345.714751 -285.584997)
			(xy 345.729279 -285.535844) (xy 345.750705 -285.489282) (xy 345.778587 -285.446273) (xy 345.812349 -285.407708)
			(xy 345.851292 -285.374383) (xy 345.894612 -285.346988) (xy 345.941413 -285.326087) (xy 345.990727 -285.312115)
			(xy 346.016072 -285.308294) (xy 346.04071 -285.304992) (xy 346.21343 -285.006034) (xy 346.203778 -284.98292)
			(xy 346.195312 -284.961367) (xy 346.183427 -284.916612) (xy 346.177458 -284.870692) (xy 346.177108 -284.847538)
			(xy 346.177606 -284.820889) (xy 346.185549 -284.768185) (xy 346.201259 -284.717255) (xy 346.224385 -284.669234)
			(xy 346.254409 -284.625197) (xy 346.290661 -284.586126) (xy 346.332332 -284.552895) (xy 346.37849 -284.526246)
			(xy 346.428104 -284.506774) (xy 346.480066 -284.494914) (xy 346.533216 -284.490931) (xy 346.586366 -284.494914)
			(xy 346.638328 -284.506774) (xy 346.687942 -284.526246) (xy 346.7341 -284.552895) (xy 346.775771 -284.586126)
			(xy 346.812023 -284.625197) (xy 346.842047 -284.669234) (xy 346.865173 -284.717255) (xy 346.880883 -284.768185)
			(xy 346.888826 -284.820889) (xy 346.889324 -284.847538) (xy 346.888838 -284.873175) (xy 346.881492 -284.923921)
			(xy 346.866944 -284.973089) (xy 346.845494 -285.019661) (xy 346.817586 -285.062675) (xy 346.783796 -285.101242)
			(xy 346.744825 -285.134563) (xy 346.701476 -285.161949) (xy 346.654648 -285.182836) (xy 346.605309 -285.196789)
			(xy 346.579952 -285.200598) (xy 346.55506 -285.2039) (xy 346.382594 -285.50235) (xy 346.392246 -285.525464)
			(xy 346.400747 -285.547102) (xy 346.41274 -285.592017) (xy 346.418791 -285.63811) (xy 346.41917 -285.661354)
			(xy 346.646754 -285.661354) (xy 346.647252 -285.634705) (xy 346.655195 -285.582001) (xy 346.670905 -285.531071)
			(xy 346.694031 -285.48305) (xy 346.724055 -285.439013) (xy 346.760307 -285.399942) (xy 346.801978 -285.366711)
			(xy 346.848136 -285.340062) (xy 346.89775 -285.32059) (xy 346.949712 -285.30873) (xy 347.002862 -285.304747)
			(xy 347.056012 -285.30873) (xy 347.107974 -285.32059) (xy 347.157588 -285.340062) (xy 347.203746 -285.366711)
			(xy 347.245417 -285.399942) (xy 347.281669 -285.439013) (xy 347.311693 -285.48305) (xy 347.334819 -285.531071)
			(xy 347.350529 -285.582001) (xy 347.358472 -285.634705) (xy 347.35897 -285.661354) (xy 347.586554 -285.661354)
			(xy 347.587023 -285.635726) (xy 347.594351 -285.584997) (xy 347.608879 -285.535844) (xy 347.630305 -285.489282)
			(xy 347.658187 -285.446273) (xy 347.691949 -285.407708) (xy 347.730892 -285.374383) (xy 347.774212 -285.346988)
			(xy 347.821013 -285.326087) (xy 347.870327 -285.312115) (xy 347.895672 -285.308294) (xy 347.92031 -285.304992)
			(xy 348.09303 -285.006034) (xy 348.083378 -284.98292) (xy 348.074912 -284.961367) (xy 348.063027 -284.916612)
			(xy 348.057058 -284.870692) (xy 348.056708 -284.847538) (xy 348.057206 -284.820889) (xy 348.065149 -284.768185)
			(xy 348.080859 -284.717255) (xy 348.103985 -284.669234) (xy 348.134009 -284.625197) (xy 348.170261 -284.586126)
			(xy 348.211932 -284.552895) (xy 348.25809 -284.526246) (xy 348.307704 -284.506774) (xy 348.359666 -284.494914)
			(xy 348.412816 -284.490931) (xy 348.465966 -284.494914) (xy 348.517928 -284.506774) (xy 348.567542 -284.526246)
			(xy 348.6137 -284.552895) (xy 348.655371 -284.586126) (xy 348.691623 -284.625197) (xy 348.721647 -284.669234)
			(xy 348.744773 -284.717255) (xy 348.760483 -284.768185) (xy 348.768426 -284.820889) (xy 348.768924 -284.847538)
			(xy 348.768438 -284.873175) (xy 348.768292 -284.874187) (xy 348.997006 -284.874187) (xy 348.997006 -284.820889)
			(xy 349.004949 -284.768185) (xy 349.020659 -284.717255) (xy 349.043785 -284.669234) (xy 349.073809 -284.625197)
			(xy 349.110061 -284.586126) (xy 349.151732 -284.552895) (xy 349.19789 -284.526246) (xy 349.247504 -284.506774)
			(xy 349.299466 -284.494914) (xy 349.352616 -284.490931) (xy 349.405766 -284.494914) (xy 349.457728 -284.506774)
			(xy 349.507342 -284.526246) (xy 349.5535 -284.552895) (xy 349.595171 -284.586126) (xy 349.631423 -284.625197)
			(xy 349.661447 -284.669234) (xy 349.684573 -284.717255) (xy 349.700283 -284.768185) (xy 349.708226 -284.820889)
			(xy 349.708724 -284.847538) (xy 349.708226 -284.874187) (xy 349.700283 -284.926891) (xy 349.684573 -284.977821)
			(xy 349.661447 -285.025842) (xy 349.631423 -285.069879) (xy 349.595171 -285.10895) (xy 349.5535 -285.142181)
			(xy 349.507342 -285.16883) (xy 349.457728 -285.188302) (xy 349.405766 -285.200162) (xy 349.352616 -285.204146)
			(xy 349.299466 -285.200162) (xy 349.247504 -285.188302) (xy 349.19789 -285.16883) (xy 349.151732 -285.142181)
			(xy 349.110061 -285.10895) (xy 349.073809 -285.069879) (xy 349.043785 -285.025842) (xy 349.020659 -284.977821)
			(xy 349.004949 -284.926891) (xy 348.997006 -284.874187) (xy 348.768292 -284.874187) (xy 348.761092 -284.923921)
			(xy 348.746544 -284.973089) (xy 348.725094 -285.019661) (xy 348.697186 -285.062675) (xy 348.663396 -285.101242)
			(xy 348.624425 -285.134563) (xy 348.581076 -285.161949) (xy 348.534248 -285.182836) (xy 348.484909 -285.196789)
			(xy 348.459552 -285.200598) (xy 348.43466 -285.2039) (xy 348.262194 -285.50235) (xy 348.271846 -285.525464)
			(xy 348.280347 -285.547102) (xy 348.29234 -285.592017) (xy 348.298391 -285.63811) (xy 348.29877 -285.661354)
			(xy 348.526354 -285.661354) (xy 348.526852 -285.634705) (xy 348.534795 -285.582001) (xy 348.550505 -285.531071)
			(xy 348.573631 -285.48305) (xy 348.603655 -285.439013) (xy 348.639907 -285.399942) (xy 348.681578 -285.366711)
			(xy 348.727736 -285.340062) (xy 348.77735 -285.32059) (xy 348.829312 -285.30873) (xy 348.882462 -285.304747)
			(xy 348.935612 -285.30873) (xy 348.987574 -285.32059) (xy 349.037188 -285.340062) (xy 349.083346 -285.366711)
			(xy 349.125017 -285.399942) (xy 349.161269 -285.439013) (xy 349.191293 -285.48305) (xy 349.214419 -285.531071)
			(xy 349.230129 -285.582001) (xy 349.238072 -285.634705) (xy 349.23857 -285.661354) (xy 349.466154 -285.661354)
			(xy 349.466623 -285.635726) (xy 349.473951 -285.584997) (xy 349.488479 -285.535844) (xy 349.509905 -285.489282)
			(xy 349.537787 -285.446273) (xy 349.571549 -285.407708) (xy 349.610492 -285.374383) (xy 349.653812 -285.346988)
			(xy 349.700613 -285.326087) (xy 349.749927 -285.312115) (xy 349.775272 -285.308294) (xy 349.79991 -285.304992)
			(xy 349.97263 -285.006034) (xy 349.962978 -284.98292) (xy 349.954512 -284.961367) (xy 349.942627 -284.916612)
			(xy 349.936658 -284.870692) (xy 349.936308 -284.847538) (xy 349.936806 -284.820889) (xy 349.944749 -284.768185)
			(xy 349.960459 -284.717255) (xy 349.983585 -284.669234) (xy 350.013609 -284.625197) (xy 350.049861 -284.586126)
			(xy 350.091532 -284.552895) (xy 350.13769 -284.526246) (xy 350.187304 -284.506774) (xy 350.239266 -284.494914)
			(xy 350.292416 -284.490931) (xy 350.345566 -284.494914) (xy 350.397528 -284.506774) (xy 350.447142 -284.526246)
			(xy 350.4933 -284.552895) (xy 350.534971 -284.586126) (xy 350.571223 -284.625197) (xy 350.601247 -284.669234)
			(xy 350.624373 -284.717255) (xy 350.640083 -284.768185) (xy 350.648026 -284.820889) (xy 350.648524 -284.847538)
			(xy 350.648038 -284.873175) (xy 350.647892 -284.874187) (xy 350.876352 -284.874187) (xy 350.876352 -284.820889)
			(xy 350.884295 -284.768185) (xy 350.900005 -284.717255) (xy 350.923131 -284.669234) (xy 350.953155 -284.625197)
			(xy 350.989407 -284.586126) (xy 351.031078 -284.552895) (xy 351.077236 -284.526246) (xy 351.12685 -284.506774)
			(xy 351.178812 -284.494914) (xy 351.231962 -284.490931) (xy 351.285112 -284.494914) (xy 351.337074 -284.506774)
			(xy 351.386688 -284.526246) (xy 351.432846 -284.552895) (xy 351.474517 -284.586126) (xy 351.510769 -284.625197)
			(xy 351.540793 -284.669234) (xy 351.563919 -284.717255) (xy 351.579629 -284.768185) (xy 351.587572 -284.820889)
			(xy 351.58807 -284.847538) (xy 351.587572 -284.874187) (xy 351.579629 -284.926891) (xy 351.563919 -284.977821)
			(xy 351.540793 -285.025842) (xy 351.510769 -285.069879) (xy 351.474517 -285.10895) (xy 351.432846 -285.142181)
			(xy 351.386688 -285.16883) (xy 351.337074 -285.188302) (xy 351.285112 -285.200162) (xy 351.231962 -285.204146)
			(xy 351.178812 -285.200162) (xy 351.12685 -285.188302) (xy 351.077236 -285.16883) (xy 351.031078 -285.142181)
			(xy 350.989407 -285.10895) (xy 350.953155 -285.069879) (xy 350.923131 -285.025842) (xy 350.900005 -284.977821)
			(xy 350.884295 -284.926891) (xy 350.876352 -284.874187) (xy 350.647892 -284.874187) (xy 350.640692 -284.923921)
			(xy 350.626144 -284.973089) (xy 350.604694 -285.019661) (xy 350.576786 -285.062675) (xy 350.542996 -285.101242)
			(xy 350.504025 -285.134563) (xy 350.460676 -285.161949) (xy 350.413848 -285.182836) (xy 350.364509 -285.196789)
			(xy 350.339152 -285.200598) (xy 350.31426 -285.2039) (xy 350.141794 -285.50235) (xy 350.151446 -285.525464)
			(xy 350.159947 -285.547102) (xy 350.17194 -285.592017) (xy 350.177991 -285.63811) (xy 350.17837 -285.661354)
			(xy 350.405954 -285.661354) (xy 350.406452 -285.634705) (xy 350.414395 -285.582001) (xy 350.430105 -285.531071)
			(xy 350.453231 -285.48305) (xy 350.483255 -285.439013) (xy 350.519507 -285.399942) (xy 350.561178 -285.366711)
			(xy 350.607336 -285.340062) (xy 350.65695 -285.32059) (xy 350.708912 -285.30873) (xy 350.762062 -285.304747)
			(xy 350.815212 -285.30873) (xy 350.867174 -285.32059) (xy 350.916788 -285.340062) (xy 350.962946 -285.366711)
			(xy 351.004617 -285.399942) (xy 351.040869 -285.439013) (xy 351.070893 -285.48305) (xy 351.094019 -285.531071)
			(xy 351.109729 -285.582001) (xy 351.117672 -285.634705) (xy 351.11817 -285.661354) (xy 351.117777 -285.684557)
			(xy 351.111732 -285.730567) (xy 351.099754 -285.7754) (xy 351.091246 -285.79699) (xy 351.081848 -285.820104)
			(xy 351.254568 -286.119062) (xy 351.279206 -286.122364) (xy 351.304541 -286.126233) (xy 351.353844 -286.140219)
			(xy 351.400634 -286.161125) (xy 351.443945 -286.188521) (xy 351.482884 -286.221841) (xy 351.516645 -286.260397)
			(xy 351.544533 -286.303393) (xy 351.565972 -286.349942) (xy 351.580519 -286.399082) (xy 351.587873 -286.4498)
			(xy 351.588324 -286.475424) (xy 351.587826 -286.502073) (xy 351.579883 -286.554777) (xy 351.564173 -286.605707)
			(xy 351.541047 -286.653728) (xy 351.511023 -286.697765) (xy 351.474771 -286.736836) (xy 351.4331 -286.770067)
			(xy 351.386942 -286.796716) (xy 351.337328 -286.816188) (xy 351.285366 -286.828048) (xy 351.232216 -286.832032)
			(xy 351.179066 -286.828048) (xy 351.127104 -286.816188) (xy 351.07749 -286.796716) (xy 351.031332 -286.770067)
			(xy 350.989661 -286.736836) (xy 350.953409 -286.697765) (xy 350.923385 -286.653728) (xy 350.900259 -286.605707)
			(xy 350.884549 -286.554777) (xy 350.876606 -286.502073) (xy 350.876108 -286.475424) (xy 350.876484 -286.452179)
			(xy 350.882528 -286.406084) (xy 350.894516 -286.361166) (xy 350.903032 -286.339534) (xy 350.912684 -286.31642)
			(xy 350.739964 -286.017716) (xy 350.715326 -286.014414) (xy 350.689977 -286.010553) (xy 350.64064 -285.996602)
			(xy 350.593814 -285.975719) (xy 350.550466 -285.948337) (xy 350.511492 -285.915023) (xy 350.477698 -285.876464)
			(xy 350.449784 -285.833457) (xy 350.428324 -285.786892) (xy 350.413764 -285.737731) (xy 350.406404 -285.68699)
			(xy 350.405954 -285.661354) (xy 350.17837 -285.661354) (xy 350.177872 -285.688003) (xy 350.169929 -285.740707)
			(xy 350.154219 -285.791637) (xy 350.131093 -285.839658) (xy 350.101069 -285.883695) (xy 350.064817 -285.922766)
			(xy 350.023146 -285.955997) (xy 349.976988 -285.982646) (xy 349.927374 -286.002118) (xy 349.875412 -286.013978)
			(xy 349.822262 -286.017962) (xy 349.769112 -286.013978) (xy 349.71715 -286.002118) (xy 349.667536 -285.982646)
			(xy 349.621378 -285.955997) (xy 349.579707 -285.922766) (xy 349.543455 -285.883695) (xy 349.513431 -285.839658)
			(xy 349.490305 -285.791637) (xy 349.474595 -285.740707) (xy 349.466652 -285.688003) (xy 349.466154 -285.661354)
			(xy 349.23857 -285.661354) (xy 349.238177 -285.684557) (xy 349.232132 -285.730567) (xy 349.220154 -285.7754)
			(xy 349.211646 -285.79699) (xy 349.202248 -285.820104) (xy 349.374968 -286.119062) (xy 349.399606 -286.122364)
			(xy 349.424941 -286.126233) (xy 349.474244 -286.140219) (xy 349.521034 -286.161125) (xy 349.564345 -286.188521)
			(xy 349.603284 -286.221841) (xy 349.637045 -286.260397) (xy 349.664933 -286.303393) (xy 349.686372 -286.349942)
			(xy 349.700919 -286.399082) (xy 349.708273 -286.4498) (xy 349.708724 -286.475424) (xy 349.708226 -286.502073)
			(xy 349.936552 -286.502073) (xy 349.936552 -286.448775) (xy 349.944495 -286.396071) (xy 349.960205 -286.345141)
			(xy 349.983331 -286.29712) (xy 350.013355 -286.253083) (xy 350.049607 -286.214012) (xy 350.091278 -286.180781)
			(xy 350.137436 -286.154132) (xy 350.18705 -286.13466) (xy 350.239012 -286.1228) (xy 350.292162 -286.118817)
			(xy 350.345312 -286.1228) (xy 350.397274 -286.13466) (xy 350.446888 -286.154132) (xy 350.493046 -286.180781)
			(xy 350.534717 -286.214012) (xy 350.570969 -286.253083) (xy 350.600993 -286.29712) (xy 350.624119 -286.345141)
			(xy 350.639829 -286.396071) (xy 350.647772 -286.448775) (xy 350.64827 -286.475424) (xy 350.647772 -286.502073)
			(xy 350.639829 -286.554777) (xy 350.624119 -286.605707) (xy 350.600993 -286.653728) (xy 350.570969 -286.697765)
			(xy 350.534717 -286.736836) (xy 350.493046 -286.770067) (xy 350.446888 -286.796716) (xy 350.397274 -286.816188)
			(xy 350.345312 -286.828048) (xy 350.292162 -286.832032) (xy 350.239012 -286.828048) (xy 350.18705 -286.816188)
			(xy 350.137436 -286.796716) (xy 350.091278 -286.770067) (xy 350.049607 -286.736836) (xy 350.013355 -286.697765)
			(xy 349.983331 -286.653728) (xy 349.960205 -286.605707) (xy 349.944495 -286.554777) (xy 349.936552 -286.502073)
			(xy 349.708226 -286.502073) (xy 349.700283 -286.554777) (xy 349.684573 -286.605707) (xy 349.661447 -286.653728)
			(xy 349.631423 -286.697765) (xy 349.595171 -286.736836) (xy 349.5535 -286.770067) (xy 349.507342 -286.796716)
			(xy 349.457728 -286.816188) (xy 349.405766 -286.828048) (xy 349.352616 -286.832032) (xy 349.299466 -286.828048)
			(xy 349.247504 -286.816188) (xy 349.19789 -286.796716) (xy 349.151732 -286.770067) (xy 349.110061 -286.736836)
			(xy 349.073809 -286.697765) (xy 349.043785 -286.653728) (xy 349.020659 -286.605707) (xy 349.004949 -286.554777)
			(xy 348.997006 -286.502073) (xy 348.996508 -286.475424) (xy 348.996884 -286.452179) (xy 349.002928 -286.406084)
			(xy 349.014916 -286.361166) (xy 349.023432 -286.339534) (xy 349.033084 -286.31642) (xy 348.860364 -286.017716)
			(xy 348.835726 -286.014414) (xy 348.810377 -286.010553) (xy 348.76104 -285.996602) (xy 348.714214 -285.975719)
			(xy 348.670866 -285.948337) (xy 348.631892 -285.915023) (xy 348.598098 -285.876464) (xy 348.570184 -285.833457)
			(xy 348.548724 -285.786892) (xy 348.534164 -285.737731) (xy 348.526804 -285.68699) (xy 348.526354 -285.661354)
			(xy 348.29877 -285.661354) (xy 348.298272 -285.688003) (xy 348.290329 -285.740707) (xy 348.274619 -285.791637)
			(xy 348.251493 -285.839658) (xy 348.221469 -285.883695) (xy 348.185217 -285.922766) (xy 348.143546 -285.955997)
			(xy 348.097388 -285.982646) (xy 348.047774 -286.002118) (xy 347.995812 -286.013978) (xy 347.942662 -286.017962)
			(xy 347.889512 -286.013978) (xy 347.83755 -286.002118) (xy 347.787936 -285.982646) (xy 347.741778 -285.955997)
			(xy 347.700107 -285.922766) (xy 347.663855 -285.883695) (xy 347.633831 -285.839658) (xy 347.610705 -285.791637)
			(xy 347.594995 -285.740707) (xy 347.587052 -285.688003) (xy 347.586554 -285.661354) (xy 347.35897 -285.661354)
			(xy 347.358577 -285.684557) (xy 347.352532 -285.730567) (xy 347.340554 -285.7754) (xy 347.332046 -285.79699)
			(xy 347.322648 -285.820104) (xy 347.495368 -286.119062) (xy 347.520006 -286.122364) (xy 347.545341 -286.126233)
			(xy 347.594644 -286.140219) (xy 347.641434 -286.161125) (xy 347.684745 -286.188521) (xy 347.723684 -286.221841)
			(xy 347.757445 -286.260397) (xy 347.785333 -286.303393) (xy 347.806772 -286.349942) (xy 347.821319 -286.399082)
			(xy 347.828673 -286.4498) (xy 347.829124 -286.475424) (xy 347.828626 -286.502073) (xy 348.056952 -286.502073)
			(xy 348.056952 -286.448775) (xy 348.064895 -286.396071) (xy 348.080605 -286.345141) (xy 348.103731 -286.29712)
			(xy 348.133755 -286.253083) (xy 348.170007 -286.214012) (xy 348.211678 -286.180781) (xy 348.257836 -286.154132)
			(xy 348.30745 -286.13466) (xy 348.359412 -286.1228) (xy 348.412562 -286.118817) (xy 348.465712 -286.1228)
			(xy 348.517674 -286.13466) (xy 348.567288 -286.154132) (xy 348.613446 -286.180781) (xy 348.655117 -286.214012)
			(xy 348.691369 -286.253083) (xy 348.721393 -286.29712) (xy 348.744519 -286.345141) (xy 348.760229 -286.396071)
			(xy 348.768172 -286.448775) (xy 348.76867 -286.475424) (xy 348.768172 -286.502073) (xy 348.760229 -286.554777)
			(xy 348.744519 -286.605707) (xy 348.721393 -286.653728) (xy 348.691369 -286.697765) (xy 348.655117 -286.736836)
			(xy 348.613446 -286.770067) (xy 348.567288 -286.796716) (xy 348.517674 -286.816188) (xy 348.465712 -286.828048)
			(xy 348.412562 -286.832032) (xy 348.359412 -286.828048) (xy 348.30745 -286.816188) (xy 348.257836 -286.796716)
			(xy 348.211678 -286.770067) (xy 348.170007 -286.736836) (xy 348.133755 -286.697765) (xy 348.103731 -286.653728)
			(xy 348.080605 -286.605707) (xy 348.064895 -286.554777) (xy 348.056952 -286.502073) (xy 347.828626 -286.502073)
			(xy 347.820683 -286.554777) (xy 347.804973 -286.605707) (xy 347.781847 -286.653728) (xy 347.751823 -286.697765)
			(xy 347.715571 -286.736836) (xy 347.6739 -286.770067) (xy 347.627742 -286.796716) (xy 347.578128 -286.816188)
			(xy 347.526166 -286.828048) (xy 347.473016 -286.832032) (xy 347.419866 -286.828048) (xy 347.367904 -286.816188)
			(xy 347.31829 -286.796716) (xy 347.272132 -286.770067) (xy 347.230461 -286.736836) (xy 347.194209 -286.697765)
			(xy 347.164185 -286.653728) (xy 347.141059 -286.605707) (xy 347.125349 -286.554777) (xy 347.117406 -286.502073)
			(xy 347.116908 -286.475424) (xy 347.117284 -286.452179) (xy 347.123328 -286.406084) (xy 347.135316 -286.361166)
			(xy 347.143832 -286.339534) (xy 347.153484 -286.31642) (xy 346.980764 -286.017716) (xy 346.956126 -286.014414)
			(xy 346.930777 -286.010553) (xy 346.88144 -285.996602) (xy 346.834614 -285.975719) (xy 346.791266 -285.948337)
			(xy 346.752292 -285.915023) (xy 346.718498 -285.876464) (xy 346.690584 -285.833457) (xy 346.669124 -285.786892)
			(xy 346.654564 -285.737731) (xy 346.647204 -285.68699) (xy 346.646754 -285.661354) (xy 346.41917 -285.661354)
			(xy 346.418672 -285.688003) (xy 346.410729 -285.740707) (xy 346.395019 -285.791637) (xy 346.371893 -285.839658)
			(xy 346.341869 -285.883695) (xy 346.305617 -285.922766) (xy 346.263946 -285.955997) (xy 346.217788 -285.982646)
			(xy 346.168174 -286.002118) (xy 346.116212 -286.013978) (xy 346.063062 -286.017962) (xy 346.009912 -286.013978)
			(xy 345.95795 -286.002118) (xy 345.908336 -285.982646) (xy 345.862178 -285.955997) (xy 345.820507 -285.922766)
			(xy 345.784255 -285.883695) (xy 345.754231 -285.839658) (xy 345.731105 -285.791637) (xy 345.715395 -285.740707)
			(xy 345.707452 -285.688003) (xy 345.706954 -285.661354) (xy 345.47937 -285.661354) (xy 345.478977 -285.684557)
			(xy 345.472932 -285.730567) (xy 345.460954 -285.7754) (xy 345.452446 -285.79699) (xy 345.443048 -285.820104)
			(xy 345.615768 -286.119062) (xy 345.640406 -286.122364) (xy 345.665741 -286.126233) (xy 345.715044 -286.140219)
			(xy 345.761834 -286.161125) (xy 345.805145 -286.188521) (xy 345.844084 -286.221841) (xy 345.877845 -286.260397)
			(xy 345.905733 -286.303393) (xy 345.927172 -286.349942) (xy 345.941719 -286.399082) (xy 345.949073 -286.4498)
			(xy 345.949524 -286.475424) (xy 345.949026 -286.502073) (xy 346.177352 -286.502073) (xy 346.177352 -286.448775)
			(xy 346.185295 -286.396071) (xy 346.201005 -286.345141) (xy 346.224131 -286.29712) (xy 346.254155 -286.253083)
			(xy 346.290407 -286.214012) (xy 346.332078 -286.180781) (xy 346.378236 -286.154132) (xy 346.42785 -286.13466)
			(xy 346.479812 -286.1228) (xy 346.532962 -286.118817) (xy 346.586112 -286.1228) (xy 346.638074 -286.13466)
			(xy 346.687688 -286.154132) (xy 346.733846 -286.180781) (xy 346.775517 -286.214012) (xy 346.811769 -286.253083)
			(xy 346.841793 -286.29712) (xy 346.864919 -286.345141) (xy 346.880629 -286.396071) (xy 346.888572 -286.448775)
			(xy 346.88907 -286.475424) (xy 346.888572 -286.502073) (xy 346.880629 -286.554777) (xy 346.864919 -286.605707)
			(xy 346.841793 -286.653728) (xy 346.811769 -286.697765) (xy 346.775517 -286.736836) (xy 346.733846 -286.770067)
			(xy 346.687688 -286.796716) (xy 346.638074 -286.816188) (xy 346.586112 -286.828048) (xy 346.532962 -286.832032)
			(xy 346.479812 -286.828048) (xy 346.42785 -286.816188) (xy 346.378236 -286.796716) (xy 346.332078 -286.770067)
			(xy 346.290407 -286.736836) (xy 346.254155 -286.697765) (xy 346.224131 -286.653728) (xy 346.201005 -286.605707)
			(xy 346.185295 -286.554777) (xy 346.177352 -286.502073) (xy 345.949026 -286.502073) (xy 345.941083 -286.554777)
			(xy 345.925373 -286.605707) (xy 345.902247 -286.653728) (xy 345.872223 -286.697765) (xy 345.835971 -286.736836)
			(xy 345.7943 -286.770067) (xy 345.748142 -286.796716) (xy 345.698528 -286.816188) (xy 345.646566 -286.828048)
			(xy 345.593416 -286.832032) (xy 345.540266 -286.828048) (xy 345.488304 -286.816188) (xy 345.43869 -286.796716)
			(xy 345.392532 -286.770067) (xy 345.350861 -286.736836) (xy 345.314609 -286.697765) (xy 345.284585 -286.653728)
			(xy 345.261459 -286.605707) (xy 345.245749 -286.554777) (xy 345.237806 -286.502073) (xy 345.237308 -286.475424)
			(xy 345.237684 -286.452179) (xy 345.243728 -286.406084) (xy 345.255716 -286.361166) (xy 345.264232 -286.339534)
			(xy 345.273884 -286.31642) (xy 345.101164 -286.017716) (xy 345.076526 -286.014414) (xy 345.051177 -286.010553)
			(xy 345.00184 -285.996602) (xy 344.955014 -285.975719) (xy 344.911666 -285.948337) (xy 344.872692 -285.915023)
			(xy 344.838898 -285.876464) (xy 344.810984 -285.833457) (xy 344.789524 -285.786892) (xy 344.774964 -285.737731)
			(xy 344.767604 -285.68699) (xy 344.767154 -285.661354) (xy 344.53957 -285.661354) (xy 344.539072 -285.688003)
			(xy 344.531129 -285.740707) (xy 344.515419 -285.791637) (xy 344.492293 -285.839658) (xy 344.462269 -285.883695)
			(xy 344.426017 -285.922766) (xy 344.384346 -285.955997) (xy 344.338188 -285.982646) (xy 344.288574 -286.002118)
			(xy 344.236612 -286.013978) (xy 344.183462 -286.017962) (xy 344.130312 -286.013978) (xy 344.07835 -286.002118)
			(xy 344.028736 -285.982646) (xy 343.982578 -285.955997) (xy 343.940907 -285.922766) (xy 343.904655 -285.883695)
			(xy 343.874631 -285.839658) (xy 343.851505 -285.791637) (xy 343.835795 -285.740707) (xy 343.827852 -285.688003)
			(xy 343.827354 -285.661354) (xy 343.59977 -285.661354) (xy 343.599377 -285.684557) (xy 343.593332 -285.730567)
			(xy 343.581354 -285.7754) (xy 343.572846 -285.79699) (xy 343.563448 -285.820104) (xy 343.736168 -286.119062)
			(xy 343.760806 -286.122364) (xy 343.786141 -286.126233) (xy 343.835444 -286.140219) (xy 343.882234 -286.161125)
			(xy 343.925545 -286.188521) (xy 343.964484 -286.221841) (xy 343.998245 -286.260397) (xy 344.026133 -286.303393)
			(xy 344.047572 -286.349942) (xy 344.062119 -286.399082) (xy 344.069473 -286.4498) (xy 344.069924 -286.475424)
			(xy 344.069426 -286.502073) (xy 344.297752 -286.502073) (xy 344.297752 -286.448775) (xy 344.305695 -286.396071)
			(xy 344.321405 -286.345141) (xy 344.344531 -286.29712) (xy 344.374555 -286.253083) (xy 344.410807 -286.214012)
			(xy 344.452478 -286.180781) (xy 344.498636 -286.154132) (xy 344.54825 -286.13466) (xy 344.600212 -286.1228)
			(xy 344.653362 -286.118817) (xy 344.706512 -286.1228) (xy 344.758474 -286.13466) (xy 344.808088 -286.154132)
			(xy 344.854246 -286.180781) (xy 344.895917 -286.214012) (xy 344.932169 -286.253083) (xy 344.962193 -286.29712)
			(xy 344.985319 -286.345141) (xy 345.001029 -286.396071) (xy 345.008972 -286.448775) (xy 345.00947 -286.475424)
			(xy 345.008972 -286.502073) (xy 345.001029 -286.554777) (xy 344.985319 -286.605707) (xy 344.962193 -286.653728)
			(xy 344.932169 -286.697765) (xy 344.895917 -286.736836) (xy 344.854246 -286.770067) (xy 344.808088 -286.796716)
			(xy 344.758474 -286.816188) (xy 344.706512 -286.828048) (xy 344.653362 -286.832032) (xy 344.600212 -286.828048)
			(xy 344.54825 -286.816188) (xy 344.498636 -286.796716) (xy 344.452478 -286.770067) (xy 344.410807 -286.736836)
			(xy 344.374555 -286.697765) (xy 344.344531 -286.653728) (xy 344.321405 -286.605707) (xy 344.305695 -286.554777)
			(xy 344.297752 -286.502073) (xy 344.069426 -286.502073) (xy 344.061483 -286.554777) (xy 344.045773 -286.605707)
			(xy 344.022647 -286.653728) (xy 343.992623 -286.697765) (xy 343.956371 -286.736836) (xy 343.9147 -286.770067)
			(xy 343.868542 -286.796716) (xy 343.818928 -286.816188) (xy 343.766966 -286.828048) (xy 343.713816 -286.832032)
			(xy 343.660666 -286.828048) (xy 343.608704 -286.816188) (xy 343.55909 -286.796716) (xy 343.512932 -286.770067)
			(xy 343.471261 -286.736836) (xy 343.435009 -286.697765) (xy 343.404985 -286.653728) (xy 343.381859 -286.605707)
			(xy 343.366149 -286.554777) (xy 343.358206 -286.502073) (xy 343.357708 -286.475424) (xy 343.358084 -286.452179)
			(xy 343.364128 -286.406084) (xy 343.376116 -286.361166) (xy 343.384632 -286.339534) (xy 343.394284 -286.31642)
			(xy 343.221564 -286.017716) (xy 343.196926 -286.014414) (xy 343.171577 -286.010553) (xy 343.12224 -285.996602)
			(xy 343.075414 -285.975719) (xy 343.032066 -285.948337) (xy 342.993092 -285.915023) (xy 342.959298 -285.876464)
			(xy 342.931384 -285.833457) (xy 342.909924 -285.786892) (xy 342.895364 -285.737731) (xy 342.888004 -285.68699)
			(xy 342.887554 -285.661354) (xy 342.65997 -285.661354) (xy 342.659472 -285.688003) (xy 342.651529 -285.740707)
			(xy 342.635819 -285.791637) (xy 342.612693 -285.839658) (xy 342.582669 -285.883695) (xy 342.546417 -285.922766)
			(xy 342.504746 -285.955997) (xy 342.458588 -285.982646) (xy 342.408974 -286.002118) (xy 342.357012 -286.013978)
			(xy 342.303862 -286.017962) (xy 342.250712 -286.013978) (xy 342.19875 -286.002118) (xy 342.149136 -285.982646)
			(xy 342.102978 -285.955997) (xy 342.061307 -285.922766) (xy 342.025055 -285.883695) (xy 341.995031 -285.839658)
			(xy 341.971905 -285.791637) (xy 341.956195 -285.740707) (xy 341.948252 -285.688003) (xy 341.947754 -285.661354)
			(xy 341.72017 -285.661354) (xy 341.719777 -285.684557) (xy 341.713732 -285.730567) (xy 341.701754 -285.7754)
			(xy 341.693246 -285.79699) (xy 341.683848 -285.820104) (xy 341.856568 -286.119062) (xy 341.881206 -286.122364)
			(xy 341.906541 -286.126233) (xy 341.955844 -286.140219) (xy 342.002634 -286.161125) (xy 342.045945 -286.188521)
			(xy 342.084884 -286.221841) (xy 342.118645 -286.260397) (xy 342.146533 -286.303393) (xy 342.167972 -286.349942)
			(xy 342.182519 -286.399082) (xy 342.189873 -286.4498) (xy 342.190324 -286.475424) (xy 342.189826 -286.502073)
			(xy 342.418152 -286.502073) (xy 342.418152 -286.448775) (xy 342.426095 -286.396071) (xy 342.441805 -286.345141)
			(xy 342.464931 -286.29712) (xy 342.494955 -286.253083) (xy 342.531207 -286.214012) (xy 342.572878 -286.180781)
			(xy 342.619036 -286.154132) (xy 342.66865 -286.13466) (xy 342.720612 -286.1228) (xy 342.773762 -286.118817)
			(xy 342.826912 -286.1228) (xy 342.878874 -286.13466) (xy 342.928488 -286.154132) (xy 342.974646 -286.180781)
			(xy 343.016317 -286.214012) (xy 343.052569 -286.253083) (xy 343.082593 -286.29712) (xy 343.105719 -286.345141)
			(xy 343.121429 -286.396071) (xy 343.129372 -286.448775) (xy 343.12987 -286.475424) (xy 343.129372 -286.502073)
			(xy 343.121429 -286.554777) (xy 343.105719 -286.605707) (xy 343.082593 -286.653728) (xy 343.052569 -286.697765)
			(xy 343.016317 -286.736836) (xy 342.974646 -286.770067) (xy 342.928488 -286.796716) (xy 342.878874 -286.816188)
			(xy 342.826912 -286.828048) (xy 342.773762 -286.832032) (xy 342.720612 -286.828048) (xy 342.66865 -286.816188)
			(xy 342.619036 -286.796716) (xy 342.572878 -286.770067) (xy 342.531207 -286.736836) (xy 342.494955 -286.697765)
			(xy 342.464931 -286.653728) (xy 342.441805 -286.605707) (xy 342.426095 -286.554777) (xy 342.418152 -286.502073)
			(xy 342.189826 -286.502073) (xy 342.181883 -286.554777) (xy 342.166173 -286.605707) (xy 342.143047 -286.653728)
			(xy 342.113023 -286.697765) (xy 342.076771 -286.736836) (xy 342.0351 -286.770067) (xy 341.988942 -286.796716)
			(xy 341.939328 -286.816188) (xy 341.887366 -286.828048) (xy 341.834216 -286.832032) (xy 341.781066 -286.828048)
			(xy 341.729104 -286.816188) (xy 341.67949 -286.796716) (xy 341.633332 -286.770067) (xy 341.591661 -286.736836)
			(xy 341.555409 -286.697765) (xy 341.525385 -286.653728) (xy 341.502259 -286.605707) (xy 341.486549 -286.554777)
			(xy 341.478606 -286.502073) (xy 341.478108 -286.475424) (xy 341.478484 -286.452179) (xy 341.484528 -286.406084)
			(xy 341.496516 -286.361166) (xy 341.505032 -286.339534) (xy 341.514684 -286.31642) (xy 341.341964 -286.017716)
			(xy 341.317326 -286.014414) (xy 341.291977 -286.010553) (xy 341.24264 -285.996602) (xy 341.195814 -285.975719)
			(xy 341.152466 -285.948337) (xy 341.113492 -285.915023) (xy 341.079698 -285.876464) (xy 341.051784 -285.833457)
			(xy 341.030324 -285.786892) (xy 341.015764 -285.737731) (xy 341.008404 -285.68699) (xy 341.007954 -285.661354)
			(xy 340.78037 -285.661354) (xy 340.779872 -285.688003) (xy 340.771929 -285.740707) (xy 340.756219 -285.791637)
			(xy 340.733093 -285.839658) (xy 340.703069 -285.883695) (xy 340.666817 -285.922766) (xy 340.625146 -285.955997)
			(xy 340.578988 -285.982646) (xy 340.529374 -286.002118) (xy 340.477412 -286.013978) (xy 340.424262 -286.017962)
			(xy 340.371112 -286.013978) (xy 340.31915 -286.002118) (xy 340.269536 -285.982646) (xy 340.223378 -285.955997)
			(xy 340.181707 -285.922766) (xy 340.145455 -285.883695) (xy 340.115431 -285.839658) (xy 340.092305 -285.791637)
			(xy 340.076595 -285.740707) (xy 340.068652 -285.688003) (xy 340.068154 -285.661354) (xy 339.840824 -285.661354)
			(xy 339.840439 -285.684599) (xy 339.834399 -285.730694) (xy 339.822415 -285.775612) (xy 339.8139 -285.797244)
			(xy 339.804248 -285.820358) (xy 339.976968 -286.119062) (xy 340.001606 -286.122364) (xy 340.026941 -286.126233)
			(xy 340.076244 -286.140219) (xy 340.123034 -286.161125) (xy 340.166345 -286.188521) (xy 340.205284 -286.221841)
			(xy 340.239045 -286.260397) (xy 340.266933 -286.303393) (xy 340.288372 -286.349942) (xy 340.302919 -286.399082)
			(xy 340.310273 -286.4498) (xy 340.310724 -286.475424) (xy 340.310226 -286.502073) (xy 340.538806 -286.502073)
			(xy 340.538806 -286.448775) (xy 340.546749 -286.396071) (xy 340.562459 -286.345141) (xy 340.585585 -286.29712)
			(xy 340.615609 -286.253083) (xy 340.651861 -286.214012) (xy 340.693532 -286.180781) (xy 340.73969 -286.154132)
			(xy 340.789304 -286.13466) (xy 340.841266 -286.1228) (xy 340.894416 -286.118817) (xy 340.947566 -286.1228)
			(xy 340.999528 -286.13466) (xy 341.049142 -286.154132) (xy 341.0953 -286.180781) (xy 341.136971 -286.214012)
			(xy 341.173223 -286.253083) (xy 341.203247 -286.29712) (xy 341.226373 -286.345141) (xy 341.242083 -286.396071)
			(xy 341.250026 -286.448775) (xy 341.250524 -286.475424) (xy 341.250026 -286.502073) (xy 341.242083 -286.554777)
			(xy 341.226373 -286.605707) (xy 341.203247 -286.653728) (xy 341.173223 -286.697765) (xy 341.136971 -286.736836)
			(xy 341.0953 -286.770067) (xy 341.049142 -286.796716) (xy 340.999528 -286.816188) (xy 340.947566 -286.828048)
			(xy 340.894416 -286.832032) (xy 340.841266 -286.828048) (xy 340.789304 -286.816188) (xy 340.73969 -286.796716)
			(xy 340.693532 -286.770067) (xy 340.651861 -286.736836) (xy 340.615609 -286.697765) (xy 340.585585 -286.653728)
			(xy 340.562459 -286.605707) (xy 340.546749 -286.554777) (xy 340.538806 -286.502073) (xy 340.310226 -286.502073)
			(xy 340.302283 -286.554777) (xy 340.286573 -286.605707) (xy 340.263447 -286.653728) (xy 340.233423 -286.697765)
			(xy 340.197171 -286.736836) (xy 340.1555 -286.770067) (xy 340.109342 -286.796716) (xy 340.059728 -286.816188)
			(xy 340.007766 -286.828048) (xy 339.954616 -286.832032) (xy 339.901466 -286.828048) (xy 339.849504 -286.816188)
			(xy 339.79989 -286.796716) (xy 339.753732 -286.770067) (xy 339.712061 -286.736836) (xy 339.675809 -286.697765)
			(xy 339.645785 -286.653728) (xy 339.622659 -286.605707) (xy 339.606949 -286.554777) (xy 339.599006 -286.502073)
			(xy 339.598508 -286.475424) (xy 339.598884 -286.452179) (xy 339.604928 -286.406084) (xy 339.616916 -286.361166)
			(xy 339.625432 -286.339534) (xy 339.635084 -286.31642) (xy 339.462364 -286.017716) (xy 339.437726 -286.014414)
			(xy 339.412391 -286.010541) (xy 339.363087 -285.996559) (xy 339.316295 -285.975654) (xy 339.272983 -285.94826)
			(xy 339.234043 -285.91494) (xy 339.200281 -285.876384) (xy 339.172393 -285.833388) (xy 339.150955 -285.786838)
			(xy 339.13641 -285.737697) (xy 339.129057 -285.686978) (xy 339.128608 -285.661354) (xy 338.901024 -285.661354)
			(xy 338.900526 -285.688003) (xy 338.892583 -285.740707) (xy 338.876873 -285.791637) (xy 338.853747 -285.839658)
			(xy 338.823723 -285.883695) (xy 338.787471 -285.922766) (xy 338.7458 -285.955997) (xy 338.699642 -285.982646)
			(xy 338.650028 -286.002118) (xy 338.598066 -286.013978) (xy 338.544916 -286.017962) (xy 338.491766 -286.013978)
			(xy 338.439804 -286.002118) (xy 338.39019 -285.982646) (xy 338.344032 -285.955997) (xy 338.302361 -285.922766)
			(xy 338.266109 -285.883695) (xy 338.236085 -285.839658) (xy 338.212959 -285.791637) (xy 338.197249 -285.740707)
			(xy 338.189306 -285.688003) (xy 338.188808 -285.661354) (xy 337.96097 -285.661354) (xy 337.960588 -285.684599)
			(xy 337.954547 -285.730694) (xy 337.942561 -285.775612) (xy 337.934046 -285.797244) (xy 337.924394 -285.820358)
			(xy 338.097114 -286.119062) (xy 338.121752 -286.122364) (xy 338.147093 -286.126197) (xy 338.196396 -286.140189)
			(xy 338.243186 -286.161101) (xy 338.286497 -286.188502) (xy 338.325434 -286.221826) (xy 338.359194 -286.260386)
			(xy 338.387081 -286.303385) (xy 338.408519 -286.349936) (xy 338.423065 -286.399079) (xy 338.43042 -286.449799)
			(xy 338.43087 -286.475424) (xy 338.430372 -286.502073) (xy 338.658952 -286.502073) (xy 338.658952 -286.448775)
			(xy 338.666895 -286.396071) (xy 338.682605 -286.345141) (xy 338.705731 -286.29712) (xy 338.735755 -286.253083)
			(xy 338.772007 -286.214012) (xy 338.813678 -286.180781) (xy 338.859836 -286.154132) (xy 338.90945 -286.13466)
			(xy 338.961412 -286.1228) (xy 339.014562 -286.118817) (xy 339.067712 -286.1228) (xy 339.119674 -286.13466)
			(xy 339.169288 -286.154132) (xy 339.215446 -286.180781) (xy 339.257117 -286.214012) (xy 339.293369 -286.253083)
			(xy 339.323393 -286.29712) (xy 339.346519 -286.345141) (xy 339.362229 -286.396071) (xy 339.370172 -286.448775)
			(xy 339.37067 -286.475424) (xy 339.370172 -286.502073) (xy 339.362229 -286.554777) (xy 339.346519 -286.605707)
			(xy 339.323393 -286.653728) (xy 339.293369 -286.697765) (xy 339.257117 -286.736836) (xy 339.215446 -286.770067)
			(xy 339.169288 -286.796716) (xy 339.119674 -286.816188) (xy 339.067712 -286.828048) (xy 339.014562 -286.832032)
			(xy 338.961412 -286.828048) (xy 338.90945 -286.816188) (xy 338.859836 -286.796716) (xy 338.813678 -286.770067)
			(xy 338.772007 -286.736836) (xy 338.735755 -286.697765) (xy 338.705731 -286.653728) (xy 338.682605 -286.605707)
			(xy 338.666895 -286.554777) (xy 338.658952 -286.502073) (xy 338.430372 -286.502073) (xy 338.422429 -286.554777)
			(xy 338.406719 -286.605707) (xy 338.383593 -286.653728) (xy 338.353569 -286.697765) (xy 338.317317 -286.736836)
			(xy 338.275646 -286.770067) (xy 338.229488 -286.796716) (xy 338.179874 -286.816188) (xy 338.127912 -286.828048)
			(xy 338.074762 -286.832032) (xy 338.021612 -286.828048) (xy 337.96965 -286.816188) (xy 337.920036 -286.796716)
			(xy 337.873878 -286.770067) (xy 337.832207 -286.736836) (xy 337.795955 -286.697765) (xy 337.765931 -286.653728)
			(xy 337.742805 -286.605707) (xy 337.727095 -286.554777) (xy 337.719152 -286.502073) (xy 337.718654 -286.475424)
			(xy 337.719034 -286.452179) (xy 337.725076 -286.406084) (xy 337.737062 -286.361166) (xy 337.745578 -286.339534)
			(xy 337.75523 -286.31642) (xy 337.58251 -286.017716) (xy 337.557872 -286.014414) (xy 337.53253 -286.010584)
			(xy 337.483225 -285.996594) (xy 337.436434 -285.975683) (xy 337.393122 -285.948282) (xy 337.354184 -285.914958)
			(xy 337.320423 -285.876398) (xy 337.292537 -285.833398) (xy 337.2711 -285.786845) (xy 337.256555 -285.737701)
			(xy 337.249203 -285.68698) (xy 337.248754 -285.661354) (xy 337.02117 -285.661354) (xy 337.020672 -285.688003)
			(xy 337.012729 -285.740707) (xy 336.997019 -285.791637) (xy 336.973893 -285.839658) (xy 336.943869 -285.883695)
			(xy 336.907617 -285.922766) (xy 336.865946 -285.955997) (xy 336.819788 -285.982646) (xy 336.770174 -286.002118)
			(xy 336.718212 -286.013978) (xy 336.665062 -286.017962) (xy 336.611912 -286.013978) (xy 336.55995 -286.002118)
			(xy 336.510336 -285.982646) (xy 336.464178 -285.955997) (xy 336.422507 -285.922766) (xy 336.386255 -285.883695)
			(xy 336.356231 -285.839658) (xy 336.333105 -285.791637) (xy 336.317395 -285.740707) (xy 336.309452 -285.688003)
			(xy 336.080872 -285.688003) (xy 336.072929 -285.740707) (xy 336.057219 -285.791637) (xy 336.034093 -285.839658)
			(xy 336.004069 -285.883695) (xy 335.967817 -285.922766) (xy 335.926146 -285.955997) (xy 335.879988 -285.982646)
			(xy 335.830374 -286.002118) (xy 335.778412 -286.013978) (xy 335.725262 -286.017962) (xy 335.672112 -286.013978)
			(xy 335.62015 -286.002118) (xy 335.570536 -285.982646) (xy 335.524378 -285.955997) (xy 335.482707 -285.922766)
			(xy 335.446455 -285.883695) (xy 335.416431 -285.839658) (xy 335.393305 -285.791637) (xy 335.377595 -285.740707)
			(xy 335.369652 -285.688003) (xy 335.369154 -285.661354) (xy 335.14157 -285.661354) (xy 335.141072 -285.688003)
			(xy 335.133129 -285.740707) (xy 335.117419 -285.791637) (xy 335.094293 -285.839658) (xy 335.064269 -285.883695)
			(xy 335.028017 -285.922766) (xy 334.986346 -285.955997) (xy 334.940188 -285.982646) (xy 334.890574 -286.002118)
			(xy 334.838612 -286.013978) (xy 334.785462 -286.017962) (xy 334.732312 -286.013978) (xy 334.68035 -286.002118)
			(xy 334.630736 -285.982646) (xy 334.584578 -285.955997) (xy 334.542907 -285.922766) (xy 334.506655 -285.883695)
			(xy 334.476631 -285.839658) (xy 334.453505 -285.791637) (xy 334.437795 -285.740707) (xy 334.429852 -285.688003)
			(xy 334.200384 -285.688003) (xy 334.198394 -285.714564) (xy 334.18653 -285.76654) (xy 334.167051 -285.816167)
			(xy 334.140393 -285.862336) (xy 334.107151 -285.904016) (xy 334.068068 -285.940276) (xy 334.024017 -285.970305)
			(xy 333.975982 -285.993433) (xy 333.925037 -286.009143) (xy 333.872318 -286.017083) (xy 333.845662 -286.017462)
			(xy 333.816694 -286.016893) (xy 333.759522 -286.007518) (xy 333.704618 -285.98902) (xy 333.653428 -285.961887)
			(xy 333.630016 -285.944818) (xy 333.618494 -285.936632) (xy 333.592182 -285.926343) (xy 333.564058 -285.923657)
			(xy 333.536274 -285.928777) (xy 333.510955 -285.941313) (xy 333.490039 -285.960306) (xy 333.475126 -285.984301)
			(xy 333.467357 -286.011464) (xy 333.466948 -286.02559) (xy 333.466948 -286.129476) (xy 333.499968 -286.141668)
			(xy 333.525141 -286.15157) (xy 333.572401 -286.177883) (xy 333.615137 -286.211041) (xy 333.652367 -286.250281)
			(xy 333.683234 -286.2947) (xy 333.707028 -286.343277) (xy 333.7232 -286.394894) (xy 333.73138 -286.448363)
			(xy 333.731379 -286.475424) (xy 333.959454 -286.475424) (xy 333.959952 -286.448775) (xy 333.967895 -286.396071)
			(xy 333.983605 -286.345141) (xy 334.006731 -286.29712) (xy 334.036755 -286.253083) (xy 334.073007 -286.214012)
			(xy 334.114678 -286.180781) (xy 334.160836 -286.154132) (xy 334.21045 -286.13466) (xy 334.262412 -286.1228)
			(xy 334.315562 -286.118817) (xy 334.368712 -286.1228) (xy 334.420674 -286.13466) (xy 334.470288 -286.154132)
			(xy 334.516446 -286.180781) (xy 334.558117 -286.214012) (xy 334.594369 -286.253083) (xy 334.624393 -286.29712)
			(xy 334.647519 -286.345141) (xy 334.663229 -286.396071) (xy 334.671172 -286.448775) (xy 334.67167 -286.4754)
			(xy 334.898817 -286.4754) (xy 334.902799 -286.422258) (xy 334.914657 -286.370302) (xy 334.934125 -286.320694)
			(xy 334.960769 -286.274542) (xy 334.993994 -286.232875) (xy 335.033057 -286.196626) (xy 335.077087 -286.166603)
			(xy 335.125099 -286.143477) (xy 335.176021 -286.127765) (xy 335.228716 -286.119817) (xy 335.255362 -286.119316)
			(xy 335.280377 -286.119704) (xy 335.329917 -286.126698) (xy 335.377991 -286.140552) (xy 335.423655 -286.160995)
			(xy 335.466009 -286.187625) (xy 335.504222 -286.219918) (xy 335.537542 -286.257239) (xy 335.55178 -286.277812)
			(xy 335.898744 -286.277812) (xy 335.912992 -286.257249) (xy 335.946319 -286.219941) (xy 335.984534 -286.187658)
			(xy 336.026887 -286.161036) (xy 336.072547 -286.140596) (xy 336.120615 -286.12674) (xy 336.170149 -286.119741)
			(xy 336.195162 -286.119316) (xy 336.221817 -286.119739) (xy 336.274532 -286.127679) (xy 336.325474 -286.143388)
			(xy 336.373506 -286.166514) (xy 336.417554 -286.196542) (xy 336.456635 -286.232799) (xy 336.489875 -286.274477)
			(xy 336.516531 -286.320643) (xy 336.536009 -286.370267) (xy 336.547872 -286.42224) (xy 336.551856 -286.4754)
			(xy 336.547872 -286.52856) (xy 336.536009 -286.580533) (xy 336.516531 -286.630157) (xy 336.489875 -286.676323)
			(xy 336.456635 -286.718001) (xy 336.417554 -286.754258) (xy 336.373506 -286.784286) (xy 336.325474 -286.807412)
			(xy 336.274532 -286.823121) (xy 336.221817 -286.831061) (xy 336.195162 -286.831532) (xy 336.170146 -286.831148)
			(xy 336.120605 -286.824157) (xy 336.07253 -286.810304) (xy 336.026866 -286.78986) (xy 335.984511 -286.763229)
			(xy 335.946299 -286.730934) (xy 335.91298 -286.69361) (xy 335.898744 -286.673036) (xy 335.55178 -286.673036)
			(xy 335.537532 -286.693598) (xy 335.504204 -286.730904) (xy 335.465988 -286.763185) (xy 335.423634 -286.789807)
			(xy 335.377975 -286.810247) (xy 335.329907 -286.824104) (xy 335.280375 -286.831106) (xy 335.255362 -286.831532)
			(xy 335.228716 -286.830983) (xy 335.176021 -286.823035) (xy 335.125099 -286.807323) (xy 335.077087 -286.784197)
			(xy 335.033057 -286.754174) (xy 334.993994 -286.717925) (xy 334.960769 -286.676258) (xy 334.934125 -286.630106)
			(xy 334.914657 -286.580498) (xy 334.902799 -286.528542) (xy 334.898817 -286.4754) (xy 334.67167 -286.4754)
			(xy 334.67167 -286.475424) (xy 334.671299 -286.498628) (xy 334.665246 -286.544638) (xy 334.653258 -286.589471)
			(xy 334.644746 -286.61106) (xy 334.635348 -286.634174) (xy 334.807814 -286.932878) (xy 334.832706 -286.93618)
			(xy 334.85803 -286.940046) (xy 334.907302 -286.954063) (xy 334.954058 -286.974993) (xy 334.997334 -287.002403)
			(xy 335.036238 -287.035729) (xy 335.069968 -287.074284) (xy 335.097829 -287.117272) (xy 335.119245 -287.163807)
			(xy 335.133776 -287.212929) (xy 335.141122 -287.263627) (xy 335.14157 -287.28924) (xy 335.141072 -287.315889)
			(xy 335.369652 -287.315889) (xy 335.369652 -287.262591) (xy 335.377595 -287.209887) (xy 335.393305 -287.158957)
			(xy 335.416431 -287.110936) (xy 335.446455 -287.066899) (xy 335.482707 -287.027828) (xy 335.524378 -286.994597)
			(xy 335.570536 -286.967948) (xy 335.62015 -286.948476) (xy 335.672112 -286.936616) (xy 335.725262 -286.932633)
			(xy 335.778412 -286.936616) (xy 335.830374 -286.948476) (xy 335.879988 -286.967948) (xy 335.926146 -286.994597)
			(xy 335.967817 -287.027828) (xy 336.004069 -287.066899) (xy 336.034093 -287.110936) (xy 336.057219 -287.158957)
			(xy 336.072929 -287.209887) (xy 336.080872 -287.262591) (xy 336.08137 -287.28924) (xy 336.080872 -287.315889)
			(xy 336.309452 -287.315889) (xy 336.309452 -287.262591) (xy 336.317395 -287.209887) (xy 336.333105 -287.158957)
			(xy 336.356231 -287.110936) (xy 336.386255 -287.066899) (xy 336.422507 -287.027828) (xy 336.464178 -286.994597)
			(xy 336.510336 -286.967948) (xy 336.55995 -286.948476) (xy 336.611912 -286.936616) (xy 336.665062 -286.932633)
			(xy 336.718212 -286.936616) (xy 336.770174 -286.948476) (xy 336.819788 -286.967948) (xy 336.865946 -286.994597)
			(xy 336.907617 -287.027828) (xy 336.943869 -287.066899) (xy 336.973893 -287.110936) (xy 336.997019 -287.158957)
			(xy 337.012729 -287.209887) (xy 337.020672 -287.262591) (xy 337.02117 -287.28924) (xy 337.020672 -287.315889)
			(xy 337.249252 -287.315889) (xy 337.249252 -287.262591) (xy 337.257195 -287.209887) (xy 337.272905 -287.158957)
			(xy 337.296031 -287.110936) (xy 337.326055 -287.066899) (xy 337.362307 -287.027828) (xy 337.403978 -286.994597)
			(xy 337.450136 -286.967948) (xy 337.49975 -286.948476) (xy 337.551712 -286.936616) (xy 337.604862 -286.932633)
			(xy 337.658012 -286.936616) (xy 337.709974 -286.948476) (xy 337.759588 -286.967948) (xy 337.805746 -286.994597)
			(xy 337.847417 -287.027828) (xy 337.883669 -287.066899) (xy 337.913693 -287.110936) (xy 337.936819 -287.158957)
			(xy 337.952529 -287.209887) (xy 337.960472 -287.262591) (xy 337.96097 -287.28924) (xy 337.960472 -287.315889)
			(xy 338.189306 -287.315889) (xy 338.189306 -287.262591) (xy 338.197249 -287.209887) (xy 338.212959 -287.158957)
			(xy 338.236085 -287.110936) (xy 338.266109 -287.066899) (xy 338.302361 -287.027828) (xy 338.344032 -286.994597)
			(xy 338.39019 -286.967948) (xy 338.439804 -286.948476) (xy 338.491766 -286.936616) (xy 338.544916 -286.932633)
			(xy 338.598066 -286.936616) (xy 338.650028 -286.948476) (xy 338.699642 -286.967948) (xy 338.7458 -286.994597)
			(xy 338.787471 -287.027828) (xy 338.823723 -287.066899) (xy 338.853747 -287.110936) (xy 338.876873 -287.158957)
			(xy 338.892583 -287.209887) (xy 338.900526 -287.262591) (xy 338.901024 -287.28924) (xy 338.900526 -287.315889)
			(xy 339.129106 -287.315889) (xy 339.129106 -287.262591) (xy 339.137049 -287.209887) (xy 339.152759 -287.158957)
			(xy 339.175885 -287.110936) (xy 339.205909 -287.066899) (xy 339.242161 -287.027828) (xy 339.283832 -286.994597)
			(xy 339.32999 -286.967948) (xy 339.379604 -286.948476) (xy 339.431566 -286.936616) (xy 339.484716 -286.932633)
			(xy 339.537866 -286.936616) (xy 339.589828 -286.948476) (xy 339.639442 -286.967948) (xy 339.6856 -286.994597)
			(xy 339.727271 -287.027828) (xy 339.763523 -287.066899) (xy 339.793547 -287.110936) (xy 339.816673 -287.158957)
			(xy 339.832383 -287.209887) (xy 339.840326 -287.262591) (xy 339.840824 -287.28924) (xy 339.840326 -287.315889)
			(xy 340.068906 -287.315889) (xy 340.068906 -287.262591) (xy 340.076849 -287.209887) (xy 340.092559 -287.158957)
			(xy 340.115685 -287.110936) (xy 340.145709 -287.066899) (xy 340.181961 -287.027828) (xy 340.223632 -286.994597)
			(xy 340.26979 -286.967948) (xy 340.319404 -286.948476) (xy 340.371366 -286.936616) (xy 340.424516 -286.932633)
			(xy 340.477666 -286.936616) (xy 340.529628 -286.948476) (xy 340.579242 -286.967948) (xy 340.6254 -286.994597)
			(xy 340.667071 -287.027828) (xy 340.703323 -287.066899) (xy 340.733347 -287.110936) (xy 340.756473 -287.158957)
			(xy 340.772183 -287.209887) (xy 340.780126 -287.262591) (xy 340.780624 -287.28924) (xy 340.780126 -287.315889)
			(xy 341.008452 -287.315889) (xy 341.008452 -287.262591) (xy 341.016395 -287.209887) (xy 341.032105 -287.158957)
			(xy 341.055231 -287.110936) (xy 341.085255 -287.066899) (xy 341.121507 -287.027828) (xy 341.163178 -286.994597)
			(xy 341.209336 -286.967948) (xy 341.25895 -286.948476) (xy 341.310912 -286.936616) (xy 341.364062 -286.932633)
			(xy 341.417212 -286.936616) (xy 341.469174 -286.948476) (xy 341.518788 -286.967948) (xy 341.564946 -286.994597)
			(xy 341.606617 -287.027828) (xy 341.642869 -287.066899) (xy 341.672893 -287.110936) (xy 341.696019 -287.158957)
			(xy 341.711729 -287.209887) (xy 341.719672 -287.262591) (xy 341.72017 -287.28924) (xy 341.719672 -287.315889)
			(xy 341.948252 -287.315889) (xy 341.948252 -287.262591) (xy 341.956195 -287.209887) (xy 341.971905 -287.158957)
			(xy 341.995031 -287.110936) (xy 342.025055 -287.066899) (xy 342.061307 -287.027828) (xy 342.102978 -286.994597)
			(xy 342.149136 -286.967948) (xy 342.19875 -286.948476) (xy 342.250712 -286.936616) (xy 342.303862 -286.932633)
			(xy 342.357012 -286.936616) (xy 342.408974 -286.948476) (xy 342.458588 -286.967948) (xy 342.504746 -286.994597)
			(xy 342.546417 -287.027828) (xy 342.582669 -287.066899) (xy 342.612693 -287.110936) (xy 342.635819 -287.158957)
			(xy 342.651529 -287.209887) (xy 342.659472 -287.262591) (xy 342.65997 -287.28924) (xy 342.659472 -287.315889)
			(xy 342.888052 -287.315889) (xy 342.888052 -287.262591) (xy 342.895995 -287.209887) (xy 342.911705 -287.158957)
			(xy 342.934831 -287.110936) (xy 342.964855 -287.066899) (xy 343.001107 -287.027828) (xy 343.042778 -286.994597)
			(xy 343.088936 -286.967948) (xy 343.13855 -286.948476) (xy 343.190512 -286.936616) (xy 343.243662 -286.932633)
			(xy 343.296812 -286.936616) (xy 343.348774 -286.948476) (xy 343.398388 -286.967948) (xy 343.444546 -286.994597)
			(xy 343.486217 -287.027828) (xy 343.522469 -287.066899) (xy 343.552493 -287.110936) (xy 343.575619 -287.158957)
			(xy 343.591329 -287.209887) (xy 343.599272 -287.262591) (xy 343.59977 -287.28924) (xy 343.599272 -287.315889)
			(xy 343.827852 -287.315889) (xy 343.827852 -287.262591) (xy 343.835795 -287.209887) (xy 343.851505 -287.158957)
			(xy 343.874631 -287.110936) (xy 343.904655 -287.066899) (xy 343.940907 -287.027828) (xy 343.982578 -286.994597)
			(xy 344.028736 -286.967948) (xy 344.07835 -286.948476) (xy 344.130312 -286.936616) (xy 344.183462 -286.932633)
			(xy 344.236612 -286.936616) (xy 344.288574 -286.948476) (xy 344.338188 -286.967948) (xy 344.384346 -286.994597)
			(xy 344.426017 -287.027828) (xy 344.462269 -287.066899) (xy 344.492293 -287.110936) (xy 344.515419 -287.158957)
			(xy 344.531129 -287.209887) (xy 344.539072 -287.262591) (xy 344.53957 -287.28924) (xy 344.539072 -287.315889)
			(xy 344.767652 -287.315889) (xy 344.767652 -287.262591) (xy 344.775595 -287.209887) (xy 344.791305 -287.158957)
			(xy 344.814431 -287.110936) (xy 344.844455 -287.066899) (xy 344.880707 -287.027828) (xy 344.922378 -286.994597)
			(xy 344.968536 -286.967948) (xy 345.01815 -286.948476) (xy 345.070112 -286.936616) (xy 345.123262 -286.932633)
			(xy 345.176412 -286.936616) (xy 345.228374 -286.948476) (xy 345.277988 -286.967948) (xy 345.324146 -286.994597)
			(xy 345.365817 -287.027828) (xy 345.402069 -287.066899) (xy 345.432093 -287.110936) (xy 345.455219 -287.158957)
			(xy 345.470929 -287.209887) (xy 345.478872 -287.262591) (xy 345.47937 -287.28924) (xy 345.478872 -287.315889)
			(xy 345.707452 -287.315889) (xy 345.707452 -287.262591) (xy 345.715395 -287.209887) (xy 345.731105 -287.158957)
			(xy 345.754231 -287.110936) (xy 345.784255 -287.066899) (xy 345.820507 -287.027828) (xy 345.862178 -286.994597)
			(xy 345.908336 -286.967948) (xy 345.95795 -286.948476) (xy 346.009912 -286.936616) (xy 346.063062 -286.932633)
			(xy 346.116212 -286.936616) (xy 346.168174 -286.948476) (xy 346.217788 -286.967948) (xy 346.263946 -286.994597)
			(xy 346.305617 -287.027828) (xy 346.341869 -287.066899) (xy 346.371893 -287.110936) (xy 346.395019 -287.158957)
			(xy 346.410729 -287.209887) (xy 346.418672 -287.262591) (xy 346.41917 -287.28924) (xy 346.418672 -287.315889)
			(xy 346.647252 -287.315889) (xy 346.647252 -287.262591) (xy 346.655195 -287.209887) (xy 346.670905 -287.158957)
			(xy 346.694031 -287.110936) (xy 346.724055 -287.066899) (xy 346.760307 -287.027828) (xy 346.801978 -286.994597)
			(xy 346.848136 -286.967948) (xy 346.89775 -286.948476) (xy 346.949712 -286.936616) (xy 347.002862 -286.932633)
			(xy 347.056012 -286.936616) (xy 347.107974 -286.948476) (xy 347.157588 -286.967948) (xy 347.203746 -286.994597)
			(xy 347.245417 -287.027828) (xy 347.281669 -287.066899) (xy 347.311693 -287.110936) (xy 347.334819 -287.158957)
			(xy 347.350529 -287.209887) (xy 347.358472 -287.262591) (xy 347.35897 -287.28924) (xy 347.358472 -287.315889)
			(xy 347.587052 -287.315889) (xy 347.587052 -287.262591) (xy 347.594995 -287.209887) (xy 347.610705 -287.158957)
			(xy 347.633831 -287.110936) (xy 347.663855 -287.066899) (xy 347.700107 -287.027828) (xy 347.741778 -286.994597)
			(xy 347.787936 -286.967948) (xy 347.83755 -286.948476) (xy 347.889512 -286.936616) (xy 347.942662 -286.932633)
			(xy 347.995812 -286.936616) (xy 348.047774 -286.948476) (xy 348.097388 -286.967948) (xy 348.143546 -286.994597)
			(xy 348.185217 -287.027828) (xy 348.221469 -287.066899) (xy 348.251493 -287.110936) (xy 348.274619 -287.158957)
			(xy 348.290329 -287.209887) (xy 348.298272 -287.262591) (xy 348.29877 -287.28924) (xy 348.298272 -287.315889)
			(xy 348.526852 -287.315889) (xy 348.526852 -287.262591) (xy 348.534795 -287.209887) (xy 348.550505 -287.158957)
			(xy 348.573631 -287.110936) (xy 348.603655 -287.066899) (xy 348.639907 -287.027828) (xy 348.681578 -286.994597)
			(xy 348.727736 -286.967948) (xy 348.77735 -286.948476) (xy 348.829312 -286.936616) (xy 348.882462 -286.932633)
			(xy 348.935612 -286.936616) (xy 348.987574 -286.948476) (xy 349.037188 -286.967948) (xy 349.083346 -286.994597)
			(xy 349.125017 -287.027828) (xy 349.161269 -287.066899) (xy 349.191293 -287.110936) (xy 349.214419 -287.158957)
			(xy 349.230129 -287.209887) (xy 349.238072 -287.262591) (xy 349.23857 -287.28924) (xy 349.238072 -287.315889)
			(xy 349.466652 -287.315889) (xy 349.466652 -287.262591) (xy 349.474595 -287.209887) (xy 349.490305 -287.158957)
			(xy 349.513431 -287.110936) (xy 349.543455 -287.066899) (xy 349.579707 -287.027828) (xy 349.621378 -286.994597)
			(xy 349.667536 -286.967948) (xy 349.71715 -286.948476) (xy 349.769112 -286.936616) (xy 349.822262 -286.932633)
			(xy 349.875412 -286.936616) (xy 349.927374 -286.948476) (xy 349.976988 -286.967948) (xy 350.023146 -286.994597)
			(xy 350.064817 -287.027828) (xy 350.101069 -287.066899) (xy 350.131093 -287.110936) (xy 350.154219 -287.158957)
			(xy 350.169929 -287.209887) (xy 350.177872 -287.262591) (xy 350.17837 -287.28924) (xy 350.177872 -287.315889)
			(xy 350.406452 -287.315889) (xy 350.406452 -287.262591) (xy 350.414395 -287.209887) (xy 350.430105 -287.158957)
			(xy 350.453231 -287.110936) (xy 350.483255 -287.066899) (xy 350.519507 -287.027828) (xy 350.561178 -286.994597)
			(xy 350.607336 -286.967948) (xy 350.65695 -286.948476) (xy 350.708912 -286.936616) (xy 350.762062 -286.932633)
			(xy 350.815212 -286.936616) (xy 350.867174 -286.948476) (xy 350.916788 -286.967948) (xy 350.962946 -286.994597)
			(xy 351.004617 -287.027828) (xy 351.040869 -287.066899) (xy 351.070893 -287.110936) (xy 351.094019 -287.158957)
			(xy 351.109729 -287.209887) (xy 351.117672 -287.262591) (xy 351.11817 -287.28924) (xy 351.117672 -287.315889)
			(xy 351.109729 -287.368593) (xy 351.094019 -287.419523) (xy 351.070893 -287.467544) (xy 351.040869 -287.511581)
			(xy 351.004617 -287.550652) (xy 350.962946 -287.583883) (xy 350.916788 -287.610532) (xy 350.867174 -287.630004)
			(xy 350.815212 -287.641864) (xy 350.762062 -287.645848) (xy 350.708912 -287.641864) (xy 350.65695 -287.630004)
			(xy 350.607336 -287.610532) (xy 350.561178 -287.583883) (xy 350.519507 -287.550652) (xy 350.483255 -287.511581)
			(xy 350.453231 -287.467544) (xy 350.430105 -287.419523) (xy 350.414395 -287.368593) (xy 350.406452 -287.315889)
			(xy 350.177872 -287.315889) (xy 350.169929 -287.368593) (xy 350.154219 -287.419523) (xy 350.131093 -287.467544)
			(xy 350.101069 -287.511581) (xy 350.064817 -287.550652) (xy 350.023146 -287.583883) (xy 349.976988 -287.610532)
			(xy 349.927374 -287.630004) (xy 349.875412 -287.641864) (xy 349.822262 -287.645848) (xy 349.769112 -287.641864)
			(xy 349.71715 -287.630004) (xy 349.667536 -287.610532) (xy 349.621378 -287.583883) (xy 349.579707 -287.550652)
			(xy 349.543455 -287.511581) (xy 349.513431 -287.467544) (xy 349.490305 -287.419523) (xy 349.474595 -287.368593)
			(xy 349.466652 -287.315889) (xy 349.238072 -287.315889) (xy 349.230129 -287.368593) (xy 349.214419 -287.419523)
			(xy 349.191293 -287.467544) (xy 349.161269 -287.511581) (xy 349.125017 -287.550652) (xy 349.083346 -287.583883)
			(xy 349.037188 -287.610532) (xy 348.987574 -287.630004) (xy 348.935612 -287.641864) (xy 348.882462 -287.645848)
			(xy 348.829312 -287.641864) (xy 348.77735 -287.630004) (xy 348.727736 -287.610532) (xy 348.681578 -287.583883)
			(xy 348.639907 -287.550652) (xy 348.603655 -287.511581) (xy 348.573631 -287.467544) (xy 348.550505 -287.419523)
			(xy 348.534795 -287.368593) (xy 348.526852 -287.315889) (xy 348.298272 -287.315889) (xy 348.290329 -287.368593)
			(xy 348.274619 -287.419523) (xy 348.251493 -287.467544) (xy 348.221469 -287.511581) (xy 348.185217 -287.550652)
			(xy 348.143546 -287.583883) (xy 348.097388 -287.610532) (xy 348.047774 -287.630004) (xy 347.995812 -287.641864)
			(xy 347.942662 -287.645848) (xy 347.889512 -287.641864) (xy 347.83755 -287.630004) (xy 347.787936 -287.610532)
			(xy 347.741778 -287.583883) (xy 347.700107 -287.550652) (xy 347.663855 -287.511581) (xy 347.633831 -287.467544)
			(xy 347.610705 -287.419523) (xy 347.594995 -287.368593) (xy 347.587052 -287.315889) (xy 347.358472 -287.315889)
			(xy 347.350529 -287.368593) (xy 347.334819 -287.419523) (xy 347.311693 -287.467544) (xy 347.281669 -287.511581)
			(xy 347.245417 -287.550652) (xy 347.203746 -287.583883) (xy 347.157588 -287.610532) (xy 347.107974 -287.630004)
			(xy 347.056012 -287.641864) (xy 347.002862 -287.645848) (xy 346.949712 -287.641864) (xy 346.89775 -287.630004)
			(xy 346.848136 -287.610532) (xy 346.801978 -287.583883) (xy 346.760307 -287.550652) (xy 346.724055 -287.511581)
			(xy 346.694031 -287.467544) (xy 346.670905 -287.419523) (xy 346.655195 -287.368593) (xy 346.647252 -287.315889)
			(xy 346.418672 -287.315889) (xy 346.410729 -287.368593) (xy 346.395019 -287.419523) (xy 346.371893 -287.467544)
			(xy 346.341869 -287.511581) (xy 346.305617 -287.550652) (xy 346.263946 -287.583883) (xy 346.217788 -287.610532)
			(xy 346.168174 -287.630004) (xy 346.116212 -287.641864) (xy 346.063062 -287.645848) (xy 346.009912 -287.641864)
			(xy 345.95795 -287.630004) (xy 345.908336 -287.610532) (xy 345.862178 -287.583883) (xy 345.820507 -287.550652)
			(xy 345.784255 -287.511581) (xy 345.754231 -287.467544) (xy 345.731105 -287.419523) (xy 345.715395 -287.368593)
			(xy 345.707452 -287.315889) (xy 345.478872 -287.315889) (xy 345.470929 -287.368593) (xy 345.455219 -287.419523)
			(xy 345.432093 -287.467544) (xy 345.402069 -287.511581) (xy 345.365817 -287.550652) (xy 345.324146 -287.583883)
			(xy 345.277988 -287.610532) (xy 345.228374 -287.630004) (xy 345.176412 -287.641864) (xy 345.123262 -287.645848)
			(xy 345.070112 -287.641864) (xy 345.01815 -287.630004) (xy 344.968536 -287.610532) (xy 344.922378 -287.583883)
			(xy 344.880707 -287.550652) (xy 344.844455 -287.511581) (xy 344.814431 -287.467544) (xy 344.791305 -287.419523)
			(xy 344.775595 -287.368593) (xy 344.767652 -287.315889) (xy 344.539072 -287.315889) (xy 344.531129 -287.368593)
			(xy 344.515419 -287.419523) (xy 344.492293 -287.467544) (xy 344.462269 -287.511581) (xy 344.426017 -287.550652)
			(xy 344.384346 -287.583883) (xy 344.338188 -287.610532) (xy 344.288574 -287.630004) (xy 344.236612 -287.641864)
			(xy 344.183462 -287.645848) (xy 344.130312 -287.641864) (xy 344.07835 -287.630004) (xy 344.028736 -287.610532)
			(xy 343.982578 -287.583883) (xy 343.940907 -287.550652) (xy 343.904655 -287.511581) (xy 343.874631 -287.467544)
			(xy 343.851505 -287.419523) (xy 343.835795 -287.368593) (xy 343.827852 -287.315889) (xy 343.599272 -287.315889)
			(xy 343.591329 -287.368593) (xy 343.575619 -287.419523) (xy 343.552493 -287.467544) (xy 343.522469 -287.511581)
			(xy 343.486217 -287.550652) (xy 343.444546 -287.583883) (xy 343.398388 -287.610532) (xy 343.348774 -287.630004)
			(xy 343.296812 -287.641864) (xy 343.243662 -287.645848) (xy 343.190512 -287.641864) (xy 343.13855 -287.630004)
			(xy 343.088936 -287.610532) (xy 343.042778 -287.583883) (xy 343.001107 -287.550652) (xy 342.964855 -287.511581)
			(xy 342.934831 -287.467544) (xy 342.911705 -287.419523) (xy 342.895995 -287.368593) (xy 342.888052 -287.315889)
			(xy 342.659472 -287.315889) (xy 342.651529 -287.368593) (xy 342.635819 -287.419523) (xy 342.612693 -287.467544)
			(xy 342.582669 -287.511581) (xy 342.546417 -287.550652) (xy 342.504746 -287.583883) (xy 342.458588 -287.610532)
			(xy 342.408974 -287.630004) (xy 342.357012 -287.641864) (xy 342.303862 -287.645848) (xy 342.250712 -287.641864)
			(xy 342.19875 -287.630004) (xy 342.149136 -287.610532) (xy 342.102978 -287.583883) (xy 342.061307 -287.550652)
			(xy 342.025055 -287.511581) (xy 341.995031 -287.467544) (xy 341.971905 -287.419523) (xy 341.956195 -287.368593)
			(xy 341.948252 -287.315889) (xy 341.719672 -287.315889) (xy 341.711729 -287.368593) (xy 341.696019 -287.419523)
			(xy 341.672893 -287.467544) (xy 341.642869 -287.511581) (xy 341.606617 -287.550652) (xy 341.564946 -287.583883)
			(xy 341.518788 -287.610532) (xy 341.469174 -287.630004) (xy 341.417212 -287.641864) (xy 341.364062 -287.645848)
			(xy 341.310912 -287.641864) (xy 341.25895 -287.630004) (xy 341.209336 -287.610532) (xy 341.163178 -287.583883)
			(xy 341.121507 -287.550652) (xy 341.085255 -287.511581) (xy 341.055231 -287.467544) (xy 341.032105 -287.419523)
			(xy 341.016395 -287.368593) (xy 341.008452 -287.315889) (xy 340.780126 -287.315889) (xy 340.772183 -287.368593)
			(xy 340.756473 -287.419523) (xy 340.733347 -287.467544) (xy 340.703323 -287.511581) (xy 340.667071 -287.550652)
			(xy 340.6254 -287.583883) (xy 340.579242 -287.610532) (xy 340.529628 -287.630004) (xy 340.477666 -287.641864)
			(xy 340.424516 -287.645848) (xy 340.371366 -287.641864) (xy 340.319404 -287.630004) (xy 340.26979 -287.610532)
			(xy 340.223632 -287.583883) (xy 340.181961 -287.550652) (xy 340.145709 -287.511581) (xy 340.115685 -287.467544)
			(xy 340.092559 -287.419523) (xy 340.076849 -287.368593) (xy 340.068906 -287.315889) (xy 339.840326 -287.315889)
			(xy 339.832383 -287.368593) (xy 339.816673 -287.419523) (xy 339.793547 -287.467544) (xy 339.763523 -287.511581)
			(xy 339.727271 -287.550652) (xy 339.6856 -287.583883) (xy 339.639442 -287.610532) (xy 339.589828 -287.630004)
			(xy 339.537866 -287.641864) (xy 339.484716 -287.645848) (xy 339.431566 -287.641864) (xy 339.379604 -287.630004)
			(xy 339.32999 -287.610532) (xy 339.283832 -287.583883) (xy 339.242161 -287.550652) (xy 339.205909 -287.511581)
			(xy 339.175885 -287.467544) (xy 339.152759 -287.419523) (xy 339.137049 -287.368593) (xy 339.129106 -287.315889)
			(xy 338.900526 -287.315889) (xy 338.892583 -287.368593) (xy 338.876873 -287.419523) (xy 338.853747 -287.467544)
			(xy 338.823723 -287.511581) (xy 338.787471 -287.550652) (xy 338.7458 -287.583883) (xy 338.699642 -287.610532)
			(xy 338.650028 -287.630004) (xy 338.598066 -287.641864) (xy 338.544916 -287.645848) (xy 338.491766 -287.641864)
			(xy 338.439804 -287.630004) (xy 338.39019 -287.610532) (xy 338.344032 -287.583883) (xy 338.302361 -287.550652)
			(xy 338.266109 -287.511581) (xy 338.236085 -287.467544) (xy 338.212959 -287.419523) (xy 338.197249 -287.368593)
			(xy 338.189306 -287.315889) (xy 337.960472 -287.315889) (xy 337.952529 -287.368593) (xy 337.936819 -287.419523)
			(xy 337.913693 -287.467544) (xy 337.883669 -287.511581) (xy 337.847417 -287.550652) (xy 337.805746 -287.583883)
			(xy 337.759588 -287.610532) (xy 337.709974 -287.630004) (xy 337.658012 -287.641864) (xy 337.604862 -287.645848)
			(xy 337.551712 -287.641864) (xy 337.49975 -287.630004) (xy 337.450136 -287.610532) (xy 337.403978 -287.583883)
			(xy 337.362307 -287.550652) (xy 337.326055 -287.511581) (xy 337.296031 -287.467544) (xy 337.272905 -287.419523)
			(xy 337.257195 -287.368593) (xy 337.249252 -287.315889) (xy 337.020672 -287.315889) (xy 337.012729 -287.368593)
			(xy 336.997019 -287.419523) (xy 336.973893 -287.467544) (xy 336.943869 -287.511581) (xy 336.907617 -287.550652)
			(xy 336.865946 -287.583883) (xy 336.819788 -287.610532) (xy 336.770174 -287.630004) (xy 336.718212 -287.641864)
			(xy 336.665062 -287.645848) (xy 336.611912 -287.641864) (xy 336.55995 -287.630004) (xy 336.510336 -287.610532)
			(xy 336.464178 -287.583883) (xy 336.422507 -287.550652) (xy 336.386255 -287.511581) (xy 336.356231 -287.467544)
			(xy 336.333105 -287.419523) (xy 336.317395 -287.368593) (xy 336.309452 -287.315889) (xy 336.080872 -287.315889)
			(xy 336.072929 -287.368593) (xy 336.057219 -287.419523) (xy 336.034093 -287.467544) (xy 336.004069 -287.511581)
			(xy 335.967817 -287.550652) (xy 335.926146 -287.583883) (xy 335.879988 -287.610532) (xy 335.830374 -287.630004)
			(xy 335.778412 -287.641864) (xy 335.725262 -287.645848) (xy 335.672112 -287.641864) (xy 335.62015 -287.630004)
			(xy 335.570536 -287.610532) (xy 335.524378 -287.583883) (xy 335.482707 -287.550652) (xy 335.446455 -287.511581)
			(xy 335.416431 -287.467544) (xy 335.393305 -287.419523) (xy 335.377595 -287.368593) (xy 335.369652 -287.315889)
			(xy 335.141072 -287.315889) (xy 335.133129 -287.368593) (xy 335.117419 -287.419523) (xy 335.094293 -287.467544)
			(xy 335.064269 -287.511581) (xy 335.028017 -287.550652) (xy 334.986346 -287.583883) (xy 334.940188 -287.610532)
			(xy 334.890574 -287.630004) (xy 334.838612 -287.641864) (xy 334.785462 -287.645848) (xy 334.732312 -287.641864)
			(xy 334.68035 -287.630004) (xy 334.630736 -287.610532) (xy 334.584578 -287.583883) (xy 334.542907 -287.550652)
			(xy 334.506655 -287.511581) (xy 334.476631 -287.467544) (xy 334.453505 -287.419523) (xy 334.437795 -287.368593)
			(xy 334.429852 -287.315889) (xy 334.429354 -287.28924) (xy 334.429744 -287.266037) (xy 334.435789 -287.220027)
			(xy 334.447769 -287.175194) (xy 334.456278 -287.153604) (xy 334.465676 -287.13049) (xy 334.29321 -286.831786)
			(xy 334.268318 -286.828484) (xy 334.242995 -286.824616) (xy 334.193728 -286.810592) (xy 334.146976 -286.789658)
			(xy 334.103704 -286.762245) (xy 334.064803 -286.728919) (xy 334.031074 -286.690366) (xy 334.003213 -286.647381)
			(xy 333.981794 -286.600849) (xy 333.967259 -286.55173) (xy 333.959907 -286.501036) (xy 333.959454 -286.475424)
			(xy 333.731379 -286.475424) (xy 333.731379 -286.502454) (xy 333.723196 -286.555923) (xy 333.707021 -286.607539)
			(xy 333.683226 -286.656114) (xy 333.652357 -286.700532) (xy 333.615125 -286.739771) (xy 333.572387 -286.772926)
			(xy 333.525125 -286.799237) (xy 333.499968 -286.80918) (xy 333.466948 -286.821372) (xy 333.466948 -287.597088)
			(xy 333.999565 -288.129705) (xy 334.899752 -288.129705) (xy 334.899752 -288.076407) (xy 334.907695 -288.023703)
			(xy 334.923405 -287.972773) (xy 334.946531 -287.924752) (xy 334.976555 -287.880715) (xy 335.012807 -287.841644)
			(xy 335.054478 -287.808413) (xy 335.100636 -287.781764) (xy 335.15025 -287.762292) (xy 335.202212 -287.750432)
			(xy 335.255362 -287.746449) (xy 335.308512 -287.750432) (xy 335.360474 -287.762292) (xy 335.410088 -287.781764)
			(xy 335.456246 -287.808413) (xy 335.497917 -287.841644) (xy 335.534169 -287.880715) (xy 335.564193 -287.924752)
			(xy 335.587319 -287.972773) (xy 335.603029 -288.023703) (xy 335.610972 -288.076407) (xy 335.61147 -288.103056)
			(xy 335.610972 -288.129705) (xy 335.603029 -288.182409) (xy 335.587319 -288.233339) (xy 335.564193 -288.28136)
			(xy 335.534169 -288.325397) (xy 335.497917 -288.364468) (xy 335.456246 -288.397699) (xy 335.410088 -288.424348)
			(xy 335.360474 -288.44382) (xy 335.308512 -288.45568) (xy 335.255362 -288.459664) (xy 335.202212 -288.45568)
			(xy 335.15025 -288.44382) (xy 335.100636 -288.424348) (xy 335.054478 -288.397699) (xy 335.012807 -288.364468)
			(xy 334.976555 -288.325397) (xy 334.946531 -288.28136) (xy 334.923405 -288.233339) (xy 334.907695 -288.182409)
			(xy 334.899752 -288.129705) (xy 333.999565 -288.129705) (xy 334.706468 -288.836608) (xy 335.376266 -288.836608)
		)
		(stroke
			(width 0)
			(type solid)
		)
		(fill yes)
		(layer "In13.Cu")
		(net "PVCCFA_EHV_FIVRA_CPU0")
	)
	(gr_poly
		(pts
			(xy 10.838434 -317.820548) (xy 10.853749 -317.798226) (xy 10.890037 -317.758057) (xy 10.931989 -317.723847)
			(xy 10.978638 -317.696385) (xy 11.028907 -317.676303) (xy 11.081638 -317.664066) (xy 11.135614 -317.659956)
			(xy 11.18959 -317.664066) (xy 11.242321 -317.676303) (xy 11.29259 -317.696385) (xy 11.339239 -317.723847)
			(xy 11.381191 -317.758057) (xy 11.417479 -317.798226) (xy 11.432794 -317.820548) (xy 18.382234 -317.820548)
			(xy 18.397549 -317.798226) (xy 18.433837 -317.758057) (xy 18.475789 -317.723847) (xy 18.522438 -317.696385)
			(xy 18.572707 -317.676303) (xy 18.625438 -317.664066) (xy 18.679414 -317.659956) (xy 18.73339 -317.664066)
			(xy 18.786121 -317.676303) (xy 18.83639 -317.696385) (xy 18.883039 -317.723847) (xy 18.924991 -317.758057)
			(xy 18.961279 -317.798226) (xy 18.976594 -317.820548) (xy 25.926034 -317.820548) (xy 25.941349 -317.798226)
			(xy 25.977637 -317.758057) (xy 26.019589 -317.723847) (xy 26.066238 -317.696385) (xy 26.116507 -317.676303)
			(xy 26.169238 -317.664066) (xy 26.223214 -317.659956) (xy 26.27719 -317.664066) (xy 26.329921 -317.676303)
			(xy 26.38019 -317.696385) (xy 26.426839 -317.723847) (xy 26.468791 -317.758057) (xy 26.505079 -317.798226)
			(xy 26.520394 -317.820548) (xy 32.991044 -317.820548) (xy 33.005141 -317.820087) (xy 33.032258 -317.81237)
			(xy 33.056234 -317.797534) (xy 33.075242 -317.776711) (xy 33.087835 -317.751485) (xy 33.093054 -317.723778)
			(xy 33.090501 -317.695699) (xy 33.080372 -317.669387) (xy 33.063436 -317.646846) (xy 33.052512 -317.637922)
			(xy 33.037095 -317.626044) (xy 33.007732 -317.600496) (xy 32.993838 -317.586868) (xy 32.598614 -317.191644)
			(xy 32.576256 -317.168627) (xy 32.536271 -317.118438) (xy 32.502152 -317.06409) (xy 32.474329 -317.006266)
			(xy 32.453151 -316.945692) (xy 32.438883 -316.883128) (xy 32.431706 -316.819361) (xy 32.431228 -316.787276)
			(xy 32.431228 -314.569094) (xy 32.431712 -314.535821) (xy 32.439437 -314.469726) (xy 32.454784 -314.404974)
			(xy 32.477543 -314.342442) (xy 32.507409 -314.282975) (xy 32.543976 -314.227377) (xy 32.586751 -314.1764)
			(xy 32.635154 -314.130734) (xy 32.688532 -314.090996) (xy 32.746162 -314.057723) (xy 32.807265 -314.031366)
			(xy 32.871015 -314.01228) (xy 32.936549 -314.000725) (xy 33.002982 -313.996856) (xy 33.069415 -314.000725)
			(xy 33.134949 -314.01228) (xy 33.198699 -314.031366) (xy 33.259802 -314.057723) (xy 33.317432 -314.090996)
			(xy 33.37081 -314.130734) (xy 33.419213 -314.1764) (xy 33.461988 -314.227377) (xy 33.498555 -314.282975)
			(xy 33.528421 -314.342442) (xy 33.55118 -314.404974) (xy 33.566527 -314.469726) (xy 33.574252 -314.535821)
			(xy 33.574736 -314.569094) (xy 33.574736 -314.643241) (xy 46.608736 -314.643241) (xy 46.608736 -314.589943)
			(xy 46.616679 -314.537239) (xy 46.632389 -314.486309) (xy 46.655515 -314.438288) (xy 46.685539 -314.394251)
			(xy 46.721791 -314.35518) (xy 46.763462 -314.321949) (xy 46.80962 -314.2953) (xy 46.859234 -314.275828)
			(xy 46.911196 -314.263968) (xy 46.964346 -314.259985) (xy 47.017496 -314.263968) (xy 47.069458 -314.275828)
			(xy 47.119072 -314.2953) (xy 47.16523 -314.321949) (xy 47.206901 -314.35518) (xy 47.243153 -314.394251)
			(xy 47.273177 -314.438288) (xy 47.296303 -314.486309) (xy 47.312013 -314.537239) (xy 47.319956 -314.589943)
			(xy 47.320454 -314.616592) (xy 47.319956 -314.643241) (xy 47.312013 -314.695945) (xy 47.296303 -314.746875)
			(xy 47.273177 -314.794896) (xy 47.243153 -314.838933) (xy 47.206901 -314.878004) (xy 47.16523 -314.911235)
			(xy 47.119072 -314.937884) (xy 47.069458 -314.957356) (xy 47.017496 -314.969216) (xy 46.964346 -314.9732)
			(xy 46.911196 -314.969216) (xy 46.859234 -314.957356) (xy 46.80962 -314.937884) (xy 46.763462 -314.911235)
			(xy 46.721791 -314.878004) (xy 46.685539 -314.838933) (xy 46.655515 -314.794896) (xy 46.632389 -314.746875)
			(xy 46.616679 -314.695945) (xy 46.608736 -314.643241) (xy 33.574736 -314.643241) (xy 33.574736 -315.493379)
			(xy 35.621204 -315.493379) (xy 35.621204 -315.440081) (xy 35.629147 -315.387377) (xy 35.644857 -315.336447)
			(xy 35.667983 -315.288426) (xy 35.698007 -315.244389) (xy 35.734259 -315.205318) (xy 35.77593 -315.172087)
			(xy 35.822088 -315.145438) (xy 35.871702 -315.125966) (xy 35.923664 -315.114106) (xy 35.976814 -315.110123)
			(xy 36.029964 -315.114106) (xy 36.081926 -315.125966) (xy 36.13154 -315.145438) (xy 36.177698 -315.172087)
			(xy 36.219369 -315.205318) (xy 36.255621 -315.244389) (xy 36.285645 -315.288426) (xy 36.308771 -315.336447)
			(xy 36.324481 -315.387377) (xy 36.332424 -315.440081) (xy 36.332922 -315.46673) (xy 36.332424 -315.493379)
			(xy 50.734204 -315.493379) (xy 50.734204 -315.440081) (xy 50.742147 -315.387377) (xy 50.757857 -315.336447)
			(xy 50.780983 -315.288426) (xy 50.811007 -315.244389) (xy 50.847259 -315.205318) (xy 50.88893 -315.172087)
			(xy 50.935088 -315.145438) (xy 50.984702 -315.125966) (xy 51.036664 -315.114106) (xy 51.089814 -315.110123)
			(xy 51.142964 -315.114106) (xy 51.194926 -315.125966) (xy 51.24454 -315.145438) (xy 51.290698 -315.172087)
			(xy 51.332369 -315.205318) (xy 51.368621 -315.244389) (xy 51.398645 -315.288426) (xy 51.421771 -315.336447)
			(xy 51.437481 -315.387377) (xy 51.445424 -315.440081) (xy 51.445922 -315.46673) (xy 51.445424 -315.493379)
			(xy 51.437481 -315.546083) (xy 51.421771 -315.597013) (xy 51.398645 -315.645034) (xy 51.368621 -315.689071)
			(xy 51.332369 -315.728142) (xy 51.290698 -315.761373) (xy 51.24454 -315.788022) (xy 51.194926 -315.807494)
			(xy 51.142964 -315.819354) (xy 51.089814 -315.823338) (xy 51.036664 -315.819354) (xy 50.984702 -315.807494)
			(xy 50.935088 -315.788022) (xy 50.88893 -315.761373) (xy 50.847259 -315.728142) (xy 50.811007 -315.689071)
			(xy 50.780983 -315.645034) (xy 50.757857 -315.597013) (xy 50.742147 -315.546083) (xy 50.734204 -315.493379)
			(xy 36.332424 -315.493379) (xy 36.324481 -315.546083) (xy 36.308771 -315.597013) (xy 36.285645 -315.645034)
			(xy 36.255621 -315.689071) (xy 36.219369 -315.728142) (xy 36.177698 -315.761373) (xy 36.13154 -315.788022)
			(xy 36.081926 -315.807494) (xy 36.029964 -315.819354) (xy 35.976814 -315.823338) (xy 35.923664 -315.819354)
			(xy 35.871702 -315.807494) (xy 35.822088 -315.788022) (xy 35.77593 -315.761373) (xy 35.734259 -315.728142)
			(xy 35.698007 -315.689071) (xy 35.667983 -315.645034) (xy 35.644857 -315.597013) (xy 35.629147 -315.546083)
			(xy 35.621204 -315.493379) (xy 33.574736 -315.493379) (xy 33.574736 -316.343263) (xy 46.608736 -316.343263)
			(xy 46.608736 -316.289965) (xy 46.616679 -316.237261) (xy 46.632389 -316.186331) (xy 46.655515 -316.13831)
			(xy 46.685539 -316.094273) (xy 46.721791 -316.055202) (xy 46.763462 -316.021971) (xy 46.80962 -315.995322)
			(xy 46.859234 -315.97585) (xy 46.911196 -315.96399) (xy 46.964346 -315.960007) (xy 47.017496 -315.96399)
			(xy 47.069458 -315.97585) (xy 47.119072 -315.995322) (xy 47.16523 -316.021971) (xy 47.206901 -316.055202)
			(xy 47.243153 -316.094273) (xy 47.273177 -316.13831) (xy 47.296303 -316.186331) (xy 47.312013 -316.237261)
			(xy 47.319956 -316.289965) (xy 47.320454 -316.316614) (xy 47.319956 -316.343263) (xy 47.312013 -316.395967)
			(xy 47.296303 -316.446897) (xy 47.273177 -316.494918) (xy 47.243153 -316.538955) (xy 47.206901 -316.578026)
			(xy 47.16523 -316.611257) (xy 47.119072 -316.637906) (xy 47.069458 -316.657378) (xy 47.017496 -316.669238)
			(xy 46.964346 -316.673222) (xy 46.911196 -316.669238) (xy 46.859234 -316.657378) (xy 46.80962 -316.637906)
			(xy 46.763462 -316.611257) (xy 46.721791 -316.578026) (xy 46.685539 -316.538955) (xy 46.655515 -316.494918)
			(xy 46.632389 -316.446897) (xy 46.616679 -316.395967) (xy 46.608736 -316.343263) (xy 33.574736 -316.343263)
			(xy 33.574736 -316.550294) (xy 33.635188 -316.610492) (xy 34.809176 -316.610492) (xy 34.841269 -316.610956)
			(xy 34.905049 -316.61817) (xy 34.967621 -316.632476) (xy 35.0282 -316.653695) (xy 35.086023 -316.68156)
			(xy 35.140364 -316.71572) (xy 35.190541 -316.755748) (xy 35.213544 -316.778132) (xy 35.487102 -317.05169)
			(xy 35.49737 -317.061322) (xy 35.521943 -317.075041) (xy 35.549326 -317.081538) (xy 35.577443 -317.080319)
			(xy 35.604161 -317.071477) (xy 35.627455 -317.055682) (xy 35.645557 -317.034133) (xy 35.651694 -317.021464)
			(xy 35.662555 -316.998258) (xy 35.689953 -316.954964) (xy 35.723272 -316.916042) (xy 35.761825 -316.882297)
			(xy 35.804816 -316.854426) (xy 35.851358 -316.833003) (xy 35.900489 -316.818471) (xy 35.951196 -316.811131)
			(xy 35.976814 -316.810644) (xy 36.004798 -316.811194) (xy 36.060076 -316.81995) (xy 36.113304 -316.837246)
			(xy 36.163172 -316.862654) (xy 36.208452 -316.895549) (xy 36.248029 -316.935122) (xy 36.280929 -316.980399)
			(xy 36.306341 -317.030264) (xy 36.323642 -317.083491) (xy 36.332403 -317.138768) (xy 36.332922 -317.166752)
			(xy 36.332757 -317.182199) (xy 36.331785 -317.193401) (xy 43.165004 -317.193401) (xy 43.165004 -317.140103)
			(xy 43.172947 -317.087399) (xy 43.188657 -317.036469) (xy 43.211783 -316.988448) (xy 43.241807 -316.944411)
			(xy 43.278059 -316.90534) (xy 43.31973 -316.872109) (xy 43.365888 -316.84546) (xy 43.415502 -316.825988)
			(xy 43.467464 -316.814128) (xy 43.520614 -316.810145) (xy 43.573764 -316.814128) (xy 43.625726 -316.825988)
			(xy 43.67534 -316.84546) (xy 43.721498 -316.872109) (xy 43.763169 -316.90534) (xy 43.799421 -316.944411)
			(xy 43.829445 -316.988448) (xy 43.852571 -317.036469) (xy 43.868281 -317.087399) (xy 43.876224 -317.140103)
			(xy 43.876722 -317.166752) (xy 43.876224 -317.193401) (xy 50.708804 -317.193401) (xy 50.708804 -317.140103)
			(xy 50.716747 -317.087399) (xy 50.732457 -317.036469) (xy 50.755583 -316.988448) (xy 50.785607 -316.944411)
			(xy 50.821859 -316.90534) (xy 50.86353 -316.872109) (xy 50.909688 -316.84546) (xy 50.959302 -316.825988)
			(xy 51.011264 -316.814128) (xy 51.064414 -316.810145) (xy 51.117564 -316.814128) (xy 51.169526 -316.825988)
			(xy 51.21914 -316.84546) (xy 51.265298 -316.872109) (xy 51.306969 -316.90534) (xy 51.343221 -316.944411)
			(xy 51.373245 -316.988448) (xy 51.396371 -317.036469) (xy 51.412081 -317.087399) (xy 51.420024 -317.140103)
			(xy 51.420522 -317.166752) (xy 51.420024 -317.193401) (xy 58.252604 -317.193401) (xy 58.252604 -317.140103)
			(xy 58.260547 -317.087399) (xy 58.276257 -317.036469) (xy 58.299383 -316.988448) (xy 58.329407 -316.944411)
			(xy 58.365659 -316.90534) (xy 58.40733 -316.872109) (xy 58.453488 -316.84546) (xy 58.503102 -316.825988)
			(xy 58.555064 -316.814128) (xy 58.608214 -316.810145) (xy 58.661364 -316.814128) (xy 58.713326 -316.825988)
			(xy 58.76294 -316.84546) (xy 58.809098 -316.872109) (xy 58.850769 -316.90534) (xy 58.887021 -316.944411)
			(xy 58.917045 -316.988448) (xy 58.940171 -317.036469) (xy 58.955881 -317.087399) (xy 58.963824 -317.140103)
			(xy 58.964322 -317.166752) (xy 58.963824 -317.193401) (xy 58.955881 -317.246105) (xy 58.940171 -317.297035)
			(xy 58.917045 -317.345056) (xy 58.887021 -317.389093) (xy 58.850769 -317.428164) (xy 58.809098 -317.461395)
			(xy 58.76294 -317.488044) (xy 58.713326 -317.507516) (xy 58.661364 -317.519376) (xy 58.608214 -317.52336)
			(xy 58.555064 -317.519376) (xy 58.503102 -317.507516) (xy 58.453488 -317.488044) (xy 58.40733 -317.461395)
			(xy 58.365659 -317.428164) (xy 58.329407 -317.389093) (xy 58.299383 -317.345056) (xy 58.276257 -317.297035)
			(xy 58.260547 -317.246105) (xy 58.252604 -317.193401) (xy 51.420024 -317.193401) (xy 51.412081 -317.246105)
			(xy 51.396371 -317.297035) (xy 51.373245 -317.345056) (xy 51.343221 -317.389093) (xy 51.306969 -317.428164)
			(xy 51.265298 -317.461395) (xy 51.21914 -317.488044) (xy 51.169526 -317.507516) (xy 51.117564 -317.519376)
			(xy 51.064414 -317.52336) (xy 51.011264 -317.519376) (xy 50.959302 -317.507516) (xy 50.909688 -317.488044)
			(xy 50.86353 -317.461395) (xy 50.821859 -317.428164) (xy 50.785607 -317.389093) (xy 50.755583 -317.345056)
			(xy 50.732457 -317.297035) (xy 50.716747 -317.246105) (xy 50.708804 -317.193401) (xy 43.876224 -317.193401)
			(xy 43.868281 -317.246105) (xy 43.852571 -317.297035) (xy 43.829445 -317.345056) (xy 43.799421 -317.389093)
			(xy 43.763169 -317.428164) (xy 43.721498 -317.461395) (xy 43.67534 -317.488044) (xy 43.625726 -317.507516)
			(xy 43.573764 -317.519376) (xy 43.520614 -317.52336) (xy 43.467464 -317.519376) (xy 43.415502 -317.507516)
			(xy 43.365888 -317.488044) (xy 43.31973 -317.461395) (xy 43.278059 -317.428164) (xy 43.241807 -317.389093)
			(xy 43.211783 -317.345056) (xy 43.188657 -317.297035) (xy 43.172947 -317.246105) (xy 43.165004 -317.193401)
			(xy 36.331785 -317.193401) (xy 36.330087 -317.212976) (xy 36.327588 -317.22822) (xy 36.325493 -317.242903)
			(xy 36.328903 -317.272351) (xy 36.340625 -317.29958) (xy 36.359672 -317.322296) (xy 36.384439 -317.338588)
			(xy 36.412841 -317.347082) (xy 36.427664 -317.3476) (xy 40.583866 -317.3476) (xy 40.618114 -317.348089)
			(xy 40.686123 -317.356241) (xy 40.752671 -317.372457) (xy 40.816807 -317.396504) (xy 40.877611 -317.428038)
			(xy 40.906192 -317.446914) (xy 40.939335 -317.462346) (xy 41.001749 -317.500415) (xy 41.058805 -317.546128)
			(xy 41.10957 -317.598738) (xy 41.153217 -317.657388) (xy 41.171622 -317.688976) (xy 41.193716 -317.679993)
			(xy 41.239704 -317.667346) (xy 41.286967 -317.660947) (xy 41.310814 -317.660528) (xy 41.335944 -317.660961)
			(xy 41.385704 -317.66803) (xy 41.433975 -317.682027) (xy 41.479799 -317.702672) (xy 41.522264 -317.729556)
			(xy 41.560527 -317.762144) (xy 41.593827 -317.799788) (xy 41.607994 -317.820548) (xy 48.557434 -317.820548)
			(xy 48.572749 -317.798226) (xy 48.609037 -317.758057) (xy 48.650989 -317.723847) (xy 48.697638 -317.696385)
			(xy 48.747907 -317.676303) (xy 48.800638 -317.664066) (xy 48.854614 -317.659956) (xy 48.90859 -317.664066)
			(xy 48.961321 -317.676303) (xy 49.01159 -317.696385) (xy 49.058239 -317.723847) (xy 49.100191 -317.758057)
			(xy 49.136479 -317.798226) (xy 49.151794 -317.820548) (xy 56.101234 -317.820548) (xy 56.116549 -317.798226)
			(xy 56.152837 -317.758057) (xy 56.194789 -317.723847) (xy 56.241438 -317.696385) (xy 56.291707 -317.676303)
			(xy 56.344438 -317.664066) (xy 56.398414 -317.659956) (xy 56.45239 -317.664066) (xy 56.505121 -317.676303)
			(xy 56.55539 -317.696385) (xy 56.602039 -317.723847) (xy 56.643991 -317.758057) (xy 56.680279 -317.798226)
			(xy 56.695594 -317.820548) (xy 59.4106 -317.820548) (xy 61.723016 -315.508132) (xy 61.721746 -315.485272)
			(xy 61.721238 -315.46673) (xy 61.721719 -315.440741) (xy 61.729847 -315.389401) (xy 61.745907 -315.339965)
			(xy 61.769504 -315.293651) (xy 61.800056 -315.2516) (xy 61.836812 -315.214846) (xy 61.878865 -315.184295)
			(xy 61.92518 -315.160701) (xy 61.974617 -315.144643) (xy 62.025956 -315.136518) (xy 62.051946 -315.136022)
			(xy 62.070488 -315.13653) (xy 62.093348 -315.1378) (xy 64.9605 -312.270648) (xy 64.9605 -254.35306)
			(xy 64.96011 -254.339727) (xy 64.953212 -254.313969) (xy 64.939872 -254.290879) (xy 64.921003 -254.272037)
			(xy 64.897894 -254.258731) (xy 64.872126 -254.251871) (xy 64.84546 -254.251926) (xy 64.832484 -254.255016)
			(xy 64.809737 -254.260749) (xy 64.763229 -254.266871) (xy 64.739774 -254.267208) (xy 64.713126 -254.266709)
			(xy 64.660426 -254.258762) (xy 64.609498 -254.243049) (xy 64.561481 -254.219922) (xy 64.517447 -254.189898)
			(xy 64.47838 -254.153646) (xy 64.445151 -254.111976) (xy 64.418505 -254.065819) (xy 64.399034 -254.016207)
			(xy 64.387175 -253.964247) (xy 64.383192 -253.9111) (xy 64.387175 -253.857953) (xy 64.399034 -253.805993)
			(xy 64.418505 -253.756381) (xy 64.445151 -253.710224) (xy 64.47838 -253.668554) (xy 64.517447 -253.632302)
			(xy 64.561481 -253.602278) (xy 64.609498 -253.579151) (xy 64.660426 -253.563438) (xy 64.713126 -253.555491)
			(xy 64.739774 -253.554992) (xy 64.763228 -253.555348) (xy 64.809737 -253.561458) (xy 64.832484 -253.567184)
			(xy 64.845456 -253.570267) (xy 64.872111 -253.570298) (xy 64.897865 -253.563425) (xy 64.92096 -253.550119)
			(xy 64.939823 -253.531285) (xy 64.953165 -253.50821) (xy 64.960077 -253.482467) (xy 64.9605 -253.46914)
			(xy 64.9605 -189.055248) (xy 64.262 -188.356748) (xy 53.83403 -188.356748) (xy 53.810082 -188.370605)
			(xy 53.758872 -188.391547) (xy 53.70504 -188.404317) (xy 53.64988 -188.408609) (xy 53.59472 -188.404317)
			(xy 53.540888 -188.391547) (xy 53.489678 -188.370605) (xy 53.46573 -188.356748) (xy 21.869146 -188.356748)
			(xy 21.85797 -188.392308) (xy 21.848911 -188.419217) (xy 21.823953 -188.470214) (xy 21.791713 -188.516948)
			(xy 21.752902 -188.558388) (xy 21.708379 -188.593619) (xy 21.659125 -188.621861) (xy 21.60623 -188.642492)
			(xy 21.550861 -188.655056) (xy 21.494242 -188.659275) (xy 21.437623 -188.655056) (xy 21.382254 -188.642492)
			(xy 21.329359 -188.621861) (xy 21.280105 -188.593619) (xy 21.235582 -188.558388) (xy 21.196771 -188.516948)
			(xy 21.164531 -188.470214) (xy 21.139573 -188.419217) (xy 21.130514 -188.392308) (xy 21.119338 -188.356748)
			(xy 8.7884 -188.356748) (xy 8.5852 -188.559948) (xy 8.5852 -189.333886) (xy 9.988804 -190.737744)
			(xy 10.008928 -190.758595) (xy 10.043026 -190.805445) (xy 10.069374 -190.857054) (xy 10.087322 -190.91215)
			(xy 10.096428 -190.969376) (xy 10.097008 -190.998348) (xy 10.097008 -191.700404) (xy 18.352768 -191.700404)
			(xy 18.356839 -191.644782) (xy 18.368965 -191.590345) (xy 18.388888 -191.538254) (xy 18.416184 -191.489619)
			(xy 18.45027 -191.445476) (xy 18.490419 -191.406767) (xy 18.535777 -191.374316) (xy 18.585377 -191.348815)
			(xy 18.638161 -191.330808) (xy 18.693004 -191.320678) (xy 18.748738 -191.318641) (xy 18.804175 -191.324741)
			(xy 18.858132 -191.338847) (xy 18.909461 -191.360659) (xy 18.957067 -191.389713) (xy 18.999935 -191.425388)
			(xy 19.037152 -191.466925) (xy 19.067925 -191.513438) (xy 19.091597 -191.563935) (xy 19.107665 -191.617342)
			(xy 19.115785 -191.672518) (xy 19.116294 -191.700404) (xy 19.115785 -191.72829) (xy 19.107665 -191.783466)
			(xy 19.091597 -191.836873) (xy 19.067925 -191.88737) (xy 19.037152 -191.933883) (xy 18.999935 -191.97542)
			(xy 18.957067 -192.011095) (xy 18.909461 -192.040149) (xy 18.858132 -192.061961) (xy 18.804175 -192.076067)
			(xy 18.748738 -192.082167) (xy 18.693004 -192.08013) (xy 18.638161 -192.07) (xy 18.585377 -192.051993)
			(xy 18.535777 -192.026492) (xy 18.490419 -191.994041) (xy 18.45027 -191.955332) (xy 18.416184 -191.911189)
			(xy 18.388888 -191.862554) (xy 18.368965 -191.810463) (xy 18.356839 -191.756026) (xy 18.352768 -191.700404)
			(xy 10.097008 -191.700404) (xy 10.097008 -192.848484) (xy 18.352768 -192.848484) (xy 18.356839 -192.792862)
			(xy 18.368965 -192.738425) (xy 18.388888 -192.686334) (xy 18.416184 -192.637699) (xy 18.45027 -192.593556)
			(xy 18.490419 -192.554847) (xy 18.535777 -192.522396) (xy 18.585377 -192.496895) (xy 18.638161 -192.478888)
			(xy 18.693004 -192.468758) (xy 18.748738 -192.466721) (xy 18.804175 -192.472821) (xy 18.858132 -192.486927)
			(xy 18.909461 -192.508739) (xy 18.957067 -192.537793) (xy 18.999935 -192.573468) (xy 19.037152 -192.615005)
			(xy 19.067925 -192.661518) (xy 19.091597 -192.712015) (xy 19.107665 -192.765422) (xy 19.115785 -192.820598)
			(xy 19.116294 -192.848484) (xy 20.437346 -192.848484) (xy 20.441417 -192.792862) (xy 20.453543 -192.738425)
			(xy 20.473466 -192.686334) (xy 20.500762 -192.637699) (xy 20.534848 -192.593556) (xy 20.574997 -192.554847)
			(xy 20.620355 -192.522396) (xy 20.669955 -192.496895) (xy 20.722739 -192.478888) (xy 20.777582 -192.468758)
			(xy 20.833316 -192.466721) (xy 20.888753 -192.472821) (xy 20.94271 -192.486927) (xy 20.994039 -192.508739)
			(xy 21.041645 -192.537793) (xy 21.084513 -192.573468) (xy 21.12173 -192.615005) (xy 21.152503 -192.661518)
			(xy 21.176175 -192.712015) (xy 21.192243 -192.765422) (xy 21.200363 -192.820598) (xy 21.200872 -192.848484)
			(xy 21.200738 -192.85585) (xy 21.43074 -192.85585) (xy 21.434811 -192.800228) (xy 21.446937 -192.745791)
			(xy 21.46686 -192.6937) (xy 21.494156 -192.645065) (xy 21.528242 -192.600922) (xy 21.568391 -192.562213)
			(xy 21.613749 -192.529762) (xy 21.663349 -192.504261) (xy 21.716133 -192.486254) (xy 21.770976 -192.476124)
			(xy 21.82671 -192.474087) (xy 21.882147 -192.480187) (xy 21.936104 -192.494293) (xy 21.987433 -192.516105)
			(xy 22.035039 -192.545159) (xy 22.077907 -192.580834) (xy 22.115124 -192.622371) (xy 22.145897 -192.668884)
			(xy 22.169569 -192.719381) (xy 22.179601 -192.752726) (xy 27.69184 -192.752726) (xy 27.695911 -192.697104)
			(xy 27.708037 -192.642667) (xy 27.72796 -192.590576) (xy 27.755256 -192.541941) (xy 27.789342 -192.497798)
			(xy 27.829491 -192.459089) (xy 27.874849 -192.426638) (xy 27.924449 -192.401137) (xy 27.977233 -192.38313)
			(xy 28.032076 -192.373) (xy 28.08781 -192.370963) (xy 28.143247 -192.377063) (xy 28.197204 -192.391169)
			(xy 28.248533 -192.412981) (xy 28.296139 -192.442035) (xy 28.339007 -192.47771) (xy 28.376224 -192.519247)
			(xy 28.379452 -192.524126) (xy 37.94074 -192.524126) (xy 37.944811 -192.468504) (xy 37.956937 -192.414067)
			(xy 37.97686 -192.361976) (xy 38.004156 -192.313341) (xy 38.038242 -192.269198) (xy 38.078391 -192.230489)
			(xy 38.123749 -192.198038) (xy 38.173349 -192.172537) (xy 38.226133 -192.15453) (xy 38.280976 -192.1444)
			(xy 38.33671 -192.142363) (xy 38.392147 -192.148463) (xy 38.446104 -192.162569) (xy 38.497433 -192.184381)
			(xy 38.545039 -192.213435) (xy 38.587907 -192.24911) (xy 38.625124 -192.290647) (xy 38.64438 -192.319752)
			(xy 46.821056 -192.319752) (xy 46.821056 -192.265248) (xy 46.828813 -192.211298) (xy 46.844168 -192.159001)
			(xy 46.86681 -192.109421) (xy 46.896277 -192.063569) (xy 46.931969 -192.022376) (xy 46.973161 -191.986683)
			(xy 47.019013 -191.957215) (xy 47.068591 -191.934572) (xy 47.120888 -191.919215) (xy 47.174838 -191.911457)
			(xy 47.20209 -191.91097) (xy 47.231082 -191.911497) (xy 47.288399 -191.920264) (xy 47.343727 -191.937611)
			(xy 47.39579 -191.963139) (xy 47.443384 -191.996258) (xy 47.485413 -192.036204) (xy 47.503588 -192.058798)
			(xy 47.5126 -192.069773) (xy 47.535503 -192.086551) (xy 47.56214 -192.096373) (xy 47.590452 -192.09848)
			(xy 47.61825 -192.092709) (xy 47.643384 -192.079506) (xy 47.663911 -192.059893) (xy 47.671482 -192.047876)
			(xy 47.686278 -192.023698) (xy 47.721914 -191.979617) (xy 47.76368 -191.941294) (xy 47.810656 -191.909572)
			(xy 47.861808 -191.885149) (xy 47.91601 -191.868563) (xy 47.97207 -191.860179) (xy 48.000412 -191.859662)
			(xy 48.029222 -191.860183) (xy 48.086184 -191.868861) (xy 48.141194 -191.886003) (xy 48.193003 -191.91122)
			(xy 48.240432 -191.943939) (xy 48.261778 -191.963294) (xy 48.273444 -191.973537) (xy 48.30135 -191.987104)
			(xy 48.332043 -191.991657) (xy 48.362685 -191.986777) (xy 48.390445 -191.972915) (xy 48.401986 -191.962532)
			(xy 48.423474 -191.94261) (xy 48.471368 -191.908856) (xy 48.523857 -191.882818) (xy 48.579709 -191.865107)
			(xy 48.637612 -191.856139) (xy 48.666908 -191.855598) (xy 48.694159 -191.856072) (xy 48.748107 -191.86383)
			(xy 48.800402 -191.879186) (xy 48.849979 -191.901828) (xy 48.895829 -191.931295) (xy 48.937019 -191.966987)
			(xy 48.97271 -192.008178) (xy 49.002176 -192.054028) (xy 49.024817 -192.103606) (xy 49.040172 -192.155901)
			(xy 49.047928 -192.209849) (xy 49.047928 -192.237106) (xy 49.30089 -192.237106) (xy 49.304961 -192.181484)
			(xy 49.317087 -192.127047) (xy 49.33701 -192.074956) (xy 49.364306 -192.026321) (xy 49.398392 -191.982178)
			(xy 49.438541 -191.943469) (xy 49.483899 -191.911018) (xy 49.533499 -191.885517) (xy 49.586283 -191.86751)
			(xy 49.641126 -191.85738) (xy 49.69686 -191.855343) (xy 49.752297 -191.861443) (xy 49.806254 -191.875549)
			(xy 49.857583 -191.897361) (xy 49.905189 -191.926415) (xy 49.948057 -191.96209) (xy 49.985274 -192.003627)
			(xy 50.016047 -192.05014) (xy 50.039719 -192.100637) (xy 50.055787 -192.154044) (xy 50.063907 -192.20922)
			(xy 50.064416 -192.237106) (xy 50.064342 -192.24117) (xy 51.33289 -192.24117) (xy 51.336961 -192.185548)
			(xy 51.349087 -192.131111) (xy 51.36901 -192.07902) (xy 51.396306 -192.030385) (xy 51.430392 -191.986242)
			(xy 51.470541 -191.947533) (xy 51.515899 -191.915082) (xy 51.565499 -191.889581) (xy 51.618283 -191.871574)
			(xy 51.673126 -191.861444) (xy 51.72886 -191.859407) (xy 51.784297 -191.865507) (xy 51.838254 -191.879613)
			(xy 51.889583 -191.901425) (xy 51.937189 -191.930479) (xy 51.980057 -191.966154) (xy 52.017274 -192.007691)
			(xy 52.048047 -192.054204) (xy 52.071719 -192.104701) (xy 52.087787 -192.158108) (xy 52.095907 -192.213284)
			(xy 52.096416 -192.24117) (xy 53.36489 -192.24117) (xy 53.368961 -192.185548) (xy 53.381087 -192.131111)
			(xy 53.40101 -192.07902) (xy 53.428306 -192.030385) (xy 53.462392 -191.986242) (xy 53.502541 -191.947533)
			(xy 53.547899 -191.915082) (xy 53.597499 -191.889581) (xy 53.650283 -191.871574) (xy 53.705126 -191.861444)
			(xy 53.76086 -191.859407) (xy 53.816297 -191.865507) (xy 53.870254 -191.879613) (xy 53.921583 -191.901425)
			(xy 53.969189 -191.930479) (xy 54.012057 -191.966154) (xy 54.049274 -192.007691) (xy 54.080047 -192.054204)
			(xy 54.103719 -192.104701) (xy 54.119787 -192.158108) (xy 54.127907 -192.213284) (xy 54.128416 -192.24117)
			(xy 54.127907 -192.269056) (xy 54.127628 -192.270949) (xy 54.696888 -192.270949) (xy 54.696888 -192.216451)
			(xy 54.704644 -192.162508) (xy 54.719997 -192.110217) (xy 54.742635 -192.060643) (xy 54.772097 -192.014795)
			(xy 54.807784 -191.973607) (xy 54.84897 -191.937917) (xy 54.894815 -191.90845) (xy 54.944387 -191.885808)
			(xy 54.996676 -191.87045) (xy 55.050619 -191.86269) (xy 55.077868 -191.862202) (xy 55.104824 -191.862711)
			(xy 55.158199 -191.870292) (xy 55.209977 -191.885306) (xy 55.259128 -191.907455) (xy 55.304674 -191.9363)
			(xy 55.345708 -191.971265) (xy 55.381416 -192.011655) (xy 55.396638 -192.033906) (xy 55.404978 -192.045741)
			(xy 55.427026 -192.064492) (xy 55.453448 -192.076304) (xy 55.482123 -192.08023) (xy 55.510748 -192.075955)
			(xy 55.537024 -192.063821) (xy 55.558841 -192.044803) (xy 55.567072 -192.03289) (xy 55.58216 -192.010121)
			(xy 55.617836 -191.96876) (xy 55.659048 -191.932912) (xy 55.704953 -191.903311) (xy 55.754612 -191.880563)
			(xy 55.807009 -191.865133) (xy 55.861071 -191.857337) (xy 55.888382 -191.856868) (xy 55.915634 -191.857378)
			(xy 55.969583 -191.865132) (xy 56.02188 -191.880486) (xy 56.021889 -191.88049) (xy 61.97168 -191.88049)
			(xy 61.975751 -191.824868) (xy 61.987877 -191.770431) (xy 62.0078 -191.71834) (xy 62.035096 -191.669705)
			(xy 62.069182 -191.625562) (xy 62.109331 -191.586853) (xy 62.154689 -191.554402) (xy 62.204289 -191.528901)
			(xy 62.257073 -191.510894) (xy 62.311916 -191.500764) (xy 62.36765 -191.498727) (xy 62.423087 -191.504827)
			(xy 62.477044 -191.518933) (xy 62.528373 -191.540745) (xy 62.575979 -191.569799) (xy 62.618847 -191.605474)
			(xy 62.656064 -191.647011) (xy 62.686837 -191.693524) (xy 62.710509 -191.744021) (xy 62.726577 -191.797428)
			(xy 62.734697 -191.852604) (xy 62.734789 -191.85763) (xy 63.89446 -191.85763) (xy 63.898531 -191.802008)
			(xy 63.910657 -191.747571) (xy 63.93058 -191.69548) (xy 63.957876 -191.646845) (xy 63.991962 -191.602702)
			(xy 64.032111 -191.563993) (xy 64.077469 -191.531542) (xy 64.127069 -191.506041) (xy 64.179853 -191.488034)
			(xy 64.234696 -191.477904) (xy 64.29043 -191.475867) (xy 64.345867 -191.481967) (xy 64.399824 -191.496073)
			(xy 64.451153 -191.517885) (xy 64.498759 -191.546939) (xy 64.541627 -191.582614) (xy 64.578844 -191.624151)
			(xy 64.609617 -191.670664) (xy 64.633289 -191.721161) (xy 64.649357 -191.774568) (xy 64.657477 -191.829744)
			(xy 64.657986 -191.85763) (xy 64.657477 -191.885516) (xy 64.649357 -191.940692) (xy 64.633289 -191.994099)
			(xy 64.609617 -192.044596) (xy 64.578844 -192.091109) (xy 64.541627 -192.132646) (xy 64.498759 -192.168321)
			(xy 64.451153 -192.197375) (xy 64.399824 -192.219187) (xy 64.345867 -192.233293) (xy 64.29043 -192.239393)
			(xy 64.234696 -192.237356) (xy 64.179853 -192.227226) (xy 64.127069 -192.209219) (xy 64.077469 -192.183718)
			(xy 64.032111 -192.151267) (xy 63.991962 -192.112558) (xy 63.957876 -192.068415) (xy 63.93058 -192.01978)
			(xy 63.910657 -191.967689) (xy 63.898531 -191.913252) (xy 63.89446 -191.85763) (xy 62.734789 -191.85763)
			(xy 62.735206 -191.88049) (xy 62.734697 -191.908376) (xy 62.726577 -191.963552) (xy 62.710509 -192.016959)
			(xy 62.686837 -192.067456) (xy 62.656064 -192.113969) (xy 62.618847 -192.155506) (xy 62.575979 -192.191181)
			(xy 62.528373 -192.220235) (xy 62.477044 -192.242047) (xy 62.423087 -192.256153) (xy 62.36765 -192.262253)
			(xy 62.311916 -192.260216) (xy 62.257073 -192.250086) (xy 62.204289 -192.232079) (xy 62.154689 -192.206578)
			(xy 62.109331 -192.174127) (xy 62.069182 -192.135418) (xy 62.035096 -192.091275) (xy 62.0078 -192.04264)
			(xy 61.987877 -191.990549) (xy 61.975751 -191.936112) (xy 61.97168 -191.88049) (xy 56.021889 -191.88049)
			(xy 56.071459 -191.903126) (xy 56.117312 -191.932592) (xy 56.158504 -191.968283) (xy 56.194198 -192.009474)
			(xy 56.223665 -192.055325) (xy 56.246308 -192.104903) (xy 56.261664 -192.157199) (xy 56.269421 -192.211148)
			(xy 56.269421 -192.265652) (xy 56.261664 -192.319601) (xy 56.246308 -192.371897) (xy 56.223665 -192.421475)
			(xy 56.194198 -192.467326) (xy 56.158504 -192.508517) (xy 56.117312 -192.544208) (xy 56.071459 -192.573674)
			(xy 56.02188 -192.596314) (xy 55.969583 -192.611668) (xy 55.915634 -192.619422) (xy 55.888382 -192.619884)
			(xy 55.861425 -192.619419) (xy 55.808047 -192.611832) (xy 55.756268 -192.59681) (xy 55.707117 -192.574653)
			(xy 55.661571 -192.545802) (xy 55.620538 -192.51083) (xy 55.584833 -192.470434) (xy 55.569612 -192.44818)
			(xy 55.561208 -192.436395) (xy 55.539174 -192.417649) (xy 55.512766 -192.405836) (xy 55.484105 -192.401904)
			(xy 55.455492 -192.40617) (xy 55.429224 -192.41829) (xy 55.407409 -192.437291) (xy 55.399178 -192.449196)
			(xy 55.384119 -192.471985) (xy 55.348439 -192.513347) (xy 55.307222 -192.549194) (xy 55.261312 -192.578792)
			(xy 55.211648 -192.601537) (xy 55.159246 -192.616962) (xy 55.10518 -192.624752) (xy 55.077868 -192.625218)
			(xy 55.050619 -192.62471) (xy 54.996676 -192.61695) (xy 54.944387 -192.601592) (xy 54.894815 -192.57895)
			(xy 54.84897 -192.549483) (xy 54.807784 -192.513793) (xy 54.772097 -192.472605) (xy 54.742635 -192.426757)
			(xy 54.719997 -192.377183) (xy 54.704644 -192.324892) (xy 54.696888 -192.270949) (xy 54.127628 -192.270949)
			(xy 54.119787 -192.324232) (xy 54.103719 -192.377639) (xy 54.080047 -192.428136) (xy 54.049274 -192.474649)
			(xy 54.012057 -192.516186) (xy 53.969189 -192.551861) (xy 53.921583 -192.580915) (xy 53.870254 -192.602727)
			(xy 53.816297 -192.616833) (xy 53.76086 -192.622933) (xy 53.705126 -192.620896) (xy 53.650283 -192.610766)
			(xy 53.597499 -192.592759) (xy 53.547899 -192.567258) (xy 53.502541 -192.534807) (xy 53.462392 -192.496098)
			(xy 53.428306 -192.451955) (xy 53.40101 -192.40332) (xy 53.381087 -192.351229) (xy 53.368961 -192.296792)
			(xy 53.36489 -192.24117) (xy 52.096416 -192.24117) (xy 52.095907 -192.269056) (xy 52.087787 -192.324232)
			(xy 52.071719 -192.377639) (xy 52.048047 -192.428136) (xy 52.017274 -192.474649) (xy 51.980057 -192.516186)
			(xy 51.937189 -192.551861) (xy 51.889583 -192.580915) (xy 51.838254 -192.602727) (xy 51.784297 -192.616833)
			(xy 51.72886 -192.622933) (xy 51.673126 -192.620896) (xy 51.618283 -192.610766) (xy 51.565499 -192.592759)
			(xy 51.515899 -192.567258) (xy 51.470541 -192.534807) (xy 51.430392 -192.496098) (xy 51.396306 -192.451955)
			(xy 51.36901 -192.40332) (xy 51.349087 -192.351229) (xy 51.336961 -192.296792) (xy 51.33289 -192.24117)
			(xy 50.064342 -192.24117) (xy 50.063907 -192.264992) (xy 50.055787 -192.320168) (xy 50.039719 -192.373575)
			(xy 50.016047 -192.424072) (xy 49.985274 -192.470585) (xy 49.948057 -192.512122) (xy 49.905189 -192.547797)
			(xy 49.857583 -192.576851) (xy 49.806254 -192.598663) (xy 49.752297 -192.612769) (xy 49.69686 -192.618869)
			(xy 49.641126 -192.616832) (xy 49.586283 -192.606702) (xy 49.533499 -192.588695) (xy 49.483899 -192.563194)
			(xy 49.438541 -192.530743) (xy 49.398392 -192.492034) (xy 49.364306 -192.447891) (xy 49.33701 -192.399256)
			(xy 49.317087 -192.347165) (xy 49.304961 -192.292728) (xy 49.30089 -192.237106) (xy 49.047928 -192.237106)
			(xy 49.047928 -192.264351) (xy 49.040172 -192.318299) (xy 49.024817 -192.370594) (xy 49.002176 -192.420172)
			(xy 48.97271 -192.466022) (xy 48.937019 -192.507213) (xy 48.895829 -192.542905) (xy 48.849979 -192.572372)
			(xy 48.800402 -192.595014) (xy 48.748107 -192.61037) (xy 48.694159 -192.618128) (xy 48.666908 -192.618614)
			(xy 48.6381 -192.618061) (xy 48.58114 -192.609387) (xy 48.526131 -192.592251) (xy 48.474322 -192.567042)
			(xy 48.42689 -192.534333) (xy 48.405542 -192.514982) (xy 48.393863 -192.504752) (xy 48.365963 -192.491173)
			(xy 48.335272 -192.486612) (xy 48.304629 -192.491491) (xy 48.276872 -192.505357) (xy 48.265334 -192.515744)
			(xy 48.243892 -192.535717) (xy 48.195984 -192.569461) (xy 48.143483 -192.595488) (xy 48.087621 -192.613188)
			(xy 48.029711 -192.622143) (xy 48.000412 -192.622678) (xy 47.971419 -192.622169) (xy 47.9141 -192.613402)
			(xy 47.858771 -192.596052) (xy 47.806708 -192.570521) (xy 47.759114 -192.537398) (xy 47.717087 -192.497447)
			(xy 47.698914 -192.47485) (xy 47.689893 -192.463886) (xy 47.66699 -192.447117) (xy 47.640356 -192.437301)
			(xy 47.612049 -192.435195) (xy 47.584256 -192.440963) (xy 47.559124 -192.454158) (xy 47.538595 -192.47376)
			(xy 47.53102 -192.485772) (xy 47.51624 -192.50996) (xy 47.480599 -192.554038) (xy 47.43883 -192.592359)
			(xy 47.391851 -192.624079) (xy 47.340697 -192.6485) (xy 47.286493 -192.665085) (xy 47.230432 -192.673469)
			(xy 47.20209 -192.673986) (xy 47.174838 -192.673543) (xy 47.120888 -192.665785) (xy 47.068591 -192.650428)
			(xy 47.019013 -192.627785) (xy 46.973161 -192.598317) (xy 46.931969 -192.562624) (xy 46.896277 -192.521431)
			(xy 46.86681 -192.475579) (xy 46.844168 -192.425999) (xy 46.828813 -192.373702) (xy 46.821056 -192.319752)
			(xy 38.64438 -192.319752) (xy 38.655897 -192.33716) (xy 38.679569 -192.387657) (xy 38.695637 -192.441064)
			(xy 38.703757 -192.49624) (xy 38.704266 -192.524126) (xy 38.703757 -192.552012) (xy 38.695637 -192.607188)
			(xy 38.679569 -192.660595) (xy 38.655897 -192.711092) (xy 38.625124 -192.757605) (xy 38.587907 -192.799142)
			(xy 38.545039 -192.834817) (xy 38.497433 -192.863871) (xy 38.446104 -192.885683) (xy 38.392147 -192.899789)
			(xy 38.33671 -192.905889) (xy 38.280976 -192.903852) (xy 38.226133 -192.893722) (xy 38.173349 -192.875715)
			(xy 38.123749 -192.850214) (xy 38.078391 -192.817763) (xy 38.038242 -192.779054) (xy 38.004156 -192.734911)
			(xy 37.97686 -192.686276) (xy 37.956937 -192.634185) (xy 37.944811 -192.579748) (xy 37.94074 -192.524126)
			(xy 28.379452 -192.524126) (xy 28.406997 -192.56576) (xy 28.430669 -192.616257) (xy 28.446737 -192.669664)
			(xy 28.454857 -192.72484) (xy 28.455366 -192.752726) (xy 28.454857 -192.780612) (xy 28.446737 -192.835788)
			(xy 28.430669 -192.889195) (xy 28.406997 -192.939692) (xy 28.376224 -192.986205) (xy 28.339007 -193.027742)
			(xy 28.296139 -193.063417) (xy 28.248533 -193.092471) (xy 28.197204 -193.114283) (xy 28.143247 -193.128389)
			(xy 28.08781 -193.134489) (xy 28.032076 -193.132452) (xy 27.977233 -193.122322) (xy 27.924449 -193.104315)
			(xy 27.874849 -193.078814) (xy 27.829491 -193.046363) (xy 27.789342 -193.007654) (xy 27.755256 -192.963511)
			(xy 27.72796 -192.914876) (xy 27.708037 -192.862785) (xy 27.695911 -192.808348) (xy 27.69184 -192.752726)
			(xy 22.179601 -192.752726) (xy 22.185637 -192.772788) (xy 22.193757 -192.827964) (xy 22.194266 -192.85585)
			(xy 22.193757 -192.883736) (xy 22.185637 -192.938912) (xy 22.169569 -192.992319) (xy 22.145897 -193.042816)
			(xy 22.115124 -193.089329) (xy 22.077907 -193.130866) (xy 22.035039 -193.166541) (xy 21.987433 -193.195595)
			(xy 21.936104 -193.217407) (xy 21.882147 -193.231513) (xy 21.82671 -193.237613) (xy 21.770976 -193.235576)
			(xy 21.716133 -193.225446) (xy 21.663349 -193.207439) (xy 21.613749 -193.181938) (xy 21.568391 -193.149487)
			(xy 21.528242 -193.110778) (xy 21.494156 -193.066635) (xy 21.46686 -193.018) (xy 21.446937 -192.965909)
			(xy 21.434811 -192.911472) (xy 21.43074 -192.85585) (xy 21.200738 -192.85585) (xy 21.200363 -192.87637)
			(xy 21.192243 -192.931546) (xy 21.176175 -192.984953) (xy 21.152503 -193.03545) (xy 21.12173 -193.081963)
			(xy 21.084513 -193.1235) (xy 21.041645 -193.159175) (xy 20.994039 -193.188229) (xy 20.94271 -193.210041)
			(xy 20.888753 -193.224147) (xy 20.833316 -193.230247) (xy 20.777582 -193.22821) (xy 20.722739 -193.21808)
			(xy 20.669955 -193.200073) (xy 20.620355 -193.174572) (xy 20.574997 -193.142121) (xy 20.534848 -193.103412)
			(xy 20.500762 -193.059269) (xy 20.473466 -193.010634) (xy 20.453543 -192.958543) (xy 20.441417 -192.904106)
			(xy 20.437346 -192.848484) (xy 19.116294 -192.848484) (xy 19.115785 -192.87637) (xy 19.107665 -192.931546)
			(xy 19.091597 -192.984953) (xy 19.067925 -193.03545) (xy 19.037152 -193.081963) (xy 18.999935 -193.1235)
			(xy 18.957067 -193.159175) (xy 18.909461 -193.188229) (xy 18.858132 -193.210041) (xy 18.804175 -193.224147)
			(xy 18.748738 -193.230247) (xy 18.693004 -193.22821) (xy 18.638161 -193.21808) (xy 18.585377 -193.200073)
			(xy 18.535777 -193.174572) (xy 18.490419 -193.142121) (xy 18.45027 -193.103412) (xy 18.416184 -193.059269)
			(xy 18.388888 -193.010634) (xy 18.368965 -192.958543) (xy 18.356839 -192.904106) (xy 18.352768 -192.848484)
			(xy 10.097008 -192.848484) (xy 10.097008 -194.793341) (xy 14.198336 -194.793341) (xy 14.198336 -194.740043)
			(xy 14.206279 -194.687339) (xy 14.221989 -194.636409) (xy 14.245115 -194.588388) (xy 14.275139 -194.544351)
			(xy 14.311391 -194.50528) (xy 14.353062 -194.472049) (xy 14.39922 -194.4454) (xy 14.448834 -194.425928)
			(xy 14.500796 -194.414068) (xy 14.553946 -194.410085) (xy 14.607096 -194.414068) (xy 14.659058 -194.425928)
			(xy 14.708672 -194.4454) (xy 14.75483 -194.472049) (xy 14.763115 -194.478656) (xy 16.969992 -194.478656)
			(xy 16.974063 -194.423034) (xy 16.986189 -194.368597) (xy 17.006112 -194.316506) (xy 17.033408 -194.267871)
			(xy 17.067494 -194.223728) (xy 17.107643 -194.185019) (xy 17.153001 -194.152568) (xy 17.202601 -194.127067)
			(xy 17.255385 -194.10906) (xy 17.310228 -194.09893) (xy 17.365962 -194.096893) (xy 17.421399 -194.102993)
			(xy 17.475356 -194.117099) (xy 17.526685 -194.138911) (xy 17.574291 -194.167965) (xy 17.617159 -194.20364)
			(xy 17.654376 -194.245177) (xy 17.685149 -194.29169) (xy 17.708821 -194.342187) (xy 17.724889 -194.395594)
			(xy 17.733009 -194.45077) (xy 17.733518 -194.478656) (xy 17.733009 -194.506542) (xy 17.724889 -194.561718)
			(xy 17.708821 -194.615125) (xy 17.685149 -194.665622) (xy 17.654376 -194.712135) (xy 17.617159 -194.753672)
			(xy 17.574291 -194.789347) (xy 17.567747 -194.793341) (xy 21.742136 -194.793341) (xy 21.742136 -194.740043)
			(xy 21.750079 -194.687339) (xy 21.765789 -194.636409) (xy 21.788915 -194.588388) (xy 21.818939 -194.544351)
			(xy 21.855191 -194.50528) (xy 21.896862 -194.472049) (xy 21.94302 -194.4454) (xy 21.992634 -194.425928)
			(xy 22.044596 -194.414068) (xy 22.097746 -194.410085) (xy 22.150896 -194.414068) (xy 22.202858 -194.425928)
			(xy 22.252472 -194.4454) (xy 22.29863 -194.472049) (xy 22.340301 -194.50528) (xy 22.376553 -194.544351)
			(xy 22.406577 -194.588388) (xy 22.429703 -194.636409) (xy 22.445413 -194.687339) (xy 22.453356 -194.740043)
			(xy 22.453854 -194.766692) (xy 22.453465 -194.787499) (xy 29.252408 -194.787499) (xy 29.252408 -194.734201)
			(xy 29.260351 -194.681497) (xy 29.276061 -194.630567) (xy 29.299187 -194.582546) (xy 29.329211 -194.538509)
			(xy 29.365463 -194.499438) (xy 29.407134 -194.466207) (xy 29.453292 -194.439558) (xy 29.502906 -194.420086)
			(xy 29.554868 -194.408226) (xy 29.608018 -194.404243) (xy 29.661168 -194.408226) (xy 29.71313 -194.420086)
			(xy 29.762744 -194.439558) (xy 29.808902 -194.466207) (xy 29.850573 -194.499438) (xy 29.886825 -194.538509)
			(xy 29.916849 -194.582546) (xy 29.939975 -194.630567) (xy 29.955685 -194.681497) (xy 29.963628 -194.734201)
			(xy 29.964126 -194.76085) (xy 29.963628 -194.787499) (xy 36.821608 -194.787499) (xy 36.821608 -194.734201)
			(xy 36.829551 -194.681497) (xy 36.845261 -194.630567) (xy 36.868387 -194.582546) (xy 36.898411 -194.538509)
			(xy 36.934663 -194.499438) (xy 36.976334 -194.466207) (xy 37.022492 -194.439558) (xy 37.072106 -194.420086)
			(xy 37.124068 -194.408226) (xy 37.177218 -194.404243) (xy 37.230368 -194.408226) (xy 37.28233 -194.420086)
			(xy 37.331944 -194.439558) (xy 37.378102 -194.466207) (xy 37.419773 -194.499438) (xy 37.456025 -194.538509)
			(xy 37.486049 -194.582546) (xy 37.509175 -194.630567) (xy 37.524885 -194.681497) (xy 37.532828 -194.734201)
			(xy 37.533326 -194.76085) (xy 37.532828 -194.787499) (xy 37.531948 -194.793341) (xy 44.373536 -194.793341)
			(xy 44.373536 -194.740043) (xy 44.381479 -194.687339) (xy 44.397189 -194.636409) (xy 44.420315 -194.588388)
			(xy 44.450339 -194.544351) (xy 44.486591 -194.50528) (xy 44.528262 -194.472049) (xy 44.57442 -194.4454)
			(xy 44.624034 -194.425928) (xy 44.675996 -194.414068) (xy 44.729146 -194.410085) (xy 44.782296 -194.414068)
			(xy 44.834258 -194.425928) (xy 44.883872 -194.4454) (xy 44.93003 -194.472049) (xy 44.971701 -194.50528)
			(xy 45.007953 -194.544351) (xy 45.037977 -194.588388) (xy 45.061103 -194.636409) (xy 45.076813 -194.687339)
			(xy 45.084756 -194.740043) (xy 45.085254 -194.766692) (xy 45.084756 -194.793341) (xy 51.917336 -194.793341)
			(xy 51.917336 -194.740043) (xy 51.925279 -194.687339) (xy 51.940989 -194.636409) (xy 51.964115 -194.588388)
			(xy 51.994139 -194.544351) (xy 52.030391 -194.50528) (xy 52.072062 -194.472049) (xy 52.11822 -194.4454)
			(xy 52.167834 -194.425928) (xy 52.219796 -194.414068) (xy 52.272946 -194.410085) (xy 52.326096 -194.414068)
			(xy 52.378058 -194.425928) (xy 52.427672 -194.4454) (xy 52.47383 -194.472049) (xy 52.515501 -194.50528)
			(xy 52.551753 -194.544351) (xy 52.581777 -194.588388) (xy 52.604903 -194.636409) (xy 52.620613 -194.687339)
			(xy 52.628556 -194.740043) (xy 52.629054 -194.766692) (xy 52.628556 -194.793341) (xy 59.461136 -194.793341)
			(xy 59.461136 -194.740043) (xy 59.469079 -194.687339) (xy 59.484789 -194.636409) (xy 59.507915 -194.588388)
			(xy 59.537939 -194.544351) (xy 59.574191 -194.50528) (xy 59.615862 -194.472049) (xy 59.66202 -194.4454)
			(xy 59.711634 -194.425928) (xy 59.763596 -194.414068) (xy 59.816746 -194.410085) (xy 59.869896 -194.414068)
			(xy 59.921858 -194.425928) (xy 59.971472 -194.4454) (xy 60.01763 -194.472049) (xy 60.059301 -194.50528)
			(xy 60.095553 -194.544351) (xy 60.125577 -194.588388) (xy 60.148703 -194.636409) (xy 60.164413 -194.687339)
			(xy 60.172356 -194.740043) (xy 60.172854 -194.766692) (xy 60.172356 -194.793341) (xy 60.164413 -194.846045)
			(xy 60.148703 -194.896975) (xy 60.125577 -194.944996) (xy 60.095553 -194.989033) (xy 60.059301 -195.028104)
			(xy 60.01763 -195.061335) (xy 59.971472 -195.087984) (xy 59.921858 -195.107456) (xy 59.869896 -195.119316)
			(xy 59.816746 -195.1233) (xy 59.763596 -195.119316) (xy 59.711634 -195.107456) (xy 59.66202 -195.087984)
			(xy 59.615862 -195.061335) (xy 59.574191 -195.028104) (xy 59.537939 -194.989033) (xy 59.507915 -194.944996)
			(xy 59.484789 -194.896975) (xy 59.469079 -194.846045) (xy 59.461136 -194.793341) (xy 52.628556 -194.793341)
			(xy 52.620613 -194.846045) (xy 52.604903 -194.896975) (xy 52.581777 -194.944996) (xy 52.551753 -194.989033)
			(xy 52.515501 -195.028104) (xy 52.47383 -195.061335) (xy 52.427672 -195.087984) (xy 52.378058 -195.107456)
			(xy 52.326096 -195.119316) (xy 52.272946 -195.1233) (xy 52.219796 -195.119316) (xy 52.167834 -195.107456)
			(xy 52.11822 -195.087984) (xy 52.072062 -195.061335) (xy 52.030391 -195.028104) (xy 51.994139 -194.989033)
			(xy 51.964115 -194.944996) (xy 51.940989 -194.896975) (xy 51.925279 -194.846045) (xy 51.917336 -194.793341)
			(xy 45.084756 -194.793341) (xy 45.076813 -194.846045) (xy 45.061103 -194.896975) (xy 45.037977 -194.944996)
			(xy 45.007953 -194.989033) (xy 44.971701 -195.028104) (xy 44.93003 -195.061335) (xy 44.883872 -195.087984)
			(xy 44.834258 -195.107456) (xy 44.782296 -195.119316) (xy 44.729146 -195.1233) (xy 44.675996 -195.119316)
			(xy 44.624034 -195.107456) (xy 44.57442 -195.087984) (xy 44.528262 -195.061335) (xy 44.486591 -195.028104)
			(xy 44.450339 -194.989033) (xy 44.420315 -194.944996) (xy 44.397189 -194.896975) (xy 44.381479 -194.846045)
			(xy 44.373536 -194.793341) (xy 37.531948 -194.793341) (xy 37.524885 -194.840203) (xy 37.509175 -194.891133)
			(xy 37.486049 -194.939154) (xy 37.456025 -194.983191) (xy 37.419773 -195.022262) (xy 37.378102 -195.055493)
			(xy 37.331944 -195.082142) (xy 37.28233 -195.101614) (xy 37.230368 -195.113474) (xy 37.177218 -195.117458)
			(xy 37.124068 -195.113474) (xy 37.072106 -195.101614) (xy 37.022492 -195.082142) (xy 36.976334 -195.055493)
			(xy 36.934663 -195.022262) (xy 36.898411 -194.983191) (xy 36.868387 -194.939154) (xy 36.845261 -194.891133)
			(xy 36.829551 -194.840203) (xy 36.821608 -194.787499) (xy 29.963628 -194.787499) (xy 29.955685 -194.840203)
			(xy 29.939975 -194.891133) (xy 29.916849 -194.939154) (xy 29.886825 -194.983191) (xy 29.850573 -195.022262)
			(xy 29.808902 -195.055493) (xy 29.762744 -195.082142) (xy 29.71313 -195.101614) (xy 29.661168 -195.113474)
			(xy 29.608018 -195.117458) (xy 29.554868 -195.113474) (xy 29.502906 -195.101614) (xy 29.453292 -195.082142)
			(xy 29.407134 -195.055493) (xy 29.365463 -195.022262) (xy 29.329211 -194.983191) (xy 29.299187 -194.939154)
			(xy 29.276061 -194.891133) (xy 29.260351 -194.840203) (xy 29.252408 -194.787499) (xy 22.453465 -194.787499)
			(xy 22.453356 -194.793341) (xy 22.445413 -194.846045) (xy 22.429703 -194.896975) (xy 22.406577 -194.944996)
			(xy 22.376553 -194.989033) (xy 22.340301 -195.028104) (xy 22.29863 -195.061335) (xy 22.252472 -195.087984)
			(xy 22.202858 -195.107456) (xy 22.150896 -195.119316) (xy 22.097746 -195.1233) (xy 22.044596 -195.119316)
			(xy 21.992634 -195.107456) (xy 21.94302 -195.087984) (xy 21.896862 -195.061335) (xy 21.855191 -195.028104)
			(xy 21.818939 -194.989033) (xy 21.788915 -194.944996) (xy 21.765789 -194.896975) (xy 21.750079 -194.846045)
			(xy 21.742136 -194.793341) (xy 17.567747 -194.793341) (xy 17.526685 -194.818401) (xy 17.475356 -194.840213)
			(xy 17.421399 -194.854319) (xy 17.365962 -194.860419) (xy 17.310228 -194.858382) (xy 17.255385 -194.848252)
			(xy 17.202601 -194.830245) (xy 17.153001 -194.804744) (xy 17.107643 -194.772293) (xy 17.067494 -194.733584)
			(xy 17.033408 -194.689441) (xy 17.006112 -194.640806) (xy 16.986189 -194.588715) (xy 16.974063 -194.534278)
			(xy 16.969992 -194.478656) (xy 14.763115 -194.478656) (xy 14.796501 -194.50528) (xy 14.832753 -194.544351)
			(xy 14.862777 -194.588388) (xy 14.885903 -194.636409) (xy 14.901613 -194.687339) (xy 14.909556 -194.740043)
			(xy 14.910054 -194.766692) (xy 14.909556 -194.793341) (xy 14.901613 -194.846045) (xy 14.885903 -194.896975)
			(xy 14.862777 -194.944996) (xy 14.832753 -194.989033) (xy 14.796501 -195.028104) (xy 14.75483 -195.061335)
			(xy 14.708672 -195.087984) (xy 14.659058 -195.107456) (xy 14.607096 -195.119316) (xy 14.553946 -195.1233)
			(xy 14.500796 -195.119316) (xy 14.448834 -195.107456) (xy 14.39922 -195.087984) (xy 14.353062 -195.061335)
			(xy 14.311391 -195.028104) (xy 14.275139 -194.989033) (xy 14.245115 -194.944996) (xy 14.221989 -194.896975)
			(xy 14.206279 -194.846045) (xy 14.198336 -194.793341) (xy 10.097008 -194.793341) (xy 10.097008 -195.643225)
			(xy 20.533604 -195.643225) (xy 20.533604 -195.589927) (xy 20.541547 -195.537223) (xy 20.557257 -195.486293)
			(xy 20.580383 -195.438272) (xy 20.610407 -195.394235) (xy 20.646659 -195.355164) (xy 20.68833 -195.321933)
			(xy 20.734488 -195.295284) (xy 20.784102 -195.275812) (xy 20.836064 -195.263952) (xy 20.889214 -195.259969)
			(xy 20.942364 -195.263952) (xy 20.994326 -195.275812) (xy 21.04394 -195.295284) (xy 21.090098 -195.321933)
			(xy 21.131769 -195.355164) (xy 21.168021 -195.394235) (xy 21.198045 -195.438272) (xy 21.221171 -195.486293)
			(xy 21.236881 -195.537223) (xy 21.244824 -195.589927) (xy 21.245322 -195.616576) (xy 21.244824 -195.643225)
			(xy 35.621204 -195.643225) (xy 35.621204 -195.589927) (xy 35.629147 -195.537223) (xy 35.644857 -195.486293)
			(xy 35.667983 -195.438272) (xy 35.698007 -195.394235) (xy 35.734259 -195.355164) (xy 35.77593 -195.321933)
			(xy 35.822088 -195.295284) (xy 35.871702 -195.275812) (xy 35.923664 -195.263952) (xy 35.976814 -195.259969)
			(xy 36.029964 -195.263952) (xy 36.081926 -195.275812) (xy 36.13154 -195.295284) (xy 36.177698 -195.321933)
			(xy 36.219369 -195.355164) (xy 36.255621 -195.394235) (xy 36.285645 -195.438272) (xy 36.308771 -195.486293)
			(xy 36.324481 -195.537223) (xy 36.332424 -195.589927) (xy 36.332922 -195.616576) (xy 36.332424 -195.643225)
			(xy 50.708804 -195.643225) (xy 50.708804 -195.589927) (xy 50.716747 -195.537223) (xy 50.732457 -195.486293)
			(xy 50.755583 -195.438272) (xy 50.785607 -195.394235) (xy 50.821859 -195.355164) (xy 50.86353 -195.321933)
			(xy 50.909688 -195.295284) (xy 50.959302 -195.275812) (xy 51.011264 -195.263952) (xy 51.064414 -195.259969)
			(xy 51.117564 -195.263952) (xy 51.169526 -195.275812) (xy 51.21914 -195.295284) (xy 51.265298 -195.321933)
			(xy 51.306969 -195.355164) (xy 51.343221 -195.394235) (xy 51.373245 -195.438272) (xy 51.396371 -195.486293)
			(xy 51.412081 -195.537223) (xy 51.420024 -195.589927) (xy 51.420522 -195.616576) (xy 51.420024 -195.643225)
			(xy 51.412081 -195.695929) (xy 51.396371 -195.746859) (xy 51.373245 -195.79488) (xy 51.343221 -195.838917)
			(xy 51.306969 -195.877988) (xy 51.265298 -195.911219) (xy 51.21914 -195.937868) (xy 51.169526 -195.95734)
			(xy 51.117564 -195.9692) (xy 51.064414 -195.973184) (xy 51.011264 -195.9692) (xy 50.959302 -195.95734)
			(xy 50.909688 -195.937868) (xy 50.86353 -195.911219) (xy 50.821859 -195.877988) (xy 50.785607 -195.838917)
			(xy 50.755583 -195.79488) (xy 50.732457 -195.746859) (xy 50.716747 -195.695929) (xy 50.708804 -195.643225)
			(xy 36.332424 -195.643225) (xy 36.324481 -195.695929) (xy 36.308771 -195.746859) (xy 36.285645 -195.79488)
			(xy 36.255621 -195.838917) (xy 36.219369 -195.877988) (xy 36.177698 -195.911219) (xy 36.13154 -195.937868)
			(xy 36.081926 -195.95734) (xy 36.029964 -195.9692) (xy 35.976814 -195.973184) (xy 35.923664 -195.9692)
			(xy 35.871702 -195.95734) (xy 35.822088 -195.937868) (xy 35.77593 -195.911219) (xy 35.734259 -195.877988)
			(xy 35.698007 -195.838917) (xy 35.667983 -195.79488) (xy 35.644857 -195.746859) (xy 35.629147 -195.695929)
			(xy 35.621204 -195.643225) (xy 21.244824 -195.643225) (xy 21.236881 -195.695929) (xy 21.221171 -195.746859)
			(xy 21.198045 -195.79488) (xy 21.168021 -195.838917) (xy 21.131769 -195.877988) (xy 21.090098 -195.911219)
			(xy 21.04394 -195.937868) (xy 20.994326 -195.95734) (xy 20.942364 -195.9692) (xy 20.889214 -195.973184)
			(xy 20.836064 -195.9692) (xy 20.784102 -195.95734) (xy 20.734488 -195.937868) (xy 20.68833 -195.911219)
			(xy 20.646659 -195.877988) (xy 20.610407 -195.838917) (xy 20.580383 -195.79488) (xy 20.557257 -195.746859)
			(xy 20.541547 -195.695929) (xy 20.533604 -195.643225) (xy 10.097008 -195.643225) (xy 10.097008 -195.824348)
			(xy 10.096449 -195.853321) (xy 10.087341 -195.910549) (xy 10.069389 -195.965645) (xy 10.043035 -196.017253)
			(xy 10.008928 -196.064101) (xy 9.988804 -196.084952) (xy 9.6774 -196.39661) (xy 9.6774 -196.493363)
			(xy 16.433536 -196.493363) (xy 16.433536 -196.440065) (xy 16.441479 -196.387361) (xy 16.457189 -196.336431)
			(xy 16.480315 -196.28841) (xy 16.510339 -196.244373) (xy 16.546591 -196.205302) (xy 16.588262 -196.172071)
			(xy 16.63442 -196.145422) (xy 16.684034 -196.12595) (xy 16.735996 -196.11409) (xy 16.789146 -196.110107)
			(xy 16.842296 -196.11409) (xy 16.894258 -196.12595) (xy 16.943872 -196.145422) (xy 16.99003 -196.172071)
			(xy 17.031701 -196.205302) (xy 17.067953 -196.244373) (xy 17.097977 -196.28841) (xy 17.121103 -196.336431)
			(xy 17.136813 -196.387361) (xy 17.144756 -196.440065) (xy 17.145254 -196.466714) (xy 17.144756 -196.493363)
			(xy 31.521136 -196.493363) (xy 31.521136 -196.440065) (xy 31.529079 -196.387361) (xy 31.544789 -196.336431)
			(xy 31.567915 -196.28841) (xy 31.597939 -196.244373) (xy 31.634191 -196.205302) (xy 31.675862 -196.172071)
			(xy 31.72202 -196.145422) (xy 31.771634 -196.12595) (xy 31.823596 -196.11409) (xy 31.876746 -196.110107)
			(xy 31.929896 -196.11409) (xy 31.981858 -196.12595) (xy 32.031472 -196.145422) (xy 32.07763 -196.172071)
			(xy 32.119301 -196.205302) (xy 32.155553 -196.244373) (xy 32.185577 -196.28841) (xy 32.208703 -196.336431)
			(xy 32.224413 -196.387361) (xy 32.232356 -196.440065) (xy 32.232854 -196.466714) (xy 32.232356 -196.493363)
			(xy 46.608736 -196.493363) (xy 46.608736 -196.440065) (xy 46.616679 -196.387361) (xy 46.632389 -196.336431)
			(xy 46.655515 -196.28841) (xy 46.685539 -196.244373) (xy 46.721791 -196.205302) (xy 46.763462 -196.172071)
			(xy 46.80962 -196.145422) (xy 46.859234 -196.12595) (xy 46.911196 -196.11409) (xy 46.964346 -196.110107)
			(xy 47.017496 -196.11409) (xy 47.069458 -196.12595) (xy 47.119072 -196.145422) (xy 47.16523 -196.172071)
			(xy 47.206901 -196.205302) (xy 47.243153 -196.244373) (xy 47.273177 -196.28841) (xy 47.296303 -196.336431)
			(xy 47.312013 -196.387361) (xy 47.319956 -196.440065) (xy 47.320454 -196.466714) (xy 47.319956 -196.493363)
			(xy 47.312013 -196.546067) (xy 47.296303 -196.596997) (xy 47.273177 -196.645018) (xy 47.243153 -196.689055)
			(xy 47.206901 -196.728126) (xy 47.16523 -196.761357) (xy 47.119072 -196.788006) (xy 47.069458 -196.807478)
			(xy 47.017496 -196.819338) (xy 46.964346 -196.823322) (xy 46.911196 -196.819338) (xy 46.859234 -196.807478)
			(xy 46.80962 -196.788006) (xy 46.763462 -196.761357) (xy 46.721791 -196.728126) (xy 46.685539 -196.689055)
			(xy 46.655515 -196.645018) (xy 46.632389 -196.596997) (xy 46.616679 -196.546067) (xy 46.608736 -196.493363)
			(xy 32.232356 -196.493363) (xy 32.224413 -196.546067) (xy 32.208703 -196.596997) (xy 32.185577 -196.645018)
			(xy 32.155553 -196.689055) (xy 32.119301 -196.728126) (xy 32.07763 -196.761357) (xy 32.031472 -196.788006)
			(xy 31.981858 -196.807478) (xy 31.929896 -196.819338) (xy 31.876746 -196.823322) (xy 31.823596 -196.819338)
			(xy 31.771634 -196.807478) (xy 31.72202 -196.788006) (xy 31.675862 -196.761357) (xy 31.634191 -196.728126)
			(xy 31.597939 -196.689055) (xy 31.567915 -196.645018) (xy 31.544789 -196.596997) (xy 31.529079 -196.546067)
			(xy 31.521136 -196.493363) (xy 17.144756 -196.493363) (xy 17.136813 -196.546067) (xy 17.121103 -196.596997)
			(xy 17.097977 -196.645018) (xy 17.067953 -196.689055) (xy 17.031701 -196.728126) (xy 16.99003 -196.761357)
			(xy 16.943872 -196.788006) (xy 16.894258 -196.807478) (xy 16.842296 -196.819338) (xy 16.789146 -196.823322)
			(xy 16.735996 -196.819338) (xy 16.684034 -196.807478) (xy 16.63442 -196.788006) (xy 16.588262 -196.761357)
			(xy 16.546591 -196.728126) (xy 16.510339 -196.689055) (xy 16.480315 -196.645018) (xy 16.457189 -196.596997)
			(xy 16.441479 -196.546067) (xy 16.433536 -196.493363) (xy 9.6774 -196.493363) (xy 9.6774 -197.343247)
			(xy 20.533604 -197.343247) (xy 20.533604 -197.289949) (xy 20.541547 -197.237245) (xy 20.557257 -197.186315)
			(xy 20.580383 -197.138294) (xy 20.610407 -197.094257) (xy 20.646659 -197.055186) (xy 20.68833 -197.021955)
			(xy 20.734488 -196.995306) (xy 20.784102 -196.975834) (xy 20.836064 -196.963974) (xy 20.889214 -196.959991)
			(xy 20.942364 -196.963974) (xy 20.994326 -196.975834) (xy 21.04394 -196.995306) (xy 21.090098 -197.021955)
			(xy 21.131769 -197.055186) (xy 21.168021 -197.094257) (xy 21.198045 -197.138294) (xy 21.221171 -197.186315)
			(xy 21.236881 -197.237245) (xy 21.244824 -197.289949) (xy 21.245322 -197.316598) (xy 21.244824 -197.343247)
			(xy 35.621204 -197.343247) (xy 35.621204 -197.289949) (xy 35.629147 -197.237245) (xy 35.644857 -197.186315)
			(xy 35.667983 -197.138294) (xy 35.698007 -197.094257) (xy 35.734259 -197.055186) (xy 35.77593 -197.021955)
			(xy 35.822088 -196.995306) (xy 35.871702 -196.975834) (xy 35.923664 -196.963974) (xy 35.976814 -196.959991)
			(xy 36.029964 -196.963974) (xy 36.081926 -196.975834) (xy 36.13154 -196.995306) (xy 36.177698 -197.021955)
			(xy 36.219369 -197.055186) (xy 36.255621 -197.094257) (xy 36.285645 -197.138294) (xy 36.308771 -197.186315)
			(xy 36.324481 -197.237245) (xy 36.332424 -197.289949) (xy 36.332922 -197.316598) (xy 36.332424 -197.343247)
			(xy 50.708804 -197.343247) (xy 50.708804 -197.289949) (xy 50.716747 -197.237245) (xy 50.732457 -197.186315)
			(xy 50.755583 -197.138294) (xy 50.785607 -197.094257) (xy 50.821859 -197.055186) (xy 50.86353 -197.021955)
			(xy 50.909688 -196.995306) (xy 50.959302 -196.975834) (xy 51.011264 -196.963974) (xy 51.064414 -196.959991)
			(xy 51.117564 -196.963974) (xy 51.169526 -196.975834) (xy 51.21914 -196.995306) (xy 51.265298 -197.021955)
			(xy 51.306969 -197.055186) (xy 51.343221 -197.094257) (xy 51.373245 -197.138294) (xy 51.396371 -197.186315)
			(xy 51.412081 -197.237245) (xy 51.420024 -197.289949) (xy 51.420522 -197.316598) (xy 51.420024 -197.343247)
			(xy 51.412081 -197.395951) (xy 51.396371 -197.446881) (xy 51.373245 -197.494902) (xy 51.343221 -197.538939)
			(xy 51.306969 -197.57801) (xy 51.265298 -197.611241) (xy 51.21914 -197.63789) (xy 51.169526 -197.657362)
			(xy 51.117564 -197.669222) (xy 51.064414 -197.673206) (xy 51.011264 -197.669222) (xy 50.959302 -197.657362)
			(xy 50.909688 -197.63789) (xy 50.86353 -197.611241) (xy 50.821859 -197.57801) (xy 50.785607 -197.538939)
			(xy 50.755583 -197.494902) (xy 50.732457 -197.446881) (xy 50.716747 -197.395951) (xy 50.708804 -197.343247)
			(xy 36.332424 -197.343247) (xy 36.324481 -197.395951) (xy 36.308771 -197.446881) (xy 36.285645 -197.494902)
			(xy 36.255621 -197.538939) (xy 36.219369 -197.57801) (xy 36.177698 -197.611241) (xy 36.13154 -197.63789)
			(xy 36.081926 -197.657362) (xy 36.029964 -197.669222) (xy 35.976814 -197.673206) (xy 35.923664 -197.669222)
			(xy 35.871702 -197.657362) (xy 35.822088 -197.63789) (xy 35.77593 -197.611241) (xy 35.734259 -197.57801)
			(xy 35.698007 -197.538939) (xy 35.667983 -197.494902) (xy 35.644857 -197.446881) (xy 35.629147 -197.395951)
			(xy 35.621204 -197.343247) (xy 21.244824 -197.343247) (xy 21.236881 -197.395951) (xy 21.221171 -197.446881)
			(xy 21.198045 -197.494902) (xy 21.168021 -197.538939) (xy 21.131769 -197.57801) (xy 21.090098 -197.611241)
			(xy 21.04394 -197.63789) (xy 20.994326 -197.657362) (xy 20.942364 -197.669222) (xy 20.889214 -197.673206)
			(xy 20.836064 -197.669222) (xy 20.784102 -197.657362) (xy 20.734488 -197.63789) (xy 20.68833 -197.611241)
			(xy 20.646659 -197.57801) (xy 20.610407 -197.538939) (xy 20.580383 -197.494902) (xy 20.557257 -197.446881)
			(xy 20.541547 -197.395951) (xy 20.533604 -197.343247) (xy 9.6774 -197.343247) (xy 9.6774 -198.193385)
			(xy 16.433536 -198.193385) (xy 16.433536 -198.140087) (xy 16.441479 -198.087383) (xy 16.457189 -198.036453)
			(xy 16.480315 -197.988432) (xy 16.510339 -197.944395) (xy 16.546591 -197.905324) (xy 16.588262 -197.872093)
			(xy 16.63442 -197.845444) (xy 16.684034 -197.825972) (xy 16.735996 -197.814112) (xy 16.789146 -197.810129)
			(xy 16.842296 -197.814112) (xy 16.894258 -197.825972) (xy 16.943872 -197.845444) (xy 16.99003 -197.872093)
			(xy 17.031701 -197.905324) (xy 17.067953 -197.944395) (xy 17.097977 -197.988432) (xy 17.121103 -198.036453)
			(xy 17.136813 -198.087383) (xy 17.144756 -198.140087) (xy 17.145254 -198.166736) (xy 17.144756 -198.193385)
			(xy 31.521136 -198.193385) (xy 31.521136 -198.140087) (xy 31.529079 -198.087383) (xy 31.544789 -198.036453)
			(xy 31.567915 -197.988432) (xy 31.597939 -197.944395) (xy 31.634191 -197.905324) (xy 31.675862 -197.872093)
			(xy 31.72202 -197.845444) (xy 31.771634 -197.825972) (xy 31.823596 -197.814112) (xy 31.876746 -197.810129)
			(xy 31.929896 -197.814112) (xy 31.981858 -197.825972) (xy 32.031472 -197.845444) (xy 32.07763 -197.872093)
			(xy 32.119301 -197.905324) (xy 32.155553 -197.944395) (xy 32.185577 -197.988432) (xy 32.208703 -198.036453)
			(xy 32.224413 -198.087383) (xy 32.232356 -198.140087) (xy 32.232854 -198.166736) (xy 32.232356 -198.193385)
			(xy 46.608736 -198.193385) (xy 46.608736 -198.140087) (xy 46.616679 -198.087383) (xy 46.632389 -198.036453)
			(xy 46.655515 -197.988432) (xy 46.685539 -197.944395) (xy 46.721791 -197.905324) (xy 46.763462 -197.872093)
			(xy 46.80962 -197.845444) (xy 46.859234 -197.825972) (xy 46.911196 -197.814112) (xy 46.964346 -197.810129)
			(xy 47.017496 -197.814112) (xy 47.069458 -197.825972) (xy 47.119072 -197.845444) (xy 47.16523 -197.872093)
			(xy 47.206901 -197.905324) (xy 47.243153 -197.944395) (xy 47.273177 -197.988432) (xy 47.296303 -198.036453)
			(xy 47.312013 -198.087383) (xy 47.319956 -198.140087) (xy 47.320454 -198.166736) (xy 47.319956 -198.193385)
			(xy 47.312013 -198.246089) (xy 47.296303 -198.297019) (xy 47.273177 -198.34504) (xy 47.243153 -198.389077)
			(xy 47.206901 -198.428148) (xy 47.16523 -198.461379) (xy 47.119072 -198.488028) (xy 47.069458 -198.5075)
			(xy 47.017496 -198.51936) (xy 46.964346 -198.523344) (xy 46.911196 -198.51936) (xy 46.859234 -198.5075)
			(xy 46.80962 -198.488028) (xy 46.763462 -198.461379) (xy 46.721791 -198.428148) (xy 46.685539 -198.389077)
			(xy 46.655515 -198.34504) (xy 46.632389 -198.297019) (xy 46.616679 -198.246089) (xy 46.608736 -198.193385)
			(xy 32.232356 -198.193385) (xy 32.224413 -198.246089) (xy 32.208703 -198.297019) (xy 32.185577 -198.34504)
			(xy 32.155553 -198.389077) (xy 32.119301 -198.428148) (xy 32.07763 -198.461379) (xy 32.031472 -198.488028)
			(xy 31.981858 -198.5075) (xy 31.929896 -198.51936) (xy 31.876746 -198.523344) (xy 31.823596 -198.51936)
			(xy 31.771634 -198.5075) (xy 31.72202 -198.488028) (xy 31.675862 -198.461379) (xy 31.634191 -198.428148)
			(xy 31.597939 -198.389077) (xy 31.567915 -198.34504) (xy 31.544789 -198.297019) (xy 31.529079 -198.246089)
			(xy 31.521136 -198.193385) (xy 17.144756 -198.193385) (xy 17.136813 -198.246089) (xy 17.121103 -198.297019)
			(xy 17.097977 -198.34504) (xy 17.067953 -198.389077) (xy 17.031701 -198.428148) (xy 16.99003 -198.461379)
			(xy 16.943872 -198.488028) (xy 16.894258 -198.5075) (xy 16.842296 -198.51936) (xy 16.789146 -198.523344)
			(xy 16.735996 -198.51936) (xy 16.684034 -198.5075) (xy 16.63442 -198.488028) (xy 16.588262 -198.461379)
			(xy 16.546591 -198.428148) (xy 16.510339 -198.389077) (xy 16.480315 -198.34504) (xy 16.457189 -198.297019)
			(xy 16.441479 -198.246089) (xy 16.433536 -198.193385) (xy 9.6774 -198.193385) (xy 9.6774 -199.043269)
			(xy 20.533604 -199.043269) (xy 20.533604 -198.989971) (xy 20.541547 -198.937267) (xy 20.557257 -198.886337)
			(xy 20.580383 -198.838316) (xy 20.610407 -198.794279) (xy 20.646659 -198.755208) (xy 20.68833 -198.721977)
			(xy 20.734488 -198.695328) (xy 20.784102 -198.675856) (xy 20.836064 -198.663996) (xy 20.889214 -198.660013)
			(xy 20.942364 -198.663996) (xy 20.994326 -198.675856) (xy 21.04394 -198.695328) (xy 21.090098 -198.721977)
			(xy 21.131769 -198.755208) (xy 21.168021 -198.794279) (xy 21.198045 -198.838316) (xy 21.221171 -198.886337)
			(xy 21.236881 -198.937267) (xy 21.244824 -198.989971) (xy 21.245322 -199.01662) (xy 21.244824 -199.043269)
			(xy 35.621204 -199.043269) (xy 35.621204 -198.989971) (xy 35.629147 -198.937267) (xy 35.644857 -198.886337)
			(xy 35.667983 -198.838316) (xy 35.698007 -198.794279) (xy 35.734259 -198.755208) (xy 35.77593 -198.721977)
			(xy 35.822088 -198.695328) (xy 35.871702 -198.675856) (xy 35.923664 -198.663996) (xy 35.976814 -198.660013)
			(xy 36.029964 -198.663996) (xy 36.081926 -198.675856) (xy 36.13154 -198.695328) (xy 36.177698 -198.721977)
			(xy 36.219369 -198.755208) (xy 36.255621 -198.794279) (xy 36.285645 -198.838316) (xy 36.308771 -198.886337)
			(xy 36.324481 -198.937267) (xy 36.332424 -198.989971) (xy 36.332922 -199.01662) (xy 36.332424 -199.043269)
			(xy 50.708804 -199.043269) (xy 50.708804 -198.989971) (xy 50.716747 -198.937267) (xy 50.732457 -198.886337)
			(xy 50.755583 -198.838316) (xy 50.785607 -198.794279) (xy 50.821859 -198.755208) (xy 50.86353 -198.721977)
			(xy 50.909688 -198.695328) (xy 50.959302 -198.675856) (xy 51.011264 -198.663996) (xy 51.064414 -198.660013)
			(xy 51.117564 -198.663996) (xy 51.169526 -198.675856) (xy 51.21914 -198.695328) (xy 51.265298 -198.721977)
			(xy 51.306969 -198.755208) (xy 51.343221 -198.794279) (xy 51.373245 -198.838316) (xy 51.396371 -198.886337)
			(xy 51.412081 -198.937267) (xy 51.420024 -198.989971) (xy 51.420522 -199.01662) (xy 51.420024 -199.043269)
			(xy 51.412081 -199.095973) (xy 51.396371 -199.146903) (xy 51.373245 -199.194924) (xy 51.343221 -199.238961)
			(xy 51.306969 -199.278032) (xy 51.265298 -199.311263) (xy 51.21914 -199.337912) (xy 51.169526 -199.357384)
			(xy 51.117564 -199.369244) (xy 51.064414 -199.373228) (xy 51.011264 -199.369244) (xy 50.959302 -199.357384)
			(xy 50.909688 -199.337912) (xy 50.86353 -199.311263) (xy 50.821859 -199.278032) (xy 50.785607 -199.238961)
			(xy 50.755583 -199.194924) (xy 50.732457 -199.146903) (xy 50.716747 -199.095973) (xy 50.708804 -199.043269)
			(xy 36.332424 -199.043269) (xy 36.324481 -199.095973) (xy 36.308771 -199.146903) (xy 36.285645 -199.194924)
			(xy 36.255621 -199.238961) (xy 36.219369 -199.278032) (xy 36.177698 -199.311263) (xy 36.13154 -199.337912)
			(xy 36.081926 -199.357384) (xy 36.029964 -199.369244) (xy 35.976814 -199.373228) (xy 35.923664 -199.369244)
			(xy 35.871702 -199.357384) (xy 35.822088 -199.337912) (xy 35.77593 -199.311263) (xy 35.734259 -199.278032)
			(xy 35.698007 -199.238961) (xy 35.667983 -199.194924) (xy 35.644857 -199.146903) (xy 35.629147 -199.095973)
			(xy 35.621204 -199.043269) (xy 21.244824 -199.043269) (xy 21.236881 -199.095973) (xy 21.221171 -199.146903)
			(xy 21.198045 -199.194924) (xy 21.168021 -199.238961) (xy 21.131769 -199.278032) (xy 21.090098 -199.311263)
			(xy 21.04394 -199.337912) (xy 20.994326 -199.357384) (xy 20.942364 -199.369244) (xy 20.889214 -199.373228)
			(xy 20.836064 -199.369244) (xy 20.784102 -199.357384) (xy 20.734488 -199.337912) (xy 20.68833 -199.311263)
			(xy 20.646659 -199.278032) (xy 20.610407 -199.238961) (xy 20.580383 -199.194924) (xy 20.557257 -199.146903)
			(xy 20.541547 -199.095973) (xy 20.533604 -199.043269) (xy 9.6774 -199.043269) (xy 9.6774 -199.893407)
			(xy 16.433536 -199.893407) (xy 16.433536 -199.840109) (xy 16.441479 -199.787405) (xy 16.457189 -199.736475)
			(xy 16.480315 -199.688454) (xy 16.510339 -199.644417) (xy 16.546591 -199.605346) (xy 16.588262 -199.572115)
			(xy 16.63442 -199.545466) (xy 16.684034 -199.525994) (xy 16.735996 -199.514134) (xy 16.789146 -199.510151)
			(xy 16.842296 -199.514134) (xy 16.894258 -199.525994) (xy 16.943872 -199.545466) (xy 16.99003 -199.572115)
			(xy 17.031701 -199.605346) (xy 17.067953 -199.644417) (xy 17.097977 -199.688454) (xy 17.121103 -199.736475)
			(xy 17.136813 -199.787405) (xy 17.144756 -199.840109) (xy 17.145254 -199.866758) (xy 17.144756 -199.893407)
			(xy 20.533604 -199.893407) (xy 20.533604 -199.840109) (xy 20.541547 -199.787405) (xy 20.557257 -199.736475)
			(xy 20.580383 -199.688454) (xy 20.610407 -199.644417) (xy 20.646659 -199.605346) (xy 20.68833 -199.572115)
			(xy 20.734488 -199.545466) (xy 20.784102 -199.525994) (xy 20.836064 -199.514134) (xy 20.889214 -199.510151)
			(xy 20.942364 -199.514134) (xy 20.994326 -199.525994) (xy 21.04394 -199.545466) (xy 21.090098 -199.572115)
			(xy 21.131769 -199.605346) (xy 21.168021 -199.644417) (xy 21.198045 -199.688454) (xy 21.221171 -199.736475)
			(xy 21.236881 -199.787405) (xy 21.244824 -199.840109) (xy 21.245322 -199.866758) (xy 21.244824 -199.893407)
			(xy 31.521136 -199.893407) (xy 31.521136 -199.840109) (xy 31.529079 -199.787405) (xy 31.544789 -199.736475)
			(xy 31.567915 -199.688454) (xy 31.597939 -199.644417) (xy 31.634191 -199.605346) (xy 31.675862 -199.572115)
			(xy 31.72202 -199.545466) (xy 31.771634 -199.525994) (xy 31.823596 -199.514134) (xy 31.876746 -199.510151)
			(xy 31.929896 -199.514134) (xy 31.981858 -199.525994) (xy 32.031472 -199.545466) (xy 32.07763 -199.572115)
			(xy 32.119301 -199.605346) (xy 32.155553 -199.644417) (xy 32.185577 -199.688454) (xy 32.208703 -199.736475)
			(xy 32.224413 -199.787405) (xy 32.232356 -199.840109) (xy 32.232854 -199.866758) (xy 32.232356 -199.893407)
			(xy 35.621204 -199.893407) (xy 35.621204 -199.840109) (xy 35.629147 -199.787405) (xy 35.644857 -199.736475)
			(xy 35.667983 -199.688454) (xy 35.698007 -199.644417) (xy 35.734259 -199.605346) (xy 35.77593 -199.572115)
			(xy 35.822088 -199.545466) (xy 35.871702 -199.525994) (xy 35.923664 -199.514134) (xy 35.976814 -199.510151)
			(xy 36.029964 -199.514134) (xy 36.081926 -199.525994) (xy 36.13154 -199.545466) (xy 36.177698 -199.572115)
			(xy 36.219369 -199.605346) (xy 36.255621 -199.644417) (xy 36.285645 -199.688454) (xy 36.308771 -199.736475)
			(xy 36.324481 -199.787405) (xy 36.332424 -199.840109) (xy 36.332922 -199.866758) (xy 36.332424 -199.893407)
			(xy 46.608736 -199.893407) (xy 46.608736 -199.840109) (xy 46.616679 -199.787405) (xy 46.632389 -199.736475)
			(xy 46.655515 -199.688454) (xy 46.685539 -199.644417) (xy 46.721791 -199.605346) (xy 46.763462 -199.572115)
			(xy 46.80962 -199.545466) (xy 46.859234 -199.525994) (xy 46.911196 -199.514134) (xy 46.964346 -199.510151)
			(xy 47.017496 -199.514134) (xy 47.069458 -199.525994) (xy 47.119072 -199.545466) (xy 47.16523 -199.572115)
			(xy 47.206901 -199.605346) (xy 47.243153 -199.644417) (xy 47.273177 -199.688454) (xy 47.296303 -199.736475)
			(xy 47.312013 -199.787405) (xy 47.319956 -199.840109) (xy 47.320454 -199.866758) (xy 47.319956 -199.893407)
			(xy 50.708804 -199.893407) (xy 50.708804 -199.840109) (xy 50.716747 -199.787405) (xy 50.732457 -199.736475)
			(xy 50.755583 -199.688454) (xy 50.785607 -199.644417) (xy 50.821859 -199.605346) (xy 50.86353 -199.572115)
			(xy 50.909688 -199.545466) (xy 50.959302 -199.525994) (xy 51.011264 -199.514134) (xy 51.064414 -199.510151)
			(xy 51.117564 -199.514134) (xy 51.169526 -199.525994) (xy 51.21914 -199.545466) (xy 51.265298 -199.572115)
			(xy 51.306969 -199.605346) (xy 51.343221 -199.644417) (xy 51.373245 -199.688454) (xy 51.396371 -199.736475)
			(xy 51.412081 -199.787405) (xy 51.420024 -199.840109) (xy 51.420522 -199.866758) (xy 51.420024 -199.893407)
			(xy 51.412081 -199.946111) (xy 51.396371 -199.997041) (xy 51.373245 -200.045062) (xy 51.343221 -200.089099)
			(xy 51.306969 -200.12817) (xy 51.265298 -200.161401) (xy 51.21914 -200.18805) (xy 51.169526 -200.207522)
			(xy 51.117564 -200.219382) (xy 51.064414 -200.223366) (xy 51.011264 -200.219382) (xy 50.959302 -200.207522)
			(xy 50.909688 -200.18805) (xy 50.86353 -200.161401) (xy 50.821859 -200.12817) (xy 50.785607 -200.089099)
			(xy 50.755583 -200.045062) (xy 50.732457 -199.997041) (xy 50.716747 -199.946111) (xy 50.708804 -199.893407)
			(xy 47.319956 -199.893407) (xy 47.312013 -199.946111) (xy 47.296303 -199.997041) (xy 47.273177 -200.045062)
			(xy 47.243153 -200.089099) (xy 47.206901 -200.12817) (xy 47.16523 -200.161401) (xy 47.119072 -200.18805)
			(xy 47.069458 -200.207522) (xy 47.017496 -200.219382) (xy 46.964346 -200.223366) (xy 46.911196 -200.219382)
			(xy 46.859234 -200.207522) (xy 46.80962 -200.18805) (xy 46.763462 -200.161401) (xy 46.721791 -200.12817)
			(xy 46.685539 -200.089099) (xy 46.655515 -200.045062) (xy 46.632389 -199.997041) (xy 46.616679 -199.946111)
			(xy 46.608736 -199.893407) (xy 36.332424 -199.893407) (xy 36.324481 -199.946111) (xy 36.308771 -199.997041)
			(xy 36.285645 -200.045062) (xy 36.255621 -200.089099) (xy 36.219369 -200.12817) (xy 36.177698 -200.161401)
			(xy 36.13154 -200.18805) (xy 36.081926 -200.207522) (xy 36.029964 -200.219382) (xy 35.976814 -200.223366)
			(xy 35.923664 -200.219382) (xy 35.871702 -200.207522) (xy 35.822088 -200.18805) (xy 35.77593 -200.161401)
			(xy 35.734259 -200.12817) (xy 35.698007 -200.089099) (xy 35.667983 -200.045062) (xy 35.644857 -199.997041)
			(xy 35.629147 -199.946111) (xy 35.621204 -199.893407) (xy 32.232356 -199.893407) (xy 32.224413 -199.946111)
			(xy 32.208703 -199.997041) (xy 32.185577 -200.045062) (xy 32.155553 -200.089099) (xy 32.119301 -200.12817)
			(xy 32.07763 -200.161401) (xy 32.031472 -200.18805) (xy 31.981858 -200.207522) (xy 31.929896 -200.219382)
			(xy 31.876746 -200.223366) (xy 31.823596 -200.219382) (xy 31.771634 -200.207522) (xy 31.72202 -200.18805)
			(xy 31.675862 -200.161401) (xy 31.634191 -200.12817) (xy 31.597939 -200.089099) (xy 31.567915 -200.045062)
			(xy 31.544789 -199.997041) (xy 31.529079 -199.946111) (xy 31.521136 -199.893407) (xy 21.244824 -199.893407)
			(xy 21.236881 -199.946111) (xy 21.221171 -199.997041) (xy 21.198045 -200.045062) (xy 21.168021 -200.089099)
			(xy 21.131769 -200.12817) (xy 21.090098 -200.161401) (xy 21.04394 -200.18805) (xy 20.994326 -200.207522)
			(xy 20.942364 -200.219382) (xy 20.889214 -200.223366) (xy 20.836064 -200.219382) (xy 20.784102 -200.207522)
			(xy 20.734488 -200.18805) (xy 20.68833 -200.161401) (xy 20.646659 -200.12817) (xy 20.610407 -200.089099)
			(xy 20.580383 -200.045062) (xy 20.557257 -199.997041) (xy 20.541547 -199.946111) (xy 20.533604 -199.893407)
			(xy 17.144756 -199.893407) (xy 17.136813 -199.946111) (xy 17.121103 -199.997041) (xy 17.097977 -200.045062)
			(xy 17.067953 -200.089099) (xy 17.031701 -200.12817) (xy 16.99003 -200.161401) (xy 16.943872 -200.18805)
			(xy 16.894258 -200.207522) (xy 16.842296 -200.219382) (xy 16.789146 -200.223366) (xy 16.735996 -200.219382)
			(xy 16.684034 -200.207522) (xy 16.63442 -200.18805) (xy 16.588262 -200.161401) (xy 16.546591 -200.12817)
			(xy 16.510339 -200.089099) (xy 16.480315 -200.045062) (xy 16.457189 -199.997041) (xy 16.441479 -199.946111)
			(xy 16.433536 -199.893407) (xy 9.6774 -199.893407) (xy 9.6774 -200.743291) (xy 16.433536 -200.743291)
			(xy 16.433536 -200.689993) (xy 16.441479 -200.637289) (xy 16.457189 -200.586359) (xy 16.480315 -200.538338)
			(xy 16.510339 -200.494301) (xy 16.546591 -200.45523) (xy 16.588262 -200.421999) (xy 16.63442 -200.39535)
			(xy 16.684034 -200.375878) (xy 16.735996 -200.364018) (xy 16.789146 -200.360035) (xy 16.842296 -200.364018)
			(xy 16.894258 -200.375878) (xy 16.943872 -200.39535) (xy 16.99003 -200.421999) (xy 17.031701 -200.45523)
			(xy 17.067953 -200.494301) (xy 17.097977 -200.538338) (xy 17.121103 -200.586359) (xy 17.136813 -200.637289)
			(xy 17.144756 -200.689993) (xy 17.145254 -200.716642) (xy 17.144756 -200.743291) (xy 31.521136 -200.743291)
			(xy 31.521136 -200.689993) (xy 31.529079 -200.637289) (xy 31.544789 -200.586359) (xy 31.567915 -200.538338)
			(xy 31.597939 -200.494301) (xy 31.634191 -200.45523) (xy 31.675862 -200.421999) (xy 31.72202 -200.39535)
			(xy 31.771634 -200.375878) (xy 31.823596 -200.364018) (xy 31.876746 -200.360035) (xy 31.929896 -200.364018)
			(xy 31.981858 -200.375878) (xy 32.031472 -200.39535) (xy 32.07763 -200.421999) (xy 32.119301 -200.45523)
			(xy 32.155553 -200.494301) (xy 32.185577 -200.538338) (xy 32.208703 -200.586359) (xy 32.224413 -200.637289)
			(xy 32.232356 -200.689993) (xy 32.232854 -200.716642) (xy 32.232356 -200.743291) (xy 46.608736 -200.743291)
			(xy 46.608736 -200.689993) (xy 46.616679 -200.637289) (xy 46.632389 -200.586359) (xy 46.655515 -200.538338)
			(xy 46.685539 -200.494301) (xy 46.721791 -200.45523) (xy 46.763462 -200.421999) (xy 46.80962 -200.39535)
			(xy 46.859234 -200.375878) (xy 46.911196 -200.364018) (xy 46.964346 -200.360035) (xy 47.017496 -200.364018)
			(xy 47.069458 -200.375878) (xy 47.119072 -200.39535) (xy 47.16523 -200.421999) (xy 47.206901 -200.45523)
			(xy 47.243153 -200.494301) (xy 47.273177 -200.538338) (xy 47.296303 -200.586359) (xy 47.312013 -200.637289)
			(xy 47.319956 -200.689993) (xy 47.320454 -200.716642) (xy 47.319956 -200.743291) (xy 47.312013 -200.795995)
			(xy 47.296303 -200.846925) (xy 47.273177 -200.894946) (xy 47.243153 -200.938983) (xy 47.206901 -200.978054)
			(xy 47.16523 -201.011285) (xy 47.119072 -201.037934) (xy 47.069458 -201.057406) (xy 47.017496 -201.069266)
			(xy 46.964346 -201.07325) (xy 46.911196 -201.069266) (xy 46.859234 -201.057406) (xy 46.80962 -201.037934)
			(xy 46.763462 -201.011285) (xy 46.721791 -200.978054) (xy 46.685539 -200.938983) (xy 46.655515 -200.894946)
			(xy 46.632389 -200.846925) (xy 46.616679 -200.795995) (xy 46.608736 -200.743291) (xy 32.232356 -200.743291)
			(xy 32.224413 -200.795995) (xy 32.208703 -200.846925) (xy 32.185577 -200.894946) (xy 32.155553 -200.938983)
			(xy 32.119301 -200.978054) (xy 32.07763 -201.011285) (xy 32.031472 -201.037934) (xy 31.981858 -201.057406)
			(xy 31.929896 -201.069266) (xy 31.876746 -201.07325) (xy 31.823596 -201.069266) (xy 31.771634 -201.057406)
			(xy 31.72202 -201.037934) (xy 31.675862 -201.011285) (xy 31.634191 -200.978054) (xy 31.597939 -200.938983)
			(xy 31.567915 -200.894946) (xy 31.544789 -200.846925) (xy 31.529079 -200.795995) (xy 31.521136 -200.743291)
			(xy 17.144756 -200.743291) (xy 17.136813 -200.795995) (xy 17.121103 -200.846925) (xy 17.097977 -200.894946)
			(xy 17.067953 -200.938983) (xy 17.031701 -200.978054) (xy 16.99003 -201.011285) (xy 16.943872 -201.037934)
			(xy 16.894258 -201.057406) (xy 16.842296 -201.069266) (xy 16.789146 -201.07325) (xy 16.735996 -201.069266)
			(xy 16.684034 -201.057406) (xy 16.63442 -201.037934) (xy 16.588262 -201.011285) (xy 16.546591 -200.978054)
			(xy 16.510339 -200.938983) (xy 16.480315 -200.894946) (xy 16.457189 -200.846925) (xy 16.441479 -200.795995)
			(xy 16.433536 -200.743291) (xy 9.6774 -200.743291) (xy 9.6774 -201.593429) (xy 20.533604 -201.593429)
			(xy 20.533604 -201.540131) (xy 20.541547 -201.487427) (xy 20.557257 -201.436497) (xy 20.580383 -201.388476)
			(xy 20.610407 -201.344439) (xy 20.646659 -201.305368) (xy 20.68833 -201.272137) (xy 20.734488 -201.245488)
			(xy 20.784102 -201.226016) (xy 20.836064 -201.214156) (xy 20.889214 -201.210173) (xy 20.942364 -201.214156)
			(xy 20.994326 -201.226016) (xy 21.04394 -201.245488) (xy 21.090098 -201.272137) (xy 21.131769 -201.305368)
			(xy 21.168021 -201.344439) (xy 21.198045 -201.388476) (xy 21.221171 -201.436497) (xy 21.236881 -201.487427)
			(xy 21.244824 -201.540131) (xy 21.245322 -201.56678) (xy 21.244824 -201.593429) (xy 35.621204 -201.593429)
			(xy 35.621204 -201.540131) (xy 35.629147 -201.487427) (xy 35.644857 -201.436497) (xy 35.667983 -201.388476)
			(xy 35.698007 -201.344439) (xy 35.734259 -201.305368) (xy 35.77593 -201.272137) (xy 35.822088 -201.245488)
			(xy 35.871702 -201.226016) (xy 35.923664 -201.214156) (xy 35.976814 -201.210173) (xy 36.029964 -201.214156)
			(xy 36.081926 -201.226016) (xy 36.13154 -201.245488) (xy 36.177698 -201.272137) (xy 36.219369 -201.305368)
			(xy 36.255621 -201.344439) (xy 36.285645 -201.388476) (xy 36.308771 -201.436497) (xy 36.324481 -201.487427)
			(xy 36.332424 -201.540131) (xy 36.332922 -201.56678) (xy 36.332424 -201.593429) (xy 50.708804 -201.593429)
			(xy 50.708804 -201.540131) (xy 50.716747 -201.487427) (xy 50.732457 -201.436497) (xy 50.755583 -201.388476)
			(xy 50.785607 -201.344439) (xy 50.821859 -201.305368) (xy 50.86353 -201.272137) (xy 50.909688 -201.245488)
			(xy 50.959302 -201.226016) (xy 51.011264 -201.214156) (xy 51.064414 -201.210173) (xy 51.117564 -201.214156)
			(xy 51.169526 -201.226016) (xy 51.21914 -201.245488) (xy 51.265298 -201.272137) (xy 51.306969 -201.305368)
			(xy 51.343221 -201.344439) (xy 51.373245 -201.388476) (xy 51.396371 -201.436497) (xy 51.412081 -201.487427)
			(xy 51.420024 -201.540131) (xy 51.420522 -201.56678) (xy 51.420024 -201.593429) (xy 51.412081 -201.646133)
			(xy 51.396371 -201.697063) (xy 51.373245 -201.745084) (xy 51.343221 -201.789121) (xy 51.306969 -201.828192)
			(xy 51.265298 -201.861423) (xy 51.21914 -201.888072) (xy 51.169526 -201.907544) (xy 51.117564 -201.919404)
			(xy 51.064414 -201.923388) (xy 51.011264 -201.919404) (xy 50.959302 -201.907544) (xy 50.909688 -201.888072)
			(xy 50.86353 -201.861423) (xy 50.821859 -201.828192) (xy 50.785607 -201.789121) (xy 50.755583 -201.745084)
			(xy 50.732457 -201.697063) (xy 50.716747 -201.646133) (xy 50.708804 -201.593429) (xy 36.332424 -201.593429)
			(xy 36.324481 -201.646133) (xy 36.308771 -201.697063) (xy 36.285645 -201.745084) (xy 36.255621 -201.789121)
			(xy 36.219369 -201.828192) (xy 36.177698 -201.861423) (xy 36.13154 -201.888072) (xy 36.081926 -201.907544)
			(xy 36.029964 -201.919404) (xy 35.976814 -201.923388) (xy 35.923664 -201.919404) (xy 35.871702 -201.907544)
			(xy 35.822088 -201.888072) (xy 35.77593 -201.861423) (xy 35.734259 -201.828192) (xy 35.698007 -201.789121)
			(xy 35.667983 -201.745084) (xy 35.644857 -201.697063) (xy 35.629147 -201.646133) (xy 35.621204 -201.593429)
			(xy 21.244824 -201.593429) (xy 21.236881 -201.646133) (xy 21.221171 -201.697063) (xy 21.198045 -201.745084)
			(xy 21.168021 -201.789121) (xy 21.131769 -201.828192) (xy 21.090098 -201.861423) (xy 21.04394 -201.888072)
			(xy 20.994326 -201.907544) (xy 20.942364 -201.919404) (xy 20.889214 -201.923388) (xy 20.836064 -201.919404)
			(xy 20.784102 -201.907544) (xy 20.734488 -201.888072) (xy 20.68833 -201.861423) (xy 20.646659 -201.828192)
			(xy 20.610407 -201.789121) (xy 20.580383 -201.745084) (xy 20.557257 -201.697063) (xy 20.541547 -201.646133)
			(xy 20.533604 -201.593429) (xy 9.6774 -201.593429) (xy 9.6774 -202.443313) (xy 16.433536 -202.443313)
			(xy 16.433536 -202.390015) (xy 16.441479 -202.337311) (xy 16.457189 -202.286381) (xy 16.480315 -202.23836)
			(xy 16.510339 -202.194323) (xy 16.546591 -202.155252) (xy 16.588262 -202.122021) (xy 16.63442 -202.095372)
			(xy 16.684034 -202.0759) (xy 16.735996 -202.06404) (xy 16.789146 -202.060057) (xy 16.842296 -202.06404)
			(xy 16.894258 -202.0759) (xy 16.943872 -202.095372) (xy 16.99003 -202.122021) (xy 17.031701 -202.155252)
			(xy 17.067953 -202.194323) (xy 17.097977 -202.23836) (xy 17.121103 -202.286381) (xy 17.136813 -202.337311)
			(xy 17.144756 -202.390015) (xy 17.145254 -202.416664) (xy 17.144756 -202.443313) (xy 31.521136 -202.443313)
			(xy 31.521136 -202.390015) (xy 31.529079 -202.337311) (xy 31.544789 -202.286381) (xy 31.567915 -202.23836)
			(xy 31.597939 -202.194323) (xy 31.634191 -202.155252) (xy 31.675862 -202.122021) (xy 31.72202 -202.095372)
			(xy 31.771634 -202.0759) (xy 31.823596 -202.06404) (xy 31.876746 -202.060057) (xy 31.929896 -202.06404)
			(xy 31.981858 -202.0759) (xy 32.031472 -202.095372) (xy 32.07763 -202.122021) (xy 32.119301 -202.155252)
			(xy 32.155553 -202.194323) (xy 32.185577 -202.23836) (xy 32.208703 -202.286381) (xy 32.224413 -202.337311)
			(xy 32.232356 -202.390015) (xy 32.232854 -202.416664) (xy 32.232356 -202.443313) (xy 46.608736 -202.443313)
			(xy 46.608736 -202.390015) (xy 46.616679 -202.337311) (xy 46.632389 -202.286381) (xy 46.655515 -202.23836)
			(xy 46.685539 -202.194323) (xy 46.721791 -202.155252) (xy 46.763462 -202.122021) (xy 46.80962 -202.095372)
			(xy 46.859234 -202.0759) (xy 46.911196 -202.06404) (xy 46.964346 -202.060057) (xy 47.017496 -202.06404)
			(xy 47.069458 -202.0759) (xy 47.119072 -202.095372) (xy 47.16523 -202.122021) (xy 47.206901 -202.155252)
			(xy 47.243153 -202.194323) (xy 47.273177 -202.23836) (xy 47.296303 -202.286381) (xy 47.312013 -202.337311)
			(xy 47.319956 -202.390015) (xy 47.320454 -202.416664) (xy 47.319956 -202.443313) (xy 47.312013 -202.496017)
			(xy 47.296303 -202.546947) (xy 47.273177 -202.594968) (xy 47.243153 -202.639005) (xy 47.206901 -202.678076)
			(xy 47.16523 -202.711307) (xy 47.119072 -202.737956) (xy 47.069458 -202.757428) (xy 47.017496 -202.769288)
			(xy 46.964346 -202.773272) (xy 46.911196 -202.769288) (xy 46.859234 -202.757428) (xy 46.80962 -202.737956)
			(xy 46.763462 -202.711307) (xy 46.721791 -202.678076) (xy 46.685539 -202.639005) (xy 46.655515 -202.594968)
			(xy 46.632389 -202.546947) (xy 46.616679 -202.496017) (xy 46.608736 -202.443313) (xy 32.232356 -202.443313)
			(xy 32.224413 -202.496017) (xy 32.208703 -202.546947) (xy 32.185577 -202.594968) (xy 32.155553 -202.639005)
			(xy 32.119301 -202.678076) (xy 32.07763 -202.711307) (xy 32.031472 -202.737956) (xy 31.981858 -202.757428)
			(xy 31.929896 -202.769288) (xy 31.876746 -202.773272) (xy 31.823596 -202.769288) (xy 31.771634 -202.757428)
			(xy 31.72202 -202.737956) (xy 31.675862 -202.711307) (xy 31.634191 -202.678076) (xy 31.597939 -202.639005)
			(xy 31.567915 -202.594968) (xy 31.544789 -202.546947) (xy 31.529079 -202.496017) (xy 31.521136 -202.443313)
			(xy 17.144756 -202.443313) (xy 17.136813 -202.496017) (xy 17.121103 -202.546947) (xy 17.097977 -202.594968)
			(xy 17.067953 -202.639005) (xy 17.031701 -202.678076) (xy 16.99003 -202.711307) (xy 16.943872 -202.737956)
			(xy 16.894258 -202.757428) (xy 16.842296 -202.769288) (xy 16.789146 -202.773272) (xy 16.735996 -202.769288)
			(xy 16.684034 -202.757428) (xy 16.63442 -202.737956) (xy 16.588262 -202.711307) (xy 16.546591 -202.678076)
			(xy 16.510339 -202.639005) (xy 16.480315 -202.594968) (xy 16.457189 -202.546947) (xy 16.441479 -202.496017)
			(xy 16.433536 -202.443313) (xy 9.6774 -202.443313) (xy 9.6774 -203.293451) (xy 20.533604 -203.293451)
			(xy 20.533604 -203.240153) (xy 20.541547 -203.187449) (xy 20.557257 -203.136519) (xy 20.580383 -203.088498)
			(xy 20.610407 -203.044461) (xy 20.646659 -203.00539) (xy 20.68833 -202.972159) (xy 20.734488 -202.94551)
			(xy 20.784102 -202.926038) (xy 20.836064 -202.914178) (xy 20.889214 -202.910195) (xy 20.942364 -202.914178)
			(xy 20.994326 -202.926038) (xy 21.04394 -202.94551) (xy 21.090098 -202.972159) (xy 21.131769 -203.00539)
			(xy 21.168021 -203.044461) (xy 21.198045 -203.088498) (xy 21.221171 -203.136519) (xy 21.236881 -203.187449)
			(xy 21.244824 -203.240153) (xy 21.245322 -203.266802) (xy 21.244824 -203.293451) (xy 35.621204 -203.293451)
			(xy 35.621204 -203.240153) (xy 35.629147 -203.187449) (xy 35.644857 -203.136519) (xy 35.667983 -203.088498)
			(xy 35.698007 -203.044461) (xy 35.734259 -203.00539) (xy 35.77593 -202.972159) (xy 35.822088 -202.94551)
			(xy 35.871702 -202.926038) (xy 35.923664 -202.914178) (xy 35.976814 -202.910195) (xy 36.029964 -202.914178)
			(xy 36.081926 -202.926038) (xy 36.13154 -202.94551) (xy 36.177698 -202.972159) (xy 36.219369 -203.00539)
			(xy 36.255621 -203.044461) (xy 36.285645 -203.088498) (xy 36.308771 -203.136519) (xy 36.324481 -203.187449)
			(xy 36.332424 -203.240153) (xy 36.332922 -203.266802) (xy 36.332424 -203.293451) (xy 50.708804 -203.293451)
			(xy 50.708804 -203.240153) (xy 50.716747 -203.187449) (xy 50.732457 -203.136519) (xy 50.755583 -203.088498)
			(xy 50.785607 -203.044461) (xy 50.821859 -203.00539) (xy 50.86353 -202.972159) (xy 50.909688 -202.94551)
			(xy 50.959302 -202.926038) (xy 51.011264 -202.914178) (xy 51.064414 -202.910195) (xy 51.117564 -202.914178)
			(xy 51.169526 -202.926038) (xy 51.21914 -202.94551) (xy 51.265298 -202.972159) (xy 51.306969 -203.00539)
			(xy 51.343221 -203.044461) (xy 51.373245 -203.088498) (xy 51.396371 -203.136519) (xy 51.412081 -203.187449)
			(xy 51.420024 -203.240153) (xy 51.420522 -203.266802) (xy 51.420024 -203.293451) (xy 51.412081 -203.346155)
			(xy 51.396371 -203.397085) (xy 51.373245 -203.445106) (xy 51.343221 -203.489143) (xy 51.306969 -203.528214)
			(xy 51.265298 -203.561445) (xy 51.21914 -203.588094) (xy 51.169526 -203.607566) (xy 51.117564 -203.619426)
			(xy 51.064414 -203.62341) (xy 51.011264 -203.619426) (xy 50.959302 -203.607566) (xy 50.909688 -203.588094)
			(xy 50.86353 -203.561445) (xy 50.821859 -203.528214) (xy 50.785607 -203.489143) (xy 50.755583 -203.445106)
			(xy 50.732457 -203.397085) (xy 50.716747 -203.346155) (xy 50.708804 -203.293451) (xy 36.332424 -203.293451)
			(xy 36.324481 -203.346155) (xy 36.308771 -203.397085) (xy 36.285645 -203.445106) (xy 36.255621 -203.489143)
			(xy 36.219369 -203.528214) (xy 36.177698 -203.561445) (xy 36.13154 -203.588094) (xy 36.081926 -203.607566)
			(xy 36.029964 -203.619426) (xy 35.976814 -203.62341) (xy 35.923664 -203.619426) (xy 35.871702 -203.607566)
			(xy 35.822088 -203.588094) (xy 35.77593 -203.561445) (xy 35.734259 -203.528214) (xy 35.698007 -203.489143)
			(xy 35.667983 -203.445106) (xy 35.644857 -203.397085) (xy 35.629147 -203.346155) (xy 35.621204 -203.293451)
			(xy 21.244824 -203.293451) (xy 21.236881 -203.346155) (xy 21.221171 -203.397085) (xy 21.198045 -203.445106)
			(xy 21.168021 -203.489143) (xy 21.131769 -203.528214) (xy 21.090098 -203.561445) (xy 21.04394 -203.588094)
			(xy 20.994326 -203.607566) (xy 20.942364 -203.619426) (xy 20.889214 -203.62341) (xy 20.836064 -203.619426)
			(xy 20.784102 -203.607566) (xy 20.734488 -203.588094) (xy 20.68833 -203.561445) (xy 20.646659 -203.528214)
			(xy 20.610407 -203.489143) (xy 20.580383 -203.445106) (xy 20.557257 -203.397085) (xy 20.541547 -203.346155)
			(xy 20.533604 -203.293451) (xy 9.6774 -203.293451) (xy 9.6774 -204.143335) (xy 16.433536 -204.143335)
			(xy 16.433536 -204.090037) (xy 16.441479 -204.037333) (xy 16.457189 -203.986403) (xy 16.480315 -203.938382)
			(xy 16.510339 -203.894345) (xy 16.546591 -203.855274) (xy 16.588262 -203.822043) (xy 16.63442 -203.795394)
			(xy 16.684034 -203.775922) (xy 16.735996 -203.764062) (xy 16.789146 -203.760079) (xy 16.842296 -203.764062)
			(xy 16.894258 -203.775922) (xy 16.943872 -203.795394) (xy 16.99003 -203.822043) (xy 17.031701 -203.855274)
			(xy 17.067953 -203.894345) (xy 17.097977 -203.938382) (xy 17.121103 -203.986403) (xy 17.136813 -204.037333)
			(xy 17.144756 -204.090037) (xy 17.145254 -204.116686) (xy 17.144756 -204.143335) (xy 31.521136 -204.143335)
			(xy 31.521136 -204.090037) (xy 31.529079 -204.037333) (xy 31.544789 -203.986403) (xy 31.567915 -203.938382)
			(xy 31.597939 -203.894345) (xy 31.634191 -203.855274) (xy 31.675862 -203.822043) (xy 31.72202 -203.795394)
			(xy 31.771634 -203.775922) (xy 31.823596 -203.764062) (xy 31.876746 -203.760079) (xy 31.929896 -203.764062)
			(xy 31.981858 -203.775922) (xy 32.031472 -203.795394) (xy 32.07763 -203.822043) (xy 32.119301 -203.855274)
			(xy 32.155553 -203.894345) (xy 32.185577 -203.938382) (xy 32.208703 -203.986403) (xy 32.224413 -204.037333)
			(xy 32.232356 -204.090037) (xy 32.232854 -204.116686) (xy 32.232356 -204.143335) (xy 46.608736 -204.143335)
			(xy 46.608736 -204.090037) (xy 46.616679 -204.037333) (xy 46.632389 -203.986403) (xy 46.655515 -203.938382)
			(xy 46.685539 -203.894345) (xy 46.721791 -203.855274) (xy 46.763462 -203.822043) (xy 46.80962 -203.795394)
			(xy 46.859234 -203.775922) (xy 46.911196 -203.764062) (xy 46.964346 -203.760079) (xy 47.017496 -203.764062)
			(xy 47.069458 -203.775922) (xy 47.119072 -203.795394) (xy 47.16523 -203.822043) (xy 47.206901 -203.855274)
			(xy 47.243153 -203.894345) (xy 47.273177 -203.938382) (xy 47.296303 -203.986403) (xy 47.312013 -204.037333)
			(xy 47.319956 -204.090037) (xy 47.320454 -204.116686) (xy 47.319956 -204.143335) (xy 47.312013 -204.196039)
			(xy 47.296303 -204.246969) (xy 47.273177 -204.29499) (xy 47.243153 -204.339027) (xy 47.206901 -204.378098)
			(xy 47.16523 -204.411329) (xy 47.119072 -204.437978) (xy 47.069458 -204.45745) (xy 47.017496 -204.46931)
			(xy 46.964346 -204.473294) (xy 46.911196 -204.46931) (xy 46.859234 -204.45745) (xy 46.80962 -204.437978)
			(xy 46.763462 -204.411329) (xy 46.721791 -204.378098) (xy 46.685539 -204.339027) (xy 46.655515 -204.29499)
			(xy 46.632389 -204.246969) (xy 46.616679 -204.196039) (xy 46.608736 -204.143335) (xy 32.232356 -204.143335)
			(xy 32.224413 -204.196039) (xy 32.208703 -204.246969) (xy 32.185577 -204.29499) (xy 32.155553 -204.339027)
			(xy 32.119301 -204.378098) (xy 32.07763 -204.411329) (xy 32.031472 -204.437978) (xy 31.981858 -204.45745)
			(xy 31.929896 -204.46931) (xy 31.876746 -204.473294) (xy 31.823596 -204.46931) (xy 31.771634 -204.45745)
			(xy 31.72202 -204.437978) (xy 31.675862 -204.411329) (xy 31.634191 -204.378098) (xy 31.597939 -204.339027)
			(xy 31.567915 -204.29499) (xy 31.544789 -204.246969) (xy 31.529079 -204.196039) (xy 31.521136 -204.143335)
			(xy 17.144756 -204.143335) (xy 17.136813 -204.196039) (xy 17.121103 -204.246969) (xy 17.097977 -204.29499)
			(xy 17.067953 -204.339027) (xy 17.031701 -204.378098) (xy 16.99003 -204.411329) (xy 16.943872 -204.437978)
			(xy 16.894258 -204.45745) (xy 16.842296 -204.46931) (xy 16.789146 -204.473294) (xy 16.735996 -204.46931)
			(xy 16.684034 -204.45745) (xy 16.63442 -204.437978) (xy 16.588262 -204.411329) (xy 16.546591 -204.378098)
			(xy 16.510339 -204.339027) (xy 16.480315 -204.29499) (xy 16.457189 -204.246969) (xy 16.441479 -204.196039)
			(xy 16.433536 -204.143335) (xy 9.6774 -204.143335) (xy 9.6774 -204.993219) (xy 20.533604 -204.993219)
			(xy 20.533604 -204.939921) (xy 20.541547 -204.887217) (xy 20.557257 -204.836287) (xy 20.580383 -204.788266)
			(xy 20.610407 -204.744229) (xy 20.646659 -204.705158) (xy 20.68833 -204.671927) (xy 20.734488 -204.645278)
			(xy 20.784102 -204.625806) (xy 20.836064 -204.613946) (xy 20.889214 -204.609963) (xy 20.942364 -204.613946)
			(xy 20.994326 -204.625806) (xy 21.04394 -204.645278) (xy 21.090098 -204.671927) (xy 21.131769 -204.705158)
			(xy 21.168021 -204.744229) (xy 21.198045 -204.788266) (xy 21.221171 -204.836287) (xy 21.236881 -204.887217)
			(xy 21.244824 -204.939921) (xy 21.245322 -204.96657) (xy 21.244824 -204.993219) (xy 35.621204 -204.993219)
			(xy 35.621204 -204.939921) (xy 35.629147 -204.887217) (xy 35.644857 -204.836287) (xy 35.667983 -204.788266)
			(xy 35.698007 -204.744229) (xy 35.734259 -204.705158) (xy 35.77593 -204.671927) (xy 35.822088 -204.645278)
			(xy 35.871702 -204.625806) (xy 35.923664 -204.613946) (xy 35.976814 -204.609963) (xy 36.029964 -204.613946)
			(xy 36.081926 -204.625806) (xy 36.13154 -204.645278) (xy 36.177698 -204.671927) (xy 36.219369 -204.705158)
			(xy 36.255621 -204.744229) (xy 36.285645 -204.788266) (xy 36.308771 -204.836287) (xy 36.324481 -204.887217)
			(xy 36.332424 -204.939921) (xy 36.332922 -204.96657) (xy 36.332424 -204.993219) (xy 50.708804 -204.993219)
			(xy 50.708804 -204.939921) (xy 50.716747 -204.887217) (xy 50.732457 -204.836287) (xy 50.755583 -204.788266)
			(xy 50.785607 -204.744229) (xy 50.821859 -204.705158) (xy 50.86353 -204.671927) (xy 50.909688 -204.645278)
			(xy 50.959302 -204.625806) (xy 51.011264 -204.613946) (xy 51.064414 -204.609963) (xy 51.117564 -204.613946)
			(xy 51.169526 -204.625806) (xy 51.21914 -204.645278) (xy 51.265298 -204.671927) (xy 51.306969 -204.705158)
			(xy 51.343221 -204.744229) (xy 51.373245 -204.788266) (xy 51.396371 -204.836287) (xy 51.412081 -204.887217)
			(xy 51.420024 -204.939921) (xy 51.420522 -204.96657) (xy 51.420024 -204.993219) (xy 51.412081 -205.045923)
			(xy 51.396371 -205.096853) (xy 51.373245 -205.144874) (xy 51.343221 -205.188911) (xy 51.306969 -205.227982)
			(xy 51.265298 -205.261213) (xy 51.21914 -205.287862) (xy 51.169526 -205.307334) (xy 51.117564 -205.319194)
			(xy 51.064414 -205.323178) (xy 51.011264 -205.319194) (xy 50.959302 -205.307334) (xy 50.909688 -205.287862)
			(xy 50.86353 -205.261213) (xy 50.821859 -205.227982) (xy 50.785607 -205.188911) (xy 50.755583 -205.144874)
			(xy 50.732457 -205.096853) (xy 50.716747 -205.045923) (xy 50.708804 -204.993219) (xy 36.332424 -204.993219)
			(xy 36.324481 -205.045923) (xy 36.308771 -205.096853) (xy 36.285645 -205.144874) (xy 36.255621 -205.188911)
			(xy 36.219369 -205.227982) (xy 36.177698 -205.261213) (xy 36.13154 -205.287862) (xy 36.081926 -205.307334)
			(xy 36.029964 -205.319194) (xy 35.976814 -205.323178) (xy 35.923664 -205.319194) (xy 35.871702 -205.307334)
			(xy 35.822088 -205.287862) (xy 35.77593 -205.261213) (xy 35.734259 -205.227982) (xy 35.698007 -205.188911)
			(xy 35.667983 -205.144874) (xy 35.644857 -205.096853) (xy 35.629147 -205.045923) (xy 35.621204 -204.993219)
			(xy 21.244824 -204.993219) (xy 21.236881 -205.045923) (xy 21.221171 -205.096853) (xy 21.198045 -205.144874)
			(xy 21.168021 -205.188911) (xy 21.131769 -205.227982) (xy 21.090098 -205.261213) (xy 21.04394 -205.287862)
			(xy 20.994326 -205.307334) (xy 20.942364 -205.319194) (xy 20.889214 -205.323178) (xy 20.836064 -205.319194)
			(xy 20.784102 -205.307334) (xy 20.734488 -205.287862) (xy 20.68833 -205.261213) (xy 20.646659 -205.227982)
			(xy 20.610407 -205.188911) (xy 20.580383 -205.144874) (xy 20.557257 -205.096853) (xy 20.541547 -205.045923)
			(xy 20.533604 -204.993219) (xy 9.6774 -204.993219) (xy 9.6774 -205.843357) (xy 16.433536 -205.843357)
			(xy 16.433536 -205.790059) (xy 16.441479 -205.737355) (xy 16.457189 -205.686425) (xy 16.480315 -205.638404)
			(xy 16.510339 -205.594367) (xy 16.546591 -205.555296) (xy 16.588262 -205.522065) (xy 16.63442 -205.495416)
			(xy 16.684034 -205.475944) (xy 16.735996 -205.464084) (xy 16.789146 -205.460101) (xy 16.842296 -205.464084)
			(xy 16.894258 -205.475944) (xy 16.943872 -205.495416) (xy 16.99003 -205.522065) (xy 17.031701 -205.555296)
			(xy 17.067953 -205.594367) (xy 17.097977 -205.638404) (xy 17.121103 -205.686425) (xy 17.136813 -205.737355)
			(xy 17.144756 -205.790059) (xy 17.145254 -205.816708) (xy 17.144756 -205.843357) (xy 31.521136 -205.843357)
			(xy 31.521136 -205.790059) (xy 31.529079 -205.737355) (xy 31.544789 -205.686425) (xy 31.567915 -205.638404)
			(xy 31.597939 -205.594367) (xy 31.634191 -205.555296) (xy 31.675862 -205.522065) (xy 31.72202 -205.495416)
			(xy 31.771634 -205.475944) (xy 31.823596 -205.464084) (xy 31.876746 -205.460101) (xy 31.929896 -205.464084)
			(xy 31.981858 -205.475944) (xy 32.031472 -205.495416) (xy 32.07763 -205.522065) (xy 32.119301 -205.555296)
			(xy 32.155553 -205.594367) (xy 32.185577 -205.638404) (xy 32.208703 -205.686425) (xy 32.224413 -205.737355)
			(xy 32.232356 -205.790059) (xy 32.232854 -205.816708) (xy 32.232356 -205.843357) (xy 46.608736 -205.843357)
			(xy 46.608736 -205.790059) (xy 46.616679 -205.737355) (xy 46.632389 -205.686425) (xy 46.655515 -205.638404)
			(xy 46.685539 -205.594367) (xy 46.721791 -205.555296) (xy 46.763462 -205.522065) (xy 46.80962 -205.495416)
			(xy 46.859234 -205.475944) (xy 46.911196 -205.464084) (xy 46.964346 -205.460101) (xy 47.017496 -205.464084)
			(xy 47.069458 -205.475944) (xy 47.119072 -205.495416) (xy 47.16523 -205.522065) (xy 47.206901 -205.555296)
			(xy 47.243153 -205.594367) (xy 47.273177 -205.638404) (xy 47.296303 -205.686425) (xy 47.312013 -205.737355)
			(xy 47.319956 -205.790059) (xy 47.320454 -205.816708) (xy 47.319956 -205.843357) (xy 47.312013 -205.896061)
			(xy 47.296303 -205.946991) (xy 47.273177 -205.995012) (xy 47.243153 -206.039049) (xy 47.206901 -206.07812)
			(xy 47.16523 -206.111351) (xy 47.119072 -206.138) (xy 47.069458 -206.157472) (xy 47.017496 -206.169332)
			(xy 46.964346 -206.173316) (xy 46.911196 -206.169332) (xy 46.859234 -206.157472) (xy 46.80962 -206.138)
			(xy 46.763462 -206.111351) (xy 46.721791 -206.07812) (xy 46.685539 -206.039049) (xy 46.655515 -205.995012)
			(xy 46.632389 -205.946991) (xy 46.616679 -205.896061) (xy 46.608736 -205.843357) (xy 32.232356 -205.843357)
			(xy 32.224413 -205.896061) (xy 32.208703 -205.946991) (xy 32.185577 -205.995012) (xy 32.155553 -206.039049)
			(xy 32.119301 -206.07812) (xy 32.07763 -206.111351) (xy 32.031472 -206.138) (xy 31.981858 -206.157472)
			(xy 31.929896 -206.169332) (xy 31.876746 -206.173316) (xy 31.823596 -206.169332) (xy 31.771634 -206.157472)
			(xy 31.72202 -206.138) (xy 31.675862 -206.111351) (xy 31.634191 -206.07812) (xy 31.597939 -206.039049)
			(xy 31.567915 -205.995012) (xy 31.544789 -205.946991) (xy 31.529079 -205.896061) (xy 31.521136 -205.843357)
			(xy 17.144756 -205.843357) (xy 17.136813 -205.896061) (xy 17.121103 -205.946991) (xy 17.097977 -205.995012)
			(xy 17.067953 -206.039049) (xy 17.031701 -206.07812) (xy 16.99003 -206.111351) (xy 16.943872 -206.138)
			(xy 16.894258 -206.157472) (xy 16.842296 -206.169332) (xy 16.789146 -206.173316) (xy 16.735996 -206.169332)
			(xy 16.684034 -206.157472) (xy 16.63442 -206.138) (xy 16.588262 -206.111351) (xy 16.546591 -206.07812)
			(xy 16.510339 -206.039049) (xy 16.480315 -205.995012) (xy 16.457189 -205.946991) (xy 16.441479 -205.896061)
			(xy 16.433536 -205.843357) (xy 9.6774 -205.843357) (xy 9.6774 -206.693241) (xy 20.533604 -206.693241)
			(xy 20.533604 -206.639943) (xy 20.541547 -206.587239) (xy 20.557257 -206.536309) (xy 20.580383 -206.488288)
			(xy 20.610407 -206.444251) (xy 20.646659 -206.40518) (xy 20.68833 -206.371949) (xy 20.734488 -206.3453)
			(xy 20.784102 -206.325828) (xy 20.836064 -206.313968) (xy 20.889214 -206.309985) (xy 20.942364 -206.313968)
			(xy 20.994326 -206.325828) (xy 21.04394 -206.3453) (xy 21.090098 -206.371949) (xy 21.131769 -206.40518)
			(xy 21.168021 -206.444251) (xy 21.198045 -206.488288) (xy 21.221171 -206.536309) (xy 21.236881 -206.587239)
			(xy 21.244824 -206.639943) (xy 21.245322 -206.666592) (xy 21.244824 -206.693241) (xy 35.621204 -206.693241)
			(xy 35.621204 -206.639943) (xy 35.629147 -206.587239) (xy 35.644857 -206.536309) (xy 35.667983 -206.488288)
			(xy 35.698007 -206.444251) (xy 35.734259 -206.40518) (xy 35.77593 -206.371949) (xy 35.822088 -206.3453)
			(xy 35.871702 -206.325828) (xy 35.923664 -206.313968) (xy 35.976814 -206.309985) (xy 36.029964 -206.313968)
			(xy 36.081926 -206.325828) (xy 36.13154 -206.3453) (xy 36.177698 -206.371949) (xy 36.219369 -206.40518)
			(xy 36.255621 -206.444251) (xy 36.285645 -206.488288) (xy 36.308771 -206.536309) (xy 36.324481 -206.587239)
			(xy 36.332424 -206.639943) (xy 36.332922 -206.666592) (xy 36.332424 -206.693241) (xy 50.708804 -206.693241)
			(xy 50.708804 -206.639943) (xy 50.716747 -206.587239) (xy 50.732457 -206.536309) (xy 50.755583 -206.488288)
			(xy 50.785607 -206.444251) (xy 50.821859 -206.40518) (xy 50.86353 -206.371949) (xy 50.909688 -206.3453)
			(xy 50.959302 -206.325828) (xy 51.011264 -206.313968) (xy 51.064414 -206.309985) (xy 51.117564 -206.313968)
			(xy 51.169526 -206.325828) (xy 51.21914 -206.3453) (xy 51.265298 -206.371949) (xy 51.306969 -206.40518)
			(xy 51.343221 -206.444251) (xy 51.373245 -206.488288) (xy 51.396371 -206.536309) (xy 51.412081 -206.587239)
			(xy 51.420024 -206.639943) (xy 51.420522 -206.666592) (xy 51.420024 -206.693241) (xy 51.412081 -206.745945)
			(xy 51.396371 -206.796875) (xy 51.373245 -206.844896) (xy 51.343221 -206.888933) (xy 51.306969 -206.928004)
			(xy 51.265298 -206.961235) (xy 51.21914 -206.987884) (xy 51.169526 -207.007356) (xy 51.117564 -207.019216)
			(xy 51.064414 -207.0232) (xy 51.011264 -207.019216) (xy 50.959302 -207.007356) (xy 50.909688 -206.987884)
			(xy 50.86353 -206.961235) (xy 50.821859 -206.928004) (xy 50.785607 -206.888933) (xy 50.755583 -206.844896)
			(xy 50.732457 -206.796875) (xy 50.716747 -206.745945) (xy 50.708804 -206.693241) (xy 36.332424 -206.693241)
			(xy 36.324481 -206.745945) (xy 36.308771 -206.796875) (xy 36.285645 -206.844896) (xy 36.255621 -206.888933)
			(xy 36.219369 -206.928004) (xy 36.177698 -206.961235) (xy 36.13154 -206.987884) (xy 36.081926 -207.007356)
			(xy 36.029964 -207.019216) (xy 35.976814 -207.0232) (xy 35.923664 -207.019216) (xy 35.871702 -207.007356)
			(xy 35.822088 -206.987884) (xy 35.77593 -206.961235) (xy 35.734259 -206.928004) (xy 35.698007 -206.888933)
			(xy 35.667983 -206.844896) (xy 35.644857 -206.796875) (xy 35.629147 -206.745945) (xy 35.621204 -206.693241)
			(xy 21.244824 -206.693241) (xy 21.236881 -206.745945) (xy 21.221171 -206.796875) (xy 21.198045 -206.844896)
			(xy 21.168021 -206.888933) (xy 21.131769 -206.928004) (xy 21.090098 -206.961235) (xy 21.04394 -206.987884)
			(xy 20.994326 -207.007356) (xy 20.942364 -207.019216) (xy 20.889214 -207.0232) (xy 20.836064 -207.019216)
			(xy 20.784102 -207.007356) (xy 20.734488 -206.987884) (xy 20.68833 -206.961235) (xy 20.646659 -206.928004)
			(xy 20.610407 -206.888933) (xy 20.580383 -206.844896) (xy 20.557257 -206.796875) (xy 20.541547 -206.745945)
			(xy 20.533604 -206.693241) (xy 9.6774 -206.693241) (xy 9.6774 -207.543379) (xy 16.433536 -207.543379)
			(xy 16.433536 -207.490081) (xy 16.441479 -207.437377) (xy 16.457189 -207.386447) (xy 16.480315 -207.338426)
			(xy 16.510339 -207.294389) (xy 16.546591 -207.255318) (xy 16.588262 -207.222087) (xy 16.63442 -207.195438)
			(xy 16.684034 -207.175966) (xy 16.735996 -207.164106) (xy 16.789146 -207.160123) (xy 16.842296 -207.164106)
			(xy 16.894258 -207.175966) (xy 16.943872 -207.195438) (xy 16.99003 -207.222087) (xy 17.031701 -207.255318)
			(xy 17.067953 -207.294389) (xy 17.097977 -207.338426) (xy 17.121103 -207.386447) (xy 17.136813 -207.437377)
			(xy 17.144756 -207.490081) (xy 17.145254 -207.51673) (xy 17.144756 -207.543379) (xy 31.521136 -207.543379)
			(xy 31.521136 -207.490081) (xy 31.529079 -207.437377) (xy 31.544789 -207.386447) (xy 31.567915 -207.338426)
			(xy 31.597939 -207.294389) (xy 31.634191 -207.255318) (xy 31.675862 -207.222087) (xy 31.72202 -207.195438)
			(xy 31.771634 -207.175966) (xy 31.823596 -207.164106) (xy 31.876746 -207.160123) (xy 31.929896 -207.164106)
			(xy 31.981858 -207.175966) (xy 32.031472 -207.195438) (xy 32.07763 -207.222087) (xy 32.119301 -207.255318)
			(xy 32.155553 -207.294389) (xy 32.185577 -207.338426) (xy 32.208703 -207.386447) (xy 32.224413 -207.437377)
			(xy 32.232356 -207.490081) (xy 32.232854 -207.51673) (xy 32.232356 -207.543379) (xy 46.608736 -207.543379)
			(xy 46.608736 -207.490081) (xy 46.616679 -207.437377) (xy 46.632389 -207.386447) (xy 46.655515 -207.338426)
			(xy 46.685539 -207.294389) (xy 46.721791 -207.255318) (xy 46.763462 -207.222087) (xy 46.80962 -207.195438)
			(xy 46.859234 -207.175966) (xy 46.911196 -207.164106) (xy 46.964346 -207.160123) (xy 47.017496 -207.164106)
			(xy 47.069458 -207.175966) (xy 47.119072 -207.195438) (xy 47.16523 -207.222087) (xy 47.206901 -207.255318)
			(xy 47.243153 -207.294389) (xy 47.273177 -207.338426) (xy 47.296303 -207.386447) (xy 47.312013 -207.437377)
			(xy 47.319956 -207.490081) (xy 47.320454 -207.51673) (xy 47.319956 -207.543379) (xy 47.312013 -207.596083)
			(xy 47.296303 -207.647013) (xy 47.273177 -207.695034) (xy 47.243153 -207.739071) (xy 47.206901 -207.778142)
			(xy 47.16523 -207.811373) (xy 47.119072 -207.838022) (xy 47.069458 -207.857494) (xy 47.017496 -207.869354)
			(xy 46.964346 -207.873338) (xy 46.911196 -207.869354) (xy 46.859234 -207.857494) (xy 46.80962 -207.838022)
			(xy 46.763462 -207.811373) (xy 46.721791 -207.778142) (xy 46.685539 -207.739071) (xy 46.655515 -207.695034)
			(xy 46.632389 -207.647013) (xy 46.616679 -207.596083) (xy 46.608736 -207.543379) (xy 32.232356 -207.543379)
			(xy 32.224413 -207.596083) (xy 32.208703 -207.647013) (xy 32.185577 -207.695034) (xy 32.155553 -207.739071)
			(xy 32.119301 -207.778142) (xy 32.07763 -207.811373) (xy 32.031472 -207.838022) (xy 31.981858 -207.857494)
			(xy 31.929896 -207.869354) (xy 31.876746 -207.873338) (xy 31.823596 -207.869354) (xy 31.771634 -207.857494)
			(xy 31.72202 -207.838022) (xy 31.675862 -207.811373) (xy 31.634191 -207.778142) (xy 31.597939 -207.739071)
			(xy 31.567915 -207.695034) (xy 31.544789 -207.647013) (xy 31.529079 -207.596083) (xy 31.521136 -207.543379)
			(xy 17.144756 -207.543379) (xy 17.136813 -207.596083) (xy 17.121103 -207.647013) (xy 17.097977 -207.695034)
			(xy 17.067953 -207.739071) (xy 17.031701 -207.778142) (xy 16.99003 -207.811373) (xy 16.943872 -207.838022)
			(xy 16.894258 -207.857494) (xy 16.842296 -207.869354) (xy 16.789146 -207.873338) (xy 16.735996 -207.869354)
			(xy 16.684034 -207.857494) (xy 16.63442 -207.838022) (xy 16.588262 -207.811373) (xy 16.546591 -207.778142)
			(xy 16.510339 -207.739071) (xy 16.480315 -207.695034) (xy 16.457189 -207.647013) (xy 16.441479 -207.596083)
			(xy 16.433536 -207.543379) (xy 9.6774 -207.543379) (xy 9.6774 -208.393263) (xy 20.533604 -208.393263)
			(xy 20.533604 -208.339965) (xy 20.541547 -208.287261) (xy 20.557257 -208.236331) (xy 20.580383 -208.18831)
			(xy 20.610407 -208.144273) (xy 20.646659 -208.105202) (xy 20.68833 -208.071971) (xy 20.734488 -208.045322)
			(xy 20.784102 -208.02585) (xy 20.836064 -208.01399) (xy 20.889214 -208.010007) (xy 20.942364 -208.01399)
			(xy 20.994326 -208.02585) (xy 21.04394 -208.045322) (xy 21.090098 -208.071971) (xy 21.131769 -208.105202)
			(xy 21.168021 -208.144273) (xy 21.198045 -208.18831) (xy 21.221171 -208.236331) (xy 21.236881 -208.287261)
			(xy 21.244824 -208.339965) (xy 21.245322 -208.366614) (xy 21.244824 -208.393263) (xy 35.621204 -208.393263)
			(xy 35.621204 -208.339965) (xy 35.629147 -208.287261) (xy 35.644857 -208.236331) (xy 35.667983 -208.18831)
			(xy 35.698007 -208.144273) (xy 35.734259 -208.105202) (xy 35.77593 -208.071971) (xy 35.822088 -208.045322)
			(xy 35.871702 -208.02585) (xy 35.923664 -208.01399) (xy 35.976814 -208.010007) (xy 36.029964 -208.01399)
			(xy 36.081926 -208.02585) (xy 36.13154 -208.045322) (xy 36.177698 -208.071971) (xy 36.219369 -208.105202)
			(xy 36.255621 -208.144273) (xy 36.285645 -208.18831) (xy 36.308771 -208.236331) (xy 36.324481 -208.287261)
			(xy 36.332424 -208.339965) (xy 36.332922 -208.366614) (xy 36.332424 -208.393263) (xy 50.708804 -208.393263)
			(xy 50.708804 -208.339965) (xy 50.716747 -208.287261) (xy 50.732457 -208.236331) (xy 50.755583 -208.18831)
			(xy 50.785607 -208.144273) (xy 50.821859 -208.105202) (xy 50.86353 -208.071971) (xy 50.909688 -208.045322)
			(xy 50.959302 -208.02585) (xy 51.011264 -208.01399) (xy 51.064414 -208.010007) (xy 51.117564 -208.01399)
			(xy 51.169526 -208.02585) (xy 51.21914 -208.045322) (xy 51.265298 -208.071971) (xy 51.306969 -208.105202)
			(xy 51.343221 -208.144273) (xy 51.373245 -208.18831) (xy 51.396371 -208.236331) (xy 51.412081 -208.287261)
			(xy 51.420024 -208.339965) (xy 51.420522 -208.366614) (xy 51.420024 -208.393263) (xy 51.412081 -208.445967)
			(xy 51.396371 -208.496897) (xy 51.373245 -208.544918) (xy 51.343221 -208.588955) (xy 51.306969 -208.628026)
			(xy 51.265298 -208.661257) (xy 51.21914 -208.687906) (xy 51.169526 -208.707378) (xy 51.117564 -208.719238)
			(xy 51.064414 -208.723222) (xy 51.011264 -208.719238) (xy 50.959302 -208.707378) (xy 50.909688 -208.687906)
			(xy 50.86353 -208.661257) (xy 50.821859 -208.628026) (xy 50.785607 -208.588955) (xy 50.755583 -208.544918)
			(xy 50.732457 -208.496897) (xy 50.716747 -208.445967) (xy 50.708804 -208.393263) (xy 36.332424 -208.393263)
			(xy 36.324481 -208.445967) (xy 36.308771 -208.496897) (xy 36.285645 -208.544918) (xy 36.255621 -208.588955)
			(xy 36.219369 -208.628026) (xy 36.177698 -208.661257) (xy 36.13154 -208.687906) (xy 36.081926 -208.707378)
			(xy 36.029964 -208.719238) (xy 35.976814 -208.723222) (xy 35.923664 -208.719238) (xy 35.871702 -208.707378)
			(xy 35.822088 -208.687906) (xy 35.77593 -208.661257) (xy 35.734259 -208.628026) (xy 35.698007 -208.588955)
			(xy 35.667983 -208.544918) (xy 35.644857 -208.496897) (xy 35.629147 -208.445967) (xy 35.621204 -208.393263)
			(xy 21.244824 -208.393263) (xy 21.236881 -208.445967) (xy 21.221171 -208.496897) (xy 21.198045 -208.544918)
			(xy 21.168021 -208.588955) (xy 21.131769 -208.628026) (xy 21.090098 -208.661257) (xy 21.04394 -208.687906)
			(xy 20.994326 -208.707378) (xy 20.942364 -208.719238) (xy 20.889214 -208.723222) (xy 20.836064 -208.719238)
			(xy 20.784102 -208.707378) (xy 20.734488 -208.687906) (xy 20.68833 -208.661257) (xy 20.646659 -208.628026)
			(xy 20.610407 -208.588955) (xy 20.580383 -208.544918) (xy 20.557257 -208.496897) (xy 20.541547 -208.445967)
			(xy 20.533604 -208.393263) (xy 9.6774 -208.393263) (xy 9.6774 -209.243401) (xy 16.433536 -209.243401)
			(xy 16.433536 -209.190103) (xy 16.441479 -209.137399) (xy 16.457189 -209.086469) (xy 16.480315 -209.038448)
			(xy 16.510339 -208.994411) (xy 16.546591 -208.95534) (xy 16.588262 -208.922109) (xy 16.63442 -208.89546)
			(xy 16.684034 -208.875988) (xy 16.735996 -208.864128) (xy 16.789146 -208.860145) (xy 16.842296 -208.864128)
			(xy 16.894258 -208.875988) (xy 16.943872 -208.89546) (xy 16.99003 -208.922109) (xy 17.031701 -208.95534)
			(xy 17.067953 -208.994411) (xy 17.097977 -209.038448) (xy 17.121103 -209.086469) (xy 17.136813 -209.137399)
			(xy 17.144756 -209.190103) (xy 17.145254 -209.216752) (xy 17.144756 -209.243401) (xy 20.533604 -209.243401)
			(xy 20.533604 -209.190103) (xy 20.541547 -209.137399) (xy 20.557257 -209.086469) (xy 20.580383 -209.038448)
			(xy 20.610407 -208.994411) (xy 20.646659 -208.95534) (xy 20.68833 -208.922109) (xy 20.734488 -208.89546)
			(xy 20.784102 -208.875988) (xy 20.836064 -208.864128) (xy 20.889214 -208.860145) (xy 20.942364 -208.864128)
			(xy 20.994326 -208.875988) (xy 21.04394 -208.89546) (xy 21.090098 -208.922109) (xy 21.131769 -208.95534)
			(xy 21.168021 -208.994411) (xy 21.198045 -209.038448) (xy 21.221171 -209.086469) (xy 21.236881 -209.137399)
			(xy 21.244824 -209.190103) (xy 21.245322 -209.216752) (xy 21.244824 -209.243401) (xy 31.521136 -209.243401)
			(xy 31.521136 -209.190103) (xy 31.529079 -209.137399) (xy 31.544789 -209.086469) (xy 31.567915 -209.038448)
			(xy 31.597939 -208.994411) (xy 31.634191 -208.95534) (xy 31.675862 -208.922109) (xy 31.72202 -208.89546)
			(xy 31.771634 -208.875988) (xy 31.823596 -208.864128) (xy 31.876746 -208.860145) (xy 31.929896 -208.864128)
			(xy 31.981858 -208.875988) (xy 32.031472 -208.89546) (xy 32.07763 -208.922109) (xy 32.119301 -208.95534)
			(xy 32.155553 -208.994411) (xy 32.185577 -209.038448) (xy 32.208703 -209.086469) (xy 32.224413 -209.137399)
			(xy 32.232356 -209.190103) (xy 32.232854 -209.216752) (xy 32.232356 -209.243401) (xy 35.621204 -209.243401)
			(xy 35.621204 -209.190103) (xy 35.629147 -209.137399) (xy 35.644857 -209.086469) (xy 35.667983 -209.038448)
			(xy 35.698007 -208.994411) (xy 35.734259 -208.95534) (xy 35.77593 -208.922109) (xy 35.822088 -208.89546)
			(xy 35.871702 -208.875988) (xy 35.923664 -208.864128) (xy 35.976814 -208.860145) (xy 36.029964 -208.864128)
			(xy 36.081926 -208.875988) (xy 36.13154 -208.89546) (xy 36.177698 -208.922109) (xy 36.219369 -208.95534)
			(xy 36.255621 -208.994411) (xy 36.285645 -209.038448) (xy 36.308771 -209.086469) (xy 36.324481 -209.137399)
			(xy 36.332424 -209.190103) (xy 36.332922 -209.216752) (xy 36.332424 -209.243401) (xy 46.608736 -209.243401)
			(xy 46.608736 -209.190103) (xy 46.616679 -209.137399) (xy 46.632389 -209.086469) (xy 46.655515 -209.038448)
			(xy 46.685539 -208.994411) (xy 46.721791 -208.95534) (xy 46.763462 -208.922109) (xy 46.80962 -208.89546)
			(xy 46.859234 -208.875988) (xy 46.911196 -208.864128) (xy 46.964346 -208.860145) (xy 47.017496 -208.864128)
			(xy 47.069458 -208.875988) (xy 47.119072 -208.89546) (xy 47.16523 -208.922109) (xy 47.206901 -208.95534)
			(xy 47.243153 -208.994411) (xy 47.273177 -209.038448) (xy 47.296303 -209.086469) (xy 47.312013 -209.137399)
			(xy 47.319956 -209.190103) (xy 47.320454 -209.216752) (xy 47.319956 -209.243401) (xy 50.708804 -209.243401)
			(xy 50.708804 -209.190103) (xy 50.716747 -209.137399) (xy 50.732457 -209.086469) (xy 50.755583 -209.038448)
			(xy 50.785607 -208.994411) (xy 50.821859 -208.95534) (xy 50.86353 -208.922109) (xy 50.909688 -208.89546)
			(xy 50.959302 -208.875988) (xy 51.011264 -208.864128) (xy 51.064414 -208.860145) (xy 51.117564 -208.864128)
			(xy 51.169526 -208.875988) (xy 51.21914 -208.89546) (xy 51.265298 -208.922109) (xy 51.306969 -208.95534)
			(xy 51.343221 -208.994411) (xy 51.373245 -209.038448) (xy 51.396371 -209.086469) (xy 51.412081 -209.137399)
			(xy 51.420024 -209.190103) (xy 51.420522 -209.216752) (xy 51.420024 -209.243401) (xy 51.412081 -209.296105)
			(xy 51.396371 -209.347035) (xy 51.373245 -209.395056) (xy 51.343221 -209.439093) (xy 51.306969 -209.478164)
			(xy 51.265298 -209.511395) (xy 51.21914 -209.538044) (xy 51.169526 -209.557516) (xy 51.117564 -209.569376)
			(xy 51.064414 -209.57336) (xy 51.011264 -209.569376) (xy 50.959302 -209.557516) (xy 50.909688 -209.538044)
			(xy 50.86353 -209.511395) (xy 50.821859 -209.478164) (xy 50.785607 -209.439093) (xy 50.755583 -209.395056)
			(xy 50.732457 -209.347035) (xy 50.716747 -209.296105) (xy 50.708804 -209.243401) (xy 47.319956 -209.243401)
			(xy 47.312013 -209.296105) (xy 47.296303 -209.347035) (xy 47.273177 -209.395056) (xy 47.243153 -209.439093)
			(xy 47.206901 -209.478164) (xy 47.16523 -209.511395) (xy 47.119072 -209.538044) (xy 47.069458 -209.557516)
			(xy 47.017496 -209.569376) (xy 46.964346 -209.57336) (xy 46.911196 -209.569376) (xy 46.859234 -209.557516)
			(xy 46.80962 -209.538044) (xy 46.763462 -209.511395) (xy 46.721791 -209.478164) (xy 46.685539 -209.439093)
			(xy 46.655515 -209.395056) (xy 46.632389 -209.347035) (xy 46.616679 -209.296105) (xy 46.608736 -209.243401)
			(xy 36.332424 -209.243401) (xy 36.324481 -209.296105) (xy 36.308771 -209.347035) (xy 36.285645 -209.395056)
			(xy 36.255621 -209.439093) (xy 36.219369 -209.478164) (xy 36.177698 -209.511395) (xy 36.13154 -209.538044)
			(xy 36.081926 -209.557516) (xy 36.029964 -209.569376) (xy 35.976814 -209.57336) (xy 35.923664 -209.569376)
			(xy 35.871702 -209.557516) (xy 35.822088 -209.538044) (xy 35.77593 -209.511395) (xy 35.734259 -209.478164)
			(xy 35.698007 -209.439093) (xy 35.667983 -209.395056) (xy 35.644857 -209.347035) (xy 35.629147 -209.296105)
			(xy 35.621204 -209.243401) (xy 32.232356 -209.243401) (xy 32.224413 -209.296105) (xy 32.208703 -209.347035)
			(xy 32.185577 -209.395056) (xy 32.155553 -209.439093) (xy 32.119301 -209.478164) (xy 32.07763 -209.511395)
			(xy 32.031472 -209.538044) (xy 31.981858 -209.557516) (xy 31.929896 -209.569376) (xy 31.876746 -209.57336)
			(xy 31.823596 -209.569376) (xy 31.771634 -209.557516) (xy 31.72202 -209.538044) (xy 31.675862 -209.511395)
			(xy 31.634191 -209.478164) (xy 31.597939 -209.439093) (xy 31.567915 -209.395056) (xy 31.544789 -209.347035)
			(xy 31.529079 -209.296105) (xy 31.521136 -209.243401) (xy 21.244824 -209.243401) (xy 21.236881 -209.296105)
			(xy 21.221171 -209.347035) (xy 21.198045 -209.395056) (xy 21.168021 -209.439093) (xy 21.131769 -209.478164)
			(xy 21.090098 -209.511395) (xy 21.04394 -209.538044) (xy 20.994326 -209.557516) (xy 20.942364 -209.569376)
			(xy 20.889214 -209.57336) (xy 20.836064 -209.569376) (xy 20.784102 -209.557516) (xy 20.734488 -209.538044)
			(xy 20.68833 -209.511395) (xy 20.646659 -209.478164) (xy 20.610407 -209.439093) (xy 20.580383 -209.395056)
			(xy 20.557257 -209.347035) (xy 20.541547 -209.296105) (xy 20.533604 -209.243401) (xy 17.144756 -209.243401)
			(xy 17.136813 -209.296105) (xy 17.121103 -209.347035) (xy 17.097977 -209.395056) (xy 17.067953 -209.439093)
			(xy 17.031701 -209.478164) (xy 16.99003 -209.511395) (xy 16.943872 -209.538044) (xy 16.894258 -209.557516)
			(xy 16.842296 -209.569376) (xy 16.789146 -209.57336) (xy 16.735996 -209.569376) (xy 16.684034 -209.557516)
			(xy 16.63442 -209.538044) (xy 16.588262 -209.511395) (xy 16.546591 -209.478164) (xy 16.510339 -209.439093)
			(xy 16.480315 -209.395056) (xy 16.457189 -209.347035) (xy 16.441479 -209.296105) (xy 16.433536 -209.243401)
			(xy 9.6774 -209.243401) (xy 9.6774 -210.093285) (xy 16.433536 -210.093285) (xy 16.433536 -210.039987)
			(xy 16.441479 -209.987283) (xy 16.457189 -209.936353) (xy 16.480315 -209.888332) (xy 16.510339 -209.844295)
			(xy 16.546591 -209.805224) (xy 16.588262 -209.771993) (xy 16.63442 -209.745344) (xy 16.684034 -209.725872)
			(xy 16.735996 -209.714012) (xy 16.789146 -209.710029) (xy 16.842296 -209.714012) (xy 16.894258 -209.725872)
			(xy 16.943872 -209.745344) (xy 16.99003 -209.771993) (xy 17.031701 -209.805224) (xy 17.067953 -209.844295)
			(xy 17.097977 -209.888332) (xy 17.121103 -209.936353) (xy 17.136813 -209.987283) (xy 17.144756 -210.039987)
			(xy 17.145254 -210.066636) (xy 17.144756 -210.093285) (xy 31.521136 -210.093285) (xy 31.521136 -210.039987)
			(xy 31.529079 -209.987283) (xy 31.544789 -209.936353) (xy 31.567915 -209.888332) (xy 31.597939 -209.844295)
			(xy 31.634191 -209.805224) (xy 31.675862 -209.771993) (xy 31.72202 -209.745344) (xy 31.771634 -209.725872)
			(xy 31.823596 -209.714012) (xy 31.876746 -209.710029) (xy 31.929896 -209.714012) (xy 31.981858 -209.725872)
			(xy 32.031472 -209.745344) (xy 32.07763 -209.771993) (xy 32.119301 -209.805224) (xy 32.155553 -209.844295)
			(xy 32.185577 -209.888332) (xy 32.208703 -209.936353) (xy 32.224413 -209.987283) (xy 32.232356 -210.039987)
			(xy 32.232854 -210.066636) (xy 32.232356 -210.093285) (xy 46.608736 -210.093285) (xy 46.608736 -210.039987)
			(xy 46.616679 -209.987283) (xy 46.632389 -209.936353) (xy 46.655515 -209.888332) (xy 46.685539 -209.844295)
			(xy 46.721791 -209.805224) (xy 46.763462 -209.771993) (xy 46.80962 -209.745344) (xy 46.859234 -209.725872)
			(xy 46.911196 -209.714012) (xy 46.964346 -209.710029) (xy 47.017496 -209.714012) (xy 47.069458 -209.725872)
			(xy 47.119072 -209.745344) (xy 47.16523 -209.771993) (xy 47.206901 -209.805224) (xy 47.243153 -209.844295)
			(xy 47.273177 -209.888332) (xy 47.296303 -209.936353) (xy 47.312013 -209.987283) (xy 47.319956 -210.039987)
			(xy 47.320454 -210.066636) (xy 47.319956 -210.093285) (xy 47.312013 -210.145989) (xy 47.296303 -210.196919)
			(xy 47.273177 -210.24494) (xy 47.243153 -210.288977) (xy 47.206901 -210.328048) (xy 47.16523 -210.361279)
			(xy 47.119072 -210.387928) (xy 47.069458 -210.4074) (xy 47.017496 -210.41926) (xy 46.964346 -210.423244)
			(xy 46.911196 -210.41926) (xy 46.859234 -210.4074) (xy 46.80962 -210.387928) (xy 46.763462 -210.361279)
			(xy 46.721791 -210.328048) (xy 46.685539 -210.288977) (xy 46.655515 -210.24494) (xy 46.632389 -210.196919)
			(xy 46.616679 -210.145989) (xy 46.608736 -210.093285) (xy 32.232356 -210.093285) (xy 32.224413 -210.145989)
			(xy 32.208703 -210.196919) (xy 32.185577 -210.24494) (xy 32.155553 -210.288977) (xy 32.119301 -210.328048)
			(xy 32.07763 -210.361279) (xy 32.031472 -210.387928) (xy 31.981858 -210.4074) (xy 31.929896 -210.41926)
			(xy 31.876746 -210.423244) (xy 31.823596 -210.41926) (xy 31.771634 -210.4074) (xy 31.72202 -210.387928)
			(xy 31.675862 -210.361279) (xy 31.634191 -210.328048) (xy 31.597939 -210.288977) (xy 31.567915 -210.24494)
			(xy 31.544789 -210.196919) (xy 31.529079 -210.145989) (xy 31.521136 -210.093285) (xy 17.144756 -210.093285)
			(xy 17.136813 -210.145989) (xy 17.121103 -210.196919) (xy 17.097977 -210.24494) (xy 17.067953 -210.288977)
			(xy 17.031701 -210.328048) (xy 16.99003 -210.361279) (xy 16.943872 -210.387928) (xy 16.894258 -210.4074)
			(xy 16.842296 -210.41926) (xy 16.789146 -210.423244) (xy 16.735996 -210.41926) (xy 16.684034 -210.4074)
			(xy 16.63442 -210.387928) (xy 16.588262 -210.361279) (xy 16.546591 -210.328048) (xy 16.510339 -210.288977)
			(xy 16.480315 -210.24494) (xy 16.457189 -210.196919) (xy 16.441479 -210.145989) (xy 16.433536 -210.093285)
			(xy 9.6774 -210.093285) (xy 9.6774 -210.943423) (xy 20.533604 -210.943423) (xy 20.533604 -210.890125)
			(xy 20.541547 -210.837421) (xy 20.557257 -210.786491) (xy 20.580383 -210.73847) (xy 20.610407 -210.694433)
			(xy 20.646659 -210.655362) (xy 20.68833 -210.622131) (xy 20.734488 -210.595482) (xy 20.784102 -210.57601)
			(xy 20.836064 -210.56415) (xy 20.889214 -210.560167) (xy 20.942364 -210.56415) (xy 20.994326 -210.57601)
			(xy 21.04394 -210.595482) (xy 21.090098 -210.622131) (xy 21.131769 -210.655362) (xy 21.168021 -210.694433)
			(xy 21.198045 -210.73847) (xy 21.221171 -210.786491) (xy 21.236881 -210.837421) (xy 21.244824 -210.890125)
			(xy 21.245322 -210.916774) (xy 21.244824 -210.943423) (xy 35.621204 -210.943423) (xy 35.621204 -210.890125)
			(xy 35.629147 -210.837421) (xy 35.644857 -210.786491) (xy 35.667983 -210.73847) (xy 35.698007 -210.694433)
			(xy 35.734259 -210.655362) (xy 35.77593 -210.622131) (xy 35.822088 -210.595482) (xy 35.871702 -210.57601)
			(xy 35.923664 -210.56415) (xy 35.976814 -210.560167) (xy 36.029964 -210.56415) (xy 36.081926 -210.57601)
			(xy 36.13154 -210.595482) (xy 36.177698 -210.622131) (xy 36.219369 -210.655362) (xy 36.255621 -210.694433)
			(xy 36.285645 -210.73847) (xy 36.308771 -210.786491) (xy 36.324481 -210.837421) (xy 36.332424 -210.890125)
			(xy 36.332922 -210.916774) (xy 36.332424 -210.943423) (xy 50.708804 -210.943423) (xy 50.708804 -210.890125)
			(xy 50.716747 -210.837421) (xy 50.732457 -210.786491) (xy 50.755583 -210.73847) (xy 50.785607 -210.694433)
			(xy 50.821859 -210.655362) (xy 50.86353 -210.622131) (xy 50.909688 -210.595482) (xy 50.959302 -210.57601)
			(xy 51.011264 -210.56415) (xy 51.064414 -210.560167) (xy 51.117564 -210.56415) (xy 51.169526 -210.57601)
			(xy 51.21914 -210.595482) (xy 51.265298 -210.622131) (xy 51.306969 -210.655362) (xy 51.343221 -210.694433)
			(xy 51.373245 -210.73847) (xy 51.396371 -210.786491) (xy 51.412081 -210.837421) (xy 51.420024 -210.890125)
			(xy 51.420522 -210.916774) (xy 51.420024 -210.943423) (xy 51.412081 -210.996127) (xy 51.396371 -211.047057)
			(xy 51.373245 -211.095078) (xy 51.343221 -211.139115) (xy 51.306969 -211.178186) (xy 51.265298 -211.211417)
			(xy 51.21914 -211.238066) (xy 51.169526 -211.257538) (xy 51.117564 -211.269398) (xy 51.064414 -211.273382)
			(xy 51.011264 -211.269398) (xy 50.959302 -211.257538) (xy 50.909688 -211.238066) (xy 50.86353 -211.211417)
			(xy 50.821859 -211.178186) (xy 50.785607 -211.139115) (xy 50.755583 -211.095078) (xy 50.732457 -211.047057)
			(xy 50.716747 -210.996127) (xy 50.708804 -210.943423) (xy 36.332424 -210.943423) (xy 36.324481 -210.996127)
			(xy 36.308771 -211.047057) (xy 36.285645 -211.095078) (xy 36.255621 -211.139115) (xy 36.219369 -211.178186)
			(xy 36.177698 -211.211417) (xy 36.13154 -211.238066) (xy 36.081926 -211.257538) (xy 36.029964 -211.269398)
			(xy 35.976814 -211.273382) (xy 35.923664 -211.269398) (xy 35.871702 -211.257538) (xy 35.822088 -211.238066)
			(xy 35.77593 -211.211417) (xy 35.734259 -211.178186) (xy 35.698007 -211.139115) (xy 35.667983 -211.095078)
			(xy 35.644857 -211.047057) (xy 35.629147 -210.996127) (xy 35.621204 -210.943423) (xy 21.244824 -210.943423)
			(xy 21.236881 -210.996127) (xy 21.221171 -211.047057) (xy 21.198045 -211.095078) (xy 21.168021 -211.139115)
			(xy 21.131769 -211.178186) (xy 21.090098 -211.211417) (xy 21.04394 -211.238066) (xy 20.994326 -211.257538)
			(xy 20.942364 -211.269398) (xy 20.889214 -211.273382) (xy 20.836064 -211.269398) (xy 20.784102 -211.257538)
			(xy 20.734488 -211.238066) (xy 20.68833 -211.211417) (xy 20.646659 -211.178186) (xy 20.610407 -211.139115)
			(xy 20.580383 -211.095078) (xy 20.557257 -211.047057) (xy 20.541547 -210.996127) (xy 20.533604 -210.943423)
			(xy 9.6774 -210.943423) (xy 9.6774 -211.793307) (xy 16.433536 -211.793307) (xy 16.433536 -211.740009)
			(xy 16.441479 -211.687305) (xy 16.457189 -211.636375) (xy 16.480315 -211.588354) (xy 16.510339 -211.544317)
			(xy 16.546591 -211.505246) (xy 16.588262 -211.472015) (xy 16.63442 -211.445366) (xy 16.684034 -211.425894)
			(xy 16.735996 -211.414034) (xy 16.789146 -211.410051) (xy 16.842296 -211.414034) (xy 16.894258 -211.425894)
			(xy 16.943872 -211.445366) (xy 16.99003 -211.472015) (xy 17.031701 -211.505246) (xy 17.067953 -211.544317)
			(xy 17.097977 -211.588354) (xy 17.121103 -211.636375) (xy 17.136813 -211.687305) (xy 17.144756 -211.740009)
			(xy 17.145254 -211.766658) (xy 17.144756 -211.793307) (xy 31.521136 -211.793307) (xy 31.521136 -211.740009)
			(xy 31.529079 -211.687305) (xy 31.544789 -211.636375) (xy 31.567915 -211.588354) (xy 31.597939 -211.544317)
			(xy 31.634191 -211.505246) (xy 31.675862 -211.472015) (xy 31.72202 -211.445366) (xy 31.771634 -211.425894)
			(xy 31.823596 -211.414034) (xy 31.876746 -211.410051) (xy 31.929896 -211.414034) (xy 31.981858 -211.425894)
			(xy 32.031472 -211.445366) (xy 32.07763 -211.472015) (xy 32.119301 -211.505246) (xy 32.155553 -211.544317)
			(xy 32.185577 -211.588354) (xy 32.208703 -211.636375) (xy 32.224413 -211.687305) (xy 32.232356 -211.740009)
			(xy 32.232854 -211.766658) (xy 32.232356 -211.793307) (xy 46.608736 -211.793307) (xy 46.608736 -211.740009)
			(xy 46.616679 -211.687305) (xy 46.632389 -211.636375) (xy 46.655515 -211.588354) (xy 46.685539 -211.544317)
			(xy 46.721791 -211.505246) (xy 46.763462 -211.472015) (xy 46.80962 -211.445366) (xy 46.859234 -211.425894)
			(xy 46.911196 -211.414034) (xy 46.964346 -211.410051) (xy 47.017496 -211.414034) (xy 47.069458 -211.425894)
			(xy 47.119072 -211.445366) (xy 47.16523 -211.472015) (xy 47.206901 -211.505246) (xy 47.243153 -211.544317)
			(xy 47.273177 -211.588354) (xy 47.296303 -211.636375) (xy 47.312013 -211.687305) (xy 47.319956 -211.740009)
			(xy 47.320454 -211.766658) (xy 47.319956 -211.793307) (xy 47.312013 -211.846011) (xy 47.296303 -211.896941)
			(xy 47.273177 -211.944962) (xy 47.243153 -211.988999) (xy 47.206901 -212.02807) (xy 47.16523 -212.061301)
			(xy 47.119072 -212.08795) (xy 47.069458 -212.107422) (xy 47.017496 -212.119282) (xy 46.964346 -212.123266)
			(xy 46.911196 -212.119282) (xy 46.859234 -212.107422) (xy 46.80962 -212.08795) (xy 46.763462 -212.061301)
			(xy 46.721791 -212.02807) (xy 46.685539 -211.988999) (xy 46.655515 -211.944962) (xy 46.632389 -211.896941)
			(xy 46.616679 -211.846011) (xy 46.608736 -211.793307) (xy 32.232356 -211.793307) (xy 32.224413 -211.846011)
			(xy 32.208703 -211.896941) (xy 32.185577 -211.944962) (xy 32.155553 -211.988999) (xy 32.119301 -212.02807)
			(xy 32.07763 -212.061301) (xy 32.031472 -212.08795) (xy 31.981858 -212.107422) (xy 31.929896 -212.119282)
			(xy 31.876746 -212.123266) (xy 31.823596 -212.119282) (xy 31.771634 -212.107422) (xy 31.72202 -212.08795)
			(xy 31.675862 -212.061301) (xy 31.634191 -212.02807) (xy 31.597939 -211.988999) (xy 31.567915 -211.944962)
			(xy 31.544789 -211.896941) (xy 31.529079 -211.846011) (xy 31.521136 -211.793307) (xy 17.144756 -211.793307)
			(xy 17.136813 -211.846011) (xy 17.121103 -211.896941) (xy 17.097977 -211.944962) (xy 17.067953 -211.988999)
			(xy 17.031701 -212.02807) (xy 16.99003 -212.061301) (xy 16.943872 -212.08795) (xy 16.894258 -212.107422)
			(xy 16.842296 -212.119282) (xy 16.789146 -212.123266) (xy 16.735996 -212.119282) (xy 16.684034 -212.107422)
			(xy 16.63442 -212.08795) (xy 16.588262 -212.061301) (xy 16.546591 -212.02807) (xy 16.510339 -211.988999)
			(xy 16.480315 -211.944962) (xy 16.457189 -211.896941) (xy 16.441479 -211.846011) (xy 16.433536 -211.793307)
			(xy 9.6774 -211.793307) (xy 9.6774 -212.643445) (xy 20.533604 -212.643445) (xy 20.533604 -212.590147)
			(xy 20.541547 -212.537443) (xy 20.557257 -212.486513) (xy 20.580383 -212.438492) (xy 20.610407 -212.394455)
			(xy 20.646659 -212.355384) (xy 20.68833 -212.322153) (xy 20.734488 -212.295504) (xy 20.784102 -212.276032)
			(xy 20.836064 -212.264172) (xy 20.889214 -212.260189) (xy 20.942364 -212.264172) (xy 20.994326 -212.276032)
			(xy 21.04394 -212.295504) (xy 21.090098 -212.322153) (xy 21.131769 -212.355384) (xy 21.168021 -212.394455)
			(xy 21.198045 -212.438492) (xy 21.221171 -212.486513) (xy 21.236881 -212.537443) (xy 21.244824 -212.590147)
			(xy 21.245322 -212.616796) (xy 21.244824 -212.643445) (xy 35.621204 -212.643445) (xy 35.621204 -212.590147)
			(xy 35.629147 -212.537443) (xy 35.644857 -212.486513) (xy 35.667983 -212.438492) (xy 35.698007 -212.394455)
			(xy 35.734259 -212.355384) (xy 35.77593 -212.322153) (xy 35.822088 -212.295504) (xy 35.871702 -212.276032)
			(xy 35.923664 -212.264172) (xy 35.976814 -212.260189) (xy 36.029964 -212.264172) (xy 36.081926 -212.276032)
			(xy 36.13154 -212.295504) (xy 36.177698 -212.322153) (xy 36.219369 -212.355384) (xy 36.255621 -212.394455)
			(xy 36.285645 -212.438492) (xy 36.308771 -212.486513) (xy 36.324481 -212.537443) (xy 36.332424 -212.590147)
			(xy 36.332922 -212.616796) (xy 36.332424 -212.643445) (xy 50.708804 -212.643445) (xy 50.708804 -212.590147)
			(xy 50.716747 -212.537443) (xy 50.732457 -212.486513) (xy 50.755583 -212.438492) (xy 50.785607 -212.394455)
			(xy 50.821859 -212.355384) (xy 50.86353 -212.322153) (xy 50.909688 -212.295504) (xy 50.959302 -212.276032)
			(xy 51.011264 -212.264172) (xy 51.064414 -212.260189) (xy 51.117564 -212.264172) (xy 51.169526 -212.276032)
			(xy 51.21914 -212.295504) (xy 51.265298 -212.322153) (xy 51.306969 -212.355384) (xy 51.343221 -212.394455)
			(xy 51.373245 -212.438492) (xy 51.396371 -212.486513) (xy 51.412081 -212.537443) (xy 51.420024 -212.590147)
			(xy 51.420522 -212.616796) (xy 51.420024 -212.643445) (xy 51.412081 -212.696149) (xy 51.396371 -212.747079)
			(xy 51.373245 -212.7951) (xy 51.343221 -212.839137) (xy 51.306969 -212.878208) (xy 51.265298 -212.911439)
			(xy 51.21914 -212.938088) (xy 51.169526 -212.95756) (xy 51.117564 -212.96942) (xy 51.064414 -212.973404)
			(xy 51.011264 -212.96942) (xy 50.959302 -212.95756) (xy 50.909688 -212.938088) (xy 50.86353 -212.911439)
			(xy 50.821859 -212.878208) (xy 50.785607 -212.839137) (xy 50.755583 -212.7951) (xy 50.732457 -212.747079)
			(xy 50.716747 -212.696149) (xy 50.708804 -212.643445) (xy 36.332424 -212.643445) (xy 36.324481 -212.696149)
			(xy 36.308771 -212.747079) (xy 36.285645 -212.7951) (xy 36.255621 -212.839137) (xy 36.219369 -212.878208)
			(xy 36.177698 -212.911439) (xy 36.13154 -212.938088) (xy 36.081926 -212.95756) (xy 36.029964 -212.96942)
			(xy 35.976814 -212.973404) (xy 35.923664 -212.96942) (xy 35.871702 -212.95756) (xy 35.822088 -212.938088)
			(xy 35.77593 -212.911439) (xy 35.734259 -212.878208) (xy 35.698007 -212.839137) (xy 35.667983 -212.7951)
			(xy 35.644857 -212.747079) (xy 35.629147 -212.696149) (xy 35.621204 -212.643445) (xy 21.244824 -212.643445)
			(xy 21.236881 -212.696149) (xy 21.221171 -212.747079) (xy 21.198045 -212.7951) (xy 21.168021 -212.839137)
			(xy 21.131769 -212.878208) (xy 21.090098 -212.911439) (xy 21.04394 -212.938088) (xy 20.994326 -212.95756)
			(xy 20.942364 -212.96942) (xy 20.889214 -212.973404) (xy 20.836064 -212.96942) (xy 20.784102 -212.95756)
			(xy 20.734488 -212.938088) (xy 20.68833 -212.911439) (xy 20.646659 -212.878208) (xy 20.610407 -212.839137)
			(xy 20.580383 -212.7951) (xy 20.557257 -212.747079) (xy 20.541547 -212.696149) (xy 20.533604 -212.643445)
			(xy 9.6774 -212.643445) (xy 9.6774 -213.493329) (xy 16.433536 -213.493329) (xy 16.433536 -213.440031)
			(xy 16.441479 -213.387327) (xy 16.457189 -213.336397) (xy 16.480315 -213.288376) (xy 16.510339 -213.244339)
			(xy 16.546591 -213.205268) (xy 16.588262 -213.172037) (xy 16.63442 -213.145388) (xy 16.684034 -213.125916)
			(xy 16.735996 -213.114056) (xy 16.789146 -213.110073) (xy 16.842296 -213.114056) (xy 16.894258 -213.125916)
			(xy 16.943872 -213.145388) (xy 16.99003 -213.172037) (xy 17.031701 -213.205268) (xy 17.067953 -213.244339)
			(xy 17.097977 -213.288376) (xy 17.121103 -213.336397) (xy 17.136813 -213.387327) (xy 17.144756 -213.440031)
			(xy 17.145254 -213.46668) (xy 17.144756 -213.493329) (xy 31.521136 -213.493329) (xy 31.521136 -213.440031)
			(xy 31.529079 -213.387327) (xy 31.544789 -213.336397) (xy 31.567915 -213.288376) (xy 31.597939 -213.244339)
			(xy 31.634191 -213.205268) (xy 31.675862 -213.172037) (xy 31.72202 -213.145388) (xy 31.771634 -213.125916)
			(xy 31.823596 -213.114056) (xy 31.876746 -213.110073) (xy 31.929896 -213.114056) (xy 31.981858 -213.125916)
			(xy 32.031472 -213.145388) (xy 32.07763 -213.172037) (xy 32.119301 -213.205268) (xy 32.155553 -213.244339)
			(xy 32.185577 -213.288376) (xy 32.208703 -213.336397) (xy 32.224413 -213.387327) (xy 32.232356 -213.440031)
			(xy 32.232854 -213.46668) (xy 32.232356 -213.493329) (xy 46.608736 -213.493329) (xy 46.608736 -213.440031)
			(xy 46.616679 -213.387327) (xy 46.632389 -213.336397) (xy 46.655515 -213.288376) (xy 46.685539 -213.244339)
			(xy 46.721791 -213.205268) (xy 46.763462 -213.172037) (xy 46.80962 -213.145388) (xy 46.859234 -213.125916)
			(xy 46.911196 -213.114056) (xy 46.964346 -213.110073) (xy 47.017496 -213.114056) (xy 47.069458 -213.125916)
			(xy 47.119072 -213.145388) (xy 47.16523 -213.172037) (xy 47.206901 -213.205268) (xy 47.243153 -213.244339)
			(xy 47.273177 -213.288376) (xy 47.296303 -213.336397) (xy 47.312013 -213.387327) (xy 47.319956 -213.440031)
			(xy 47.320454 -213.46668) (xy 47.319956 -213.493329) (xy 47.312013 -213.546033) (xy 47.296303 -213.596963)
			(xy 47.273177 -213.644984) (xy 47.243153 -213.689021) (xy 47.206901 -213.728092) (xy 47.16523 -213.761323)
			(xy 47.119072 -213.787972) (xy 47.069458 -213.807444) (xy 47.017496 -213.819304) (xy 46.964346 -213.823288)
			(xy 46.911196 -213.819304) (xy 46.859234 -213.807444) (xy 46.80962 -213.787972) (xy 46.763462 -213.761323)
			(xy 46.721791 -213.728092) (xy 46.685539 -213.689021) (xy 46.655515 -213.644984) (xy 46.632389 -213.596963)
			(xy 46.616679 -213.546033) (xy 46.608736 -213.493329) (xy 32.232356 -213.493329) (xy 32.224413 -213.546033)
			(xy 32.208703 -213.596963) (xy 32.185577 -213.644984) (xy 32.155553 -213.689021) (xy 32.119301 -213.728092)
			(xy 32.07763 -213.761323) (xy 32.031472 -213.787972) (xy 31.981858 -213.807444) (xy 31.929896 -213.819304)
			(xy 31.876746 -213.823288) (xy 31.823596 -213.819304) (xy 31.771634 -213.807444) (xy 31.72202 -213.787972)
			(xy 31.675862 -213.761323) (xy 31.634191 -213.728092) (xy 31.597939 -213.689021) (xy 31.567915 -213.644984)
			(xy 31.544789 -213.596963) (xy 31.529079 -213.546033) (xy 31.521136 -213.493329) (xy 17.144756 -213.493329)
			(xy 17.136813 -213.546033) (xy 17.121103 -213.596963) (xy 17.097977 -213.644984) (xy 17.067953 -213.689021)
			(xy 17.031701 -213.728092) (xy 16.99003 -213.761323) (xy 16.943872 -213.787972) (xy 16.894258 -213.807444)
			(xy 16.842296 -213.819304) (xy 16.789146 -213.823288) (xy 16.735996 -213.819304) (xy 16.684034 -213.807444)
			(xy 16.63442 -213.787972) (xy 16.588262 -213.761323) (xy 16.546591 -213.728092) (xy 16.510339 -213.689021)
			(xy 16.480315 -213.644984) (xy 16.457189 -213.596963) (xy 16.441479 -213.546033) (xy 16.433536 -213.493329)
			(xy 9.6774 -213.493329) (xy 9.6774 -214.343213) (xy 20.533604 -214.343213) (xy 20.533604 -214.289915)
			(xy 20.541547 -214.237211) (xy 20.557257 -214.186281) (xy 20.580383 -214.13826) (xy 20.610407 -214.094223)
			(xy 20.646659 -214.055152) (xy 20.68833 -214.021921) (xy 20.734488 -213.995272) (xy 20.784102 -213.9758)
			(xy 20.836064 -213.96394) (xy 20.889214 -213.959957) (xy 20.942364 -213.96394) (xy 20.994326 -213.9758)
			(xy 21.04394 -213.995272) (xy 21.090098 -214.021921) (xy 21.131769 -214.055152) (xy 21.168021 -214.094223)
			(xy 21.198045 -214.13826) (xy 21.221171 -214.186281) (xy 21.236881 -214.237211) (xy 21.244824 -214.289915)
			(xy 21.245322 -214.316564) (xy 21.244824 -214.343213) (xy 35.621204 -214.343213) (xy 35.621204 -214.289915)
			(xy 35.629147 -214.237211) (xy 35.644857 -214.186281) (xy 35.667983 -214.13826) (xy 35.698007 -214.094223)
			(xy 35.734259 -214.055152) (xy 35.77593 -214.021921) (xy 35.822088 -213.995272) (xy 35.871702 -213.9758)
			(xy 35.923664 -213.96394) (xy 35.976814 -213.959957) (xy 36.029964 -213.96394) (xy 36.081926 -213.9758)
			(xy 36.13154 -213.995272) (xy 36.177698 -214.021921) (xy 36.219369 -214.055152) (xy 36.255621 -214.094223)
			(xy 36.285645 -214.13826) (xy 36.308771 -214.186281) (xy 36.324481 -214.237211) (xy 36.332424 -214.289915)
			(xy 36.332922 -214.316564) (xy 36.332424 -214.343213) (xy 50.708804 -214.343213) (xy 50.708804 -214.289915)
			(xy 50.716747 -214.237211) (xy 50.732457 -214.186281) (xy 50.755583 -214.13826) (xy 50.785607 -214.094223)
			(xy 50.821859 -214.055152) (xy 50.86353 -214.021921) (xy 50.909688 -213.995272) (xy 50.959302 -213.9758)
			(xy 51.011264 -213.96394) (xy 51.064414 -213.959957) (xy 51.117564 -213.96394) (xy 51.169526 -213.9758)
			(xy 51.21914 -213.995272) (xy 51.265298 -214.021921) (xy 51.306969 -214.055152) (xy 51.343221 -214.094223)
			(xy 51.373245 -214.13826) (xy 51.396371 -214.186281) (xy 51.412081 -214.237211) (xy 51.420024 -214.289915)
			(xy 51.420522 -214.316564) (xy 51.420024 -214.343213) (xy 51.412081 -214.395917) (xy 51.396371 -214.446847)
			(xy 51.373245 -214.494868) (xy 51.343221 -214.538905) (xy 51.306969 -214.577976) (xy 51.265298 -214.611207)
			(xy 51.21914 -214.637856) (xy 51.169526 -214.657328) (xy 51.117564 -214.669188) (xy 51.064414 -214.673172)
			(xy 51.011264 -214.669188) (xy 50.959302 -214.657328) (xy 50.909688 -214.637856) (xy 50.86353 -214.611207)
			(xy 50.821859 -214.577976) (xy 50.785607 -214.538905) (xy 50.755583 -214.494868) (xy 50.732457 -214.446847)
			(xy 50.716747 -214.395917) (xy 50.708804 -214.343213) (xy 36.332424 -214.343213) (xy 36.324481 -214.395917)
			(xy 36.308771 -214.446847) (xy 36.285645 -214.494868) (xy 36.255621 -214.538905) (xy 36.219369 -214.577976)
			(xy 36.177698 -214.611207) (xy 36.13154 -214.637856) (xy 36.081926 -214.657328) (xy 36.029964 -214.669188)
			(xy 35.976814 -214.673172) (xy 35.923664 -214.669188) (xy 35.871702 -214.657328) (xy 35.822088 -214.637856)
			(xy 35.77593 -214.611207) (xy 35.734259 -214.577976) (xy 35.698007 -214.538905) (xy 35.667983 -214.494868)
			(xy 35.644857 -214.446847) (xy 35.629147 -214.395917) (xy 35.621204 -214.343213) (xy 21.244824 -214.343213)
			(xy 21.236881 -214.395917) (xy 21.221171 -214.446847) (xy 21.198045 -214.494868) (xy 21.168021 -214.538905)
			(xy 21.131769 -214.577976) (xy 21.090098 -214.611207) (xy 21.04394 -214.637856) (xy 20.994326 -214.657328)
			(xy 20.942364 -214.669188) (xy 20.889214 -214.673172) (xy 20.836064 -214.669188) (xy 20.784102 -214.657328)
			(xy 20.734488 -214.637856) (xy 20.68833 -214.611207) (xy 20.646659 -214.577976) (xy 20.610407 -214.538905)
			(xy 20.580383 -214.494868) (xy 20.557257 -214.446847) (xy 20.541547 -214.395917) (xy 20.533604 -214.343213)
			(xy 9.6774 -214.343213) (xy 9.6774 -215.193351) (xy 16.433536 -215.193351) (xy 16.433536 -215.140053)
			(xy 16.441479 -215.087349) (xy 16.457189 -215.036419) (xy 16.480315 -214.988398) (xy 16.510339 -214.944361)
			(xy 16.546591 -214.90529) (xy 16.588262 -214.872059) (xy 16.63442 -214.84541) (xy 16.684034 -214.825938)
			(xy 16.735996 -214.814078) (xy 16.789146 -214.810095) (xy 16.842296 -214.814078) (xy 16.894258 -214.825938)
			(xy 16.943872 -214.84541) (xy 16.99003 -214.872059) (xy 17.031701 -214.90529) (xy 17.067953 -214.944361)
			(xy 17.097977 -214.988398) (xy 17.121103 -215.036419) (xy 17.136813 -215.087349) (xy 17.144756 -215.140053)
			(xy 17.145254 -215.166702) (xy 17.144756 -215.193351) (xy 31.521136 -215.193351) (xy 31.521136 -215.140053)
			(xy 31.529079 -215.087349) (xy 31.544789 -215.036419) (xy 31.567915 -214.988398) (xy 31.597939 -214.944361)
			(xy 31.634191 -214.90529) (xy 31.675862 -214.872059) (xy 31.72202 -214.84541) (xy 31.771634 -214.825938)
			(xy 31.823596 -214.814078) (xy 31.876746 -214.810095) (xy 31.929896 -214.814078) (xy 31.981858 -214.825938)
			(xy 32.031472 -214.84541) (xy 32.07763 -214.872059) (xy 32.119301 -214.90529) (xy 32.155553 -214.944361)
			(xy 32.185577 -214.988398) (xy 32.208703 -215.036419) (xy 32.224413 -215.087349) (xy 32.232356 -215.140053)
			(xy 32.232854 -215.166702) (xy 32.232356 -215.193351) (xy 46.608736 -215.193351) (xy 46.608736 -215.140053)
			(xy 46.616679 -215.087349) (xy 46.632389 -215.036419) (xy 46.655515 -214.988398) (xy 46.685539 -214.944361)
			(xy 46.721791 -214.90529) (xy 46.763462 -214.872059) (xy 46.80962 -214.84541) (xy 46.859234 -214.825938)
			(xy 46.911196 -214.814078) (xy 46.964346 -214.810095) (xy 47.017496 -214.814078) (xy 47.069458 -214.825938)
			(xy 47.119072 -214.84541) (xy 47.16523 -214.872059) (xy 47.206901 -214.90529) (xy 47.243153 -214.944361)
			(xy 47.273177 -214.988398) (xy 47.296303 -215.036419) (xy 47.312013 -215.087349) (xy 47.319956 -215.140053)
			(xy 47.320454 -215.166702) (xy 47.319956 -215.193351) (xy 47.312013 -215.246055) (xy 47.296303 -215.296985)
			(xy 47.273177 -215.345006) (xy 47.243153 -215.389043) (xy 47.206901 -215.428114) (xy 47.16523 -215.461345)
			(xy 47.119072 -215.487994) (xy 47.069458 -215.507466) (xy 47.017496 -215.519326) (xy 46.964346 -215.52331)
			(xy 46.911196 -215.519326) (xy 46.859234 -215.507466) (xy 46.80962 -215.487994) (xy 46.763462 -215.461345)
			(xy 46.721791 -215.428114) (xy 46.685539 -215.389043) (xy 46.655515 -215.345006) (xy 46.632389 -215.296985)
			(xy 46.616679 -215.246055) (xy 46.608736 -215.193351) (xy 32.232356 -215.193351) (xy 32.224413 -215.246055)
			(xy 32.208703 -215.296985) (xy 32.185577 -215.345006) (xy 32.155553 -215.389043) (xy 32.119301 -215.428114)
			(xy 32.07763 -215.461345) (xy 32.031472 -215.487994) (xy 31.981858 -215.507466) (xy 31.929896 -215.519326)
			(xy 31.876746 -215.52331) (xy 31.823596 -215.519326) (xy 31.771634 -215.507466) (xy 31.72202 -215.487994)
			(xy 31.675862 -215.461345) (xy 31.634191 -215.428114) (xy 31.597939 -215.389043) (xy 31.567915 -215.345006)
			(xy 31.544789 -215.296985) (xy 31.529079 -215.246055) (xy 31.521136 -215.193351) (xy 17.144756 -215.193351)
			(xy 17.136813 -215.246055) (xy 17.121103 -215.296985) (xy 17.097977 -215.345006) (xy 17.067953 -215.389043)
			(xy 17.031701 -215.428114) (xy 16.99003 -215.461345) (xy 16.943872 -215.487994) (xy 16.894258 -215.507466)
			(xy 16.842296 -215.519326) (xy 16.789146 -215.52331) (xy 16.735996 -215.519326) (xy 16.684034 -215.507466)
			(xy 16.63442 -215.487994) (xy 16.588262 -215.461345) (xy 16.546591 -215.428114) (xy 16.510339 -215.389043)
			(xy 16.480315 -215.345006) (xy 16.457189 -215.296985) (xy 16.441479 -215.246055) (xy 16.433536 -215.193351)
			(xy 9.6774 -215.193351) (xy 9.6774 -216.043235) (xy 20.533604 -216.043235) (xy 20.533604 -215.989937)
			(xy 20.541547 -215.937233) (xy 20.557257 -215.886303) (xy 20.580383 -215.838282) (xy 20.610407 -215.794245)
			(xy 20.646659 -215.755174) (xy 20.68833 -215.721943) (xy 20.734488 -215.695294) (xy 20.784102 -215.675822)
			(xy 20.836064 -215.663962) (xy 20.889214 -215.659979) (xy 20.942364 -215.663962) (xy 20.994326 -215.675822)
			(xy 21.04394 -215.695294) (xy 21.090098 -215.721943) (xy 21.131769 -215.755174) (xy 21.168021 -215.794245)
			(xy 21.198045 -215.838282) (xy 21.221171 -215.886303) (xy 21.236881 -215.937233) (xy 21.244824 -215.989937)
			(xy 21.245322 -216.016586) (xy 21.244824 -216.043235) (xy 35.621204 -216.043235) (xy 35.621204 -215.989937)
			(xy 35.629147 -215.937233) (xy 35.644857 -215.886303) (xy 35.667983 -215.838282) (xy 35.698007 -215.794245)
			(xy 35.734259 -215.755174) (xy 35.77593 -215.721943) (xy 35.822088 -215.695294) (xy 35.871702 -215.675822)
			(xy 35.923664 -215.663962) (xy 35.976814 -215.659979) (xy 36.029964 -215.663962) (xy 36.081926 -215.675822)
			(xy 36.13154 -215.695294) (xy 36.177698 -215.721943) (xy 36.219369 -215.755174) (xy 36.255621 -215.794245)
			(xy 36.285645 -215.838282) (xy 36.308771 -215.886303) (xy 36.324481 -215.937233) (xy 36.332424 -215.989937)
			(xy 36.332922 -216.016586) (xy 36.332424 -216.043235) (xy 50.708804 -216.043235) (xy 50.708804 -215.989937)
			(xy 50.716747 -215.937233) (xy 50.732457 -215.886303) (xy 50.755583 -215.838282) (xy 50.785607 -215.794245)
			(xy 50.821859 -215.755174) (xy 50.86353 -215.721943) (xy 50.909688 -215.695294) (xy 50.959302 -215.675822)
			(xy 51.011264 -215.663962) (xy 51.064414 -215.659979) (xy 51.117564 -215.663962) (xy 51.169526 -215.675822)
			(xy 51.21914 -215.695294) (xy 51.265298 -215.721943) (xy 51.306969 -215.755174) (xy 51.343221 -215.794245)
			(xy 51.373245 -215.838282) (xy 51.396371 -215.886303) (xy 51.412081 -215.937233) (xy 51.420024 -215.989937)
			(xy 51.420522 -216.016586) (xy 51.420024 -216.043235) (xy 51.412081 -216.095939) (xy 51.396371 -216.146869)
			(xy 51.373245 -216.19489) (xy 51.343221 -216.238927) (xy 51.306969 -216.277998) (xy 51.265298 -216.311229)
			(xy 51.21914 -216.337878) (xy 51.169526 -216.35735) (xy 51.117564 -216.36921) (xy 51.064414 -216.373194)
			(xy 51.011264 -216.36921) (xy 50.959302 -216.35735) (xy 50.909688 -216.337878) (xy 50.86353 -216.311229)
			(xy 50.821859 -216.277998) (xy 50.785607 -216.238927) (xy 50.755583 -216.19489) (xy 50.732457 -216.146869)
			(xy 50.716747 -216.095939) (xy 50.708804 -216.043235) (xy 36.332424 -216.043235) (xy 36.324481 -216.095939)
			(xy 36.308771 -216.146869) (xy 36.285645 -216.19489) (xy 36.255621 -216.238927) (xy 36.219369 -216.277998)
			(xy 36.177698 -216.311229) (xy 36.13154 -216.337878) (xy 36.081926 -216.35735) (xy 36.029964 -216.36921)
			(xy 35.976814 -216.373194) (xy 35.923664 -216.36921) (xy 35.871702 -216.35735) (xy 35.822088 -216.337878)
			(xy 35.77593 -216.311229) (xy 35.734259 -216.277998) (xy 35.698007 -216.238927) (xy 35.667983 -216.19489)
			(xy 35.644857 -216.146869) (xy 35.629147 -216.095939) (xy 35.621204 -216.043235) (xy 21.244824 -216.043235)
			(xy 21.236881 -216.095939) (xy 21.221171 -216.146869) (xy 21.198045 -216.19489) (xy 21.168021 -216.238927)
			(xy 21.131769 -216.277998) (xy 21.090098 -216.311229) (xy 21.04394 -216.337878) (xy 20.994326 -216.35735)
			(xy 20.942364 -216.36921) (xy 20.889214 -216.373194) (xy 20.836064 -216.36921) (xy 20.784102 -216.35735)
			(xy 20.734488 -216.337878) (xy 20.68833 -216.311229) (xy 20.646659 -216.277998) (xy 20.610407 -216.238927)
			(xy 20.580383 -216.19489) (xy 20.557257 -216.146869) (xy 20.541547 -216.095939) (xy 20.533604 -216.043235)
			(xy 9.6774 -216.043235) (xy 9.6774 -216.893373) (xy 16.433536 -216.893373) (xy 16.433536 -216.840075)
			(xy 16.441479 -216.787371) (xy 16.457189 -216.736441) (xy 16.480315 -216.68842) (xy 16.510339 -216.644383)
			(xy 16.546591 -216.605312) (xy 16.588262 -216.572081) (xy 16.63442 -216.545432) (xy 16.684034 -216.52596)
			(xy 16.735996 -216.5141) (xy 16.789146 -216.510117) (xy 16.842296 -216.5141) (xy 16.894258 -216.52596)
			(xy 16.943872 -216.545432) (xy 16.99003 -216.572081) (xy 17.031701 -216.605312) (xy 17.067953 -216.644383)
			(xy 17.097977 -216.68842) (xy 17.121103 -216.736441) (xy 17.136813 -216.787371) (xy 17.144756 -216.840075)
			(xy 17.145254 -216.866724) (xy 17.144756 -216.893373) (xy 31.521136 -216.893373) (xy 31.521136 -216.840075)
			(xy 31.529079 -216.787371) (xy 31.544789 -216.736441) (xy 31.567915 -216.68842) (xy 31.597939 -216.644383)
			(xy 31.634191 -216.605312) (xy 31.675862 -216.572081) (xy 31.72202 -216.545432) (xy 31.771634 -216.52596)
			(xy 31.823596 -216.5141) (xy 31.876746 -216.510117) (xy 31.929896 -216.5141) (xy 31.981858 -216.52596)
			(xy 32.031472 -216.545432) (xy 32.07763 -216.572081) (xy 32.119301 -216.605312) (xy 32.155553 -216.644383)
			(xy 32.185577 -216.68842) (xy 32.208703 -216.736441) (xy 32.224413 -216.787371) (xy 32.232356 -216.840075)
			(xy 32.232854 -216.866724) (xy 32.232356 -216.893373) (xy 46.608736 -216.893373) (xy 46.608736 -216.840075)
			(xy 46.616679 -216.787371) (xy 46.632389 -216.736441) (xy 46.655515 -216.68842) (xy 46.685539 -216.644383)
			(xy 46.721791 -216.605312) (xy 46.763462 -216.572081) (xy 46.80962 -216.545432) (xy 46.859234 -216.52596)
			(xy 46.911196 -216.5141) (xy 46.964346 -216.510117) (xy 47.017496 -216.5141) (xy 47.069458 -216.52596)
			(xy 47.119072 -216.545432) (xy 47.16523 -216.572081) (xy 47.206901 -216.605312) (xy 47.243153 -216.644383)
			(xy 47.273177 -216.68842) (xy 47.296303 -216.736441) (xy 47.312013 -216.787371) (xy 47.319956 -216.840075)
			(xy 47.320454 -216.866724) (xy 47.319956 -216.893373) (xy 47.312013 -216.946077) (xy 47.296303 -216.997007)
			(xy 47.273177 -217.045028) (xy 47.243153 -217.089065) (xy 47.206901 -217.128136) (xy 47.16523 -217.161367)
			(xy 47.119072 -217.188016) (xy 47.069458 -217.207488) (xy 47.017496 -217.219348) (xy 46.964346 -217.223332)
			(xy 46.911196 -217.219348) (xy 46.859234 -217.207488) (xy 46.80962 -217.188016) (xy 46.763462 -217.161367)
			(xy 46.721791 -217.128136) (xy 46.685539 -217.089065) (xy 46.655515 -217.045028) (xy 46.632389 -216.997007)
			(xy 46.616679 -216.946077) (xy 46.608736 -216.893373) (xy 32.232356 -216.893373) (xy 32.224413 -216.946077)
			(xy 32.208703 -216.997007) (xy 32.185577 -217.045028) (xy 32.155553 -217.089065) (xy 32.119301 -217.128136)
			(xy 32.07763 -217.161367) (xy 32.031472 -217.188016) (xy 31.981858 -217.207488) (xy 31.929896 -217.219348)
			(xy 31.876746 -217.223332) (xy 31.823596 -217.219348) (xy 31.771634 -217.207488) (xy 31.72202 -217.188016)
			(xy 31.675862 -217.161367) (xy 31.634191 -217.128136) (xy 31.597939 -217.089065) (xy 31.567915 -217.045028)
			(xy 31.544789 -216.997007) (xy 31.529079 -216.946077) (xy 31.521136 -216.893373) (xy 17.144756 -216.893373)
			(xy 17.136813 -216.946077) (xy 17.121103 -216.997007) (xy 17.097977 -217.045028) (xy 17.067953 -217.089065)
			(xy 17.031701 -217.128136) (xy 16.99003 -217.161367) (xy 16.943872 -217.188016) (xy 16.894258 -217.207488)
			(xy 16.842296 -217.219348) (xy 16.789146 -217.223332) (xy 16.735996 -217.219348) (xy 16.684034 -217.207488)
			(xy 16.63442 -217.188016) (xy 16.588262 -217.161367) (xy 16.546591 -217.128136) (xy 16.510339 -217.089065)
			(xy 16.480315 -217.045028) (xy 16.457189 -216.997007) (xy 16.441479 -216.946077) (xy 16.433536 -216.893373)
			(xy 9.6774 -216.893373) (xy 9.6774 -217.743257) (xy 20.533604 -217.743257) (xy 20.533604 -217.689959)
			(xy 20.541547 -217.637255) (xy 20.557257 -217.586325) (xy 20.580383 -217.538304) (xy 20.610407 -217.494267)
			(xy 20.646659 -217.455196) (xy 20.68833 -217.421965) (xy 20.734488 -217.395316) (xy 20.784102 -217.375844)
			(xy 20.836064 -217.363984) (xy 20.889214 -217.360001) (xy 20.942364 -217.363984) (xy 20.994326 -217.375844)
			(xy 21.04394 -217.395316) (xy 21.090098 -217.421965) (xy 21.131769 -217.455196) (xy 21.168021 -217.494267)
			(xy 21.198045 -217.538304) (xy 21.221171 -217.586325) (xy 21.236881 -217.637255) (xy 21.244824 -217.689959)
			(xy 21.245322 -217.716608) (xy 21.244824 -217.743257) (xy 35.621204 -217.743257) (xy 35.621204 -217.689959)
			(xy 35.629147 -217.637255) (xy 35.644857 -217.586325) (xy 35.667983 -217.538304) (xy 35.698007 -217.494267)
			(xy 35.734259 -217.455196) (xy 35.77593 -217.421965) (xy 35.822088 -217.395316) (xy 35.871702 -217.375844)
			(xy 35.923664 -217.363984) (xy 35.976814 -217.360001) (xy 36.029964 -217.363984) (xy 36.081926 -217.375844)
			(xy 36.13154 -217.395316) (xy 36.177698 -217.421965) (xy 36.219369 -217.455196) (xy 36.255621 -217.494267)
			(xy 36.285645 -217.538304) (xy 36.308771 -217.586325) (xy 36.324481 -217.637255) (xy 36.332424 -217.689959)
			(xy 36.332922 -217.716608) (xy 36.332424 -217.743257) (xy 50.708804 -217.743257) (xy 50.708804 -217.689959)
			(xy 50.716747 -217.637255) (xy 50.732457 -217.586325) (xy 50.755583 -217.538304) (xy 50.785607 -217.494267)
			(xy 50.821859 -217.455196) (xy 50.86353 -217.421965) (xy 50.909688 -217.395316) (xy 50.959302 -217.375844)
			(xy 51.011264 -217.363984) (xy 51.064414 -217.360001) (xy 51.117564 -217.363984) (xy 51.169526 -217.375844)
			(xy 51.21914 -217.395316) (xy 51.265298 -217.421965) (xy 51.306969 -217.455196) (xy 51.343221 -217.494267)
			(xy 51.373245 -217.538304) (xy 51.396371 -217.586325) (xy 51.412081 -217.637255) (xy 51.420024 -217.689959)
			(xy 51.420522 -217.716608) (xy 51.420024 -217.743257) (xy 51.412081 -217.795961) (xy 51.396371 -217.846891)
			(xy 51.373245 -217.894912) (xy 51.343221 -217.938949) (xy 51.306969 -217.97802) (xy 51.265298 -218.011251)
			(xy 51.21914 -218.0379) (xy 51.169526 -218.057372) (xy 51.117564 -218.069232) (xy 51.064414 -218.073216)
			(xy 51.011264 -218.069232) (xy 50.959302 -218.057372) (xy 50.909688 -218.0379) (xy 50.86353 -218.011251)
			(xy 50.821859 -217.97802) (xy 50.785607 -217.938949) (xy 50.755583 -217.894912) (xy 50.732457 -217.846891)
			(xy 50.716747 -217.795961) (xy 50.708804 -217.743257) (xy 36.332424 -217.743257) (xy 36.324481 -217.795961)
			(xy 36.308771 -217.846891) (xy 36.285645 -217.894912) (xy 36.255621 -217.938949) (xy 36.219369 -217.97802)
			(xy 36.177698 -218.011251) (xy 36.13154 -218.0379) (xy 36.081926 -218.057372) (xy 36.029964 -218.069232)
			(xy 35.976814 -218.073216) (xy 35.923664 -218.069232) (xy 35.871702 -218.057372) (xy 35.822088 -218.0379)
			(xy 35.77593 -218.011251) (xy 35.734259 -217.97802) (xy 35.698007 -217.938949) (xy 35.667983 -217.894912)
			(xy 35.644857 -217.846891) (xy 35.629147 -217.795961) (xy 35.621204 -217.743257) (xy 21.244824 -217.743257)
			(xy 21.236881 -217.795961) (xy 21.221171 -217.846891) (xy 21.198045 -217.894912) (xy 21.168021 -217.938949)
			(xy 21.131769 -217.97802) (xy 21.090098 -218.011251) (xy 21.04394 -218.0379) (xy 20.994326 -218.057372)
			(xy 20.942364 -218.069232) (xy 20.889214 -218.073216) (xy 20.836064 -218.069232) (xy 20.784102 -218.057372)
			(xy 20.734488 -218.0379) (xy 20.68833 -218.011251) (xy 20.646659 -217.97802) (xy 20.610407 -217.938949)
			(xy 20.580383 -217.894912) (xy 20.557257 -217.846891) (xy 20.541547 -217.795961) (xy 20.533604 -217.743257)
			(xy 9.6774 -217.743257) (xy 9.6774 -218.593395) (xy 16.433536 -218.593395) (xy 16.433536 -218.540097)
			(xy 16.441479 -218.487393) (xy 16.457189 -218.436463) (xy 16.480315 -218.388442) (xy 16.510339 -218.344405)
			(xy 16.546591 -218.305334) (xy 16.588262 -218.272103) (xy 16.63442 -218.245454) (xy 16.684034 -218.225982)
			(xy 16.735996 -218.214122) (xy 16.789146 -218.210139) (xy 16.842296 -218.214122) (xy 16.894258 -218.225982)
			(xy 16.943872 -218.245454) (xy 16.99003 -218.272103) (xy 17.031701 -218.305334) (xy 17.067953 -218.344405)
			(xy 17.097977 -218.388442) (xy 17.121103 -218.436463) (xy 17.136813 -218.487393) (xy 17.144756 -218.540097)
			(xy 17.145254 -218.566746) (xy 17.144756 -218.593395) (xy 20.533604 -218.593395) (xy 20.533604 -218.540097)
			(xy 20.541547 -218.487393) (xy 20.557257 -218.436463) (xy 20.580383 -218.388442) (xy 20.610407 -218.344405)
			(xy 20.646659 -218.305334) (xy 20.68833 -218.272103) (xy 20.734488 -218.245454) (xy 20.784102 -218.225982)
			(xy 20.836064 -218.214122) (xy 20.889214 -218.210139) (xy 20.942364 -218.214122) (xy 20.994326 -218.225982)
			(xy 21.04394 -218.245454) (xy 21.090098 -218.272103) (xy 21.131769 -218.305334) (xy 21.168021 -218.344405)
			(xy 21.198045 -218.388442) (xy 21.221171 -218.436463) (xy 21.236881 -218.487393) (xy 21.244824 -218.540097)
			(xy 21.245322 -218.566746) (xy 21.244824 -218.593395) (xy 31.521136 -218.593395) (xy 31.521136 -218.540097)
			(xy 31.529079 -218.487393) (xy 31.544789 -218.436463) (xy 31.567915 -218.388442) (xy 31.597939 -218.344405)
			(xy 31.634191 -218.305334) (xy 31.675862 -218.272103) (xy 31.72202 -218.245454) (xy 31.771634 -218.225982)
			(xy 31.823596 -218.214122) (xy 31.876746 -218.210139) (xy 31.929896 -218.214122) (xy 31.981858 -218.225982)
			(xy 32.031472 -218.245454) (xy 32.07763 -218.272103) (xy 32.119301 -218.305334) (xy 32.155553 -218.344405)
			(xy 32.185577 -218.388442) (xy 32.208703 -218.436463) (xy 32.224413 -218.487393) (xy 32.232356 -218.540097)
			(xy 32.232854 -218.566746) (xy 32.232356 -218.593395) (xy 35.621204 -218.593395) (xy 35.621204 -218.540097)
			(xy 35.629147 -218.487393) (xy 35.644857 -218.436463) (xy 35.667983 -218.388442) (xy 35.698007 -218.344405)
			(xy 35.734259 -218.305334) (xy 35.77593 -218.272103) (xy 35.822088 -218.245454) (xy 35.871702 -218.225982)
			(xy 35.923664 -218.214122) (xy 35.976814 -218.210139) (xy 36.029964 -218.214122) (xy 36.081926 -218.225982)
			(xy 36.13154 -218.245454) (xy 36.177698 -218.272103) (xy 36.219369 -218.305334) (xy 36.255621 -218.344405)
			(xy 36.285645 -218.388442) (xy 36.308771 -218.436463) (xy 36.324481 -218.487393) (xy 36.332424 -218.540097)
			(xy 36.332922 -218.566746) (xy 36.332424 -218.593395) (xy 46.608736 -218.593395) (xy 46.608736 -218.540097)
			(xy 46.616679 -218.487393) (xy 46.632389 -218.436463) (xy 46.655515 -218.388442) (xy 46.685539 -218.344405)
			(xy 46.721791 -218.305334) (xy 46.763462 -218.272103) (xy 46.80962 -218.245454) (xy 46.859234 -218.225982)
			(xy 46.911196 -218.214122) (xy 46.964346 -218.210139) (xy 47.017496 -218.214122) (xy 47.069458 -218.225982)
			(xy 47.119072 -218.245454) (xy 47.16523 -218.272103) (xy 47.206901 -218.305334) (xy 47.243153 -218.344405)
			(xy 47.273177 -218.388442) (xy 47.296303 -218.436463) (xy 47.312013 -218.487393) (xy 47.319956 -218.540097)
			(xy 47.320454 -218.566746) (xy 47.319956 -218.593395) (xy 50.708804 -218.593395) (xy 50.708804 -218.540097)
			(xy 50.716747 -218.487393) (xy 50.732457 -218.436463) (xy 50.755583 -218.388442) (xy 50.785607 -218.344405)
			(xy 50.821859 -218.305334) (xy 50.86353 -218.272103) (xy 50.909688 -218.245454) (xy 50.959302 -218.225982)
			(xy 51.011264 -218.214122) (xy 51.064414 -218.210139) (xy 51.117564 -218.214122) (xy 51.169526 -218.225982)
			(xy 51.21914 -218.245454) (xy 51.265298 -218.272103) (xy 51.306969 -218.305334) (xy 51.343221 -218.344405)
			(xy 51.373245 -218.388442) (xy 51.396371 -218.436463) (xy 51.412081 -218.487393) (xy 51.420024 -218.540097)
			(xy 51.420522 -218.566746) (xy 51.420024 -218.593395) (xy 51.412081 -218.646099) (xy 51.396371 -218.697029)
			(xy 51.373245 -218.74505) (xy 51.343221 -218.789087) (xy 51.306969 -218.828158) (xy 51.265298 -218.861389)
			(xy 51.21914 -218.888038) (xy 51.169526 -218.90751) (xy 51.117564 -218.91937) (xy 51.064414 -218.923354)
			(xy 51.011264 -218.91937) (xy 50.959302 -218.90751) (xy 50.909688 -218.888038) (xy 50.86353 -218.861389)
			(xy 50.821859 -218.828158) (xy 50.785607 -218.789087) (xy 50.755583 -218.74505) (xy 50.732457 -218.697029)
			(xy 50.716747 -218.646099) (xy 50.708804 -218.593395) (xy 47.319956 -218.593395) (xy 47.312013 -218.646099)
			(xy 47.296303 -218.697029) (xy 47.273177 -218.74505) (xy 47.243153 -218.789087) (xy 47.206901 -218.828158)
			(xy 47.16523 -218.861389) (xy 47.119072 -218.888038) (xy 47.069458 -218.90751) (xy 47.017496 -218.91937)
			(xy 46.964346 -218.923354) (xy 46.911196 -218.91937) (xy 46.859234 -218.90751) (xy 46.80962 -218.888038)
			(xy 46.763462 -218.861389) (xy 46.721791 -218.828158) (xy 46.685539 -218.789087) (xy 46.655515 -218.74505)
			(xy 46.632389 -218.697029) (xy 46.616679 -218.646099) (xy 46.608736 -218.593395) (xy 36.332424 -218.593395)
			(xy 36.324481 -218.646099) (xy 36.308771 -218.697029) (xy 36.285645 -218.74505) (xy 36.255621 -218.789087)
			(xy 36.219369 -218.828158) (xy 36.177698 -218.861389) (xy 36.13154 -218.888038) (xy 36.081926 -218.90751)
			(xy 36.029964 -218.91937) (xy 35.976814 -218.923354) (xy 35.923664 -218.91937) (xy 35.871702 -218.90751)
			(xy 35.822088 -218.888038) (xy 35.77593 -218.861389) (xy 35.734259 -218.828158) (xy 35.698007 -218.789087)
			(xy 35.667983 -218.74505) (xy 35.644857 -218.697029) (xy 35.629147 -218.646099) (xy 35.621204 -218.593395)
			(xy 32.232356 -218.593395) (xy 32.224413 -218.646099) (xy 32.208703 -218.697029) (xy 32.185577 -218.74505)
			(xy 32.155553 -218.789087) (xy 32.119301 -218.828158) (xy 32.07763 -218.861389) (xy 32.031472 -218.888038)
			(xy 31.981858 -218.90751) (xy 31.929896 -218.91937) (xy 31.876746 -218.923354) (xy 31.823596 -218.91937)
			(xy 31.771634 -218.90751) (xy 31.72202 -218.888038) (xy 31.675862 -218.861389) (xy 31.634191 -218.828158)
			(xy 31.597939 -218.789087) (xy 31.567915 -218.74505) (xy 31.544789 -218.697029) (xy 31.529079 -218.646099)
			(xy 31.521136 -218.593395) (xy 21.244824 -218.593395) (xy 21.236881 -218.646099) (xy 21.221171 -218.697029)
			(xy 21.198045 -218.74505) (xy 21.168021 -218.789087) (xy 21.131769 -218.828158) (xy 21.090098 -218.861389)
			(xy 21.04394 -218.888038) (xy 20.994326 -218.90751) (xy 20.942364 -218.91937) (xy 20.889214 -218.923354)
			(xy 20.836064 -218.91937) (xy 20.784102 -218.90751) (xy 20.734488 -218.888038) (xy 20.68833 -218.861389)
			(xy 20.646659 -218.828158) (xy 20.610407 -218.789087) (xy 20.580383 -218.74505) (xy 20.557257 -218.697029)
			(xy 20.541547 -218.646099) (xy 20.533604 -218.593395) (xy 17.144756 -218.593395) (xy 17.136813 -218.646099)
			(xy 17.121103 -218.697029) (xy 17.097977 -218.74505) (xy 17.067953 -218.789087) (xy 17.031701 -218.828158)
			(xy 16.99003 -218.861389) (xy 16.943872 -218.888038) (xy 16.894258 -218.90751) (xy 16.842296 -218.91937)
			(xy 16.789146 -218.923354) (xy 16.735996 -218.91937) (xy 16.684034 -218.90751) (xy 16.63442 -218.888038)
			(xy 16.588262 -218.861389) (xy 16.546591 -218.828158) (xy 16.510339 -218.789087) (xy 16.480315 -218.74505)
			(xy 16.457189 -218.697029) (xy 16.441479 -218.646099) (xy 16.433536 -218.593395) (xy 9.6774 -218.593395)
			(xy 9.6774 -219.443279) (xy 16.433536 -219.443279) (xy 16.433536 -219.389981) (xy 16.441479 -219.337277)
			(xy 16.457189 -219.286347) (xy 16.480315 -219.238326) (xy 16.510339 -219.194289) (xy 16.546591 -219.155218)
			(xy 16.588262 -219.121987) (xy 16.63442 -219.095338) (xy 16.684034 -219.075866) (xy 16.735996 -219.064006)
			(xy 16.789146 -219.060023) (xy 16.842296 -219.064006) (xy 16.894258 -219.075866) (xy 16.943872 -219.095338)
			(xy 16.99003 -219.121987) (xy 17.031701 -219.155218) (xy 17.067953 -219.194289) (xy 17.097977 -219.238326)
			(xy 17.121103 -219.286347) (xy 17.136813 -219.337277) (xy 17.144756 -219.389981) (xy 17.145254 -219.41663)
			(xy 17.144756 -219.443279) (xy 31.521136 -219.443279) (xy 31.521136 -219.389981) (xy 31.529079 -219.337277)
			(xy 31.544789 -219.286347) (xy 31.567915 -219.238326) (xy 31.597939 -219.194289) (xy 31.634191 -219.155218)
			(xy 31.675862 -219.121987) (xy 31.72202 -219.095338) (xy 31.771634 -219.075866) (xy 31.823596 -219.064006)
			(xy 31.876746 -219.060023) (xy 31.929896 -219.064006) (xy 31.981858 -219.075866) (xy 32.031472 -219.095338)
			(xy 32.07763 -219.121987) (xy 32.119301 -219.155218) (xy 32.155553 -219.194289) (xy 32.185577 -219.238326)
			(xy 32.208703 -219.286347) (xy 32.224413 -219.337277) (xy 32.232356 -219.389981) (xy 32.232854 -219.41663)
			(xy 32.232356 -219.443279) (xy 46.608736 -219.443279) (xy 46.608736 -219.389981) (xy 46.616679 -219.337277)
			(xy 46.632389 -219.286347) (xy 46.655515 -219.238326) (xy 46.685539 -219.194289) (xy 46.721791 -219.155218)
			(xy 46.763462 -219.121987) (xy 46.80962 -219.095338) (xy 46.859234 -219.075866) (xy 46.911196 -219.064006)
			(xy 46.964346 -219.060023) (xy 47.017496 -219.064006) (xy 47.069458 -219.075866) (xy 47.119072 -219.095338)
			(xy 47.16523 -219.121987) (xy 47.206901 -219.155218) (xy 47.243153 -219.194289) (xy 47.273177 -219.238326)
			(xy 47.296303 -219.286347) (xy 47.312013 -219.337277) (xy 47.319956 -219.389981) (xy 47.320454 -219.41663)
			(xy 47.319956 -219.443279) (xy 47.312013 -219.495983) (xy 47.296303 -219.546913) (xy 47.273177 -219.594934)
			(xy 47.243153 -219.638971) (xy 47.206901 -219.678042) (xy 47.16523 -219.711273) (xy 47.119072 -219.737922)
			(xy 47.069458 -219.757394) (xy 47.017496 -219.769254) (xy 46.964346 -219.773238) (xy 46.911196 -219.769254)
			(xy 46.859234 -219.757394) (xy 46.80962 -219.737922) (xy 46.763462 -219.711273) (xy 46.721791 -219.678042)
			(xy 46.685539 -219.638971) (xy 46.655515 -219.594934) (xy 46.632389 -219.546913) (xy 46.616679 -219.495983)
			(xy 46.608736 -219.443279) (xy 32.232356 -219.443279) (xy 32.224413 -219.495983) (xy 32.208703 -219.546913)
			(xy 32.185577 -219.594934) (xy 32.155553 -219.638971) (xy 32.119301 -219.678042) (xy 32.07763 -219.711273)
			(xy 32.031472 -219.737922) (xy 31.981858 -219.757394) (xy 31.929896 -219.769254) (xy 31.876746 -219.773238)
			(xy 31.823596 -219.769254) (xy 31.771634 -219.757394) (xy 31.72202 -219.737922) (xy 31.675862 -219.711273)
			(xy 31.634191 -219.678042) (xy 31.597939 -219.638971) (xy 31.567915 -219.594934) (xy 31.544789 -219.546913)
			(xy 31.529079 -219.495983) (xy 31.521136 -219.443279) (xy 17.144756 -219.443279) (xy 17.136813 -219.495983)
			(xy 17.121103 -219.546913) (xy 17.097977 -219.594934) (xy 17.067953 -219.638971) (xy 17.031701 -219.678042)
			(xy 16.99003 -219.711273) (xy 16.943872 -219.737922) (xy 16.894258 -219.757394) (xy 16.842296 -219.769254)
			(xy 16.789146 -219.773238) (xy 16.735996 -219.769254) (xy 16.684034 -219.757394) (xy 16.63442 -219.737922)
			(xy 16.588262 -219.711273) (xy 16.546591 -219.678042) (xy 16.510339 -219.638971) (xy 16.480315 -219.594934)
			(xy 16.457189 -219.546913) (xy 16.441479 -219.495983) (xy 16.433536 -219.443279) (xy 9.6774 -219.443279)
			(xy 9.6774 -220.293417) (xy 20.533604 -220.293417) (xy 20.533604 -220.240119) (xy 20.541547 -220.187415)
			(xy 20.557257 -220.136485) (xy 20.580383 -220.088464) (xy 20.610407 -220.044427) (xy 20.646659 -220.005356)
			(xy 20.68833 -219.972125) (xy 20.734488 -219.945476) (xy 20.784102 -219.926004) (xy 20.836064 -219.914144)
			(xy 20.889214 -219.910161) (xy 20.942364 -219.914144) (xy 20.994326 -219.926004) (xy 21.04394 -219.945476)
			(xy 21.090098 -219.972125) (xy 21.131769 -220.005356) (xy 21.168021 -220.044427) (xy 21.198045 -220.088464)
			(xy 21.221171 -220.136485) (xy 21.236881 -220.187415) (xy 21.244824 -220.240119) (xy 21.245322 -220.266768)
			(xy 21.244824 -220.293417) (xy 35.621204 -220.293417) (xy 35.621204 -220.240119) (xy 35.629147 -220.187415)
			(xy 35.644857 -220.136485) (xy 35.667983 -220.088464) (xy 35.698007 -220.044427) (xy 35.734259 -220.005356)
			(xy 35.77593 -219.972125) (xy 35.822088 -219.945476) (xy 35.871702 -219.926004) (xy 35.923664 -219.914144)
			(xy 35.976814 -219.910161) (xy 36.029964 -219.914144) (xy 36.081926 -219.926004) (xy 36.13154 -219.945476)
			(xy 36.177698 -219.972125) (xy 36.219369 -220.005356) (xy 36.255621 -220.044427) (xy 36.285645 -220.088464)
			(xy 36.308771 -220.136485) (xy 36.324481 -220.187415) (xy 36.332424 -220.240119) (xy 36.332922 -220.266768)
			(xy 36.332424 -220.293417) (xy 50.708804 -220.293417) (xy 50.708804 -220.240119) (xy 50.716747 -220.187415)
			(xy 50.732457 -220.136485) (xy 50.755583 -220.088464) (xy 50.785607 -220.044427) (xy 50.821859 -220.005356)
			(xy 50.86353 -219.972125) (xy 50.909688 -219.945476) (xy 50.959302 -219.926004) (xy 51.011264 -219.914144)
			(xy 51.064414 -219.910161) (xy 51.117564 -219.914144) (xy 51.169526 -219.926004) (xy 51.21914 -219.945476)
			(xy 51.265298 -219.972125) (xy 51.306969 -220.005356) (xy 51.343221 -220.044427) (xy 51.373245 -220.088464)
			(xy 51.396371 -220.136485) (xy 51.412081 -220.187415) (xy 51.420024 -220.240119) (xy 51.420522 -220.266768)
			(xy 51.420024 -220.293417) (xy 51.412081 -220.346121) (xy 51.396371 -220.397051) (xy 51.373245 -220.445072)
			(xy 51.343221 -220.489109) (xy 51.306969 -220.52818) (xy 51.265298 -220.561411) (xy 51.21914 -220.58806)
			(xy 51.169526 -220.607532) (xy 51.117564 -220.619392) (xy 51.064414 -220.623376) (xy 51.011264 -220.619392)
			(xy 50.959302 -220.607532) (xy 50.909688 -220.58806) (xy 50.86353 -220.561411) (xy 50.821859 -220.52818)
			(xy 50.785607 -220.489109) (xy 50.755583 -220.445072) (xy 50.732457 -220.397051) (xy 50.716747 -220.346121)
			(xy 50.708804 -220.293417) (xy 36.332424 -220.293417) (xy 36.324481 -220.346121) (xy 36.308771 -220.397051)
			(xy 36.285645 -220.445072) (xy 36.255621 -220.489109) (xy 36.219369 -220.52818) (xy 36.177698 -220.561411)
			(xy 36.13154 -220.58806) (xy 36.081926 -220.607532) (xy 36.029964 -220.619392) (xy 35.976814 -220.623376)
			(xy 35.923664 -220.619392) (xy 35.871702 -220.607532) (xy 35.822088 -220.58806) (xy 35.77593 -220.561411)
			(xy 35.734259 -220.52818) (xy 35.698007 -220.489109) (xy 35.667983 -220.445072) (xy 35.644857 -220.397051)
			(xy 35.629147 -220.346121) (xy 35.621204 -220.293417) (xy 21.244824 -220.293417) (xy 21.236881 -220.346121)
			(xy 21.221171 -220.397051) (xy 21.198045 -220.445072) (xy 21.168021 -220.489109) (xy 21.131769 -220.52818)
			(xy 21.090098 -220.561411) (xy 21.04394 -220.58806) (xy 20.994326 -220.607532) (xy 20.942364 -220.619392)
			(xy 20.889214 -220.623376) (xy 20.836064 -220.619392) (xy 20.784102 -220.607532) (xy 20.734488 -220.58806)
			(xy 20.68833 -220.561411) (xy 20.646659 -220.52818) (xy 20.610407 -220.489109) (xy 20.580383 -220.445072)
			(xy 20.557257 -220.397051) (xy 20.541547 -220.346121) (xy 20.533604 -220.293417) (xy 9.6774 -220.293417)
			(xy 9.6774 -221.143301) (xy 16.433536 -221.143301) (xy 16.433536 -221.090003) (xy 16.441479 -221.037299)
			(xy 16.457189 -220.986369) (xy 16.480315 -220.938348) (xy 16.510339 -220.894311) (xy 16.546591 -220.85524)
			(xy 16.588262 -220.822009) (xy 16.63442 -220.79536) (xy 16.684034 -220.775888) (xy 16.735996 -220.764028)
			(xy 16.789146 -220.760045) (xy 16.842296 -220.764028) (xy 16.894258 -220.775888) (xy 16.943872 -220.79536)
			(xy 16.99003 -220.822009) (xy 17.031701 -220.85524) (xy 17.067953 -220.894311) (xy 17.097977 -220.938348)
			(xy 17.121103 -220.986369) (xy 17.136813 -221.037299) (xy 17.144756 -221.090003) (xy 17.145254 -221.116652)
			(xy 17.144756 -221.143301) (xy 31.521136 -221.143301) (xy 31.521136 -221.090003) (xy 31.529079 -221.037299)
			(xy 31.544789 -220.986369) (xy 31.567915 -220.938348) (xy 31.597939 -220.894311) (xy 31.634191 -220.85524)
			(xy 31.675862 -220.822009) (xy 31.72202 -220.79536) (xy 31.771634 -220.775888) (xy 31.823596 -220.764028)
			(xy 31.876746 -220.760045) (xy 31.929896 -220.764028) (xy 31.981858 -220.775888) (xy 32.031472 -220.79536)
			(xy 32.07763 -220.822009) (xy 32.119301 -220.85524) (xy 32.155553 -220.894311) (xy 32.185577 -220.938348)
			(xy 32.208703 -220.986369) (xy 32.224413 -221.037299) (xy 32.232356 -221.090003) (xy 32.232854 -221.116652)
			(xy 32.232356 -221.143301) (xy 46.608736 -221.143301) (xy 46.608736 -221.090003) (xy 46.616679 -221.037299)
			(xy 46.632389 -220.986369) (xy 46.655515 -220.938348) (xy 46.685539 -220.894311) (xy 46.721791 -220.85524)
			(xy 46.763462 -220.822009) (xy 46.80962 -220.79536) (xy 46.859234 -220.775888) (xy 46.911196 -220.764028)
			(xy 46.964346 -220.760045) (xy 47.017496 -220.764028) (xy 47.069458 -220.775888) (xy 47.119072 -220.79536)
			(xy 47.16523 -220.822009) (xy 47.206901 -220.85524) (xy 47.243153 -220.894311) (xy 47.273177 -220.938348)
			(xy 47.296303 -220.986369) (xy 47.312013 -221.037299) (xy 47.319956 -221.090003) (xy 47.320454 -221.116652)
			(xy 47.319956 -221.143301) (xy 47.312013 -221.196005) (xy 47.296303 -221.246935) (xy 47.273177 -221.294956)
			(xy 47.243153 -221.338993) (xy 47.206901 -221.378064) (xy 47.16523 -221.411295) (xy 47.119072 -221.437944)
			(xy 47.069458 -221.457416) (xy 47.017496 -221.469276) (xy 46.964346 -221.47326) (xy 46.911196 -221.469276)
			(xy 46.859234 -221.457416) (xy 46.80962 -221.437944) (xy 46.763462 -221.411295) (xy 46.721791 -221.378064)
			(xy 46.685539 -221.338993) (xy 46.655515 -221.294956) (xy 46.632389 -221.246935) (xy 46.616679 -221.196005)
			(xy 46.608736 -221.143301) (xy 32.232356 -221.143301) (xy 32.224413 -221.196005) (xy 32.208703 -221.246935)
			(xy 32.185577 -221.294956) (xy 32.155553 -221.338993) (xy 32.119301 -221.378064) (xy 32.07763 -221.411295)
			(xy 32.031472 -221.437944) (xy 31.981858 -221.457416) (xy 31.929896 -221.469276) (xy 31.876746 -221.47326)
			(xy 31.823596 -221.469276) (xy 31.771634 -221.457416) (xy 31.72202 -221.437944) (xy 31.675862 -221.411295)
			(xy 31.634191 -221.378064) (xy 31.597939 -221.338993) (xy 31.567915 -221.294956) (xy 31.544789 -221.246935)
			(xy 31.529079 -221.196005) (xy 31.521136 -221.143301) (xy 17.144756 -221.143301) (xy 17.136813 -221.196005)
			(xy 17.121103 -221.246935) (xy 17.097977 -221.294956) (xy 17.067953 -221.338993) (xy 17.031701 -221.378064)
			(xy 16.99003 -221.411295) (xy 16.943872 -221.437944) (xy 16.894258 -221.457416) (xy 16.842296 -221.469276)
			(xy 16.789146 -221.47326) (xy 16.735996 -221.469276) (xy 16.684034 -221.457416) (xy 16.63442 -221.437944)
			(xy 16.588262 -221.411295) (xy 16.546591 -221.378064) (xy 16.510339 -221.338993) (xy 16.480315 -221.294956)
			(xy 16.457189 -221.246935) (xy 16.441479 -221.196005) (xy 16.433536 -221.143301) (xy 9.6774 -221.143301)
			(xy 9.6774 -221.993439) (xy 20.533604 -221.993439) (xy 20.533604 -221.940141) (xy 20.541547 -221.887437)
			(xy 20.557257 -221.836507) (xy 20.580383 -221.788486) (xy 20.610407 -221.744449) (xy 20.646659 -221.705378)
			(xy 20.68833 -221.672147) (xy 20.734488 -221.645498) (xy 20.784102 -221.626026) (xy 20.836064 -221.614166)
			(xy 20.889214 -221.610183) (xy 20.942364 -221.614166) (xy 20.994326 -221.626026) (xy 21.04394 -221.645498)
			(xy 21.090098 -221.672147) (xy 21.131769 -221.705378) (xy 21.168021 -221.744449) (xy 21.198045 -221.788486)
			(xy 21.221171 -221.836507) (xy 21.236881 -221.887437) (xy 21.244824 -221.940141) (xy 21.245322 -221.96679)
			(xy 21.244824 -221.993439) (xy 35.621204 -221.993439) (xy 35.621204 -221.940141) (xy 35.629147 -221.887437)
			(xy 35.644857 -221.836507) (xy 35.667983 -221.788486) (xy 35.698007 -221.744449) (xy 35.734259 -221.705378)
			(xy 35.77593 -221.672147) (xy 35.822088 -221.645498) (xy 35.871702 -221.626026) (xy 35.923664 -221.614166)
			(xy 35.976814 -221.610183) (xy 36.029964 -221.614166) (xy 36.081926 -221.626026) (xy 36.13154 -221.645498)
			(xy 36.177698 -221.672147) (xy 36.219369 -221.705378) (xy 36.255621 -221.744449) (xy 36.285645 -221.788486)
			(xy 36.308771 -221.836507) (xy 36.324481 -221.887437) (xy 36.332424 -221.940141) (xy 36.332922 -221.96679)
			(xy 36.332424 -221.993439) (xy 50.708804 -221.993439) (xy 50.708804 -221.940141) (xy 50.716747 -221.887437)
			(xy 50.732457 -221.836507) (xy 50.755583 -221.788486) (xy 50.785607 -221.744449) (xy 50.821859 -221.705378)
			(xy 50.86353 -221.672147) (xy 50.909688 -221.645498) (xy 50.959302 -221.626026) (xy 51.011264 -221.614166)
			(xy 51.064414 -221.610183) (xy 51.117564 -221.614166) (xy 51.169526 -221.626026) (xy 51.21914 -221.645498)
			(xy 51.265298 -221.672147) (xy 51.306969 -221.705378) (xy 51.343221 -221.744449) (xy 51.373245 -221.788486)
			(xy 51.396371 -221.836507) (xy 51.412081 -221.887437) (xy 51.420024 -221.940141) (xy 51.420522 -221.96679)
			(xy 51.420024 -221.993439) (xy 51.412081 -222.046143) (xy 51.396371 -222.097073) (xy 51.373245 -222.145094)
			(xy 51.343221 -222.189131) (xy 51.306969 -222.228202) (xy 51.265298 -222.261433) (xy 51.21914 -222.288082)
			(xy 51.169526 -222.307554) (xy 51.117564 -222.319414) (xy 51.064414 -222.323398) (xy 51.011264 -222.319414)
			(xy 50.959302 -222.307554) (xy 50.909688 -222.288082) (xy 50.86353 -222.261433) (xy 50.821859 -222.228202)
			(xy 50.785607 -222.189131) (xy 50.755583 -222.145094) (xy 50.732457 -222.097073) (xy 50.716747 -222.046143)
			(xy 50.708804 -221.993439) (xy 36.332424 -221.993439) (xy 36.324481 -222.046143) (xy 36.308771 -222.097073)
			(xy 36.285645 -222.145094) (xy 36.255621 -222.189131) (xy 36.219369 -222.228202) (xy 36.177698 -222.261433)
			(xy 36.13154 -222.288082) (xy 36.081926 -222.307554) (xy 36.029964 -222.319414) (xy 35.976814 -222.323398)
			(xy 35.923664 -222.319414) (xy 35.871702 -222.307554) (xy 35.822088 -222.288082) (xy 35.77593 -222.261433)
			(xy 35.734259 -222.228202) (xy 35.698007 -222.189131) (xy 35.667983 -222.145094) (xy 35.644857 -222.097073)
			(xy 35.629147 -222.046143) (xy 35.621204 -221.993439) (xy 21.244824 -221.993439) (xy 21.236881 -222.046143)
			(xy 21.221171 -222.097073) (xy 21.198045 -222.145094) (xy 21.168021 -222.189131) (xy 21.131769 -222.228202)
			(xy 21.090098 -222.261433) (xy 21.04394 -222.288082) (xy 20.994326 -222.307554) (xy 20.942364 -222.319414)
			(xy 20.889214 -222.323398) (xy 20.836064 -222.319414) (xy 20.784102 -222.307554) (xy 20.734488 -222.288082)
			(xy 20.68833 -222.261433) (xy 20.646659 -222.228202) (xy 20.610407 -222.189131) (xy 20.580383 -222.145094)
			(xy 20.557257 -222.097073) (xy 20.541547 -222.046143) (xy 20.533604 -221.993439) (xy 9.6774 -221.993439)
			(xy 9.6774 -222.843323) (xy 16.433536 -222.843323) (xy 16.433536 -222.790025) (xy 16.441479 -222.737321)
			(xy 16.457189 -222.686391) (xy 16.480315 -222.63837) (xy 16.510339 -222.594333) (xy 16.546591 -222.555262)
			(xy 16.588262 -222.522031) (xy 16.63442 -222.495382) (xy 16.684034 -222.47591) (xy 16.735996 -222.46405)
			(xy 16.789146 -222.460067) (xy 16.842296 -222.46405) (xy 16.894258 -222.47591) (xy 16.943872 -222.495382)
			(xy 16.99003 -222.522031) (xy 17.031701 -222.555262) (xy 17.067953 -222.594333) (xy 17.097977 -222.63837)
			(xy 17.121103 -222.686391) (xy 17.136813 -222.737321) (xy 17.144756 -222.790025) (xy 17.145254 -222.816674)
			(xy 17.144756 -222.843323) (xy 31.521136 -222.843323) (xy 31.521136 -222.790025) (xy 31.529079 -222.737321)
			(xy 31.544789 -222.686391) (xy 31.567915 -222.63837) (xy 31.597939 -222.594333) (xy 31.634191 -222.555262)
			(xy 31.675862 -222.522031) (xy 31.72202 -222.495382) (xy 31.771634 -222.47591) (xy 31.823596 -222.46405)
			(xy 31.876746 -222.460067) (xy 31.929896 -222.46405) (xy 31.981858 -222.47591) (xy 32.031472 -222.495382)
			(xy 32.07763 -222.522031) (xy 32.119301 -222.555262) (xy 32.155553 -222.594333) (xy 32.185577 -222.63837)
			(xy 32.208703 -222.686391) (xy 32.224413 -222.737321) (xy 32.232356 -222.790025) (xy 32.232854 -222.816674)
			(xy 32.232356 -222.843323) (xy 46.608736 -222.843323) (xy 46.608736 -222.790025) (xy 46.616679 -222.737321)
			(xy 46.632389 -222.686391) (xy 46.655515 -222.63837) (xy 46.685539 -222.594333) (xy 46.721791 -222.555262)
			(xy 46.763462 -222.522031) (xy 46.80962 -222.495382) (xy 46.859234 -222.47591) (xy 46.911196 -222.46405)
			(xy 46.964346 -222.460067) (xy 47.017496 -222.46405) (xy 47.069458 -222.47591) (xy 47.119072 -222.495382)
			(xy 47.16523 -222.522031) (xy 47.206901 -222.555262) (xy 47.243153 -222.594333) (xy 47.273177 -222.63837)
			(xy 47.296303 -222.686391) (xy 47.312013 -222.737321) (xy 47.319956 -222.790025) (xy 47.320454 -222.816674)
			(xy 47.319956 -222.843323) (xy 47.312013 -222.896027) (xy 47.296303 -222.946957) (xy 47.273177 -222.994978)
			(xy 47.243153 -223.039015) (xy 47.206901 -223.078086) (xy 47.16523 -223.111317) (xy 47.119072 -223.137966)
			(xy 47.069458 -223.157438) (xy 47.017496 -223.169298) (xy 46.964346 -223.173282) (xy 46.911196 -223.169298)
			(xy 46.859234 -223.157438) (xy 46.80962 -223.137966) (xy 46.763462 -223.111317) (xy 46.721791 -223.078086)
			(xy 46.685539 -223.039015) (xy 46.655515 -222.994978) (xy 46.632389 -222.946957) (xy 46.616679 -222.896027)
			(xy 46.608736 -222.843323) (xy 32.232356 -222.843323) (xy 32.224413 -222.896027) (xy 32.208703 -222.946957)
			(xy 32.185577 -222.994978) (xy 32.155553 -223.039015) (xy 32.119301 -223.078086) (xy 32.07763 -223.111317)
			(xy 32.031472 -223.137966) (xy 31.981858 -223.157438) (xy 31.929896 -223.169298) (xy 31.876746 -223.173282)
			(xy 31.823596 -223.169298) (xy 31.771634 -223.157438) (xy 31.72202 -223.137966) (xy 31.675862 -223.111317)
			(xy 31.634191 -223.078086) (xy 31.597939 -223.039015) (xy 31.567915 -222.994978) (xy 31.544789 -222.946957)
			(xy 31.529079 -222.896027) (xy 31.521136 -222.843323) (xy 17.144756 -222.843323) (xy 17.136813 -222.896027)
			(xy 17.121103 -222.946957) (xy 17.097977 -222.994978) (xy 17.067953 -223.039015) (xy 17.031701 -223.078086)
			(xy 16.99003 -223.111317) (xy 16.943872 -223.137966) (xy 16.894258 -223.157438) (xy 16.842296 -223.169298)
			(xy 16.789146 -223.173282) (xy 16.735996 -223.169298) (xy 16.684034 -223.157438) (xy 16.63442 -223.137966)
			(xy 16.588262 -223.111317) (xy 16.546591 -223.078086) (xy 16.510339 -223.039015) (xy 16.480315 -222.994978)
			(xy 16.457189 -222.946957) (xy 16.441479 -222.896027) (xy 16.433536 -222.843323) (xy 9.6774 -222.843323)
			(xy 9.6774 -223.693207) (xy 20.533604 -223.693207) (xy 20.533604 -223.639909) (xy 20.541547 -223.587205)
			(xy 20.557257 -223.536275) (xy 20.580383 -223.488254) (xy 20.610407 -223.444217) (xy 20.646659 -223.405146)
			(xy 20.68833 -223.371915) (xy 20.734488 -223.345266) (xy 20.784102 -223.325794) (xy 20.836064 -223.313934)
			(xy 20.889214 -223.309951) (xy 20.942364 -223.313934) (xy 20.994326 -223.325794) (xy 21.04394 -223.345266)
			(xy 21.090098 -223.371915) (xy 21.131769 -223.405146) (xy 21.168021 -223.444217) (xy 21.198045 -223.488254)
			(xy 21.221171 -223.536275) (xy 21.236881 -223.587205) (xy 21.244824 -223.639909) (xy 21.245322 -223.666558)
			(xy 21.244824 -223.693207) (xy 35.621204 -223.693207) (xy 35.621204 -223.639909) (xy 35.629147 -223.587205)
			(xy 35.644857 -223.536275) (xy 35.667983 -223.488254) (xy 35.698007 -223.444217) (xy 35.734259 -223.405146)
			(xy 35.77593 -223.371915) (xy 35.822088 -223.345266) (xy 35.871702 -223.325794) (xy 35.923664 -223.313934)
			(xy 35.976814 -223.309951) (xy 36.029964 -223.313934) (xy 36.081926 -223.325794) (xy 36.13154 -223.345266)
			(xy 36.177698 -223.371915) (xy 36.219369 -223.405146) (xy 36.255621 -223.444217) (xy 36.285645 -223.488254)
			(xy 36.308771 -223.536275) (xy 36.324481 -223.587205) (xy 36.332424 -223.639909) (xy 36.332922 -223.666558)
			(xy 36.332424 -223.693207) (xy 50.708804 -223.693207) (xy 50.708804 -223.639909) (xy 50.716747 -223.587205)
			(xy 50.732457 -223.536275) (xy 50.755583 -223.488254) (xy 50.785607 -223.444217) (xy 50.821859 -223.405146)
			(xy 50.86353 -223.371915) (xy 50.909688 -223.345266) (xy 50.959302 -223.325794) (xy 51.011264 -223.313934)
			(xy 51.064414 -223.309951) (xy 51.117564 -223.313934) (xy 51.169526 -223.325794) (xy 51.21914 -223.345266)
			(xy 51.265298 -223.371915) (xy 51.306969 -223.405146) (xy 51.343221 -223.444217) (xy 51.373245 -223.488254)
			(xy 51.396371 -223.536275) (xy 51.412081 -223.587205) (xy 51.420024 -223.639909) (xy 51.420522 -223.666558)
			(xy 51.420024 -223.693207) (xy 51.412081 -223.745911) (xy 51.396371 -223.796841) (xy 51.373245 -223.844862)
			(xy 51.343221 -223.888899) (xy 51.306969 -223.92797) (xy 51.265298 -223.961201) (xy 51.21914 -223.98785)
			(xy 51.169526 -224.007322) (xy 51.117564 -224.019182) (xy 51.064414 -224.023166) (xy 51.011264 -224.019182)
			(xy 50.959302 -224.007322) (xy 50.909688 -223.98785) (xy 50.86353 -223.961201) (xy 50.821859 -223.92797)
			(xy 50.785607 -223.888899) (xy 50.755583 -223.844862) (xy 50.732457 -223.796841) (xy 50.716747 -223.745911)
			(xy 50.708804 -223.693207) (xy 36.332424 -223.693207) (xy 36.324481 -223.745911) (xy 36.308771 -223.796841)
			(xy 36.285645 -223.844862) (xy 36.255621 -223.888899) (xy 36.219369 -223.92797) (xy 36.177698 -223.961201)
			(xy 36.13154 -223.98785) (xy 36.081926 -224.007322) (xy 36.029964 -224.019182) (xy 35.976814 -224.023166)
			(xy 35.923664 -224.019182) (xy 35.871702 -224.007322) (xy 35.822088 -223.98785) (xy 35.77593 -223.961201)
			(xy 35.734259 -223.92797) (xy 35.698007 -223.888899) (xy 35.667983 -223.844862) (xy 35.644857 -223.796841)
			(xy 35.629147 -223.745911) (xy 35.621204 -223.693207) (xy 21.244824 -223.693207) (xy 21.236881 -223.745911)
			(xy 21.221171 -223.796841) (xy 21.198045 -223.844862) (xy 21.168021 -223.888899) (xy 21.131769 -223.92797)
			(xy 21.090098 -223.961201) (xy 21.04394 -223.98785) (xy 20.994326 -224.007322) (xy 20.942364 -224.019182)
			(xy 20.889214 -224.023166) (xy 20.836064 -224.019182) (xy 20.784102 -224.007322) (xy 20.734488 -223.98785)
			(xy 20.68833 -223.961201) (xy 20.646659 -223.92797) (xy 20.610407 -223.888899) (xy 20.580383 -223.844862)
			(xy 20.557257 -223.796841) (xy 20.541547 -223.745911) (xy 20.533604 -223.693207) (xy 9.6774 -223.693207)
			(xy 9.6774 -224.543345) (xy 16.433536 -224.543345) (xy 16.433536 -224.490047) (xy 16.441479 -224.437343)
			(xy 16.457189 -224.386413) (xy 16.480315 -224.338392) (xy 16.510339 -224.294355) (xy 16.546591 -224.255284)
			(xy 16.588262 -224.222053) (xy 16.63442 -224.195404) (xy 16.684034 -224.175932) (xy 16.735996 -224.164072)
			(xy 16.789146 -224.160089) (xy 16.842296 -224.164072) (xy 16.894258 -224.175932) (xy 16.943872 -224.195404)
			(xy 16.99003 -224.222053) (xy 17.031701 -224.255284) (xy 17.067953 -224.294355) (xy 17.097977 -224.338392)
			(xy 17.121103 -224.386413) (xy 17.136813 -224.437343) (xy 17.144756 -224.490047) (xy 17.145254 -224.516696)
			(xy 17.144756 -224.543345) (xy 31.521136 -224.543345) (xy 31.521136 -224.490047) (xy 31.529079 -224.437343)
			(xy 31.544789 -224.386413) (xy 31.567915 -224.338392) (xy 31.597939 -224.294355) (xy 31.634191 -224.255284)
			(xy 31.675862 -224.222053) (xy 31.72202 -224.195404) (xy 31.771634 -224.175932) (xy 31.823596 -224.164072)
			(xy 31.876746 -224.160089) (xy 31.929896 -224.164072) (xy 31.981858 -224.175932) (xy 32.031472 -224.195404)
			(xy 32.07763 -224.222053) (xy 32.119301 -224.255284) (xy 32.155553 -224.294355) (xy 32.185577 -224.338392)
			(xy 32.208703 -224.386413) (xy 32.224413 -224.437343) (xy 32.232356 -224.490047) (xy 32.232854 -224.516696)
			(xy 32.232356 -224.543345) (xy 46.608736 -224.543345) (xy 46.608736 -224.490047) (xy 46.616679 -224.437343)
			(xy 46.632389 -224.386413) (xy 46.655515 -224.338392) (xy 46.685539 -224.294355) (xy 46.721791 -224.255284)
			(xy 46.763462 -224.222053) (xy 46.80962 -224.195404) (xy 46.859234 -224.175932) (xy 46.911196 -224.164072)
			(xy 46.964346 -224.160089) (xy 47.017496 -224.164072) (xy 47.069458 -224.175932) (xy 47.119072 -224.195404)
			(xy 47.16523 -224.222053) (xy 47.206901 -224.255284) (xy 47.243153 -224.294355) (xy 47.273177 -224.338392)
			(xy 47.296303 -224.386413) (xy 47.312013 -224.437343) (xy 47.319956 -224.490047) (xy 47.320454 -224.516696)
			(xy 47.319956 -224.543345) (xy 61.696336 -224.543345) (xy 61.696336 -224.490047) (xy 61.704279 -224.437343)
			(xy 61.719989 -224.386413) (xy 61.743115 -224.338392) (xy 61.773139 -224.294355) (xy 61.809391 -224.255284)
			(xy 61.851062 -224.222053) (xy 61.89722 -224.195404) (xy 61.946834 -224.175932) (xy 61.998796 -224.164072)
			(xy 62.051946 -224.160089) (xy 62.105096 -224.164072) (xy 62.157058 -224.175932) (xy 62.206672 -224.195404)
			(xy 62.25283 -224.222053) (xy 62.294501 -224.255284) (xy 62.330753 -224.294355) (xy 62.360777 -224.338392)
			(xy 62.383903 -224.386413) (xy 62.399613 -224.437343) (xy 62.407556 -224.490047) (xy 62.408054 -224.516696)
			(xy 62.407556 -224.543345) (xy 62.399613 -224.596049) (xy 62.383903 -224.646979) (xy 62.360777 -224.695)
			(xy 62.330753 -224.739037) (xy 62.294501 -224.778108) (xy 62.25283 -224.811339) (xy 62.206672 -224.837988)
			(xy 62.157058 -224.85746) (xy 62.105096 -224.86932) (xy 62.051946 -224.873304) (xy 61.998796 -224.86932)
			(xy 61.946834 -224.85746) (xy 61.89722 -224.837988) (xy 61.851062 -224.811339) (xy 61.809391 -224.778108)
			(xy 61.773139 -224.739037) (xy 61.743115 -224.695) (xy 61.719989 -224.646979) (xy 61.704279 -224.596049)
			(xy 61.696336 -224.543345) (xy 47.319956 -224.543345) (xy 47.312013 -224.596049) (xy 47.296303 -224.646979)
			(xy 47.273177 -224.695) (xy 47.243153 -224.739037) (xy 47.206901 -224.778108) (xy 47.16523 -224.811339)
			(xy 47.119072 -224.837988) (xy 47.069458 -224.85746) (xy 47.017496 -224.86932) (xy 46.964346 -224.873304)
			(xy 46.911196 -224.86932) (xy 46.859234 -224.85746) (xy 46.80962 -224.837988) (xy 46.763462 -224.811339)
			(xy 46.721791 -224.778108) (xy 46.685539 -224.739037) (xy 46.655515 -224.695) (xy 46.632389 -224.646979)
			(xy 46.616679 -224.596049) (xy 46.608736 -224.543345) (xy 32.232356 -224.543345) (xy 32.224413 -224.596049)
			(xy 32.208703 -224.646979) (xy 32.185577 -224.695) (xy 32.155553 -224.739037) (xy 32.119301 -224.778108)
			(xy 32.07763 -224.811339) (xy 32.031472 -224.837988) (xy 31.981858 -224.85746) (xy 31.929896 -224.86932)
			(xy 31.876746 -224.873304) (xy 31.823596 -224.86932) (xy 31.771634 -224.85746) (xy 31.72202 -224.837988)
			(xy 31.675862 -224.811339) (xy 31.634191 -224.778108) (xy 31.597939 -224.739037) (xy 31.567915 -224.695)
			(xy 31.544789 -224.646979) (xy 31.529079 -224.596049) (xy 31.521136 -224.543345) (xy 17.144756 -224.543345)
			(xy 17.136813 -224.596049) (xy 17.121103 -224.646979) (xy 17.097977 -224.695) (xy 17.067953 -224.739037)
			(xy 17.031701 -224.778108) (xy 16.99003 -224.811339) (xy 16.943872 -224.837988) (xy 16.894258 -224.85746)
			(xy 16.842296 -224.86932) (xy 16.789146 -224.873304) (xy 16.735996 -224.86932) (xy 16.684034 -224.85746)
			(xy 16.63442 -224.837988) (xy 16.588262 -224.811339) (xy 16.546591 -224.778108) (xy 16.510339 -224.739037)
			(xy 16.480315 -224.695) (xy 16.457189 -224.646979) (xy 16.441479 -224.596049) (xy 16.433536 -224.543345)
			(xy 9.6774 -224.543345) (xy 9.6774 -225.393229) (xy 20.533604 -225.393229) (xy 20.533604 -225.339931)
			(xy 20.541547 -225.287227) (xy 20.557257 -225.236297) (xy 20.580383 -225.188276) (xy 20.610407 -225.144239)
			(xy 20.646659 -225.105168) (xy 20.68833 -225.071937) (xy 20.734488 -225.045288) (xy 20.784102 -225.025816)
			(xy 20.836064 -225.013956) (xy 20.889214 -225.009973) (xy 20.942364 -225.013956) (xy 20.994326 -225.025816)
			(xy 21.04394 -225.045288) (xy 21.090098 -225.071937) (xy 21.131769 -225.105168) (xy 21.168021 -225.144239)
			(xy 21.198045 -225.188276) (xy 21.221171 -225.236297) (xy 21.236881 -225.287227) (xy 21.244824 -225.339931)
			(xy 21.245322 -225.36658) (xy 21.244824 -225.393229) (xy 35.621204 -225.393229) (xy 35.621204 -225.339931)
			(xy 35.629147 -225.287227) (xy 35.644857 -225.236297) (xy 35.667983 -225.188276) (xy 35.698007 -225.144239)
			(xy 35.734259 -225.105168) (xy 35.77593 -225.071937) (xy 35.822088 -225.045288) (xy 35.871702 -225.025816)
			(xy 35.923664 -225.013956) (xy 35.976814 -225.009973) (xy 36.029964 -225.013956) (xy 36.081926 -225.025816)
			(xy 36.13154 -225.045288) (xy 36.177698 -225.071937) (xy 36.219369 -225.105168) (xy 36.255621 -225.144239)
			(xy 36.285645 -225.188276) (xy 36.308771 -225.236297) (xy 36.324481 -225.287227) (xy 36.332424 -225.339931)
			(xy 36.332922 -225.36658) (xy 36.332424 -225.393229) (xy 50.708804 -225.393229) (xy 50.708804 -225.339931)
			(xy 50.716747 -225.287227) (xy 50.732457 -225.236297) (xy 50.755583 -225.188276) (xy 50.785607 -225.144239)
			(xy 50.821859 -225.105168) (xy 50.86353 -225.071937) (xy 50.909688 -225.045288) (xy 50.959302 -225.025816)
			(xy 51.011264 -225.013956) (xy 51.064414 -225.009973) (xy 51.117564 -225.013956) (xy 51.169526 -225.025816)
			(xy 51.21914 -225.045288) (xy 51.265298 -225.071937) (xy 51.306969 -225.105168) (xy 51.343221 -225.144239)
			(xy 51.373245 -225.188276) (xy 51.396371 -225.236297) (xy 51.412081 -225.287227) (xy 51.420024 -225.339931)
			(xy 51.420522 -225.36658) (xy 51.420024 -225.393229) (xy 51.412081 -225.445933) (xy 51.396371 -225.496863)
			(xy 51.373245 -225.544884) (xy 51.343221 -225.588921) (xy 51.306969 -225.627992) (xy 51.265298 -225.661223)
			(xy 51.21914 -225.687872) (xy 51.169526 -225.707344) (xy 51.117564 -225.719204) (xy 51.064414 -225.723188)
			(xy 51.011264 -225.719204) (xy 50.959302 -225.707344) (xy 50.909688 -225.687872) (xy 50.86353 -225.661223)
			(xy 50.821859 -225.627992) (xy 50.785607 -225.588921) (xy 50.755583 -225.544884) (xy 50.732457 -225.496863)
			(xy 50.716747 -225.445933) (xy 50.708804 -225.393229) (xy 36.332424 -225.393229) (xy 36.324481 -225.445933)
			(xy 36.308771 -225.496863) (xy 36.285645 -225.544884) (xy 36.255621 -225.588921) (xy 36.219369 -225.627992)
			(xy 36.177698 -225.661223) (xy 36.13154 -225.687872) (xy 36.081926 -225.707344) (xy 36.029964 -225.719204)
			(xy 35.976814 -225.723188) (xy 35.923664 -225.719204) (xy 35.871702 -225.707344) (xy 35.822088 -225.687872)
			(xy 35.77593 -225.661223) (xy 35.734259 -225.627992) (xy 35.698007 -225.588921) (xy 35.667983 -225.544884)
			(xy 35.644857 -225.496863) (xy 35.629147 -225.445933) (xy 35.621204 -225.393229) (xy 21.244824 -225.393229)
			(xy 21.236881 -225.445933) (xy 21.221171 -225.496863) (xy 21.198045 -225.544884) (xy 21.168021 -225.588921)
			(xy 21.131769 -225.627992) (xy 21.090098 -225.661223) (xy 21.04394 -225.687872) (xy 20.994326 -225.707344)
			(xy 20.942364 -225.719204) (xy 20.889214 -225.723188) (xy 20.836064 -225.719204) (xy 20.784102 -225.707344)
			(xy 20.734488 -225.687872) (xy 20.68833 -225.661223) (xy 20.646659 -225.627992) (xy 20.610407 -225.588921)
			(xy 20.580383 -225.544884) (xy 20.557257 -225.496863) (xy 20.541547 -225.445933) (xy 20.533604 -225.393229)
			(xy 9.6774 -225.393229) (xy 9.6774 -226.243367) (xy 16.433536 -226.243367) (xy 16.433536 -226.190069)
			(xy 16.441479 -226.137365) (xy 16.457189 -226.086435) (xy 16.480315 -226.038414) (xy 16.510339 -225.994377)
			(xy 16.546591 -225.955306) (xy 16.588262 -225.922075) (xy 16.63442 -225.895426) (xy 16.684034 -225.875954)
			(xy 16.735996 -225.864094) (xy 16.789146 -225.860111) (xy 16.842296 -225.864094) (xy 16.894258 -225.875954)
			(xy 16.943872 -225.895426) (xy 16.99003 -225.922075) (xy 17.031701 -225.955306) (xy 17.067953 -225.994377)
			(xy 17.097977 -226.038414) (xy 17.121103 -226.086435) (xy 17.136813 -226.137365) (xy 17.144756 -226.190069)
			(xy 17.145254 -226.216718) (xy 17.144756 -226.243367) (xy 31.521136 -226.243367) (xy 31.521136 -226.190069)
			(xy 31.529079 -226.137365) (xy 31.544789 -226.086435) (xy 31.567915 -226.038414) (xy 31.597939 -225.994377)
			(xy 31.634191 -225.955306) (xy 31.675862 -225.922075) (xy 31.72202 -225.895426) (xy 31.771634 -225.875954)
			(xy 31.823596 -225.864094) (xy 31.876746 -225.860111) (xy 31.929896 -225.864094) (xy 31.981858 -225.875954)
			(xy 32.031472 -225.895426) (xy 32.07763 -225.922075) (xy 32.119301 -225.955306) (xy 32.155553 -225.994377)
			(xy 32.185577 -226.038414) (xy 32.208703 -226.086435) (xy 32.224413 -226.137365) (xy 32.232356 -226.190069)
			(xy 32.232854 -226.216718) (xy 32.232356 -226.243367) (xy 46.608736 -226.243367) (xy 46.608736 -226.190069)
			(xy 46.616679 -226.137365) (xy 46.632389 -226.086435) (xy 46.655515 -226.038414) (xy 46.685539 -225.994377)
			(xy 46.721791 -225.955306) (xy 46.763462 -225.922075) (xy 46.80962 -225.895426) (xy 46.859234 -225.875954)
			(xy 46.911196 -225.864094) (xy 46.964346 -225.860111) (xy 47.017496 -225.864094) (xy 47.069458 -225.875954)
			(xy 47.119072 -225.895426) (xy 47.16523 -225.922075) (xy 47.206901 -225.955306) (xy 47.243153 -225.994377)
			(xy 47.273177 -226.038414) (xy 47.296303 -226.086435) (xy 47.312013 -226.137365) (xy 47.319956 -226.190069)
			(xy 47.320454 -226.216718) (xy 47.319956 -226.243367) (xy 61.696336 -226.243367) (xy 61.696336 -226.190069)
			(xy 61.704279 -226.137365) (xy 61.719989 -226.086435) (xy 61.743115 -226.038414) (xy 61.773139 -225.994377)
			(xy 61.809391 -225.955306) (xy 61.851062 -225.922075) (xy 61.89722 -225.895426) (xy 61.946834 -225.875954)
			(xy 61.998796 -225.864094) (xy 62.051946 -225.860111) (xy 62.105096 -225.864094) (xy 62.157058 -225.875954)
			(xy 62.206672 -225.895426) (xy 62.25283 -225.922075) (xy 62.294501 -225.955306) (xy 62.330753 -225.994377)
			(xy 62.360777 -226.038414) (xy 62.383903 -226.086435) (xy 62.399613 -226.137365) (xy 62.407556 -226.190069)
			(xy 62.408054 -226.216718) (xy 62.407556 -226.243367) (xy 62.399613 -226.296071) (xy 62.383903 -226.347001)
			(xy 62.360777 -226.395022) (xy 62.330753 -226.439059) (xy 62.294501 -226.47813) (xy 62.25283 -226.511361)
			(xy 62.206672 -226.53801) (xy 62.157058 -226.557482) (xy 62.105096 -226.569342) (xy 62.051946 -226.573326)
			(xy 61.998796 -226.569342) (xy 61.946834 -226.557482) (xy 61.89722 -226.53801) (xy 61.851062 -226.511361)
			(xy 61.809391 -226.47813) (xy 61.773139 -226.439059) (xy 61.743115 -226.395022) (xy 61.719989 -226.347001)
			(xy 61.704279 -226.296071) (xy 61.696336 -226.243367) (xy 47.319956 -226.243367) (xy 47.312013 -226.296071)
			(xy 47.296303 -226.347001) (xy 47.273177 -226.395022) (xy 47.243153 -226.439059) (xy 47.206901 -226.47813)
			(xy 47.16523 -226.511361) (xy 47.119072 -226.53801) (xy 47.069458 -226.557482) (xy 47.017496 -226.569342)
			(xy 46.964346 -226.573326) (xy 46.911196 -226.569342) (xy 46.859234 -226.557482) (xy 46.80962 -226.53801)
			(xy 46.763462 -226.511361) (xy 46.721791 -226.47813) (xy 46.685539 -226.439059) (xy 46.655515 -226.395022)
			(xy 46.632389 -226.347001) (xy 46.616679 -226.296071) (xy 46.608736 -226.243367) (xy 32.232356 -226.243367)
			(xy 32.224413 -226.296071) (xy 32.208703 -226.347001) (xy 32.185577 -226.395022) (xy 32.155553 -226.439059)
			(xy 32.119301 -226.47813) (xy 32.07763 -226.511361) (xy 32.031472 -226.53801) (xy 31.981858 -226.557482)
			(xy 31.929896 -226.569342) (xy 31.876746 -226.573326) (xy 31.823596 -226.569342) (xy 31.771634 -226.557482)
			(xy 31.72202 -226.53801) (xy 31.675862 -226.511361) (xy 31.634191 -226.47813) (xy 31.597939 -226.439059)
			(xy 31.567915 -226.395022) (xy 31.544789 -226.347001) (xy 31.529079 -226.296071) (xy 31.521136 -226.243367)
			(xy 17.144756 -226.243367) (xy 17.136813 -226.296071) (xy 17.121103 -226.347001) (xy 17.097977 -226.395022)
			(xy 17.067953 -226.439059) (xy 17.031701 -226.47813) (xy 16.99003 -226.511361) (xy 16.943872 -226.53801)
			(xy 16.894258 -226.557482) (xy 16.842296 -226.569342) (xy 16.789146 -226.573326) (xy 16.735996 -226.569342)
			(xy 16.684034 -226.557482) (xy 16.63442 -226.53801) (xy 16.588262 -226.511361) (xy 16.546591 -226.47813)
			(xy 16.510339 -226.439059) (xy 16.480315 -226.395022) (xy 16.457189 -226.347001) (xy 16.441479 -226.296071)
			(xy 16.433536 -226.243367) (xy 9.6774 -226.243367) (xy 9.6774 -227.093251) (xy 20.533604 -227.093251)
			(xy 20.533604 -227.039953) (xy 20.541547 -226.987249) (xy 20.557257 -226.936319) (xy 20.580383 -226.888298)
			(xy 20.610407 -226.844261) (xy 20.646659 -226.80519) (xy 20.68833 -226.771959) (xy 20.734488 -226.74531)
			(xy 20.784102 -226.725838) (xy 20.836064 -226.713978) (xy 20.889214 -226.709995) (xy 20.942364 -226.713978)
			(xy 20.994326 -226.725838) (xy 21.04394 -226.74531) (xy 21.090098 -226.771959) (xy 21.131769 -226.80519)
			(xy 21.168021 -226.844261) (xy 21.198045 -226.888298) (xy 21.221171 -226.936319) (xy 21.236881 -226.987249)
			(xy 21.244824 -227.039953) (xy 21.245322 -227.066602) (xy 21.244824 -227.093251) (xy 35.621204 -227.093251)
			(xy 35.621204 -227.039953) (xy 35.629147 -226.987249) (xy 35.644857 -226.936319) (xy 35.667983 -226.888298)
			(xy 35.698007 -226.844261) (xy 35.734259 -226.80519) (xy 35.77593 -226.771959) (xy 35.822088 -226.74531)
			(xy 35.871702 -226.725838) (xy 35.923664 -226.713978) (xy 35.976814 -226.709995) (xy 36.029964 -226.713978)
			(xy 36.081926 -226.725838) (xy 36.13154 -226.74531) (xy 36.177698 -226.771959) (xy 36.219369 -226.80519)
			(xy 36.255621 -226.844261) (xy 36.285645 -226.888298) (xy 36.308771 -226.936319) (xy 36.324481 -226.987249)
			(xy 36.332424 -227.039953) (xy 36.332922 -227.066602) (xy 36.332424 -227.093251) (xy 50.708804 -227.093251)
			(xy 50.708804 -227.039953) (xy 50.716747 -226.987249) (xy 50.732457 -226.936319) (xy 50.755583 -226.888298)
			(xy 50.785607 -226.844261) (xy 50.821859 -226.80519) (xy 50.86353 -226.771959) (xy 50.909688 -226.74531)
			(xy 50.959302 -226.725838) (xy 51.011264 -226.713978) (xy 51.064414 -226.709995) (xy 51.117564 -226.713978)
			(xy 51.169526 -226.725838) (xy 51.21914 -226.74531) (xy 51.265298 -226.771959) (xy 51.306969 -226.80519)
			(xy 51.343221 -226.844261) (xy 51.373245 -226.888298) (xy 51.396371 -226.936319) (xy 51.412081 -226.987249)
			(xy 51.420024 -227.039953) (xy 51.420522 -227.066602) (xy 51.420024 -227.093251) (xy 51.412081 -227.145955)
			(xy 51.396371 -227.196885) (xy 51.373245 -227.244906) (xy 51.343221 -227.288943) (xy 51.306969 -227.328014)
			(xy 51.265298 -227.361245) (xy 51.21914 -227.387894) (xy 51.169526 -227.407366) (xy 51.117564 -227.419226)
			(xy 51.064414 -227.42321) (xy 51.011264 -227.419226) (xy 50.959302 -227.407366) (xy 50.909688 -227.387894)
			(xy 50.86353 -227.361245) (xy 50.821859 -227.328014) (xy 50.785607 -227.288943) (xy 50.755583 -227.244906)
			(xy 50.732457 -227.196885) (xy 50.716747 -227.145955) (xy 50.708804 -227.093251) (xy 36.332424 -227.093251)
			(xy 36.324481 -227.145955) (xy 36.308771 -227.196885) (xy 36.285645 -227.244906) (xy 36.255621 -227.288943)
			(xy 36.219369 -227.328014) (xy 36.177698 -227.361245) (xy 36.13154 -227.387894) (xy 36.081926 -227.407366)
			(xy 36.029964 -227.419226) (xy 35.976814 -227.42321) (xy 35.923664 -227.419226) (xy 35.871702 -227.407366)
			(xy 35.822088 -227.387894) (xy 35.77593 -227.361245) (xy 35.734259 -227.328014) (xy 35.698007 -227.288943)
			(xy 35.667983 -227.244906) (xy 35.644857 -227.196885) (xy 35.629147 -227.145955) (xy 35.621204 -227.093251)
			(xy 21.244824 -227.093251) (xy 21.236881 -227.145955) (xy 21.221171 -227.196885) (xy 21.198045 -227.244906)
			(xy 21.168021 -227.288943) (xy 21.131769 -227.328014) (xy 21.090098 -227.361245) (xy 21.04394 -227.387894)
			(xy 20.994326 -227.407366) (xy 20.942364 -227.419226) (xy 20.889214 -227.42321) (xy 20.836064 -227.419226)
			(xy 20.784102 -227.407366) (xy 20.734488 -227.387894) (xy 20.68833 -227.361245) (xy 20.646659 -227.328014)
			(xy 20.610407 -227.288943) (xy 20.580383 -227.244906) (xy 20.557257 -227.196885) (xy 20.541547 -227.145955)
			(xy 20.533604 -227.093251) (xy 9.6774 -227.093251) (xy 9.6774 -227.943389) (xy 16.433536 -227.943389)
			(xy 16.433536 -227.890091) (xy 16.441479 -227.837387) (xy 16.457189 -227.786457) (xy 16.480315 -227.738436)
			(xy 16.510339 -227.694399) (xy 16.546591 -227.655328) (xy 16.588262 -227.622097) (xy 16.63442 -227.595448)
			(xy 16.684034 -227.575976) (xy 16.735996 -227.564116) (xy 16.789146 -227.560133) (xy 16.842296 -227.564116)
			(xy 16.894258 -227.575976) (xy 16.943872 -227.595448) (xy 16.99003 -227.622097) (xy 17.031701 -227.655328)
			(xy 17.067953 -227.694399) (xy 17.097977 -227.738436) (xy 17.121103 -227.786457) (xy 17.136813 -227.837387)
			(xy 17.144756 -227.890091) (xy 17.145254 -227.91674) (xy 17.144756 -227.943389) (xy 20.533604 -227.943389)
			(xy 20.533604 -227.890091) (xy 20.541547 -227.837387) (xy 20.557257 -227.786457) (xy 20.580383 -227.738436)
			(xy 20.610407 -227.694399) (xy 20.646659 -227.655328) (xy 20.68833 -227.622097) (xy 20.734488 -227.595448)
			(xy 20.784102 -227.575976) (xy 20.836064 -227.564116) (xy 20.889214 -227.560133) (xy 20.942364 -227.564116)
			(xy 20.994326 -227.575976) (xy 21.04394 -227.595448) (xy 21.090098 -227.622097) (xy 21.131769 -227.655328)
			(xy 21.168021 -227.694399) (xy 21.198045 -227.738436) (xy 21.221171 -227.786457) (xy 21.236881 -227.837387)
			(xy 21.244824 -227.890091) (xy 21.245322 -227.91674) (xy 21.244824 -227.943389) (xy 31.521136 -227.943389)
			(xy 31.521136 -227.890091) (xy 31.529079 -227.837387) (xy 31.544789 -227.786457) (xy 31.567915 -227.738436)
			(xy 31.597939 -227.694399) (xy 31.634191 -227.655328) (xy 31.675862 -227.622097) (xy 31.72202 -227.595448)
			(xy 31.771634 -227.575976) (xy 31.823596 -227.564116) (xy 31.876746 -227.560133) (xy 31.929896 -227.564116)
			(xy 31.981858 -227.575976) (xy 32.031472 -227.595448) (xy 32.07763 -227.622097) (xy 32.119301 -227.655328)
			(xy 32.155553 -227.694399) (xy 32.185577 -227.738436) (xy 32.208703 -227.786457) (xy 32.224413 -227.837387)
			(xy 32.232356 -227.890091) (xy 32.232854 -227.91674) (xy 32.232356 -227.943389) (xy 35.621204 -227.943389)
			(xy 35.621204 -227.890091) (xy 35.629147 -227.837387) (xy 35.644857 -227.786457) (xy 35.667983 -227.738436)
			(xy 35.698007 -227.694399) (xy 35.734259 -227.655328) (xy 35.77593 -227.622097) (xy 35.822088 -227.595448)
			(xy 35.871702 -227.575976) (xy 35.923664 -227.564116) (xy 35.976814 -227.560133) (xy 36.029964 -227.564116)
			(xy 36.081926 -227.575976) (xy 36.13154 -227.595448) (xy 36.177698 -227.622097) (xy 36.219369 -227.655328)
			(xy 36.255621 -227.694399) (xy 36.285645 -227.738436) (xy 36.308771 -227.786457) (xy 36.324481 -227.837387)
			(xy 36.332424 -227.890091) (xy 36.332922 -227.91674) (xy 36.332424 -227.943389) (xy 46.608736 -227.943389)
			(xy 46.608736 -227.890091) (xy 46.616679 -227.837387) (xy 46.632389 -227.786457) (xy 46.655515 -227.738436)
			(xy 46.685539 -227.694399) (xy 46.721791 -227.655328) (xy 46.763462 -227.622097) (xy 46.80962 -227.595448)
			(xy 46.859234 -227.575976) (xy 46.911196 -227.564116) (xy 46.964346 -227.560133) (xy 47.017496 -227.564116)
			(xy 47.069458 -227.575976) (xy 47.119072 -227.595448) (xy 47.16523 -227.622097) (xy 47.206901 -227.655328)
			(xy 47.243153 -227.694399) (xy 47.273177 -227.738436) (xy 47.296303 -227.786457) (xy 47.312013 -227.837387)
			(xy 47.319956 -227.890091) (xy 47.320454 -227.91674) (xy 47.319956 -227.943389) (xy 50.708804 -227.943389)
			(xy 50.708804 -227.890091) (xy 50.716747 -227.837387) (xy 50.732457 -227.786457) (xy 50.755583 -227.738436)
			(xy 50.785607 -227.694399) (xy 50.821859 -227.655328) (xy 50.86353 -227.622097) (xy 50.909688 -227.595448)
			(xy 50.959302 -227.575976) (xy 51.011264 -227.564116) (xy 51.064414 -227.560133) (xy 51.117564 -227.564116)
			(xy 51.169526 -227.575976) (xy 51.21914 -227.595448) (xy 51.265298 -227.622097) (xy 51.306969 -227.655328)
			(xy 51.343221 -227.694399) (xy 51.373245 -227.738436) (xy 51.396371 -227.786457) (xy 51.412081 -227.837387)
			(xy 51.420024 -227.890091) (xy 51.420522 -227.91674) (xy 51.420024 -227.943389) (xy 61.696336 -227.943389)
			(xy 61.696336 -227.890091) (xy 61.704279 -227.837387) (xy 61.719989 -227.786457) (xy 61.743115 -227.738436)
			(xy 61.773139 -227.694399) (xy 61.809391 -227.655328) (xy 61.851062 -227.622097) (xy 61.89722 -227.595448)
			(xy 61.946834 -227.575976) (xy 61.998796 -227.564116) (xy 62.051946 -227.560133) (xy 62.105096 -227.564116)
			(xy 62.157058 -227.575976) (xy 62.206672 -227.595448) (xy 62.25283 -227.622097) (xy 62.294501 -227.655328)
			(xy 62.330753 -227.694399) (xy 62.360777 -227.738436) (xy 62.383903 -227.786457) (xy 62.399613 -227.837387)
			(xy 62.407556 -227.890091) (xy 62.408054 -227.91674) (xy 62.407556 -227.943389) (xy 62.399613 -227.996093)
			(xy 62.383903 -228.047023) (xy 62.360777 -228.095044) (xy 62.330753 -228.139081) (xy 62.294501 -228.178152)
			(xy 62.25283 -228.211383) (xy 62.206672 -228.238032) (xy 62.157058 -228.257504) (xy 62.105096 -228.269364)
			(xy 62.051946 -228.273348) (xy 61.998796 -228.269364) (xy 61.946834 -228.257504) (xy 61.89722 -228.238032)
			(xy 61.851062 -228.211383) (xy 61.809391 -228.178152) (xy 61.773139 -228.139081) (xy 61.743115 -228.095044)
			(xy 61.719989 -228.047023) (xy 61.704279 -227.996093) (xy 61.696336 -227.943389) (xy 51.420024 -227.943389)
			(xy 51.412081 -227.996093) (xy 51.396371 -228.047023) (xy 51.373245 -228.095044) (xy 51.343221 -228.139081)
			(xy 51.306969 -228.178152) (xy 51.265298 -228.211383) (xy 51.21914 -228.238032) (xy 51.169526 -228.257504)
			(xy 51.117564 -228.269364) (xy 51.064414 -228.273348) (xy 51.011264 -228.269364) (xy 50.959302 -228.257504)
			(xy 50.909688 -228.238032) (xy 50.86353 -228.211383) (xy 50.821859 -228.178152) (xy 50.785607 -228.139081)
			(xy 50.755583 -228.095044) (xy 50.732457 -228.047023) (xy 50.716747 -227.996093) (xy 50.708804 -227.943389)
			(xy 47.319956 -227.943389) (xy 47.312013 -227.996093) (xy 47.296303 -228.047023) (xy 47.273177 -228.095044)
			(xy 47.243153 -228.139081) (xy 47.206901 -228.178152) (xy 47.16523 -228.211383) (xy 47.119072 -228.238032)
			(xy 47.069458 -228.257504) (xy 47.017496 -228.269364) (xy 46.964346 -228.273348) (xy 46.911196 -228.269364)
			(xy 46.859234 -228.257504) (xy 46.80962 -228.238032) (xy 46.763462 -228.211383) (xy 46.721791 -228.178152)
			(xy 46.685539 -228.139081) (xy 46.655515 -228.095044) (xy 46.632389 -228.047023) (xy 46.616679 -227.996093)
			(xy 46.608736 -227.943389) (xy 36.332424 -227.943389) (xy 36.324481 -227.996093) (xy 36.308771 -228.047023)
			(xy 36.285645 -228.095044) (xy 36.255621 -228.139081) (xy 36.219369 -228.178152) (xy 36.177698 -228.211383)
			(xy 36.13154 -228.238032) (xy 36.081926 -228.257504) (xy 36.029964 -228.269364) (xy 35.976814 -228.273348)
			(xy 35.923664 -228.269364) (xy 35.871702 -228.257504) (xy 35.822088 -228.238032) (xy 35.77593 -228.211383)
			(xy 35.734259 -228.178152) (xy 35.698007 -228.139081) (xy 35.667983 -228.095044) (xy 35.644857 -228.047023)
			(xy 35.629147 -227.996093) (xy 35.621204 -227.943389) (xy 32.232356 -227.943389) (xy 32.224413 -227.996093)
			(xy 32.208703 -228.047023) (xy 32.185577 -228.095044) (xy 32.155553 -228.139081) (xy 32.119301 -228.178152)
			(xy 32.07763 -228.211383) (xy 32.031472 -228.238032) (xy 31.981858 -228.257504) (xy 31.929896 -228.269364)
			(xy 31.876746 -228.273348) (xy 31.823596 -228.269364) (xy 31.771634 -228.257504) (xy 31.72202 -228.238032)
			(xy 31.675862 -228.211383) (xy 31.634191 -228.178152) (xy 31.597939 -228.139081) (xy 31.567915 -228.095044)
			(xy 31.544789 -228.047023) (xy 31.529079 -227.996093) (xy 31.521136 -227.943389) (xy 21.244824 -227.943389)
			(xy 21.236881 -227.996093) (xy 21.221171 -228.047023) (xy 21.198045 -228.095044) (xy 21.168021 -228.139081)
			(xy 21.131769 -228.178152) (xy 21.090098 -228.211383) (xy 21.04394 -228.238032) (xy 20.994326 -228.257504)
			(xy 20.942364 -228.269364) (xy 20.889214 -228.273348) (xy 20.836064 -228.269364) (xy 20.784102 -228.257504)
			(xy 20.734488 -228.238032) (xy 20.68833 -228.211383) (xy 20.646659 -228.178152) (xy 20.610407 -228.139081)
			(xy 20.580383 -228.095044) (xy 20.557257 -228.047023) (xy 20.541547 -227.996093) (xy 20.533604 -227.943389)
			(xy 17.144756 -227.943389) (xy 17.136813 -227.996093) (xy 17.121103 -228.047023) (xy 17.097977 -228.095044)
			(xy 17.067953 -228.139081) (xy 17.031701 -228.178152) (xy 16.99003 -228.211383) (xy 16.943872 -228.238032)
			(xy 16.894258 -228.257504) (xy 16.842296 -228.269364) (xy 16.789146 -228.273348) (xy 16.735996 -228.269364)
			(xy 16.684034 -228.257504) (xy 16.63442 -228.238032) (xy 16.588262 -228.211383) (xy 16.546591 -228.178152)
			(xy 16.510339 -228.139081) (xy 16.480315 -228.095044) (xy 16.457189 -228.047023) (xy 16.441479 -227.996093)
			(xy 16.433536 -227.943389) (xy 9.6774 -227.943389) (xy 9.6774 -228.793273) (xy 16.433536 -228.793273)
			(xy 16.433536 -228.739975) (xy 16.441479 -228.687271) (xy 16.457189 -228.636341) (xy 16.480315 -228.58832)
			(xy 16.510339 -228.544283) (xy 16.546591 -228.505212) (xy 16.588262 -228.471981) (xy 16.63442 -228.445332)
			(xy 16.684034 -228.42586) (xy 16.735996 -228.414) (xy 16.789146 -228.410017) (xy 16.842296 -228.414)
			(xy 16.894258 -228.42586) (xy 16.943872 -228.445332) (xy 16.99003 -228.471981) (xy 17.031701 -228.505212)
			(xy 17.067953 -228.544283) (xy 17.097977 -228.58832) (xy 17.121103 -228.636341) (xy 17.136813 -228.687271)
			(xy 17.144756 -228.739975) (xy 17.145254 -228.766624) (xy 17.144756 -228.793273) (xy 31.521136 -228.793273)
			(xy 31.521136 -228.739975) (xy 31.529079 -228.687271) (xy 31.544789 -228.636341) (xy 31.567915 -228.58832)
			(xy 31.597939 -228.544283) (xy 31.634191 -228.505212) (xy 31.675862 -228.471981) (xy 31.72202 -228.445332)
			(xy 31.771634 -228.42586) (xy 31.823596 -228.414) (xy 31.876746 -228.410017) (xy 31.929896 -228.414)
			(xy 31.981858 -228.42586) (xy 32.031472 -228.445332) (xy 32.07763 -228.471981) (xy 32.119301 -228.505212)
			(xy 32.155553 -228.544283) (xy 32.185577 -228.58832) (xy 32.208703 -228.636341) (xy 32.224413 -228.687271)
			(xy 32.232356 -228.739975) (xy 32.232854 -228.766624) (xy 32.232356 -228.793273) (xy 46.608736 -228.793273)
			(xy 46.608736 -228.739975) (xy 46.616679 -228.687271) (xy 46.632389 -228.636341) (xy 46.655515 -228.58832)
			(xy 46.685539 -228.544283) (xy 46.721791 -228.505212) (xy 46.763462 -228.471981) (xy 46.80962 -228.445332)
			(xy 46.859234 -228.42586) (xy 46.911196 -228.414) (xy 46.964346 -228.410017) (xy 47.017496 -228.414)
			(xy 47.069458 -228.42586) (xy 47.119072 -228.445332) (xy 47.16523 -228.471981) (xy 47.206901 -228.505212)
			(xy 47.243153 -228.544283) (xy 47.273177 -228.58832) (xy 47.296303 -228.636341) (xy 47.312013 -228.687271)
			(xy 47.319956 -228.739975) (xy 47.320454 -228.766624) (xy 47.319956 -228.793273) (xy 61.696336 -228.793273)
			(xy 61.696336 -228.739975) (xy 61.704279 -228.687271) (xy 61.719989 -228.636341) (xy 61.743115 -228.58832)
			(xy 61.773139 -228.544283) (xy 61.809391 -228.505212) (xy 61.851062 -228.471981) (xy 61.89722 -228.445332)
			(xy 61.946834 -228.42586) (xy 61.998796 -228.414) (xy 62.051946 -228.410017) (xy 62.105096 -228.414)
			(xy 62.157058 -228.42586) (xy 62.206672 -228.445332) (xy 62.25283 -228.471981) (xy 62.294501 -228.505212)
			(xy 62.330753 -228.544283) (xy 62.360777 -228.58832) (xy 62.383903 -228.636341) (xy 62.399613 -228.687271)
			(xy 62.407556 -228.739975) (xy 62.408054 -228.766624) (xy 62.407556 -228.793273) (xy 62.399613 -228.845977)
			(xy 62.383903 -228.896907) (xy 62.360777 -228.944928) (xy 62.330753 -228.988965) (xy 62.294501 -229.028036)
			(xy 62.25283 -229.061267) (xy 62.206672 -229.087916) (xy 62.157058 -229.107388) (xy 62.105096 -229.119248)
			(xy 62.051946 -229.123232) (xy 61.998796 -229.119248) (xy 61.946834 -229.107388) (xy 61.89722 -229.087916)
			(xy 61.851062 -229.061267) (xy 61.809391 -229.028036) (xy 61.773139 -228.988965) (xy 61.743115 -228.944928)
			(xy 61.719989 -228.896907) (xy 61.704279 -228.845977) (xy 61.696336 -228.793273) (xy 47.319956 -228.793273)
			(xy 47.312013 -228.845977) (xy 47.296303 -228.896907) (xy 47.273177 -228.944928) (xy 47.243153 -228.988965)
			(xy 47.206901 -229.028036) (xy 47.16523 -229.061267) (xy 47.119072 -229.087916) (xy 47.069458 -229.107388)
			(xy 47.017496 -229.119248) (xy 46.964346 -229.123232) (xy 46.911196 -229.119248) (xy 46.859234 -229.107388)
			(xy 46.80962 -229.087916) (xy 46.763462 -229.061267) (xy 46.721791 -229.028036) (xy 46.685539 -228.988965)
			(xy 46.655515 -228.944928) (xy 46.632389 -228.896907) (xy 46.616679 -228.845977) (xy 46.608736 -228.793273)
			(xy 32.232356 -228.793273) (xy 32.224413 -228.845977) (xy 32.208703 -228.896907) (xy 32.185577 -228.944928)
			(xy 32.155553 -228.988965) (xy 32.119301 -229.028036) (xy 32.07763 -229.061267) (xy 32.031472 -229.087916)
			(xy 31.981858 -229.107388) (xy 31.929896 -229.119248) (xy 31.876746 -229.123232) (xy 31.823596 -229.119248)
			(xy 31.771634 -229.107388) (xy 31.72202 -229.087916) (xy 31.675862 -229.061267) (xy 31.634191 -229.028036)
			(xy 31.597939 -228.988965) (xy 31.567915 -228.944928) (xy 31.544789 -228.896907) (xy 31.529079 -228.845977)
			(xy 31.521136 -228.793273) (xy 17.144756 -228.793273) (xy 17.136813 -228.845977) (xy 17.121103 -228.896907)
			(xy 17.097977 -228.944928) (xy 17.067953 -228.988965) (xy 17.031701 -229.028036) (xy 16.99003 -229.061267)
			(xy 16.943872 -229.087916) (xy 16.894258 -229.107388) (xy 16.842296 -229.119248) (xy 16.789146 -229.123232)
			(xy 16.735996 -229.119248) (xy 16.684034 -229.107388) (xy 16.63442 -229.087916) (xy 16.588262 -229.061267)
			(xy 16.546591 -229.028036) (xy 16.510339 -228.988965) (xy 16.480315 -228.944928) (xy 16.457189 -228.896907)
			(xy 16.441479 -228.845977) (xy 16.433536 -228.793273) (xy 9.6774 -228.793273) (xy 9.6774 -229.643411)
			(xy 20.533604 -229.643411) (xy 20.533604 -229.590113) (xy 20.541547 -229.537409) (xy 20.557257 -229.486479)
			(xy 20.580383 -229.438458) (xy 20.610407 -229.394421) (xy 20.646659 -229.35535) (xy 20.68833 -229.322119)
			(xy 20.734488 -229.29547) (xy 20.784102 -229.275998) (xy 20.836064 -229.264138) (xy 20.889214 -229.260155)
			(xy 20.942364 -229.264138) (xy 20.994326 -229.275998) (xy 21.04394 -229.29547) (xy 21.090098 -229.322119)
			(xy 21.131769 -229.35535) (xy 21.168021 -229.394421) (xy 21.198045 -229.438458) (xy 21.221171 -229.486479)
			(xy 21.236881 -229.537409) (xy 21.244824 -229.590113) (xy 21.245322 -229.616762) (xy 21.244824 -229.643411)
			(xy 35.621204 -229.643411) (xy 35.621204 -229.590113) (xy 35.629147 -229.537409) (xy 35.644857 -229.486479)
			(xy 35.667983 -229.438458) (xy 35.698007 -229.394421) (xy 35.734259 -229.35535) (xy 35.77593 -229.322119)
			(xy 35.822088 -229.29547) (xy 35.871702 -229.275998) (xy 35.923664 -229.264138) (xy 35.976814 -229.260155)
			(xy 36.029964 -229.264138) (xy 36.081926 -229.275998) (xy 36.13154 -229.29547) (xy 36.177698 -229.322119)
			(xy 36.219369 -229.35535) (xy 36.255621 -229.394421) (xy 36.285645 -229.438458) (xy 36.308771 -229.486479)
			(xy 36.324481 -229.537409) (xy 36.332424 -229.590113) (xy 36.332922 -229.616762) (xy 36.332424 -229.643411)
			(xy 50.708804 -229.643411) (xy 50.708804 -229.590113) (xy 50.716747 -229.537409) (xy 50.732457 -229.486479)
			(xy 50.755583 -229.438458) (xy 50.785607 -229.394421) (xy 50.821859 -229.35535) (xy 50.86353 -229.322119)
			(xy 50.909688 -229.29547) (xy 50.959302 -229.275998) (xy 51.011264 -229.264138) (xy 51.064414 -229.260155)
			(xy 51.117564 -229.264138) (xy 51.169526 -229.275998) (xy 51.21914 -229.29547) (xy 51.265298 -229.322119)
			(xy 51.306969 -229.35535) (xy 51.343221 -229.394421) (xy 51.373245 -229.438458) (xy 51.396371 -229.486479)
			(xy 51.412081 -229.537409) (xy 51.420024 -229.590113) (xy 51.420522 -229.616762) (xy 51.420024 -229.643411)
			(xy 51.412081 -229.696115) (xy 51.396371 -229.747045) (xy 51.373245 -229.795066) (xy 51.343221 -229.839103)
			(xy 51.306969 -229.878174) (xy 51.265298 -229.911405) (xy 51.21914 -229.938054) (xy 51.169526 -229.957526)
			(xy 51.117564 -229.969386) (xy 51.064414 -229.97337) (xy 51.011264 -229.969386) (xy 50.959302 -229.957526)
			(xy 50.909688 -229.938054) (xy 50.86353 -229.911405) (xy 50.821859 -229.878174) (xy 50.785607 -229.839103)
			(xy 50.755583 -229.795066) (xy 50.732457 -229.747045) (xy 50.716747 -229.696115) (xy 50.708804 -229.643411)
			(xy 36.332424 -229.643411) (xy 36.324481 -229.696115) (xy 36.308771 -229.747045) (xy 36.285645 -229.795066)
			(xy 36.255621 -229.839103) (xy 36.219369 -229.878174) (xy 36.177698 -229.911405) (xy 36.13154 -229.938054)
			(xy 36.081926 -229.957526) (xy 36.029964 -229.969386) (xy 35.976814 -229.97337) (xy 35.923664 -229.969386)
			(xy 35.871702 -229.957526) (xy 35.822088 -229.938054) (xy 35.77593 -229.911405) (xy 35.734259 -229.878174)
			(xy 35.698007 -229.839103) (xy 35.667983 -229.795066) (xy 35.644857 -229.747045) (xy 35.629147 -229.696115)
			(xy 35.621204 -229.643411) (xy 21.244824 -229.643411) (xy 21.236881 -229.696115) (xy 21.221171 -229.747045)
			(xy 21.198045 -229.795066) (xy 21.168021 -229.839103) (xy 21.131769 -229.878174) (xy 21.090098 -229.911405)
			(xy 21.04394 -229.938054) (xy 20.994326 -229.957526) (xy 20.942364 -229.969386) (xy 20.889214 -229.97337)
			(xy 20.836064 -229.969386) (xy 20.784102 -229.957526) (xy 20.734488 -229.938054) (xy 20.68833 -229.911405)
			(xy 20.646659 -229.878174) (xy 20.610407 -229.839103) (xy 20.580383 -229.795066) (xy 20.557257 -229.747045)
			(xy 20.541547 -229.696115) (xy 20.533604 -229.643411) (xy 9.6774 -229.643411) (xy 9.6774 -230.493295)
			(xy 16.433536 -230.493295) (xy 16.433536 -230.439997) (xy 16.441479 -230.387293) (xy 16.457189 -230.336363)
			(xy 16.480315 -230.288342) (xy 16.510339 -230.244305) (xy 16.546591 -230.205234) (xy 16.588262 -230.172003)
			(xy 16.63442 -230.145354) (xy 16.684034 -230.125882) (xy 16.735996 -230.114022) (xy 16.789146 -230.110039)
			(xy 16.842296 -230.114022) (xy 16.894258 -230.125882) (xy 16.943872 -230.145354) (xy 16.99003 -230.172003)
			(xy 17.031701 -230.205234) (xy 17.067953 -230.244305) (xy 17.097977 -230.288342) (xy 17.121103 -230.336363)
			(xy 17.136813 -230.387293) (xy 17.144756 -230.439997) (xy 17.145254 -230.466646) (xy 17.144756 -230.493295)
			(xy 31.521136 -230.493295) (xy 31.521136 -230.439997) (xy 31.529079 -230.387293) (xy 31.544789 -230.336363)
			(xy 31.567915 -230.288342) (xy 31.597939 -230.244305) (xy 31.634191 -230.205234) (xy 31.675862 -230.172003)
			(xy 31.72202 -230.145354) (xy 31.771634 -230.125882) (xy 31.823596 -230.114022) (xy 31.876746 -230.110039)
			(xy 31.929896 -230.114022) (xy 31.981858 -230.125882) (xy 32.031472 -230.145354) (xy 32.07763 -230.172003)
			(xy 32.119301 -230.205234) (xy 32.155553 -230.244305) (xy 32.185577 -230.288342) (xy 32.208703 -230.336363)
			(xy 32.224413 -230.387293) (xy 32.232356 -230.439997) (xy 32.232854 -230.466646) (xy 32.232356 -230.493295)
			(xy 46.608736 -230.493295) (xy 46.608736 -230.439997) (xy 46.616679 -230.387293) (xy 46.632389 -230.336363)
			(xy 46.655515 -230.288342) (xy 46.685539 -230.244305) (xy 46.721791 -230.205234) (xy 46.763462 -230.172003)
			(xy 46.80962 -230.145354) (xy 46.859234 -230.125882) (xy 46.911196 -230.114022) (xy 46.964346 -230.110039)
			(xy 47.017496 -230.114022) (xy 47.069458 -230.125882) (xy 47.119072 -230.145354) (xy 47.16523 -230.172003)
			(xy 47.206901 -230.205234) (xy 47.243153 -230.244305) (xy 47.273177 -230.288342) (xy 47.296303 -230.336363)
			(xy 47.312013 -230.387293) (xy 47.319956 -230.439997) (xy 47.320454 -230.466646) (xy 47.319956 -230.493295)
			(xy 61.696336 -230.493295) (xy 61.696336 -230.439997) (xy 61.704279 -230.387293) (xy 61.719989 -230.336363)
			(xy 61.743115 -230.288342) (xy 61.773139 -230.244305) (xy 61.809391 -230.205234) (xy 61.851062 -230.172003)
			(xy 61.89722 -230.145354) (xy 61.946834 -230.125882) (xy 61.998796 -230.114022) (xy 62.051946 -230.110039)
			(xy 62.105096 -230.114022) (xy 62.157058 -230.125882) (xy 62.206672 -230.145354) (xy 62.25283 -230.172003)
			(xy 62.294501 -230.205234) (xy 62.330753 -230.244305) (xy 62.360777 -230.288342) (xy 62.383903 -230.336363)
			(xy 62.399613 -230.387293) (xy 62.407556 -230.439997) (xy 62.408054 -230.466646) (xy 62.407556 -230.493295)
			(xy 62.399613 -230.545999) (xy 62.383903 -230.596929) (xy 62.360777 -230.64495) (xy 62.330753 -230.688987)
			(xy 62.294501 -230.728058) (xy 62.25283 -230.761289) (xy 62.206672 -230.787938) (xy 62.157058 -230.80741)
			(xy 62.105096 -230.81927) (xy 62.051946 -230.823254) (xy 61.998796 -230.81927) (xy 61.946834 -230.80741)
			(xy 61.89722 -230.787938) (xy 61.851062 -230.761289) (xy 61.809391 -230.728058) (xy 61.773139 -230.688987)
			(xy 61.743115 -230.64495) (xy 61.719989 -230.596929) (xy 61.704279 -230.545999) (xy 61.696336 -230.493295)
			(xy 47.319956 -230.493295) (xy 47.312013 -230.545999) (xy 47.296303 -230.596929) (xy 47.273177 -230.64495)
			(xy 47.243153 -230.688987) (xy 47.206901 -230.728058) (xy 47.16523 -230.761289) (xy 47.119072 -230.787938)
			(xy 47.069458 -230.80741) (xy 47.017496 -230.81927) (xy 46.964346 -230.823254) (xy 46.911196 -230.81927)
			(xy 46.859234 -230.80741) (xy 46.80962 -230.787938) (xy 46.763462 -230.761289) (xy 46.721791 -230.728058)
			(xy 46.685539 -230.688987) (xy 46.655515 -230.64495) (xy 46.632389 -230.596929) (xy 46.616679 -230.545999)
			(xy 46.608736 -230.493295) (xy 32.232356 -230.493295) (xy 32.224413 -230.545999) (xy 32.208703 -230.596929)
			(xy 32.185577 -230.64495) (xy 32.155553 -230.688987) (xy 32.119301 -230.728058) (xy 32.07763 -230.761289)
			(xy 32.031472 -230.787938) (xy 31.981858 -230.80741) (xy 31.929896 -230.81927) (xy 31.876746 -230.823254)
			(xy 31.823596 -230.81927) (xy 31.771634 -230.80741) (xy 31.72202 -230.787938) (xy 31.675862 -230.761289)
			(xy 31.634191 -230.728058) (xy 31.597939 -230.688987) (xy 31.567915 -230.64495) (xy 31.544789 -230.596929)
			(xy 31.529079 -230.545999) (xy 31.521136 -230.493295) (xy 17.144756 -230.493295) (xy 17.136813 -230.545999)
			(xy 17.121103 -230.596929) (xy 17.097977 -230.64495) (xy 17.067953 -230.688987) (xy 17.031701 -230.728058)
			(xy 16.99003 -230.761289) (xy 16.943872 -230.787938) (xy 16.894258 -230.80741) (xy 16.842296 -230.81927)
			(xy 16.789146 -230.823254) (xy 16.735996 -230.81927) (xy 16.684034 -230.80741) (xy 16.63442 -230.787938)
			(xy 16.588262 -230.761289) (xy 16.546591 -230.728058) (xy 16.510339 -230.688987) (xy 16.480315 -230.64495)
			(xy 16.457189 -230.596929) (xy 16.441479 -230.545999) (xy 16.433536 -230.493295) (xy 9.6774 -230.493295)
			(xy 9.6774 -231.343433) (xy 20.533604 -231.343433) (xy 20.533604 -231.290135) (xy 20.541547 -231.237431)
			(xy 20.557257 -231.186501) (xy 20.580383 -231.13848) (xy 20.610407 -231.094443) (xy 20.646659 -231.055372)
			(xy 20.68833 -231.022141) (xy 20.734488 -230.995492) (xy 20.784102 -230.97602) (xy 20.836064 -230.96416)
			(xy 20.889214 -230.960177) (xy 20.942364 -230.96416) (xy 20.994326 -230.97602) (xy 21.04394 -230.995492)
			(xy 21.090098 -231.022141) (xy 21.131769 -231.055372) (xy 21.168021 -231.094443) (xy 21.198045 -231.13848)
			(xy 21.221171 -231.186501) (xy 21.236881 -231.237431) (xy 21.244824 -231.290135) (xy 21.245322 -231.316784)
			(xy 21.244824 -231.343433) (xy 35.621204 -231.343433) (xy 35.621204 -231.290135) (xy 35.629147 -231.237431)
			(xy 35.644857 -231.186501) (xy 35.667983 -231.13848) (xy 35.698007 -231.094443) (xy 35.734259 -231.055372)
			(xy 35.77593 -231.022141) (xy 35.822088 -230.995492) (xy 35.871702 -230.97602) (xy 35.923664 -230.96416)
			(xy 35.976814 -230.960177) (xy 36.029964 -230.96416) (xy 36.081926 -230.97602) (xy 36.13154 -230.995492)
			(xy 36.177698 -231.022141) (xy 36.219369 -231.055372) (xy 36.255621 -231.094443) (xy 36.285645 -231.13848)
			(xy 36.308771 -231.186501) (xy 36.324481 -231.237431) (xy 36.332424 -231.290135) (xy 36.332922 -231.316784)
			(xy 36.332424 -231.343433) (xy 50.708804 -231.343433) (xy 50.708804 -231.290135) (xy 50.716747 -231.237431)
			(xy 50.732457 -231.186501) (xy 50.755583 -231.13848) (xy 50.785607 -231.094443) (xy 50.821859 -231.055372)
			(xy 50.86353 -231.022141) (xy 50.909688 -230.995492) (xy 50.959302 -230.97602) (xy 51.011264 -230.96416)
			(xy 51.064414 -230.960177) (xy 51.117564 -230.96416) (xy 51.169526 -230.97602) (xy 51.21914 -230.995492)
			(xy 51.265298 -231.022141) (xy 51.306969 -231.055372) (xy 51.343221 -231.094443) (xy 51.373245 -231.13848)
			(xy 51.396371 -231.186501) (xy 51.412081 -231.237431) (xy 51.420024 -231.290135) (xy 51.420522 -231.316784)
			(xy 51.420024 -231.343433) (xy 51.412081 -231.396137) (xy 51.396371 -231.447067) (xy 51.373245 -231.495088)
			(xy 51.343221 -231.539125) (xy 51.306969 -231.578196) (xy 51.265298 -231.611427) (xy 51.21914 -231.638076)
			(xy 51.169526 -231.657548) (xy 51.117564 -231.669408) (xy 51.064414 -231.673392) (xy 51.011264 -231.669408)
			(xy 50.959302 -231.657548) (xy 50.909688 -231.638076) (xy 50.86353 -231.611427) (xy 50.821859 -231.578196)
			(xy 50.785607 -231.539125) (xy 50.755583 -231.495088) (xy 50.732457 -231.447067) (xy 50.716747 -231.396137)
			(xy 50.708804 -231.343433) (xy 36.332424 -231.343433) (xy 36.324481 -231.396137) (xy 36.308771 -231.447067)
			(xy 36.285645 -231.495088) (xy 36.255621 -231.539125) (xy 36.219369 -231.578196) (xy 36.177698 -231.611427)
			(xy 36.13154 -231.638076) (xy 36.081926 -231.657548) (xy 36.029964 -231.669408) (xy 35.976814 -231.673392)
			(xy 35.923664 -231.669408) (xy 35.871702 -231.657548) (xy 35.822088 -231.638076) (xy 35.77593 -231.611427)
			(xy 35.734259 -231.578196) (xy 35.698007 -231.539125) (xy 35.667983 -231.495088) (xy 35.644857 -231.447067)
			(xy 35.629147 -231.396137) (xy 35.621204 -231.343433) (xy 21.244824 -231.343433) (xy 21.236881 -231.396137)
			(xy 21.221171 -231.447067) (xy 21.198045 -231.495088) (xy 21.168021 -231.539125) (xy 21.131769 -231.578196)
			(xy 21.090098 -231.611427) (xy 21.04394 -231.638076) (xy 20.994326 -231.657548) (xy 20.942364 -231.669408)
			(xy 20.889214 -231.673392) (xy 20.836064 -231.669408) (xy 20.784102 -231.657548) (xy 20.734488 -231.638076)
			(xy 20.68833 -231.611427) (xy 20.646659 -231.578196) (xy 20.610407 -231.539125) (xy 20.580383 -231.495088)
			(xy 20.557257 -231.447067) (xy 20.541547 -231.396137) (xy 20.533604 -231.343433) (xy 9.6774 -231.343433)
			(xy 9.6774 -232.193317) (xy 16.433536 -232.193317) (xy 16.433536 -232.140019) (xy 16.441479 -232.087315)
			(xy 16.457189 -232.036385) (xy 16.480315 -231.988364) (xy 16.510339 -231.944327) (xy 16.546591 -231.905256)
			(xy 16.588262 -231.872025) (xy 16.63442 -231.845376) (xy 16.684034 -231.825904) (xy 16.735996 -231.814044)
			(xy 16.789146 -231.810061) (xy 16.842296 -231.814044) (xy 16.894258 -231.825904) (xy 16.943872 -231.845376)
			(xy 16.99003 -231.872025) (xy 17.031701 -231.905256) (xy 17.067953 -231.944327) (xy 17.097977 -231.988364)
			(xy 17.121103 -232.036385) (xy 17.136813 -232.087315) (xy 17.144756 -232.140019) (xy 17.145254 -232.166668)
			(xy 17.144756 -232.193317) (xy 31.521136 -232.193317) (xy 31.521136 -232.140019) (xy 31.529079 -232.087315)
			(xy 31.544789 -232.036385) (xy 31.567915 -231.988364) (xy 31.597939 -231.944327) (xy 31.634191 -231.905256)
			(xy 31.675862 -231.872025) (xy 31.72202 -231.845376) (xy 31.771634 -231.825904) (xy 31.823596 -231.814044)
			(xy 31.876746 -231.810061) (xy 31.929896 -231.814044) (xy 31.981858 -231.825904) (xy 32.031472 -231.845376)
			(xy 32.07763 -231.872025) (xy 32.119301 -231.905256) (xy 32.155553 -231.944327) (xy 32.185577 -231.988364)
			(xy 32.208703 -232.036385) (xy 32.224413 -232.087315) (xy 32.232356 -232.140019) (xy 32.232854 -232.166668)
			(xy 32.232356 -232.193317) (xy 46.608736 -232.193317) (xy 46.608736 -232.140019) (xy 46.616679 -232.087315)
			(xy 46.632389 -232.036385) (xy 46.655515 -231.988364) (xy 46.685539 -231.944327) (xy 46.721791 -231.905256)
			(xy 46.763462 -231.872025) (xy 46.80962 -231.845376) (xy 46.859234 -231.825904) (xy 46.911196 -231.814044)
			(xy 46.964346 -231.810061) (xy 47.017496 -231.814044) (xy 47.069458 -231.825904) (xy 47.119072 -231.845376)
			(xy 47.16523 -231.872025) (xy 47.206901 -231.905256) (xy 47.243153 -231.944327) (xy 47.273177 -231.988364)
			(xy 47.296303 -232.036385) (xy 47.312013 -232.087315) (xy 47.319956 -232.140019) (xy 47.320454 -232.166668)
			(xy 47.319956 -232.193317) (xy 61.696336 -232.193317) (xy 61.696336 -232.140019) (xy 61.704279 -232.087315)
			(xy 61.719989 -232.036385) (xy 61.743115 -231.988364) (xy 61.773139 -231.944327) (xy 61.809391 -231.905256)
			(xy 61.851062 -231.872025) (xy 61.89722 -231.845376) (xy 61.946834 -231.825904) (xy 61.998796 -231.814044)
			(xy 62.051946 -231.810061) (xy 62.105096 -231.814044) (xy 62.157058 -231.825904) (xy 62.206672 -231.845376)
			(xy 62.25283 -231.872025) (xy 62.294501 -231.905256) (xy 62.330753 -231.944327) (xy 62.360777 -231.988364)
			(xy 62.383903 -232.036385) (xy 62.399613 -232.087315) (xy 62.407556 -232.140019) (xy 62.408054 -232.166668)
			(xy 62.407556 -232.193317) (xy 62.399613 -232.246021) (xy 62.383903 -232.296951) (xy 62.360777 -232.344972)
			(xy 62.330753 -232.389009) (xy 62.294501 -232.42808) (xy 62.25283 -232.461311) (xy 62.206672 -232.48796)
			(xy 62.157058 -232.507432) (xy 62.105096 -232.519292) (xy 62.051946 -232.523276) (xy 61.998796 -232.519292)
			(xy 61.946834 -232.507432) (xy 61.89722 -232.48796) (xy 61.851062 -232.461311) (xy 61.809391 -232.42808)
			(xy 61.773139 -232.389009) (xy 61.743115 -232.344972) (xy 61.719989 -232.296951) (xy 61.704279 -232.246021)
			(xy 61.696336 -232.193317) (xy 47.319956 -232.193317) (xy 47.312013 -232.246021) (xy 47.296303 -232.296951)
			(xy 47.273177 -232.344972) (xy 47.243153 -232.389009) (xy 47.206901 -232.42808) (xy 47.16523 -232.461311)
			(xy 47.119072 -232.48796) (xy 47.069458 -232.507432) (xy 47.017496 -232.519292) (xy 46.964346 -232.523276)
			(xy 46.911196 -232.519292) (xy 46.859234 -232.507432) (xy 46.80962 -232.48796) (xy 46.763462 -232.461311)
			(xy 46.721791 -232.42808) (xy 46.685539 -232.389009) (xy 46.655515 -232.344972) (xy 46.632389 -232.296951)
			(xy 46.616679 -232.246021) (xy 46.608736 -232.193317) (xy 32.232356 -232.193317) (xy 32.224413 -232.246021)
			(xy 32.208703 -232.296951) (xy 32.185577 -232.344972) (xy 32.155553 -232.389009) (xy 32.119301 -232.42808)
			(xy 32.07763 -232.461311) (xy 32.031472 -232.48796) (xy 31.981858 -232.507432) (xy 31.929896 -232.519292)
			(xy 31.876746 -232.523276) (xy 31.823596 -232.519292) (xy 31.771634 -232.507432) (xy 31.72202 -232.48796)
			(xy 31.675862 -232.461311) (xy 31.634191 -232.42808) (xy 31.597939 -232.389009) (xy 31.567915 -232.344972)
			(xy 31.544789 -232.296951) (xy 31.529079 -232.246021) (xy 31.521136 -232.193317) (xy 17.144756 -232.193317)
			(xy 17.136813 -232.246021) (xy 17.121103 -232.296951) (xy 17.097977 -232.344972) (xy 17.067953 -232.389009)
			(xy 17.031701 -232.42808) (xy 16.99003 -232.461311) (xy 16.943872 -232.48796) (xy 16.894258 -232.507432)
			(xy 16.842296 -232.519292) (xy 16.789146 -232.523276) (xy 16.735996 -232.519292) (xy 16.684034 -232.507432)
			(xy 16.63442 -232.48796) (xy 16.588262 -232.461311) (xy 16.546591 -232.42808) (xy 16.510339 -232.389009)
			(xy 16.480315 -232.344972) (xy 16.457189 -232.296951) (xy 16.441479 -232.246021) (xy 16.433536 -232.193317)
			(xy 9.6774 -232.193317) (xy 9.6774 -233.043455) (xy 20.533604 -233.043455) (xy 20.533604 -232.990157)
			(xy 20.541547 -232.937453) (xy 20.557257 -232.886523) (xy 20.580383 -232.838502) (xy 20.610407 -232.794465)
			(xy 20.646659 -232.755394) (xy 20.68833 -232.722163) (xy 20.734488 -232.695514) (xy 20.784102 -232.676042)
			(xy 20.836064 -232.664182) (xy 20.889214 -232.660199) (xy 20.942364 -232.664182) (xy 20.994326 -232.676042)
			(xy 21.04394 -232.695514) (xy 21.090098 -232.722163) (xy 21.131769 -232.755394) (xy 21.168021 -232.794465)
			(xy 21.198045 -232.838502) (xy 21.221171 -232.886523) (xy 21.236881 -232.937453) (xy 21.244824 -232.990157)
			(xy 21.245322 -233.016806) (xy 21.244824 -233.043455) (xy 35.621204 -233.043455) (xy 35.621204 -232.990157)
			(xy 35.629147 -232.937453) (xy 35.644857 -232.886523) (xy 35.667983 -232.838502) (xy 35.698007 -232.794465)
			(xy 35.734259 -232.755394) (xy 35.77593 -232.722163) (xy 35.822088 -232.695514) (xy 35.871702 -232.676042)
			(xy 35.923664 -232.664182) (xy 35.976814 -232.660199) (xy 36.029964 -232.664182) (xy 36.081926 -232.676042)
			(xy 36.13154 -232.695514) (xy 36.177698 -232.722163) (xy 36.219369 -232.755394) (xy 36.255621 -232.794465)
			(xy 36.285645 -232.838502) (xy 36.308771 -232.886523) (xy 36.324481 -232.937453) (xy 36.332424 -232.990157)
			(xy 36.332922 -233.016806) (xy 36.332424 -233.043455) (xy 50.708804 -233.043455) (xy 50.708804 -232.990157)
			(xy 50.716747 -232.937453) (xy 50.732457 -232.886523) (xy 50.755583 -232.838502) (xy 50.785607 -232.794465)
			(xy 50.821859 -232.755394) (xy 50.86353 -232.722163) (xy 50.909688 -232.695514) (xy 50.959302 -232.676042)
			(xy 51.011264 -232.664182) (xy 51.064414 -232.660199) (xy 51.117564 -232.664182) (xy 51.169526 -232.676042)
			(xy 51.21914 -232.695514) (xy 51.265298 -232.722163) (xy 51.306969 -232.755394) (xy 51.343221 -232.794465)
			(xy 51.373245 -232.838502) (xy 51.396371 -232.886523) (xy 51.412081 -232.937453) (xy 51.420024 -232.990157)
			(xy 51.420522 -233.016806) (xy 51.420024 -233.043455) (xy 51.412081 -233.096159) (xy 51.396371 -233.147089)
			(xy 51.373245 -233.19511) (xy 51.343221 -233.239147) (xy 51.306969 -233.278218) (xy 51.265298 -233.311449)
			(xy 51.21914 -233.338098) (xy 51.169526 -233.35757) (xy 51.117564 -233.36943) (xy 51.064414 -233.373414)
			(xy 51.011264 -233.36943) (xy 50.959302 -233.35757) (xy 50.909688 -233.338098) (xy 50.86353 -233.311449)
			(xy 50.821859 -233.278218) (xy 50.785607 -233.239147) (xy 50.755583 -233.19511) (xy 50.732457 -233.147089)
			(xy 50.716747 -233.096159) (xy 50.708804 -233.043455) (xy 36.332424 -233.043455) (xy 36.324481 -233.096159)
			(xy 36.308771 -233.147089) (xy 36.285645 -233.19511) (xy 36.255621 -233.239147) (xy 36.219369 -233.278218)
			(xy 36.177698 -233.311449) (xy 36.13154 -233.338098) (xy 36.081926 -233.35757) (xy 36.029964 -233.36943)
			(xy 35.976814 -233.373414) (xy 35.923664 -233.36943) (xy 35.871702 -233.35757) (xy 35.822088 -233.338098)
			(xy 35.77593 -233.311449) (xy 35.734259 -233.278218) (xy 35.698007 -233.239147) (xy 35.667983 -233.19511)
			(xy 35.644857 -233.147089) (xy 35.629147 -233.096159) (xy 35.621204 -233.043455) (xy 21.244824 -233.043455)
			(xy 21.236881 -233.096159) (xy 21.221171 -233.147089) (xy 21.198045 -233.19511) (xy 21.168021 -233.239147)
			(xy 21.131769 -233.278218) (xy 21.090098 -233.311449) (xy 21.04394 -233.338098) (xy 20.994326 -233.35757)
			(xy 20.942364 -233.36943) (xy 20.889214 -233.373414) (xy 20.836064 -233.36943) (xy 20.784102 -233.35757)
			(xy 20.734488 -233.338098) (xy 20.68833 -233.311449) (xy 20.646659 -233.278218) (xy 20.610407 -233.239147)
			(xy 20.580383 -233.19511) (xy 20.557257 -233.147089) (xy 20.541547 -233.096159) (xy 20.533604 -233.043455)
			(xy 9.6774 -233.043455) (xy 9.6774 -233.893339) (xy 16.433536 -233.893339) (xy 16.433536 -233.840041)
			(xy 16.441479 -233.787337) (xy 16.457189 -233.736407) (xy 16.480315 -233.688386) (xy 16.510339 -233.644349)
			(xy 16.546591 -233.605278) (xy 16.588262 -233.572047) (xy 16.63442 -233.545398) (xy 16.684034 -233.525926)
			(xy 16.735996 -233.514066) (xy 16.789146 -233.510083) (xy 16.842296 -233.514066) (xy 16.894258 -233.525926)
			(xy 16.943872 -233.545398) (xy 16.99003 -233.572047) (xy 17.031701 -233.605278) (xy 17.067953 -233.644349)
			(xy 17.097977 -233.688386) (xy 17.121103 -233.736407) (xy 17.136813 -233.787337) (xy 17.144756 -233.840041)
			(xy 17.145254 -233.86669) (xy 17.144756 -233.893339) (xy 31.521136 -233.893339) (xy 31.521136 -233.840041)
			(xy 31.529079 -233.787337) (xy 31.544789 -233.736407) (xy 31.567915 -233.688386) (xy 31.597939 -233.644349)
			(xy 31.634191 -233.605278) (xy 31.675862 -233.572047) (xy 31.72202 -233.545398) (xy 31.771634 -233.525926)
			(xy 31.823596 -233.514066) (xy 31.876746 -233.510083) (xy 31.929896 -233.514066) (xy 31.981858 -233.525926)
			(xy 32.031472 -233.545398) (xy 32.07763 -233.572047) (xy 32.119301 -233.605278) (xy 32.155553 -233.644349)
			(xy 32.185577 -233.688386) (xy 32.208703 -233.736407) (xy 32.224413 -233.787337) (xy 32.232356 -233.840041)
			(xy 32.232854 -233.86669) (xy 32.232356 -233.893339) (xy 46.608736 -233.893339) (xy 46.608736 -233.840041)
			(xy 46.616679 -233.787337) (xy 46.632389 -233.736407) (xy 46.655515 -233.688386) (xy 46.685539 -233.644349)
			(xy 46.721791 -233.605278) (xy 46.763462 -233.572047) (xy 46.80962 -233.545398) (xy 46.859234 -233.525926)
			(xy 46.911196 -233.514066) (xy 46.964346 -233.510083) (xy 47.017496 -233.514066) (xy 47.069458 -233.525926)
			(xy 47.119072 -233.545398) (xy 47.16523 -233.572047) (xy 47.206901 -233.605278) (xy 47.243153 -233.644349)
			(xy 47.273177 -233.688386) (xy 47.296303 -233.736407) (xy 47.312013 -233.787337) (xy 47.319956 -233.840041)
			(xy 47.320454 -233.86669) (xy 47.319956 -233.893339) (xy 47.312013 -233.946043) (xy 47.296303 -233.996973)
			(xy 47.273177 -234.044994) (xy 47.243153 -234.089031) (xy 47.206901 -234.128102) (xy 47.16523 -234.161333)
			(xy 47.119072 -234.187982) (xy 47.069458 -234.207454) (xy 47.017496 -234.219314) (xy 46.964346 -234.223298)
			(xy 46.911196 -234.219314) (xy 46.859234 -234.207454) (xy 46.80962 -234.187982) (xy 46.763462 -234.161333)
			(xy 46.721791 -234.128102) (xy 46.685539 -234.089031) (xy 46.655515 -234.044994) (xy 46.632389 -233.996973)
			(xy 46.616679 -233.946043) (xy 46.608736 -233.893339) (xy 32.232356 -233.893339) (xy 32.224413 -233.946043)
			(xy 32.208703 -233.996973) (xy 32.185577 -234.044994) (xy 32.155553 -234.089031) (xy 32.119301 -234.128102)
			(xy 32.07763 -234.161333) (xy 32.031472 -234.187982) (xy 31.981858 -234.207454) (xy 31.929896 -234.219314)
			(xy 31.876746 -234.223298) (xy 31.823596 -234.219314) (xy 31.771634 -234.207454) (xy 31.72202 -234.187982)
			(xy 31.675862 -234.161333) (xy 31.634191 -234.128102) (xy 31.597939 -234.089031) (xy 31.567915 -234.044994)
			(xy 31.544789 -233.996973) (xy 31.529079 -233.946043) (xy 31.521136 -233.893339) (xy 17.144756 -233.893339)
			(xy 17.136813 -233.946043) (xy 17.121103 -233.996973) (xy 17.097977 -234.044994) (xy 17.067953 -234.089031)
			(xy 17.031701 -234.128102) (xy 16.99003 -234.161333) (xy 16.943872 -234.187982) (xy 16.894258 -234.207454)
			(xy 16.842296 -234.219314) (xy 16.789146 -234.223298) (xy 16.735996 -234.219314) (xy 16.684034 -234.207454)
			(xy 16.63442 -234.187982) (xy 16.588262 -234.161333) (xy 16.546591 -234.128102) (xy 16.510339 -234.089031)
			(xy 16.480315 -234.044994) (xy 16.457189 -233.996973) (xy 16.441479 -233.946043) (xy 16.433536 -233.893339)
			(xy 9.6774 -233.893339) (xy 9.6774 -234.743223) (xy 20.533604 -234.743223) (xy 20.533604 -234.689925)
			(xy 20.541547 -234.637221) (xy 20.557257 -234.586291) (xy 20.580383 -234.53827) (xy 20.610407 -234.494233)
			(xy 20.646659 -234.455162) (xy 20.68833 -234.421931) (xy 20.734488 -234.395282) (xy 20.784102 -234.37581)
			(xy 20.836064 -234.36395) (xy 20.889214 -234.359967) (xy 20.942364 -234.36395) (xy 20.994326 -234.37581)
			(xy 21.04394 -234.395282) (xy 21.090098 -234.421931) (xy 21.131769 -234.455162) (xy 21.168021 -234.494233)
			(xy 21.198045 -234.53827) (xy 21.221171 -234.586291) (xy 21.236881 -234.637221) (xy 21.244824 -234.689925)
			(xy 21.245322 -234.716574) (xy 21.244824 -234.743223) (xy 35.621204 -234.743223) (xy 35.621204 -234.689925)
			(xy 35.629147 -234.637221) (xy 35.644857 -234.586291) (xy 35.667983 -234.53827) (xy 35.698007 -234.494233)
			(xy 35.734259 -234.455162) (xy 35.77593 -234.421931) (xy 35.822088 -234.395282) (xy 35.871702 -234.37581)
			(xy 35.923664 -234.36395) (xy 35.976814 -234.359967) (xy 36.029964 -234.36395) (xy 36.081926 -234.37581)
			(xy 36.13154 -234.395282) (xy 36.177698 -234.421931) (xy 36.219369 -234.455162) (xy 36.255621 -234.494233)
			(xy 36.285645 -234.53827) (xy 36.308771 -234.586291) (xy 36.324481 -234.637221) (xy 36.332424 -234.689925)
			(xy 36.332922 -234.716574) (xy 36.332424 -234.743223) (xy 50.708804 -234.743223) (xy 50.708804 -234.689925)
			(xy 50.716747 -234.637221) (xy 50.732457 -234.586291) (xy 50.755583 -234.53827) (xy 50.785607 -234.494233)
			(xy 50.821859 -234.455162) (xy 50.86353 -234.421931) (xy 50.909688 -234.395282) (xy 50.959302 -234.37581)
			(xy 51.011264 -234.36395) (xy 51.064414 -234.359967) (xy 51.117564 -234.36395) (xy 51.169526 -234.37581)
			(xy 51.21914 -234.395282) (xy 51.265298 -234.421931) (xy 51.306969 -234.455162) (xy 51.343221 -234.494233)
			(xy 51.373245 -234.53827) (xy 51.396371 -234.586291) (xy 51.412081 -234.637221) (xy 51.420024 -234.689925)
			(xy 51.420522 -234.716574) (xy 51.420024 -234.743223) (xy 51.412081 -234.795927) (xy 51.396371 -234.846857)
			(xy 51.373245 -234.894878) (xy 51.343221 -234.938915) (xy 51.306969 -234.977986) (xy 51.265298 -235.011217)
			(xy 51.21914 -235.037866) (xy 51.169526 -235.057338) (xy 51.117564 -235.069198) (xy 51.064414 -235.073182)
			(xy 51.011264 -235.069198) (xy 50.959302 -235.057338) (xy 50.909688 -235.037866) (xy 50.86353 -235.011217)
			(xy 50.821859 -234.977986) (xy 50.785607 -234.938915) (xy 50.755583 -234.894878) (xy 50.732457 -234.846857)
			(xy 50.716747 -234.795927) (xy 50.708804 -234.743223) (xy 36.332424 -234.743223) (xy 36.324481 -234.795927)
			(xy 36.308771 -234.846857) (xy 36.285645 -234.894878) (xy 36.255621 -234.938915) (xy 36.219369 -234.977986)
			(xy 36.177698 -235.011217) (xy 36.13154 -235.037866) (xy 36.081926 -235.057338) (xy 36.029964 -235.069198)
			(xy 35.976814 -235.073182) (xy 35.923664 -235.069198) (xy 35.871702 -235.057338) (xy 35.822088 -235.037866)
			(xy 35.77593 -235.011217) (xy 35.734259 -234.977986) (xy 35.698007 -234.938915) (xy 35.667983 -234.894878)
			(xy 35.644857 -234.846857) (xy 35.629147 -234.795927) (xy 35.621204 -234.743223) (xy 21.244824 -234.743223)
			(xy 21.236881 -234.795927) (xy 21.221171 -234.846857) (xy 21.198045 -234.894878) (xy 21.168021 -234.938915)
			(xy 21.131769 -234.977986) (xy 21.090098 -235.011217) (xy 21.04394 -235.037866) (xy 20.994326 -235.057338)
			(xy 20.942364 -235.069198) (xy 20.889214 -235.073182) (xy 20.836064 -235.069198) (xy 20.784102 -235.057338)
			(xy 20.734488 -235.037866) (xy 20.68833 -235.011217) (xy 20.646659 -234.977986) (xy 20.610407 -234.938915)
			(xy 20.580383 -234.894878) (xy 20.557257 -234.846857) (xy 20.541547 -234.795927) (xy 20.533604 -234.743223)
			(xy 9.6774 -234.743223) (xy 9.6774 -235.593361) (xy 16.433536 -235.593361) (xy 16.433536 -235.540063)
			(xy 16.441479 -235.487359) (xy 16.457189 -235.436429) (xy 16.480315 -235.388408) (xy 16.510339 -235.344371)
			(xy 16.546591 -235.3053) (xy 16.588262 -235.272069) (xy 16.63442 -235.24542) (xy 16.684034 -235.225948)
			(xy 16.735996 -235.214088) (xy 16.789146 -235.210105) (xy 16.842296 -235.214088) (xy 16.894258 -235.225948)
			(xy 16.943872 -235.24542) (xy 16.99003 -235.272069) (xy 17.031701 -235.3053) (xy 17.067953 -235.344371)
			(xy 17.097977 -235.388408) (xy 17.121103 -235.436429) (xy 17.136813 -235.487359) (xy 17.144756 -235.540063)
			(xy 17.145254 -235.566712) (xy 17.144756 -235.593361) (xy 31.521136 -235.593361) (xy 31.521136 -235.540063)
			(xy 31.529079 -235.487359) (xy 31.544789 -235.436429) (xy 31.567915 -235.388408) (xy 31.597939 -235.344371)
			(xy 31.634191 -235.3053) (xy 31.675862 -235.272069) (xy 31.72202 -235.24542) (xy 31.771634 -235.225948)
			(xy 31.823596 -235.214088) (xy 31.876746 -235.210105) (xy 31.929896 -235.214088) (xy 31.981858 -235.225948)
			(xy 32.031472 -235.24542) (xy 32.07763 -235.272069) (xy 32.119301 -235.3053) (xy 32.155553 -235.344371)
			(xy 32.185577 -235.388408) (xy 32.208703 -235.436429) (xy 32.224413 -235.487359) (xy 32.232356 -235.540063)
			(xy 32.232854 -235.566712) (xy 32.232356 -235.593361) (xy 46.608736 -235.593361) (xy 46.608736 -235.540063)
			(xy 46.616679 -235.487359) (xy 46.632389 -235.436429) (xy 46.655515 -235.388408) (xy 46.685539 -235.344371)
			(xy 46.721791 -235.3053) (xy 46.763462 -235.272069) (xy 46.80962 -235.24542) (xy 46.859234 -235.225948)
			(xy 46.911196 -235.214088) (xy 46.964346 -235.210105) (xy 47.017496 -235.214088) (xy 47.069458 -235.225948)
			(xy 47.119072 -235.24542) (xy 47.16523 -235.272069) (xy 47.206901 -235.3053) (xy 47.243153 -235.344371)
			(xy 47.273177 -235.388408) (xy 47.296303 -235.436429) (xy 47.312013 -235.487359) (xy 47.319956 -235.540063)
			(xy 47.320454 -235.566712) (xy 47.319956 -235.593361) (xy 47.312013 -235.646065) (xy 47.296303 -235.696995)
			(xy 47.273177 -235.745016) (xy 47.243153 -235.789053) (xy 47.206901 -235.828124) (xy 47.16523 -235.861355)
			(xy 47.119072 -235.888004) (xy 47.069458 -235.907476) (xy 47.017496 -235.919336) (xy 46.964346 -235.92332)
			(xy 46.911196 -235.919336) (xy 46.859234 -235.907476) (xy 46.80962 -235.888004) (xy 46.763462 -235.861355)
			(xy 46.721791 -235.828124) (xy 46.685539 -235.789053) (xy 46.655515 -235.745016) (xy 46.632389 -235.696995)
			(xy 46.616679 -235.646065) (xy 46.608736 -235.593361) (xy 32.232356 -235.593361) (xy 32.224413 -235.646065)
			(xy 32.208703 -235.696995) (xy 32.185577 -235.745016) (xy 32.155553 -235.789053) (xy 32.119301 -235.828124)
			(xy 32.07763 -235.861355) (xy 32.031472 -235.888004) (xy 31.981858 -235.907476) (xy 31.929896 -235.919336)
			(xy 31.876746 -235.92332) (xy 31.823596 -235.919336) (xy 31.771634 -235.907476) (xy 31.72202 -235.888004)
			(xy 31.675862 -235.861355) (xy 31.634191 -235.828124) (xy 31.597939 -235.789053) (xy 31.567915 -235.745016)
			(xy 31.544789 -235.696995) (xy 31.529079 -235.646065) (xy 31.521136 -235.593361) (xy 17.144756 -235.593361)
			(xy 17.136813 -235.646065) (xy 17.121103 -235.696995) (xy 17.097977 -235.745016) (xy 17.067953 -235.789053)
			(xy 17.031701 -235.828124) (xy 16.99003 -235.861355) (xy 16.943872 -235.888004) (xy 16.894258 -235.907476)
			(xy 16.842296 -235.919336) (xy 16.789146 -235.92332) (xy 16.735996 -235.919336) (xy 16.684034 -235.907476)
			(xy 16.63442 -235.888004) (xy 16.588262 -235.861355) (xy 16.546591 -235.828124) (xy 16.510339 -235.789053)
			(xy 16.480315 -235.745016) (xy 16.457189 -235.696995) (xy 16.441479 -235.646065) (xy 16.433536 -235.593361)
			(xy 9.6774 -235.593361) (xy 9.6774 -236.443245) (xy 20.533604 -236.443245) (xy 20.533604 -236.389947)
			(xy 20.541547 -236.337243) (xy 20.557257 -236.286313) (xy 20.580383 -236.238292) (xy 20.610407 -236.194255)
			(xy 20.646659 -236.155184) (xy 20.68833 -236.121953) (xy 20.734488 -236.095304) (xy 20.784102 -236.075832)
			(xy 20.836064 -236.063972) (xy 20.889214 -236.059989) (xy 20.942364 -236.063972) (xy 20.994326 -236.075832)
			(xy 21.04394 -236.095304) (xy 21.090098 -236.121953) (xy 21.131769 -236.155184) (xy 21.168021 -236.194255)
			(xy 21.198045 -236.238292) (xy 21.221171 -236.286313) (xy 21.236881 -236.337243) (xy 21.244824 -236.389947)
			(xy 21.245322 -236.416596) (xy 21.244824 -236.443245) (xy 35.621204 -236.443245) (xy 35.621204 -236.389947)
			(xy 35.629147 -236.337243) (xy 35.644857 -236.286313) (xy 35.667983 -236.238292) (xy 35.698007 -236.194255)
			(xy 35.734259 -236.155184) (xy 35.77593 -236.121953) (xy 35.822088 -236.095304) (xy 35.871702 -236.075832)
			(xy 35.923664 -236.063972) (xy 35.976814 -236.059989) (xy 36.029964 -236.063972) (xy 36.081926 -236.075832)
			(xy 36.13154 -236.095304) (xy 36.177698 -236.121953) (xy 36.219369 -236.155184) (xy 36.255621 -236.194255)
			(xy 36.285645 -236.238292) (xy 36.308771 -236.286313) (xy 36.324481 -236.337243) (xy 36.332424 -236.389947)
			(xy 36.332922 -236.416596) (xy 36.332424 -236.443245) (xy 50.708804 -236.443245) (xy 50.708804 -236.389947)
			(xy 50.716747 -236.337243) (xy 50.732457 -236.286313) (xy 50.755583 -236.238292) (xy 50.785607 -236.194255)
			(xy 50.821859 -236.155184) (xy 50.86353 -236.121953) (xy 50.909688 -236.095304) (xy 50.959302 -236.075832)
			(xy 51.011264 -236.063972) (xy 51.064414 -236.059989) (xy 51.117564 -236.063972) (xy 51.169526 -236.075832)
			(xy 51.21914 -236.095304) (xy 51.265298 -236.121953) (xy 51.306969 -236.155184) (xy 51.343221 -236.194255)
			(xy 51.373245 -236.238292) (xy 51.396371 -236.286313) (xy 51.412081 -236.337243) (xy 51.420024 -236.389947)
			(xy 51.420522 -236.416596) (xy 51.420024 -236.443245) (xy 51.412081 -236.495949) (xy 51.396371 -236.546879)
			(xy 51.373245 -236.5949) (xy 51.343221 -236.638937) (xy 51.306969 -236.678008) (xy 51.265298 -236.711239)
			(xy 51.21914 -236.737888) (xy 51.169526 -236.75736) (xy 51.117564 -236.76922) (xy 51.064414 -236.773204)
			(xy 51.011264 -236.76922) (xy 50.959302 -236.75736) (xy 50.909688 -236.737888) (xy 50.86353 -236.711239)
			(xy 50.821859 -236.678008) (xy 50.785607 -236.638937) (xy 50.755583 -236.5949) (xy 50.732457 -236.546879)
			(xy 50.716747 -236.495949) (xy 50.708804 -236.443245) (xy 36.332424 -236.443245) (xy 36.324481 -236.495949)
			(xy 36.308771 -236.546879) (xy 36.285645 -236.5949) (xy 36.255621 -236.638937) (xy 36.219369 -236.678008)
			(xy 36.177698 -236.711239) (xy 36.13154 -236.737888) (xy 36.081926 -236.75736) (xy 36.029964 -236.76922)
			(xy 35.976814 -236.773204) (xy 35.923664 -236.76922) (xy 35.871702 -236.75736) (xy 35.822088 -236.737888)
			(xy 35.77593 -236.711239) (xy 35.734259 -236.678008) (xy 35.698007 -236.638937) (xy 35.667983 -236.5949)
			(xy 35.644857 -236.546879) (xy 35.629147 -236.495949) (xy 35.621204 -236.443245) (xy 21.244824 -236.443245)
			(xy 21.236881 -236.495949) (xy 21.221171 -236.546879) (xy 21.198045 -236.5949) (xy 21.168021 -236.638937)
			(xy 21.131769 -236.678008) (xy 21.090098 -236.711239) (xy 21.04394 -236.737888) (xy 20.994326 -236.75736)
			(xy 20.942364 -236.76922) (xy 20.889214 -236.773204) (xy 20.836064 -236.76922) (xy 20.784102 -236.75736)
			(xy 20.734488 -236.737888) (xy 20.68833 -236.711239) (xy 20.646659 -236.678008) (xy 20.610407 -236.638937)
			(xy 20.580383 -236.5949) (xy 20.557257 -236.546879) (xy 20.541547 -236.495949) (xy 20.533604 -236.443245)
			(xy 9.6774 -236.443245) (xy 9.6774 -237.293383) (xy 16.433536 -237.293383) (xy 16.433536 -237.240085)
			(xy 16.441479 -237.187381) (xy 16.457189 -237.136451) (xy 16.480315 -237.08843) (xy 16.510339 -237.044393)
			(xy 16.546591 -237.005322) (xy 16.588262 -236.972091) (xy 16.63442 -236.945442) (xy 16.684034 -236.92597)
			(xy 16.735996 -236.91411) (xy 16.789146 -236.910127) (xy 16.842296 -236.91411) (xy 16.894258 -236.92597)
			(xy 16.943872 -236.945442) (xy 16.99003 -236.972091) (xy 17.031701 -237.005322) (xy 17.067953 -237.044393)
			(xy 17.097977 -237.08843) (xy 17.121103 -237.136451) (xy 17.136813 -237.187381) (xy 17.144756 -237.240085)
			(xy 17.145254 -237.266734) (xy 17.144756 -237.293383) (xy 20.533604 -237.293383) (xy 20.533604 -237.240085)
			(xy 20.541547 -237.187381) (xy 20.557257 -237.136451) (xy 20.580383 -237.08843) (xy 20.610407 -237.044393)
			(xy 20.646659 -237.005322) (xy 20.68833 -236.972091) (xy 20.734488 -236.945442) (xy 20.784102 -236.92597)
			(xy 20.836064 -236.91411) (xy 20.889214 -236.910127) (xy 20.942364 -236.91411) (xy 20.994326 -236.92597)
			(xy 21.04394 -236.945442) (xy 21.090098 -236.972091) (xy 21.131769 -237.005322) (xy 21.168021 -237.044393)
			(xy 21.198045 -237.08843) (xy 21.221171 -237.136451) (xy 21.236881 -237.187381) (xy 21.244824 -237.240085)
			(xy 21.245322 -237.266734) (xy 21.244824 -237.293383) (xy 31.521136 -237.293383) (xy 31.521136 -237.240085)
			(xy 31.529079 -237.187381) (xy 31.544789 -237.136451) (xy 31.567915 -237.08843) (xy 31.597939 -237.044393)
			(xy 31.634191 -237.005322) (xy 31.675862 -236.972091) (xy 31.72202 -236.945442) (xy 31.771634 -236.92597)
			(xy 31.823596 -236.91411) (xy 31.876746 -236.910127) (xy 31.929896 -236.91411) (xy 31.981858 -236.92597)
			(xy 32.031472 -236.945442) (xy 32.07763 -236.972091) (xy 32.119301 -237.005322) (xy 32.155553 -237.044393)
			(xy 32.185577 -237.08843) (xy 32.208703 -237.136451) (xy 32.224413 -237.187381) (xy 32.232356 -237.240085)
			(xy 32.232854 -237.266734) (xy 32.232356 -237.293383) (xy 35.621204 -237.293383) (xy 35.621204 -237.240085)
			(xy 35.629147 -237.187381) (xy 35.644857 -237.136451) (xy 35.667983 -237.08843) (xy 35.698007 -237.044393)
			(xy 35.734259 -237.005322) (xy 35.77593 -236.972091) (xy 35.822088 -236.945442) (xy 35.871702 -236.92597)
			(xy 35.923664 -236.91411) (xy 35.976814 -236.910127) (xy 36.029964 -236.91411) (xy 36.081926 -236.92597)
			(xy 36.13154 -236.945442) (xy 36.177698 -236.972091) (xy 36.219369 -237.005322) (xy 36.255621 -237.044393)
			(xy 36.285645 -237.08843) (xy 36.308771 -237.136451) (xy 36.324481 -237.187381) (xy 36.332424 -237.240085)
			(xy 36.332922 -237.266734) (xy 36.332424 -237.293383) (xy 46.608736 -237.293383) (xy 46.608736 -237.240085)
			(xy 46.616679 -237.187381) (xy 46.632389 -237.136451) (xy 46.655515 -237.08843) (xy 46.685539 -237.044393)
			(xy 46.721791 -237.005322) (xy 46.763462 -236.972091) (xy 46.80962 -236.945442) (xy 46.859234 -236.92597)
			(xy 46.911196 -236.91411) (xy 46.964346 -236.910127) (xy 47.017496 -236.91411) (xy 47.069458 -236.92597)
			(xy 47.119072 -236.945442) (xy 47.16523 -236.972091) (xy 47.206901 -237.005322) (xy 47.243153 -237.044393)
			(xy 47.273177 -237.08843) (xy 47.296303 -237.136451) (xy 47.312013 -237.187381) (xy 47.319956 -237.240085)
			(xy 47.320454 -237.266734) (xy 47.319956 -237.293383) (xy 50.708804 -237.293383) (xy 50.708804 -237.240085)
			(xy 50.716747 -237.187381) (xy 50.732457 -237.136451) (xy 50.755583 -237.08843) (xy 50.785607 -237.044393)
			(xy 50.821859 -237.005322) (xy 50.86353 -236.972091) (xy 50.909688 -236.945442) (xy 50.959302 -236.92597)
			(xy 51.011264 -236.91411) (xy 51.064414 -236.910127) (xy 51.117564 -236.91411) (xy 51.169526 -236.92597)
			(xy 51.21914 -236.945442) (xy 51.265298 -236.972091) (xy 51.306969 -237.005322) (xy 51.343221 -237.044393)
			(xy 51.373245 -237.08843) (xy 51.396371 -237.136451) (xy 51.412081 -237.187381) (xy 51.420024 -237.240085)
			(xy 51.420522 -237.266734) (xy 51.420024 -237.293383) (xy 51.412081 -237.346087) (xy 51.396371 -237.397017)
			(xy 51.373245 -237.445038) (xy 51.343221 -237.489075) (xy 51.306969 -237.528146) (xy 51.265298 -237.561377)
			(xy 51.21914 -237.588026) (xy 51.169526 -237.607498) (xy 51.117564 -237.619358) (xy 51.064414 -237.623342)
			(xy 51.011264 -237.619358) (xy 50.959302 -237.607498) (xy 50.909688 -237.588026) (xy 50.86353 -237.561377)
			(xy 50.821859 -237.528146) (xy 50.785607 -237.489075) (xy 50.755583 -237.445038) (xy 50.732457 -237.397017)
			(xy 50.716747 -237.346087) (xy 50.708804 -237.293383) (xy 47.319956 -237.293383) (xy 47.312013 -237.346087)
			(xy 47.296303 -237.397017) (xy 47.273177 -237.445038) (xy 47.243153 -237.489075) (xy 47.206901 -237.528146)
			(xy 47.16523 -237.561377) (xy 47.119072 -237.588026) (xy 47.069458 -237.607498) (xy 47.017496 -237.619358)
			(xy 46.964346 -237.623342) (xy 46.911196 -237.619358) (xy 46.859234 -237.607498) (xy 46.80962 -237.588026)
			(xy 46.763462 -237.561377) (xy 46.721791 -237.528146) (xy 46.685539 -237.489075) (xy 46.655515 -237.445038)
			(xy 46.632389 -237.397017) (xy 46.616679 -237.346087) (xy 46.608736 -237.293383) (xy 36.332424 -237.293383)
			(xy 36.324481 -237.346087) (xy 36.308771 -237.397017) (xy 36.285645 -237.445038) (xy 36.255621 -237.489075)
			(xy 36.219369 -237.528146) (xy 36.177698 -237.561377) (xy 36.13154 -237.588026) (xy 36.081926 -237.607498)
			(xy 36.029964 -237.619358) (xy 35.976814 -237.623342) (xy 35.923664 -237.619358) (xy 35.871702 -237.607498)
			(xy 35.822088 -237.588026) (xy 35.77593 -237.561377) (xy 35.734259 -237.528146) (xy 35.698007 -237.489075)
			(xy 35.667983 -237.445038) (xy 35.644857 -237.397017) (xy 35.629147 -237.346087) (xy 35.621204 -237.293383)
			(xy 32.232356 -237.293383) (xy 32.224413 -237.346087) (xy 32.208703 -237.397017) (xy 32.185577 -237.445038)
			(xy 32.155553 -237.489075) (xy 32.119301 -237.528146) (xy 32.07763 -237.561377) (xy 32.031472 -237.588026)
			(xy 31.981858 -237.607498) (xy 31.929896 -237.619358) (xy 31.876746 -237.623342) (xy 31.823596 -237.619358)
			(xy 31.771634 -237.607498) (xy 31.72202 -237.588026) (xy 31.675862 -237.561377) (xy 31.634191 -237.528146)
			(xy 31.597939 -237.489075) (xy 31.567915 -237.445038) (xy 31.544789 -237.397017) (xy 31.529079 -237.346087)
			(xy 31.521136 -237.293383) (xy 21.244824 -237.293383) (xy 21.236881 -237.346087) (xy 21.221171 -237.397017)
			(xy 21.198045 -237.445038) (xy 21.168021 -237.489075) (xy 21.131769 -237.528146) (xy 21.090098 -237.561377)
			(xy 21.04394 -237.588026) (xy 20.994326 -237.607498) (xy 20.942364 -237.619358) (xy 20.889214 -237.623342)
			(xy 20.836064 -237.619358) (xy 20.784102 -237.607498) (xy 20.734488 -237.588026) (xy 20.68833 -237.561377)
			(xy 20.646659 -237.528146) (xy 20.610407 -237.489075) (xy 20.580383 -237.445038) (xy 20.557257 -237.397017)
			(xy 20.541547 -237.346087) (xy 20.533604 -237.293383) (xy 17.144756 -237.293383) (xy 17.136813 -237.346087)
			(xy 17.121103 -237.397017) (xy 17.097977 -237.445038) (xy 17.067953 -237.489075) (xy 17.031701 -237.528146)
			(xy 16.99003 -237.561377) (xy 16.943872 -237.588026) (xy 16.894258 -237.607498) (xy 16.842296 -237.619358)
			(xy 16.789146 -237.623342) (xy 16.735996 -237.619358) (xy 16.684034 -237.607498) (xy 16.63442 -237.588026)
			(xy 16.588262 -237.561377) (xy 16.546591 -237.528146) (xy 16.510339 -237.489075) (xy 16.480315 -237.445038)
			(xy 16.457189 -237.397017) (xy 16.441479 -237.346087) (xy 16.433536 -237.293383) (xy 9.6774 -237.293383)
			(xy 9.6774 -238.143267) (xy 16.433536 -238.143267) (xy 16.433536 -238.089969) (xy 16.441479 -238.037265)
			(xy 16.457189 -237.986335) (xy 16.480315 -237.938314) (xy 16.510339 -237.894277) (xy 16.546591 -237.855206)
			(xy 16.588262 -237.821975) (xy 16.63442 -237.795326) (xy 16.684034 -237.775854) (xy 16.735996 -237.763994)
			(xy 16.789146 -237.760011) (xy 16.842296 -237.763994) (xy 16.894258 -237.775854) (xy 16.943872 -237.795326)
			(xy 16.99003 -237.821975) (xy 17.031701 -237.855206) (xy 17.067953 -237.894277) (xy 17.097977 -237.938314)
			(xy 17.121103 -237.986335) (xy 17.136813 -238.037265) (xy 17.144756 -238.089969) (xy 17.145254 -238.116618)
			(xy 17.144756 -238.143267) (xy 31.521136 -238.143267) (xy 31.521136 -238.089969) (xy 31.529079 -238.037265)
			(xy 31.544789 -237.986335) (xy 31.567915 -237.938314) (xy 31.597939 -237.894277) (xy 31.634191 -237.855206)
			(xy 31.675862 -237.821975) (xy 31.72202 -237.795326) (xy 31.771634 -237.775854) (xy 31.823596 -237.763994)
			(xy 31.876746 -237.760011) (xy 31.929896 -237.763994) (xy 31.981858 -237.775854) (xy 32.031472 -237.795326)
			(xy 32.07763 -237.821975) (xy 32.119301 -237.855206) (xy 32.155553 -237.894277) (xy 32.185577 -237.938314)
			(xy 32.208703 -237.986335) (xy 32.224413 -238.037265) (xy 32.232356 -238.089969) (xy 32.232854 -238.116618)
			(xy 32.232356 -238.143267) (xy 46.608736 -238.143267) (xy 46.608736 -238.089969) (xy 46.616679 -238.037265)
			(xy 46.632389 -237.986335) (xy 46.655515 -237.938314) (xy 46.685539 -237.894277) (xy 46.721791 -237.855206)
			(xy 46.763462 -237.821975) (xy 46.80962 -237.795326) (xy 46.859234 -237.775854) (xy 46.911196 -237.763994)
			(xy 46.964346 -237.760011) (xy 47.017496 -237.763994) (xy 47.069458 -237.775854) (xy 47.119072 -237.795326)
			(xy 47.16523 -237.821975) (xy 47.206901 -237.855206) (xy 47.243153 -237.894277) (xy 47.273177 -237.938314)
			(xy 47.296303 -237.986335) (xy 47.312013 -238.037265) (xy 47.319956 -238.089969) (xy 47.320454 -238.116618)
			(xy 47.319956 -238.143267) (xy 47.312013 -238.195971) (xy 47.296303 -238.246901) (xy 47.273177 -238.294922)
			(xy 47.243153 -238.338959) (xy 47.206901 -238.37803) (xy 47.16523 -238.411261) (xy 47.119072 -238.43791)
			(xy 47.069458 -238.457382) (xy 47.017496 -238.469242) (xy 46.964346 -238.473226) (xy 46.911196 -238.469242)
			(xy 46.859234 -238.457382) (xy 46.80962 -238.43791) (xy 46.763462 -238.411261) (xy 46.721791 -238.37803)
			(xy 46.685539 -238.338959) (xy 46.655515 -238.294922) (xy 46.632389 -238.246901) (xy 46.616679 -238.195971)
			(xy 46.608736 -238.143267) (xy 32.232356 -238.143267) (xy 32.224413 -238.195971) (xy 32.208703 -238.246901)
			(xy 32.185577 -238.294922) (xy 32.155553 -238.338959) (xy 32.119301 -238.37803) (xy 32.07763 -238.411261)
			(xy 32.031472 -238.43791) (xy 31.981858 -238.457382) (xy 31.929896 -238.469242) (xy 31.876746 -238.473226)
			(xy 31.823596 -238.469242) (xy 31.771634 -238.457382) (xy 31.72202 -238.43791) (xy 31.675862 -238.411261)
			(xy 31.634191 -238.37803) (xy 31.597939 -238.338959) (xy 31.567915 -238.294922) (xy 31.544789 -238.246901)
			(xy 31.529079 -238.195971) (xy 31.521136 -238.143267) (xy 17.144756 -238.143267) (xy 17.136813 -238.195971)
			(xy 17.121103 -238.246901) (xy 17.097977 -238.294922) (xy 17.067953 -238.338959) (xy 17.031701 -238.37803)
			(xy 16.99003 -238.411261) (xy 16.943872 -238.43791) (xy 16.894258 -238.457382) (xy 16.842296 -238.469242)
			(xy 16.789146 -238.473226) (xy 16.735996 -238.469242) (xy 16.684034 -238.457382) (xy 16.63442 -238.43791)
			(xy 16.588262 -238.411261) (xy 16.546591 -238.37803) (xy 16.510339 -238.338959) (xy 16.480315 -238.294922)
			(xy 16.457189 -238.246901) (xy 16.441479 -238.195971) (xy 16.433536 -238.143267) (xy 9.6774 -238.143267)
			(xy 9.6774 -238.993405) (xy 20.533604 -238.993405) (xy 20.533604 -238.940107) (xy 20.541547 -238.887403)
			(xy 20.557257 -238.836473) (xy 20.580383 -238.788452) (xy 20.610407 -238.744415) (xy 20.646659 -238.705344)
			(xy 20.68833 -238.672113) (xy 20.734488 -238.645464) (xy 20.784102 -238.625992) (xy 20.836064 -238.614132)
			(xy 20.889214 -238.610149) (xy 20.942364 -238.614132) (xy 20.994326 -238.625992) (xy 21.04394 -238.645464)
			(xy 21.090098 -238.672113) (xy 21.131769 -238.705344) (xy 21.168021 -238.744415) (xy 21.198045 -238.788452)
			(xy 21.221171 -238.836473) (xy 21.236881 -238.887403) (xy 21.244824 -238.940107) (xy 21.245322 -238.966756)
			(xy 21.244824 -238.993405) (xy 35.621204 -238.993405) (xy 35.621204 -238.940107) (xy 35.629147 -238.887403)
			(xy 35.644857 -238.836473) (xy 35.667983 -238.788452) (xy 35.698007 -238.744415) (xy 35.734259 -238.705344)
			(xy 35.77593 -238.672113) (xy 35.822088 -238.645464) (xy 35.871702 -238.625992) (xy 35.923664 -238.614132)
			(xy 35.976814 -238.610149) (xy 36.029964 -238.614132) (xy 36.081926 -238.625992) (xy 36.13154 -238.645464)
			(xy 36.177698 -238.672113) (xy 36.219369 -238.705344) (xy 36.255621 -238.744415) (xy 36.285645 -238.788452)
			(xy 36.308771 -238.836473) (xy 36.324481 -238.887403) (xy 36.332424 -238.940107) (xy 36.332922 -238.966756)
			(xy 36.332424 -238.993405) (xy 50.708804 -238.993405) (xy 50.708804 -238.940107) (xy 50.716747 -238.887403)
			(xy 50.732457 -238.836473) (xy 50.755583 -238.788452) (xy 50.785607 -238.744415) (xy 50.821859 -238.705344)
			(xy 50.86353 -238.672113) (xy 50.909688 -238.645464) (xy 50.959302 -238.625992) (xy 51.011264 -238.614132)
			(xy 51.064414 -238.610149) (xy 51.117564 -238.614132) (xy 51.169526 -238.625992) (xy 51.21914 -238.645464)
			(xy 51.265298 -238.672113) (xy 51.306969 -238.705344) (xy 51.343221 -238.744415) (xy 51.373245 -238.788452)
			(xy 51.396371 -238.836473) (xy 51.412081 -238.887403) (xy 51.420024 -238.940107) (xy 51.420522 -238.966756)
			(xy 51.420024 -238.993405) (xy 51.412081 -239.046109) (xy 51.396371 -239.097039) (xy 51.373245 -239.14506)
			(xy 51.343221 -239.189097) (xy 51.306969 -239.228168) (xy 51.265298 -239.261399) (xy 51.21914 -239.288048)
			(xy 51.169526 -239.30752) (xy 51.117564 -239.31938) (xy 51.064414 -239.323364) (xy 51.011264 -239.31938)
			(xy 50.959302 -239.30752) (xy 50.909688 -239.288048) (xy 50.86353 -239.261399) (xy 50.821859 -239.228168)
			(xy 50.785607 -239.189097) (xy 50.755583 -239.14506) (xy 50.732457 -239.097039) (xy 50.716747 -239.046109)
			(xy 50.708804 -238.993405) (xy 36.332424 -238.993405) (xy 36.324481 -239.046109) (xy 36.308771 -239.097039)
			(xy 36.285645 -239.14506) (xy 36.255621 -239.189097) (xy 36.219369 -239.228168) (xy 36.177698 -239.261399)
			(xy 36.13154 -239.288048) (xy 36.081926 -239.30752) (xy 36.029964 -239.31938) (xy 35.976814 -239.323364)
			(xy 35.923664 -239.31938) (xy 35.871702 -239.30752) (xy 35.822088 -239.288048) (xy 35.77593 -239.261399)
			(xy 35.734259 -239.228168) (xy 35.698007 -239.189097) (xy 35.667983 -239.14506) (xy 35.644857 -239.097039)
			(xy 35.629147 -239.046109) (xy 35.621204 -238.993405) (xy 21.244824 -238.993405) (xy 21.236881 -239.046109)
			(xy 21.221171 -239.097039) (xy 21.198045 -239.14506) (xy 21.168021 -239.189097) (xy 21.131769 -239.228168)
			(xy 21.090098 -239.261399) (xy 21.04394 -239.288048) (xy 20.994326 -239.30752) (xy 20.942364 -239.31938)
			(xy 20.889214 -239.323364) (xy 20.836064 -239.31938) (xy 20.784102 -239.30752) (xy 20.734488 -239.288048)
			(xy 20.68833 -239.261399) (xy 20.646659 -239.228168) (xy 20.610407 -239.189097) (xy 20.580383 -239.14506)
			(xy 20.557257 -239.097039) (xy 20.541547 -239.046109) (xy 20.533604 -238.993405) (xy 9.6774 -238.993405)
			(xy 9.6774 -239.843289) (xy 16.433536 -239.843289) (xy 16.433536 -239.789991) (xy 16.441479 -239.737287)
			(xy 16.457189 -239.686357) (xy 16.480315 -239.638336) (xy 16.510339 -239.594299) (xy 16.546591 -239.555228)
			(xy 16.588262 -239.521997) (xy 16.63442 -239.495348) (xy 16.684034 -239.475876) (xy 16.735996 -239.464016)
			(xy 16.789146 -239.460033) (xy 16.842296 -239.464016) (xy 16.894258 -239.475876) (xy 16.943872 -239.495348)
			(xy 16.99003 -239.521997) (xy 17.031701 -239.555228) (xy 17.067953 -239.594299) (xy 17.097977 -239.638336)
			(xy 17.121103 -239.686357) (xy 17.136813 -239.737287) (xy 17.144756 -239.789991) (xy 17.145254 -239.81664)
			(xy 17.144756 -239.843289) (xy 31.521136 -239.843289) (xy 31.521136 -239.789991) (xy 31.529079 -239.737287)
			(xy 31.544789 -239.686357) (xy 31.567915 -239.638336) (xy 31.597939 -239.594299) (xy 31.634191 -239.555228)
			(xy 31.675862 -239.521997) (xy 31.72202 -239.495348) (xy 31.771634 -239.475876) (xy 31.823596 -239.464016)
			(xy 31.876746 -239.460033) (xy 31.929896 -239.464016) (xy 31.981858 -239.475876) (xy 32.031472 -239.495348)
			(xy 32.07763 -239.521997) (xy 32.119301 -239.555228) (xy 32.155553 -239.594299) (xy 32.185577 -239.638336)
			(xy 32.208703 -239.686357) (xy 32.224413 -239.737287) (xy 32.232356 -239.789991) (xy 32.232854 -239.81664)
			(xy 32.232356 -239.843289) (xy 46.608736 -239.843289) (xy 46.608736 -239.789991) (xy 46.616679 -239.737287)
			(xy 46.632389 -239.686357) (xy 46.655515 -239.638336) (xy 46.685539 -239.594299) (xy 46.721791 -239.555228)
			(xy 46.763462 -239.521997) (xy 46.80962 -239.495348) (xy 46.859234 -239.475876) (xy 46.911196 -239.464016)
			(xy 46.964346 -239.460033) (xy 47.017496 -239.464016) (xy 47.069458 -239.475876) (xy 47.119072 -239.495348)
			(xy 47.16523 -239.521997) (xy 47.206901 -239.555228) (xy 47.243153 -239.594299) (xy 47.273177 -239.638336)
			(xy 47.296303 -239.686357) (xy 47.312013 -239.737287) (xy 47.319956 -239.789991) (xy 47.320454 -239.81664)
			(xy 47.319956 -239.843289) (xy 47.312013 -239.895993) (xy 47.296303 -239.946923) (xy 47.273177 -239.994944)
			(xy 47.243153 -240.038981) (xy 47.206901 -240.078052) (xy 47.16523 -240.111283) (xy 47.119072 -240.137932)
			(xy 47.069458 -240.157404) (xy 47.017496 -240.169264) (xy 46.964346 -240.173248) (xy 46.911196 -240.169264)
			(xy 46.859234 -240.157404) (xy 46.80962 -240.137932) (xy 46.763462 -240.111283) (xy 46.721791 -240.078052)
			(xy 46.685539 -240.038981) (xy 46.655515 -239.994944) (xy 46.632389 -239.946923) (xy 46.616679 -239.895993)
			(xy 46.608736 -239.843289) (xy 32.232356 -239.843289) (xy 32.224413 -239.895993) (xy 32.208703 -239.946923)
			(xy 32.185577 -239.994944) (xy 32.155553 -240.038981) (xy 32.119301 -240.078052) (xy 32.07763 -240.111283)
			(xy 32.031472 -240.137932) (xy 31.981858 -240.157404) (xy 31.929896 -240.169264) (xy 31.876746 -240.173248)
			(xy 31.823596 -240.169264) (xy 31.771634 -240.157404) (xy 31.72202 -240.137932) (xy 31.675862 -240.111283)
			(xy 31.634191 -240.078052) (xy 31.597939 -240.038981) (xy 31.567915 -239.994944) (xy 31.544789 -239.946923)
			(xy 31.529079 -239.895993) (xy 31.521136 -239.843289) (xy 17.144756 -239.843289) (xy 17.136813 -239.895993)
			(xy 17.121103 -239.946923) (xy 17.097977 -239.994944) (xy 17.067953 -240.038981) (xy 17.031701 -240.078052)
			(xy 16.99003 -240.111283) (xy 16.943872 -240.137932) (xy 16.894258 -240.157404) (xy 16.842296 -240.169264)
			(xy 16.789146 -240.173248) (xy 16.735996 -240.169264) (xy 16.684034 -240.157404) (xy 16.63442 -240.137932)
			(xy 16.588262 -240.111283) (xy 16.546591 -240.078052) (xy 16.510339 -240.038981) (xy 16.480315 -239.994944)
			(xy 16.457189 -239.946923) (xy 16.441479 -239.895993) (xy 16.433536 -239.843289) (xy 9.6774 -239.843289)
			(xy 9.6774 -240.693427) (xy 20.533604 -240.693427) (xy 20.533604 -240.640129) (xy 20.541547 -240.587425)
			(xy 20.557257 -240.536495) (xy 20.580383 -240.488474) (xy 20.610407 -240.444437) (xy 20.646659 -240.405366)
			(xy 20.68833 -240.372135) (xy 20.734488 -240.345486) (xy 20.784102 -240.326014) (xy 20.836064 -240.314154)
			(xy 20.889214 -240.310171) (xy 20.942364 -240.314154) (xy 20.994326 -240.326014) (xy 21.04394 -240.345486)
			(xy 21.090098 -240.372135) (xy 21.131769 -240.405366) (xy 21.168021 -240.444437) (xy 21.198045 -240.488474)
			(xy 21.221171 -240.536495) (xy 21.236881 -240.587425) (xy 21.244824 -240.640129) (xy 21.245322 -240.666778)
			(xy 21.244824 -240.693427) (xy 35.621204 -240.693427) (xy 35.621204 -240.640129) (xy 35.629147 -240.587425)
			(xy 35.644857 -240.536495) (xy 35.667983 -240.488474) (xy 35.698007 -240.444437) (xy 35.734259 -240.405366)
			(xy 35.77593 -240.372135) (xy 35.822088 -240.345486) (xy 35.871702 -240.326014) (xy 35.923664 -240.314154)
			(xy 35.976814 -240.310171) (xy 36.029964 -240.314154) (xy 36.081926 -240.326014) (xy 36.13154 -240.345486)
			(xy 36.177698 -240.372135) (xy 36.219369 -240.405366) (xy 36.255621 -240.444437) (xy 36.285645 -240.488474)
			(xy 36.308771 -240.536495) (xy 36.324481 -240.587425) (xy 36.332424 -240.640129) (xy 36.332922 -240.666778)
			(xy 36.332424 -240.693427) (xy 50.708804 -240.693427) (xy 50.708804 -240.640129) (xy 50.716747 -240.587425)
			(xy 50.732457 -240.536495) (xy 50.755583 -240.488474) (xy 50.785607 -240.444437) (xy 50.821859 -240.405366)
			(xy 50.86353 -240.372135) (xy 50.909688 -240.345486) (xy 50.959302 -240.326014) (xy 51.011264 -240.314154)
			(xy 51.064414 -240.310171) (xy 51.117564 -240.314154) (xy 51.169526 -240.326014) (xy 51.21914 -240.345486)
			(xy 51.265298 -240.372135) (xy 51.306969 -240.405366) (xy 51.343221 -240.444437) (xy 51.373245 -240.488474)
			(xy 51.396371 -240.536495) (xy 51.412081 -240.587425) (xy 51.420024 -240.640129) (xy 51.420522 -240.666778)
			(xy 51.420024 -240.693427) (xy 51.412081 -240.746131) (xy 51.396371 -240.797061) (xy 51.373245 -240.845082)
			(xy 51.343221 -240.889119) (xy 51.306969 -240.92819) (xy 51.265298 -240.961421) (xy 51.21914 -240.98807)
			(xy 51.169526 -241.007542) (xy 51.117564 -241.019402) (xy 51.064414 -241.023386) (xy 51.011264 -241.019402)
			(xy 50.959302 -241.007542) (xy 50.909688 -240.98807) (xy 50.86353 -240.961421) (xy 50.821859 -240.92819)
			(xy 50.785607 -240.889119) (xy 50.755583 -240.845082) (xy 50.732457 -240.797061) (xy 50.716747 -240.746131)
			(xy 50.708804 -240.693427) (xy 36.332424 -240.693427) (xy 36.324481 -240.746131) (xy 36.308771 -240.797061)
			(xy 36.285645 -240.845082) (xy 36.255621 -240.889119) (xy 36.219369 -240.92819) (xy 36.177698 -240.961421)
			(xy 36.13154 -240.98807) (xy 36.081926 -241.007542) (xy 36.029964 -241.019402) (xy 35.976814 -241.023386)
			(xy 35.923664 -241.019402) (xy 35.871702 -241.007542) (xy 35.822088 -240.98807) (xy 35.77593 -240.961421)
			(xy 35.734259 -240.92819) (xy 35.698007 -240.889119) (xy 35.667983 -240.845082) (xy 35.644857 -240.797061)
			(xy 35.629147 -240.746131) (xy 35.621204 -240.693427) (xy 21.244824 -240.693427) (xy 21.236881 -240.746131)
			(xy 21.221171 -240.797061) (xy 21.198045 -240.845082) (xy 21.168021 -240.889119) (xy 21.131769 -240.92819)
			(xy 21.090098 -240.961421) (xy 21.04394 -240.98807) (xy 20.994326 -241.007542) (xy 20.942364 -241.019402)
			(xy 20.889214 -241.023386) (xy 20.836064 -241.019402) (xy 20.784102 -241.007542) (xy 20.734488 -240.98807)
			(xy 20.68833 -240.961421) (xy 20.646659 -240.92819) (xy 20.610407 -240.889119) (xy 20.580383 -240.845082)
			(xy 20.557257 -240.797061) (xy 20.541547 -240.746131) (xy 20.533604 -240.693427) (xy 9.6774 -240.693427)
			(xy 9.6774 -241.543311) (xy 16.433536 -241.543311) (xy 16.433536 -241.490013) (xy 16.441479 -241.437309)
			(xy 16.457189 -241.386379) (xy 16.480315 -241.338358) (xy 16.510339 -241.294321) (xy 16.546591 -241.25525)
			(xy 16.588262 -241.222019) (xy 16.63442 -241.19537) (xy 16.684034 -241.175898) (xy 16.735996 -241.164038)
			(xy 16.789146 -241.160055) (xy 16.842296 -241.164038) (xy 16.894258 -241.175898) (xy 16.943872 -241.19537)
			(xy 16.99003 -241.222019) (xy 17.031701 -241.25525) (xy 17.067953 -241.294321) (xy 17.097977 -241.338358)
			(xy 17.121103 -241.386379) (xy 17.136813 -241.437309) (xy 17.144756 -241.490013) (xy 17.145254 -241.516662)
			(xy 17.144756 -241.543311) (xy 31.521136 -241.543311) (xy 31.521136 -241.490013) (xy 31.529079 -241.437309)
			(xy 31.544789 -241.386379) (xy 31.567915 -241.338358) (xy 31.597939 -241.294321) (xy 31.634191 -241.25525)
			(xy 31.675862 -241.222019) (xy 31.72202 -241.19537) (xy 31.771634 -241.175898) (xy 31.823596 -241.164038)
			(xy 31.876746 -241.160055) (xy 31.929896 -241.164038) (xy 31.981858 -241.175898) (xy 32.031472 -241.19537)
			(xy 32.07763 -241.222019) (xy 32.119301 -241.25525) (xy 32.155553 -241.294321) (xy 32.185577 -241.338358)
			(xy 32.208703 -241.386379) (xy 32.224413 -241.437309) (xy 32.232356 -241.490013) (xy 32.232854 -241.516662)
			(xy 32.232356 -241.543311) (xy 46.608736 -241.543311) (xy 46.608736 -241.490013) (xy 46.616679 -241.437309)
			(xy 46.632389 -241.386379) (xy 46.655515 -241.338358) (xy 46.685539 -241.294321) (xy 46.721791 -241.25525)
			(xy 46.763462 -241.222019) (xy 46.80962 -241.19537) (xy 46.859234 -241.175898) (xy 46.911196 -241.164038)
			(xy 46.964346 -241.160055) (xy 47.017496 -241.164038) (xy 47.069458 -241.175898) (xy 47.119072 -241.19537)
			(xy 47.16523 -241.222019) (xy 47.206901 -241.25525) (xy 47.243153 -241.294321) (xy 47.273177 -241.338358)
			(xy 47.296303 -241.386379) (xy 47.312013 -241.437309) (xy 47.319956 -241.490013) (xy 47.320454 -241.516662)
			(xy 47.319956 -241.543311) (xy 47.312013 -241.596015) (xy 47.296303 -241.646945) (xy 47.273177 -241.694966)
			(xy 47.243153 -241.739003) (xy 47.206901 -241.778074) (xy 47.16523 -241.811305) (xy 47.119072 -241.837954)
			(xy 47.069458 -241.857426) (xy 47.017496 -241.869286) (xy 46.964346 -241.87327) (xy 46.911196 -241.869286)
			(xy 46.859234 -241.857426) (xy 46.80962 -241.837954) (xy 46.763462 -241.811305) (xy 46.721791 -241.778074)
			(xy 46.685539 -241.739003) (xy 46.655515 -241.694966) (xy 46.632389 -241.646945) (xy 46.616679 -241.596015)
			(xy 46.608736 -241.543311) (xy 32.232356 -241.543311) (xy 32.224413 -241.596015) (xy 32.208703 -241.646945)
			(xy 32.185577 -241.694966) (xy 32.155553 -241.739003) (xy 32.119301 -241.778074) (xy 32.07763 -241.811305)
			(xy 32.031472 -241.837954) (xy 31.981858 -241.857426) (xy 31.929896 -241.869286) (xy 31.876746 -241.87327)
			(xy 31.823596 -241.869286) (xy 31.771634 -241.857426) (xy 31.72202 -241.837954) (xy 31.675862 -241.811305)
			(xy 31.634191 -241.778074) (xy 31.597939 -241.739003) (xy 31.567915 -241.694966) (xy 31.544789 -241.646945)
			(xy 31.529079 -241.596015) (xy 31.521136 -241.543311) (xy 17.144756 -241.543311) (xy 17.136813 -241.596015)
			(xy 17.121103 -241.646945) (xy 17.097977 -241.694966) (xy 17.067953 -241.739003) (xy 17.031701 -241.778074)
			(xy 16.99003 -241.811305) (xy 16.943872 -241.837954) (xy 16.894258 -241.857426) (xy 16.842296 -241.869286)
			(xy 16.789146 -241.87327) (xy 16.735996 -241.869286) (xy 16.684034 -241.857426) (xy 16.63442 -241.837954)
			(xy 16.588262 -241.811305) (xy 16.546591 -241.778074) (xy 16.510339 -241.739003) (xy 16.480315 -241.694966)
			(xy 16.457189 -241.646945) (xy 16.441479 -241.596015) (xy 16.433536 -241.543311) (xy 9.6774 -241.543311)
			(xy 9.6774 -242.393449) (xy 12.989804 -242.393449) (xy 12.989804 -242.340151) (xy 12.997747 -242.287447)
			(xy 13.013457 -242.236517) (xy 13.036583 -242.188496) (xy 13.066607 -242.144459) (xy 13.102859 -242.105388)
			(xy 13.14453 -242.072157) (xy 13.190688 -242.045508) (xy 13.240302 -242.026036) (xy 13.292264 -242.014176)
			(xy 13.345414 -242.010193) (xy 13.398564 -242.014176) (xy 13.450526 -242.026036) (xy 13.50014 -242.045508)
			(xy 13.546298 -242.072157) (xy 13.587969 -242.105388) (xy 13.624221 -242.144459) (xy 13.654245 -242.188496)
			(xy 13.677371 -242.236517) (xy 13.693081 -242.287447) (xy 13.701024 -242.340151) (xy 13.701522 -242.3668)
			(xy 13.701024 -242.393449) (xy 20.533604 -242.393449) (xy 20.533604 -242.340151) (xy 20.541547 -242.287447)
			(xy 20.557257 -242.236517) (xy 20.580383 -242.188496) (xy 20.610407 -242.144459) (xy 20.646659 -242.105388)
			(xy 20.68833 -242.072157) (xy 20.734488 -242.045508) (xy 20.784102 -242.026036) (xy 20.836064 -242.014176)
			(xy 20.889214 -242.010193) (xy 20.942364 -242.014176) (xy 20.994326 -242.026036) (xy 21.04394 -242.045508)
			(xy 21.090098 -242.072157) (xy 21.131769 -242.105388) (xy 21.168021 -242.144459) (xy 21.198045 -242.188496)
			(xy 21.221171 -242.236517) (xy 21.236881 -242.287447) (xy 21.244824 -242.340151) (xy 21.245322 -242.3668)
			(xy 21.244824 -242.393449) (xy 28.077404 -242.393449) (xy 28.077404 -242.340151) (xy 28.085347 -242.287447)
			(xy 28.101057 -242.236517) (xy 28.124183 -242.188496) (xy 28.154207 -242.144459) (xy 28.190459 -242.105388)
			(xy 28.23213 -242.072157) (xy 28.278288 -242.045508) (xy 28.327902 -242.026036) (xy 28.379864 -242.014176)
			(xy 28.433014 -242.010193) (xy 28.486164 -242.014176) (xy 28.538126 -242.026036) (xy 28.58774 -242.045508)
			(xy 28.633898 -242.072157) (xy 28.675569 -242.105388) (xy 28.711821 -242.144459) (xy 28.741845 -242.188496)
			(xy 28.764971 -242.236517) (xy 28.780681 -242.287447) (xy 28.788624 -242.340151) (xy 28.789122 -242.3668)
			(xy 28.788624 -242.393449) (xy 35.621204 -242.393449) (xy 35.621204 -242.340151) (xy 35.629147 -242.287447)
			(xy 35.644857 -242.236517) (xy 35.667983 -242.188496) (xy 35.698007 -242.144459) (xy 35.734259 -242.105388)
			(xy 35.77593 -242.072157) (xy 35.822088 -242.045508) (xy 35.871702 -242.026036) (xy 35.923664 -242.014176)
			(xy 35.976814 -242.010193) (xy 36.029964 -242.014176) (xy 36.081926 -242.026036) (xy 36.13154 -242.045508)
			(xy 36.177698 -242.072157) (xy 36.219369 -242.105388) (xy 36.255621 -242.144459) (xy 36.285645 -242.188496)
			(xy 36.308771 -242.236517) (xy 36.324481 -242.287447) (xy 36.332424 -242.340151) (xy 36.332922 -242.3668)
			(xy 36.332424 -242.393449) (xy 43.165004 -242.393449) (xy 43.165004 -242.340151) (xy 43.172947 -242.287447)
			(xy 43.188657 -242.236517) (xy 43.211783 -242.188496) (xy 43.241807 -242.144459) (xy 43.278059 -242.105388)
			(xy 43.31973 -242.072157) (xy 43.365888 -242.045508) (xy 43.415502 -242.026036) (xy 43.467464 -242.014176)
			(xy 43.520614 -242.010193) (xy 43.573764 -242.014176) (xy 43.625726 -242.026036) (xy 43.67534 -242.045508)
			(xy 43.721498 -242.072157) (xy 43.763169 -242.105388) (xy 43.799421 -242.144459) (xy 43.829445 -242.188496)
			(xy 43.852571 -242.236517) (xy 43.868281 -242.287447) (xy 43.876224 -242.340151) (xy 43.876722 -242.3668)
			(xy 43.876224 -242.393449) (xy 50.708804 -242.393449) (xy 50.708804 -242.340151) (xy 50.716747 -242.287447)
			(xy 50.732457 -242.236517) (xy 50.755583 -242.188496) (xy 50.785607 -242.144459) (xy 50.821859 -242.105388)
			(xy 50.86353 -242.072157) (xy 50.909688 -242.045508) (xy 50.959302 -242.026036) (xy 51.011264 -242.014176)
			(xy 51.064414 -242.010193) (xy 51.117564 -242.014176) (xy 51.169526 -242.026036) (xy 51.21914 -242.045508)
			(xy 51.265298 -242.072157) (xy 51.306969 -242.105388) (xy 51.343221 -242.144459) (xy 51.373245 -242.188496)
			(xy 51.396371 -242.236517) (xy 51.412081 -242.287447) (xy 51.420024 -242.340151) (xy 51.420522 -242.3668)
			(xy 51.420024 -242.393449) (xy 56.042804 -242.393449) (xy 56.042804 -242.340151) (xy 56.050747 -242.287447)
			(xy 56.066457 -242.236517) (xy 56.089583 -242.188496) (xy 56.119607 -242.144459) (xy 56.155859 -242.105388)
			(xy 56.19753 -242.072157) (xy 56.243688 -242.045508) (xy 56.293302 -242.026036) (xy 56.345264 -242.014176)
			(xy 56.398414 -242.010193) (xy 56.451564 -242.014176) (xy 56.503526 -242.026036) (xy 56.55314 -242.045508)
			(xy 56.599298 -242.072157) (xy 56.640969 -242.105388) (xy 56.677221 -242.144459) (xy 56.707245 -242.188496)
			(xy 56.730371 -242.236517) (xy 56.746081 -242.287447) (xy 56.754024 -242.340151) (xy 56.754522 -242.3668)
			(xy 56.754024 -242.393449) (xy 63.586604 -242.393449) (xy 63.586604 -242.340151) (xy 63.594547 -242.287447)
			(xy 63.610257 -242.236517) (xy 63.633383 -242.188496) (xy 63.663407 -242.144459) (xy 63.699659 -242.105388)
			(xy 63.74133 -242.072157) (xy 63.787488 -242.045508) (xy 63.837102 -242.026036) (xy 63.889064 -242.014176)
			(xy 63.942214 -242.010193) (xy 63.995364 -242.014176) (xy 64.047326 -242.026036) (xy 64.09694 -242.045508)
			(xy 64.143098 -242.072157) (xy 64.184769 -242.105388) (xy 64.221021 -242.144459) (xy 64.251045 -242.188496)
			(xy 64.274171 -242.236517) (xy 64.289881 -242.287447) (xy 64.297824 -242.340151) (xy 64.298322 -242.3668)
			(xy 64.297824 -242.393449) (xy 64.289881 -242.446153) (xy 64.274171 -242.497083) (xy 64.251045 -242.545104)
			(xy 64.221021 -242.589141) (xy 64.184769 -242.628212) (xy 64.143098 -242.661443) (xy 64.09694 -242.688092)
			(xy 64.047326 -242.707564) (xy 63.995364 -242.719424) (xy 63.942214 -242.723408) (xy 63.889064 -242.719424)
			(xy 63.837102 -242.707564) (xy 63.787488 -242.688092) (xy 63.74133 -242.661443) (xy 63.699659 -242.628212)
			(xy 63.663407 -242.589141) (xy 63.633383 -242.545104) (xy 63.610257 -242.497083) (xy 63.594547 -242.446153)
			(xy 63.586604 -242.393449) (xy 56.754024 -242.393449) (xy 56.746081 -242.446153) (xy 56.730371 -242.497083)
			(xy 56.707245 -242.545104) (xy 56.677221 -242.589141) (xy 56.640969 -242.628212) (xy 56.599298 -242.661443)
			(xy 56.55314 -242.688092) (xy 56.503526 -242.707564) (xy 56.451564 -242.719424) (xy 56.398414 -242.723408)
			(xy 56.345264 -242.719424) (xy 56.293302 -242.707564) (xy 56.243688 -242.688092) (xy 56.19753 -242.661443)
			(xy 56.155859 -242.628212) (xy 56.119607 -242.589141) (xy 56.089583 -242.545104) (xy 56.066457 -242.497083)
			(xy 56.050747 -242.446153) (xy 56.042804 -242.393449) (xy 51.420024 -242.393449) (xy 51.412081 -242.446153)
			(xy 51.396371 -242.497083) (xy 51.373245 -242.545104) (xy 51.343221 -242.589141) (xy 51.306969 -242.628212)
			(xy 51.265298 -242.661443) (xy 51.21914 -242.688092) (xy 51.169526 -242.707564) (xy 51.117564 -242.719424)
			(xy 51.064414 -242.723408) (xy 51.011264 -242.719424) (xy 50.959302 -242.707564) (xy 50.909688 -242.688092)
			(xy 50.86353 -242.661443) (xy 50.821859 -242.628212) (xy 50.785607 -242.589141) (xy 50.755583 -242.545104)
			(xy 50.732457 -242.497083) (xy 50.716747 -242.446153) (xy 50.708804 -242.393449) (xy 43.876224 -242.393449)
			(xy 43.868281 -242.446153) (xy 43.852571 -242.497083) (xy 43.829445 -242.545104) (xy 43.799421 -242.589141)
			(xy 43.763169 -242.628212) (xy 43.721498 -242.661443) (xy 43.67534 -242.688092) (xy 43.625726 -242.707564)
			(xy 43.573764 -242.719424) (xy 43.520614 -242.723408) (xy 43.467464 -242.719424) (xy 43.415502 -242.707564)
			(xy 43.365888 -242.688092) (xy 43.31973 -242.661443) (xy 43.278059 -242.628212) (xy 43.241807 -242.589141)
			(xy 43.211783 -242.545104) (xy 43.188657 -242.497083) (xy 43.172947 -242.446153) (xy 43.165004 -242.393449)
			(xy 36.332424 -242.393449) (xy 36.324481 -242.446153) (xy 36.308771 -242.497083) (xy 36.285645 -242.545104)
			(xy 36.255621 -242.589141) (xy 36.219369 -242.628212) (xy 36.177698 -242.661443) (xy 36.13154 -242.688092)
			(xy 36.081926 -242.707564) (xy 36.029964 -242.719424) (xy 35.976814 -242.723408) (xy 35.923664 -242.719424)
			(xy 35.871702 -242.707564) (xy 35.822088 -242.688092) (xy 35.77593 -242.661443) (xy 35.734259 -242.628212)
			(xy 35.698007 -242.589141) (xy 35.667983 -242.545104) (xy 35.644857 -242.497083) (xy 35.629147 -242.446153)
			(xy 35.621204 -242.393449) (xy 28.788624 -242.393449) (xy 28.780681 -242.446153) (xy 28.764971 -242.497083)
			(xy 28.741845 -242.545104) (xy 28.711821 -242.589141) (xy 28.675569 -242.628212) (xy 28.633898 -242.661443)
			(xy 28.58774 -242.688092) (xy 28.538126 -242.707564) (xy 28.486164 -242.719424) (xy 28.433014 -242.723408)
			(xy 28.379864 -242.719424) (xy 28.327902 -242.707564) (xy 28.278288 -242.688092) (xy 28.23213 -242.661443)
			(xy 28.190459 -242.628212) (xy 28.154207 -242.589141) (xy 28.124183 -242.545104) (xy 28.101057 -242.497083)
			(xy 28.085347 -242.446153) (xy 28.077404 -242.393449) (xy 21.244824 -242.393449) (xy 21.236881 -242.446153)
			(xy 21.221171 -242.497083) (xy 21.198045 -242.545104) (xy 21.168021 -242.589141) (xy 21.131769 -242.628212)
			(xy 21.090098 -242.661443) (xy 21.04394 -242.688092) (xy 20.994326 -242.707564) (xy 20.942364 -242.719424)
			(xy 20.889214 -242.723408) (xy 20.836064 -242.719424) (xy 20.784102 -242.707564) (xy 20.734488 -242.688092)
			(xy 20.68833 -242.661443) (xy 20.646659 -242.628212) (xy 20.610407 -242.589141) (xy 20.580383 -242.545104)
			(xy 20.557257 -242.497083) (xy 20.541547 -242.446153) (xy 20.533604 -242.393449) (xy 13.701024 -242.393449)
			(xy 13.693081 -242.446153) (xy 13.677371 -242.497083) (xy 13.654245 -242.545104) (xy 13.624221 -242.589141)
			(xy 13.587969 -242.628212) (xy 13.546298 -242.661443) (xy 13.50014 -242.688092) (xy 13.450526 -242.707564)
			(xy 13.398564 -242.719424) (xy 13.345414 -242.723408) (xy 13.292264 -242.719424) (xy 13.240302 -242.707564)
			(xy 13.190688 -242.688092) (xy 13.14453 -242.661443) (xy 13.102859 -242.628212) (xy 13.066607 -242.589141)
			(xy 13.036583 -242.545104) (xy 13.013457 -242.497083) (xy 12.997747 -242.446153) (xy 12.989804 -242.393449)
			(xy 9.6774 -242.393449) (xy 9.6774 -243.243333) (xy 12.989804 -243.243333) (xy 12.989804 -243.190035)
			(xy 12.997747 -243.137331) (xy 13.013457 -243.086401) (xy 13.036583 -243.03838) (xy 13.066607 -242.994343)
			(xy 13.102859 -242.955272) (xy 13.14453 -242.922041) (xy 13.190688 -242.895392) (xy 13.240302 -242.87592)
			(xy 13.292264 -242.86406) (xy 13.345414 -242.860077) (xy 13.398564 -242.86406) (xy 13.450526 -242.87592)
			(xy 13.50014 -242.895392) (xy 13.546298 -242.922041) (xy 13.587969 -242.955272) (xy 13.624221 -242.994343)
			(xy 13.654245 -243.03838) (xy 13.677371 -243.086401) (xy 13.693081 -243.137331) (xy 13.701024 -243.190035)
			(xy 13.701522 -243.216684) (xy 13.701024 -243.243333) (xy 16.433536 -243.243333) (xy 16.433536 -243.190035)
			(xy 16.441479 -243.137331) (xy 16.457189 -243.086401) (xy 16.480315 -243.03838) (xy 16.510339 -242.994343)
			(xy 16.546591 -242.955272) (xy 16.588262 -242.922041) (xy 16.63442 -242.895392) (xy 16.684034 -242.87592)
			(xy 16.735996 -242.86406) (xy 16.789146 -242.860077) (xy 16.842296 -242.86406) (xy 16.894258 -242.87592)
			(xy 16.943872 -242.895392) (xy 16.99003 -242.922041) (xy 17.031701 -242.955272) (xy 17.067953 -242.994343)
			(xy 17.097977 -243.03838) (xy 17.121103 -243.086401) (xy 17.136813 -243.137331) (xy 17.144756 -243.190035)
			(xy 17.145254 -243.216684) (xy 17.144756 -243.243333) (xy 20.533604 -243.243333) (xy 20.533604 -243.190035)
			(xy 20.541547 -243.137331) (xy 20.557257 -243.086401) (xy 20.580383 -243.03838) (xy 20.610407 -242.994343)
			(xy 20.646659 -242.955272) (xy 20.68833 -242.922041) (xy 20.734488 -242.895392) (xy 20.784102 -242.87592)
			(xy 20.836064 -242.86406) (xy 20.889214 -242.860077) (xy 20.942364 -242.86406) (xy 20.994326 -242.87592)
			(xy 21.04394 -242.895392) (xy 21.090098 -242.922041) (xy 21.131769 -242.955272) (xy 21.168021 -242.994343)
			(xy 21.198045 -243.03838) (xy 21.221171 -243.086401) (xy 21.236881 -243.137331) (xy 21.244824 -243.190035)
			(xy 21.245322 -243.216684) (xy 21.244824 -243.243333) (xy 23.977336 -243.243333) (xy 23.977336 -243.190035)
			(xy 23.985279 -243.137331) (xy 24.000989 -243.086401) (xy 24.024115 -243.03838) (xy 24.054139 -242.994343)
			(xy 24.090391 -242.955272) (xy 24.132062 -242.922041) (xy 24.17822 -242.895392) (xy 24.227834 -242.87592)
			(xy 24.279796 -242.86406) (xy 24.332946 -242.860077) (xy 24.386096 -242.86406) (xy 24.438058 -242.87592)
			(xy 24.487672 -242.895392) (xy 24.53383 -242.922041) (xy 24.575501 -242.955272) (xy 24.611753 -242.994343)
			(xy 24.641777 -243.03838) (xy 24.664903 -243.086401) (xy 24.680613 -243.137331) (xy 24.688556 -243.190035)
			(xy 24.689054 -243.216684) (xy 24.688556 -243.243333) (xy 28.077404 -243.243333) (xy 28.077404 -243.190035)
			(xy 28.085347 -243.137331) (xy 28.101057 -243.086401) (xy 28.124183 -243.03838) (xy 28.154207 -242.994343)
			(xy 28.190459 -242.955272) (xy 28.23213 -242.922041) (xy 28.278288 -242.895392) (xy 28.327902 -242.87592)
			(xy 28.379864 -242.86406) (xy 28.433014 -242.860077) (xy 28.486164 -242.86406) (xy 28.538126 -242.87592)
			(xy 28.58774 -242.895392) (xy 28.633898 -242.922041) (xy 28.675569 -242.955272) (xy 28.711821 -242.994343)
			(xy 28.741845 -243.03838) (xy 28.764971 -243.086401) (xy 28.780681 -243.137331) (xy 28.788624 -243.190035)
			(xy 28.789122 -243.216684) (xy 28.788624 -243.243333) (xy 31.521136 -243.243333) (xy 31.521136 -243.190035)
			(xy 31.529079 -243.137331) (xy 31.544789 -243.086401) (xy 31.567915 -243.03838) (xy 31.597939 -242.994343)
			(xy 31.634191 -242.955272) (xy 31.675862 -242.922041) (xy 31.72202 -242.895392) (xy 31.771634 -242.87592)
			(xy 31.823596 -242.86406) (xy 31.876746 -242.860077) (xy 31.929896 -242.86406) (xy 31.981858 -242.87592)
			(xy 32.031472 -242.895392) (xy 32.07763 -242.922041) (xy 32.119301 -242.955272) (xy 32.155553 -242.994343)
			(xy 32.185577 -243.03838) (xy 32.208703 -243.086401) (xy 32.224413 -243.137331) (xy 32.232356 -243.190035)
			(xy 32.232854 -243.216684) (xy 32.232356 -243.243333) (xy 35.621204 -243.243333) (xy 35.621204 -243.190035)
			(xy 35.629147 -243.137331) (xy 35.644857 -243.086401) (xy 35.667983 -243.03838) (xy 35.698007 -242.994343)
			(xy 35.734259 -242.955272) (xy 35.77593 -242.922041) (xy 35.822088 -242.895392) (xy 35.871702 -242.87592)
			(xy 35.923664 -242.86406) (xy 35.976814 -242.860077) (xy 36.029964 -242.86406) (xy 36.081926 -242.87592)
			(xy 36.13154 -242.895392) (xy 36.177698 -242.922041) (xy 36.219369 -242.955272) (xy 36.255621 -242.994343)
			(xy 36.285645 -243.03838) (xy 36.308771 -243.086401) (xy 36.324481 -243.137331) (xy 36.332424 -243.190035)
			(xy 36.332922 -243.216684) (xy 36.332424 -243.243333) (xy 39.064936 -243.243333) (xy 39.064936 -243.190035)
			(xy 39.072879 -243.137331) (xy 39.088589 -243.086401) (xy 39.111715 -243.03838) (xy 39.141739 -242.994343)
			(xy 39.177991 -242.955272) (xy 39.219662 -242.922041) (xy 39.26582 -242.895392) (xy 39.315434 -242.87592)
			(xy 39.367396 -242.86406) (xy 39.420546 -242.860077) (xy 39.473696 -242.86406) (xy 39.525658 -242.87592)
			(xy 39.575272 -242.895392) (xy 39.62143 -242.922041) (xy 39.663101 -242.955272) (xy 39.699353 -242.994343)
			(xy 39.729377 -243.03838) (xy 39.752503 -243.086401) (xy 39.768213 -243.137331) (xy 39.776156 -243.190035)
			(xy 39.776654 -243.216684) (xy 39.776156 -243.243333) (xy 43.165004 -243.243333) (xy 43.165004 -243.190035)
			(xy 43.172947 -243.137331) (xy 43.188657 -243.086401) (xy 43.211783 -243.03838) (xy 43.241807 -242.994343)
			(xy 43.278059 -242.955272) (xy 43.31973 -242.922041) (xy 43.365888 -242.895392) (xy 43.415502 -242.87592)
			(xy 43.467464 -242.86406) (xy 43.520614 -242.860077) (xy 43.573764 -242.86406) (xy 43.625726 -242.87592)
			(xy 43.67534 -242.895392) (xy 43.721498 -242.922041) (xy 43.763169 -242.955272) (xy 43.799421 -242.994343)
			(xy 43.829445 -243.03838) (xy 43.852571 -243.086401) (xy 43.868281 -243.137331) (xy 43.876224 -243.190035)
			(xy 43.876722 -243.216684) (xy 43.876224 -243.243333) (xy 46.608736 -243.243333) (xy 46.608736 -243.190035)
			(xy 46.616679 -243.137331) (xy 46.632389 -243.086401) (xy 46.655515 -243.03838) (xy 46.685539 -242.994343)
			(xy 46.721791 -242.955272) (xy 46.763462 -242.922041) (xy 46.80962 -242.895392) (xy 46.859234 -242.87592)
			(xy 46.911196 -242.86406) (xy 46.964346 -242.860077) (xy 47.017496 -242.86406) (xy 47.069458 -242.87592)
			(xy 47.119072 -242.895392) (xy 47.16523 -242.922041) (xy 47.206901 -242.955272) (xy 47.243153 -242.994343)
			(xy 47.273177 -243.03838) (xy 47.296303 -243.086401) (xy 47.312013 -243.137331) (xy 47.319956 -243.190035)
			(xy 47.320454 -243.216684) (xy 47.319956 -243.243333) (xy 50.708804 -243.243333) (xy 50.708804 -243.190035)
			(xy 50.716747 -243.137331) (xy 50.732457 -243.086401) (xy 50.755583 -243.03838) (xy 50.785607 -242.994343)
			(xy 50.821859 -242.955272) (xy 50.86353 -242.922041) (xy 50.909688 -242.895392) (xy 50.959302 -242.87592)
			(xy 51.011264 -242.86406) (xy 51.064414 -242.860077) (xy 51.117564 -242.86406) (xy 51.169526 -242.87592)
			(xy 51.21914 -242.895392) (xy 51.265298 -242.922041) (xy 51.306969 -242.955272) (xy 51.343221 -242.994343)
			(xy 51.373245 -243.03838) (xy 51.396371 -243.086401) (xy 51.412081 -243.137331) (xy 51.420024 -243.190035)
			(xy 51.420522 -243.216684) (xy 51.420024 -243.243333) (xy 54.152536 -243.243333) (xy 54.152536 -243.190035)
			(xy 54.160479 -243.137331) (xy 54.176189 -243.086401) (xy 54.199315 -243.03838) (xy 54.229339 -242.994343)
			(xy 54.265591 -242.955272) (xy 54.307262 -242.922041) (xy 54.35342 -242.895392) (xy 54.403034 -242.87592)
			(xy 54.454996 -242.86406) (xy 54.508146 -242.860077) (xy 54.561296 -242.86406) (xy 54.613258 -242.87592)
			(xy 54.662872 -242.895392) (xy 54.70903 -242.922041) (xy 54.750701 -242.955272) (xy 54.786953 -242.994343)
			(xy 54.816977 -243.03838) (xy 54.840103 -243.086401) (xy 54.855813 -243.137331) (xy 54.863756 -243.190035)
			(xy 54.864254 -243.216684) (xy 54.863756 -243.243333) (xy 56.042804 -243.243333) (xy 56.042804 -243.190035)
			(xy 56.050747 -243.137331) (xy 56.066457 -243.086401) (xy 56.089583 -243.03838) (xy 56.119607 -242.994343)
			(xy 56.155859 -242.955272) (xy 56.19753 -242.922041) (xy 56.243688 -242.895392) (xy 56.293302 -242.87592)
			(xy 56.345264 -242.86406) (xy 56.398414 -242.860077) (xy 56.451564 -242.86406) (xy 56.503526 -242.87592)
			(xy 56.55314 -242.895392) (xy 56.599298 -242.922041) (xy 56.640969 -242.955272) (xy 56.677221 -242.994343)
			(xy 56.707245 -243.03838) (xy 56.730371 -243.086401) (xy 56.746081 -243.137331) (xy 56.754024 -243.190035)
			(xy 56.754522 -243.216684) (xy 56.754024 -243.243333) (xy 61.696336 -243.243333) (xy 61.696336 -243.190035)
			(xy 61.704279 -243.137331) (xy 61.719989 -243.086401) (xy 61.743115 -243.03838) (xy 61.773139 -242.994343)
			(xy 61.809391 -242.955272) (xy 61.851062 -242.922041) (xy 61.89722 -242.895392) (xy 61.946834 -242.87592)
			(xy 61.998796 -242.86406) (xy 62.051946 -242.860077) (xy 62.105096 -242.86406) (xy 62.157058 -242.87592)
			(xy 62.206672 -242.895392) (xy 62.25283 -242.922041) (xy 62.294501 -242.955272) (xy 62.330753 -242.994343)
			(xy 62.360777 -243.03838) (xy 62.383903 -243.086401) (xy 62.399613 -243.137331) (xy 62.407556 -243.190035)
			(xy 62.408054 -243.216684) (xy 62.407556 -243.243333) (xy 63.586604 -243.243333) (xy 63.586604 -243.190035)
			(xy 63.594547 -243.137331) (xy 63.610257 -243.086401) (xy 63.633383 -243.03838) (xy 63.663407 -242.994343)
			(xy 63.699659 -242.955272) (xy 63.74133 -242.922041) (xy 63.787488 -242.895392) (xy 63.837102 -242.87592)
			(xy 63.889064 -242.86406) (xy 63.942214 -242.860077) (xy 63.995364 -242.86406) (xy 64.047326 -242.87592)
			(xy 64.09694 -242.895392) (xy 64.143098 -242.922041) (xy 64.184769 -242.955272) (xy 64.221021 -242.994343)
			(xy 64.251045 -243.03838) (xy 64.274171 -243.086401) (xy 64.289881 -243.137331) (xy 64.297824 -243.190035)
			(xy 64.298322 -243.216684) (xy 64.297824 -243.243333) (xy 64.289881 -243.296037) (xy 64.274171 -243.346967)
			(xy 64.251045 -243.394988) (xy 64.221021 -243.439025) (xy 64.184769 -243.478096) (xy 64.143098 -243.511327)
			(xy 64.09694 -243.537976) (xy 64.047326 -243.557448) (xy 63.995364 -243.569308) (xy 63.942214 -243.573292)
			(xy 63.889064 -243.569308) (xy 63.837102 -243.557448) (xy 63.787488 -243.537976) (xy 63.74133 -243.511327)
			(xy 63.699659 -243.478096) (xy 63.663407 -243.439025) (xy 63.633383 -243.394988) (xy 63.610257 -243.346967)
			(xy 63.594547 -243.296037) (xy 63.586604 -243.243333) (xy 62.407556 -243.243333) (xy 62.399613 -243.296037)
			(xy 62.383903 -243.346967) (xy 62.360777 -243.394988) (xy 62.330753 -243.439025) (xy 62.294501 -243.478096)
			(xy 62.25283 -243.511327) (xy 62.206672 -243.537976) (xy 62.157058 -243.557448) (xy 62.105096 -243.569308)
			(xy 62.051946 -243.573292) (xy 61.998796 -243.569308) (xy 61.946834 -243.557448) (xy 61.89722 -243.537976)
			(xy 61.851062 -243.511327) (xy 61.809391 -243.478096) (xy 61.773139 -243.439025) (xy 61.743115 -243.394988)
			(xy 61.719989 -243.346967) (xy 61.704279 -243.296037) (xy 61.696336 -243.243333) (xy 56.754024 -243.243333)
			(xy 56.746081 -243.296037) (xy 56.730371 -243.346967) (xy 56.707245 -243.394988) (xy 56.677221 -243.439025)
			(xy 56.640969 -243.478096) (xy 56.599298 -243.511327) (xy 56.55314 -243.537976) (xy 56.503526 -243.557448)
			(xy 56.451564 -243.569308) (xy 56.398414 -243.573292) (xy 56.345264 -243.569308) (xy 56.293302 -243.557448)
			(xy 56.243688 -243.537976) (xy 56.19753 -243.511327) (xy 56.155859 -243.478096) (xy 56.119607 -243.439025)
			(xy 56.089583 -243.394988) (xy 56.066457 -243.346967) (xy 56.050747 -243.296037) (xy 56.042804 -243.243333)
			(xy 54.863756 -243.243333) (xy 54.855813 -243.296037) (xy 54.840103 -243.346967) (xy 54.816977 -243.394988)
			(xy 54.786953 -243.439025) (xy 54.750701 -243.478096) (xy 54.70903 -243.511327) (xy 54.662872 -243.537976)
			(xy 54.613258 -243.557448) (xy 54.561296 -243.569308) (xy 54.508146 -243.573292) (xy 54.454996 -243.569308)
			(xy 54.403034 -243.557448) (xy 54.35342 -243.537976) (xy 54.307262 -243.511327) (xy 54.265591 -243.478096)
			(xy 54.229339 -243.439025) (xy 54.199315 -243.394988) (xy 54.176189 -243.346967) (xy 54.160479 -243.296037)
			(xy 54.152536 -243.243333) (xy 51.420024 -243.243333) (xy 51.412081 -243.296037) (xy 51.396371 -243.346967)
			(xy 51.373245 -243.394988) (xy 51.343221 -243.439025) (xy 51.306969 -243.478096) (xy 51.265298 -243.511327)
			(xy 51.21914 -243.537976) (xy 51.169526 -243.557448) (xy 51.117564 -243.569308) (xy 51.064414 -243.573292)
			(xy 51.011264 -243.569308) (xy 50.959302 -243.557448) (xy 50.909688 -243.537976) (xy 50.86353 -243.511327)
			(xy 50.821859 -243.478096) (xy 50.785607 -243.439025) (xy 50.755583 -243.394988) (xy 50.732457 -243.346967)
			(xy 50.716747 -243.296037) (xy 50.708804 -243.243333) (xy 47.319956 -243.243333) (xy 47.312013 -243.296037)
			(xy 47.296303 -243.346967) (xy 47.273177 -243.394988) (xy 47.243153 -243.439025) (xy 47.206901 -243.478096)
			(xy 47.16523 -243.511327) (xy 47.119072 -243.537976) (xy 47.069458 -243.557448) (xy 47.017496 -243.569308)
			(xy 46.964346 -243.573292) (xy 46.911196 -243.569308) (xy 46.859234 -243.557448) (xy 46.80962 -243.537976)
			(xy 46.763462 -243.511327) (xy 46.721791 -243.478096) (xy 46.685539 -243.439025) (xy 46.655515 -243.394988)
			(xy 46.632389 -243.346967) (xy 46.616679 -243.296037) (xy 46.608736 -243.243333) (xy 43.876224 -243.243333)
			(xy 43.868281 -243.296037) (xy 43.852571 -243.346967) (xy 43.829445 -243.394988) (xy 43.799421 -243.439025)
			(xy 43.763169 -243.478096) (xy 43.721498 -243.511327) (xy 43.67534 -243.537976) (xy 43.625726 -243.557448)
			(xy 43.573764 -243.569308) (xy 43.520614 -243.573292) (xy 43.467464 -243.569308) (xy 43.415502 -243.557448)
			(xy 43.365888 -243.537976) (xy 43.31973 -243.511327) (xy 43.278059 -243.478096) (xy 43.241807 -243.439025)
			(xy 43.211783 -243.394988) (xy 43.188657 -243.346967) (xy 43.172947 -243.296037) (xy 43.165004 -243.243333)
			(xy 39.776156 -243.243333) (xy 39.768213 -243.296037) (xy 39.752503 -243.346967) (xy 39.729377 -243.394988)
			(xy 39.699353 -243.439025) (xy 39.663101 -243.478096) (xy 39.62143 -243.511327) (xy 39.575272 -243.537976)
			(xy 39.525658 -243.557448) (xy 39.473696 -243.569308) (xy 39.420546 -243.573292) (xy 39.367396 -243.569308)
			(xy 39.315434 -243.557448) (xy 39.26582 -243.537976) (xy 39.219662 -243.511327) (xy 39.177991 -243.478096)
			(xy 39.141739 -243.439025) (xy 39.111715 -243.394988) (xy 39.088589 -243.346967) (xy 39.072879 -243.296037)
			(xy 39.064936 -243.243333) (xy 36.332424 -243.243333) (xy 36.324481 -243.296037) (xy 36.308771 -243.346967)
			(xy 36.285645 -243.394988) (xy 36.255621 -243.439025) (xy 36.219369 -243.478096) (xy 36.177698 -243.511327)
			(xy 36.13154 -243.537976) (xy 36.081926 -243.557448) (xy 36.029964 -243.569308) (xy 35.976814 -243.573292)
			(xy 35.923664 -243.569308) (xy 35.871702 -243.557448) (xy 35.822088 -243.537976) (xy 35.77593 -243.511327)
			(xy 35.734259 -243.478096) (xy 35.698007 -243.439025) (xy 35.667983 -243.394988) (xy 35.644857 -243.346967)
			(xy 35.629147 -243.296037) (xy 35.621204 -243.243333) (xy 32.232356 -243.243333) (xy 32.224413 -243.296037)
			(xy 32.208703 -243.346967) (xy 32.185577 -243.394988) (xy 32.155553 -243.439025) (xy 32.119301 -243.478096)
			(xy 32.07763 -243.511327) (xy 32.031472 -243.537976) (xy 31.981858 -243.557448) (xy 31.929896 -243.569308)
			(xy 31.876746 -243.573292) (xy 31.823596 -243.569308) (xy 31.771634 -243.557448) (xy 31.72202 -243.537976)
			(xy 31.675862 -243.511327) (xy 31.634191 -243.478096) (xy 31.597939 -243.439025) (xy 31.567915 -243.394988)
			(xy 31.544789 -243.346967) (xy 31.529079 -243.296037) (xy 31.521136 -243.243333) (xy 28.788624 -243.243333)
			(xy 28.780681 -243.296037) (xy 28.764971 -243.346967) (xy 28.741845 -243.394988) (xy 28.711821 -243.439025)
			(xy 28.675569 -243.478096) (xy 28.633898 -243.511327) (xy 28.58774 -243.537976) (xy 28.538126 -243.557448)
			(xy 28.486164 -243.569308) (xy 28.433014 -243.573292) (xy 28.379864 -243.569308) (xy 28.327902 -243.557448)
			(xy 28.278288 -243.537976) (xy 28.23213 -243.511327) (xy 28.190459 -243.478096) (xy 28.154207 -243.439025)
			(xy 28.124183 -243.394988) (xy 28.101057 -243.346967) (xy 28.085347 -243.296037) (xy 28.077404 -243.243333)
			(xy 24.688556 -243.243333) (xy 24.680613 -243.296037) (xy 24.664903 -243.346967) (xy 24.641777 -243.394988)
			(xy 24.611753 -243.439025) (xy 24.575501 -243.478096) (xy 24.53383 -243.511327) (xy 24.487672 -243.537976)
			(xy 24.438058 -243.557448) (xy 24.386096 -243.569308) (xy 24.332946 -243.573292) (xy 24.279796 -243.569308)
			(xy 24.227834 -243.557448) (xy 24.17822 -243.537976) (xy 24.132062 -243.511327) (xy 24.090391 -243.478096)
			(xy 24.054139 -243.439025) (xy 24.024115 -243.394988) (xy 24.000989 -243.346967) (xy 23.985279 -243.296037)
			(xy 23.977336 -243.243333) (xy 21.244824 -243.243333) (xy 21.236881 -243.296037) (xy 21.221171 -243.346967)
			(xy 21.198045 -243.394988) (xy 21.168021 -243.439025) (xy 21.131769 -243.478096) (xy 21.090098 -243.511327)
			(xy 21.04394 -243.537976) (xy 20.994326 -243.557448) (xy 20.942364 -243.569308) (xy 20.889214 -243.573292)
			(xy 20.836064 -243.569308) (xy 20.784102 -243.557448) (xy 20.734488 -243.537976) (xy 20.68833 -243.511327)
			(xy 20.646659 -243.478096) (xy 20.610407 -243.439025) (xy 20.580383 -243.394988) (xy 20.557257 -243.346967)
			(xy 20.541547 -243.296037) (xy 20.533604 -243.243333) (xy 17.144756 -243.243333) (xy 17.136813 -243.296037)
			(xy 17.121103 -243.346967) (xy 17.097977 -243.394988) (xy 17.067953 -243.439025) (xy 17.031701 -243.478096)
			(xy 16.99003 -243.511327) (xy 16.943872 -243.537976) (xy 16.894258 -243.557448) (xy 16.842296 -243.569308)
			(xy 16.789146 -243.573292) (xy 16.735996 -243.569308) (xy 16.684034 -243.557448) (xy 16.63442 -243.537976)
			(xy 16.588262 -243.511327) (xy 16.546591 -243.478096) (xy 16.510339 -243.439025) (xy 16.480315 -243.394988)
			(xy 16.457189 -243.346967) (xy 16.441479 -243.296037) (xy 16.433536 -243.243333) (xy 13.701024 -243.243333)
			(xy 13.693081 -243.296037) (xy 13.677371 -243.346967) (xy 13.654245 -243.394988) (xy 13.624221 -243.439025)
			(xy 13.587969 -243.478096) (xy 13.546298 -243.511327) (xy 13.50014 -243.537976) (xy 13.450526 -243.557448)
			(xy 13.398564 -243.569308) (xy 13.345414 -243.573292) (xy 13.292264 -243.569308) (xy 13.240302 -243.557448)
			(xy 13.190688 -243.537976) (xy 13.14453 -243.511327) (xy 13.102859 -243.478096) (xy 13.066607 -243.439025)
			(xy 13.036583 -243.394988) (xy 13.013457 -243.346967) (xy 12.997747 -243.296037) (xy 12.989804 -243.243333)
			(xy 9.6774 -243.243333) (xy 9.6774 -244.093217) (xy 16.433536 -244.093217) (xy 16.433536 -244.039919)
			(xy 16.441479 -243.987215) (xy 16.457189 -243.936285) (xy 16.480315 -243.888264) (xy 16.510339 -243.844227)
			(xy 16.546591 -243.805156) (xy 16.588262 -243.771925) (xy 16.63442 -243.745276) (xy 16.684034 -243.725804)
			(xy 16.735996 -243.713944) (xy 16.789146 -243.709961) (xy 16.842296 -243.713944) (xy 16.894258 -243.725804)
			(xy 16.943872 -243.745276) (xy 16.99003 -243.771925) (xy 17.031701 -243.805156) (xy 17.067953 -243.844227)
			(xy 17.097977 -243.888264) (xy 17.121103 -243.936285) (xy 17.136813 -243.987215) (xy 17.144756 -244.039919)
			(xy 17.145254 -244.066568) (xy 17.144756 -244.093217) (xy 23.977336 -244.093217) (xy 23.977336 -244.039919)
			(xy 23.985279 -243.987215) (xy 24.000989 -243.936285) (xy 24.024115 -243.888264) (xy 24.054139 -243.844227)
			(xy 24.090391 -243.805156) (xy 24.132062 -243.771925) (xy 24.17822 -243.745276) (xy 24.227834 -243.725804)
			(xy 24.279796 -243.713944) (xy 24.332946 -243.709961) (xy 24.386096 -243.713944) (xy 24.438058 -243.725804)
			(xy 24.487672 -243.745276) (xy 24.53383 -243.771925) (xy 24.575501 -243.805156) (xy 24.611753 -243.844227)
			(xy 24.641777 -243.888264) (xy 24.664903 -243.936285) (xy 24.680613 -243.987215) (xy 24.688556 -244.039919)
			(xy 24.689054 -244.066568) (xy 24.688556 -244.093217) (xy 31.521136 -244.093217) (xy 31.521136 -244.039919)
			(xy 31.529079 -243.987215) (xy 31.544789 -243.936285) (xy 31.567915 -243.888264) (xy 31.597939 -243.844227)
			(xy 31.634191 -243.805156) (xy 31.675862 -243.771925) (xy 31.72202 -243.745276) (xy 31.771634 -243.725804)
			(xy 31.823596 -243.713944) (xy 31.876746 -243.709961) (xy 31.929896 -243.713944) (xy 31.981858 -243.725804)
			(xy 32.031472 -243.745276) (xy 32.07763 -243.771925) (xy 32.119301 -243.805156) (xy 32.155553 -243.844227)
			(xy 32.185577 -243.888264) (xy 32.208703 -243.936285) (xy 32.224413 -243.987215) (xy 32.232356 -244.039919)
			(xy 32.232854 -244.066568) (xy 32.232356 -244.093217) (xy 39.064936 -244.093217) (xy 39.064936 -244.039919)
			(xy 39.072879 -243.987215) (xy 39.088589 -243.936285) (xy 39.111715 -243.888264) (xy 39.141739 -243.844227)
			(xy 39.177991 -243.805156) (xy 39.219662 -243.771925) (xy 39.26582 -243.745276) (xy 39.315434 -243.725804)
			(xy 39.367396 -243.713944) (xy 39.420546 -243.709961) (xy 39.473696 -243.713944) (xy 39.525658 -243.725804)
			(xy 39.575272 -243.745276) (xy 39.62143 -243.771925) (xy 39.663101 -243.805156) (xy 39.699353 -243.844227)
			(xy 39.729377 -243.888264) (xy 39.752503 -243.936285) (xy 39.768213 -243.987215) (xy 39.776156 -244.039919)
			(xy 39.776654 -244.066568) (xy 39.776156 -244.093217) (xy 46.608736 -244.093217) (xy 46.608736 -244.039919)
			(xy 46.616679 -243.987215) (xy 46.632389 -243.936285) (xy 46.655515 -243.888264) (xy 46.685539 -243.844227)
			(xy 46.721791 -243.805156) (xy 46.763462 -243.771925) (xy 46.80962 -243.745276) (xy 46.859234 -243.725804)
			(xy 46.911196 -243.713944) (xy 46.964346 -243.709961) (xy 47.017496 -243.713944) (xy 47.069458 -243.725804)
			(xy 47.119072 -243.745276) (xy 47.16523 -243.771925) (xy 47.206901 -243.805156) (xy 47.243153 -243.844227)
			(xy 47.273177 -243.888264) (xy 47.296303 -243.936285) (xy 47.312013 -243.987215) (xy 47.319956 -244.039919)
			(xy 47.320454 -244.066568) (xy 47.319956 -244.093217) (xy 54.152536 -244.093217) (xy 54.152536 -244.039919)
			(xy 54.160479 -243.987215) (xy 54.176189 -243.936285) (xy 54.199315 -243.888264) (xy 54.229339 -243.844227)
			(xy 54.265591 -243.805156) (xy 54.307262 -243.771925) (xy 54.35342 -243.745276) (xy 54.403034 -243.725804)
			(xy 54.454996 -243.713944) (xy 54.508146 -243.709961) (xy 54.561296 -243.713944) (xy 54.613258 -243.725804)
			(xy 54.662872 -243.745276) (xy 54.70903 -243.771925) (xy 54.750701 -243.805156) (xy 54.786953 -243.844227)
			(xy 54.816977 -243.888264) (xy 54.840103 -243.936285) (xy 54.855813 -243.987215) (xy 54.863756 -244.039919)
			(xy 54.864254 -244.066568) (xy 54.863756 -244.093217) (xy 61.696336 -244.093217) (xy 61.696336 -244.039919)
			(xy 61.704279 -243.987215) (xy 61.719989 -243.936285) (xy 61.743115 -243.888264) (xy 61.773139 -243.844227)
			(xy 61.809391 -243.805156) (xy 61.851062 -243.771925) (xy 61.89722 -243.745276) (xy 61.946834 -243.725804)
			(xy 61.998796 -243.713944) (xy 62.051946 -243.709961) (xy 62.105096 -243.713944) (xy 62.157058 -243.725804)
			(xy 62.206672 -243.745276) (xy 62.25283 -243.771925) (xy 62.294501 -243.805156) (xy 62.330753 -243.844227)
			(xy 62.360777 -243.888264) (xy 62.383903 -243.936285) (xy 62.399613 -243.987215) (xy 62.407556 -244.039919)
			(xy 62.408054 -244.066568) (xy 62.407556 -244.093217) (xy 62.399613 -244.145921) (xy 62.383903 -244.196851)
			(xy 62.360777 -244.244872) (xy 62.330753 -244.288909) (xy 62.294501 -244.32798) (xy 62.25283 -244.361211)
			(xy 62.206672 -244.38786) (xy 62.157058 -244.407332) (xy 62.105096 -244.419192) (xy 62.051946 -244.423176)
			(xy 61.998796 -244.419192) (xy 61.946834 -244.407332) (xy 61.89722 -244.38786) (xy 61.851062 -244.361211)
			(xy 61.809391 -244.32798) (xy 61.773139 -244.288909) (xy 61.743115 -244.244872) (xy 61.719989 -244.196851)
			(xy 61.704279 -244.145921) (xy 61.696336 -244.093217) (xy 54.863756 -244.093217) (xy 54.855813 -244.145921)
			(xy 54.840103 -244.196851) (xy 54.816977 -244.244872) (xy 54.786953 -244.288909) (xy 54.750701 -244.32798)
			(xy 54.70903 -244.361211) (xy 54.662872 -244.38786) (xy 54.613258 -244.407332) (xy 54.561296 -244.419192)
			(xy 54.508146 -244.423176) (xy 54.454996 -244.419192) (xy 54.403034 -244.407332) (xy 54.35342 -244.38786)
			(xy 54.307262 -244.361211) (xy 54.265591 -244.32798) (xy 54.229339 -244.288909) (xy 54.199315 -244.244872)
			(xy 54.176189 -244.196851) (xy 54.160479 -244.145921) (xy 54.152536 -244.093217) (xy 47.319956 -244.093217)
			(xy 47.312013 -244.145921) (xy 47.296303 -244.196851) (xy 47.273177 -244.244872) (xy 47.243153 -244.288909)
			(xy 47.206901 -244.32798) (xy 47.16523 -244.361211) (xy 47.119072 -244.38786) (xy 47.069458 -244.407332)
			(xy 47.017496 -244.419192) (xy 46.964346 -244.423176) (xy 46.911196 -244.419192) (xy 46.859234 -244.407332)
			(xy 46.80962 -244.38786) (xy 46.763462 -244.361211) (xy 46.721791 -244.32798) (xy 46.685539 -244.288909)
			(xy 46.655515 -244.244872) (xy 46.632389 -244.196851) (xy 46.616679 -244.145921) (xy 46.608736 -244.093217)
			(xy 39.776156 -244.093217) (xy 39.768213 -244.145921) (xy 39.752503 -244.196851) (xy 39.729377 -244.244872)
			(xy 39.699353 -244.288909) (xy 39.663101 -244.32798) (xy 39.62143 -244.361211) (xy 39.575272 -244.38786)
			(xy 39.525658 -244.407332) (xy 39.473696 -244.419192) (xy 39.420546 -244.423176) (xy 39.367396 -244.419192)
			(xy 39.315434 -244.407332) (xy 39.26582 -244.38786) (xy 39.219662 -244.361211) (xy 39.177991 -244.32798)
			(xy 39.141739 -244.288909) (xy 39.111715 -244.244872) (xy 39.088589 -244.196851) (xy 39.072879 -244.145921)
			(xy 39.064936 -244.093217) (xy 32.232356 -244.093217) (xy 32.224413 -244.145921) (xy 32.208703 -244.196851)
			(xy 32.185577 -244.244872) (xy 32.155553 -244.288909) (xy 32.119301 -244.32798) (xy 32.07763 -244.361211)
			(xy 32.031472 -244.38786) (xy 31.981858 -244.407332) (xy 31.929896 -244.419192) (xy 31.876746 -244.423176)
			(xy 31.823596 -244.419192) (xy 31.771634 -244.407332) (xy 31.72202 -244.38786) (xy 31.675862 -244.361211)
			(xy 31.634191 -244.32798) (xy 31.597939 -244.288909) (xy 31.567915 -244.244872) (xy 31.544789 -244.196851)
			(xy 31.529079 -244.145921) (xy 31.521136 -244.093217) (xy 24.688556 -244.093217) (xy 24.680613 -244.145921)
			(xy 24.664903 -244.196851) (xy 24.641777 -244.244872) (xy 24.611753 -244.288909) (xy 24.575501 -244.32798)
			(xy 24.53383 -244.361211) (xy 24.487672 -244.38786) (xy 24.438058 -244.407332) (xy 24.386096 -244.419192)
			(xy 24.332946 -244.423176) (xy 24.279796 -244.419192) (xy 24.227834 -244.407332) (xy 24.17822 -244.38786)
			(xy 24.132062 -244.361211) (xy 24.090391 -244.32798) (xy 24.054139 -244.288909) (xy 24.024115 -244.244872)
			(xy 24.000989 -244.196851) (xy 23.985279 -244.145921) (xy 23.977336 -244.093217) (xy 17.144756 -244.093217)
			(xy 17.136813 -244.145921) (xy 17.121103 -244.196851) (xy 17.097977 -244.244872) (xy 17.067953 -244.288909)
			(xy 17.031701 -244.32798) (xy 16.99003 -244.361211) (xy 16.943872 -244.38786) (xy 16.894258 -244.407332)
			(xy 16.842296 -244.419192) (xy 16.789146 -244.423176) (xy 16.735996 -244.419192) (xy 16.684034 -244.407332)
			(xy 16.63442 -244.38786) (xy 16.588262 -244.361211) (xy 16.546591 -244.32798) (xy 16.510339 -244.288909)
			(xy 16.480315 -244.244872) (xy 16.457189 -244.196851) (xy 16.441479 -244.145921) (xy 16.433536 -244.093217)
			(xy 9.6774 -244.093217) (xy 9.6774 -244.943355) (xy 12.989804 -244.943355) (xy 12.989804 -244.890057)
			(xy 12.997747 -244.837353) (xy 13.013457 -244.786423) (xy 13.036583 -244.738402) (xy 13.066607 -244.694365)
			(xy 13.102859 -244.655294) (xy 13.14453 -244.622063) (xy 13.190688 -244.595414) (xy 13.240302 -244.575942)
			(xy 13.292264 -244.564082) (xy 13.345414 -244.560099) (xy 13.398564 -244.564082) (xy 13.450526 -244.575942)
			(xy 13.50014 -244.595414) (xy 13.546298 -244.622063) (xy 13.587969 -244.655294) (xy 13.624221 -244.694365)
			(xy 13.654245 -244.738402) (xy 13.677371 -244.786423) (xy 13.693081 -244.837353) (xy 13.701024 -244.890057)
			(xy 13.701522 -244.916706) (xy 13.701024 -244.943355) (xy 20.533604 -244.943355) (xy 20.533604 -244.890057)
			(xy 20.541547 -244.837353) (xy 20.557257 -244.786423) (xy 20.580383 -244.738402) (xy 20.610407 -244.694365)
			(xy 20.646659 -244.655294) (xy 20.68833 -244.622063) (xy 20.734488 -244.595414) (xy 20.784102 -244.575942)
			(xy 20.836064 -244.564082) (xy 20.889214 -244.560099) (xy 20.942364 -244.564082) (xy 20.994326 -244.575942)
			(xy 21.04394 -244.595414) (xy 21.090098 -244.622063) (xy 21.131769 -244.655294) (xy 21.168021 -244.694365)
			(xy 21.198045 -244.738402) (xy 21.221171 -244.786423) (xy 21.236881 -244.837353) (xy 21.244824 -244.890057)
			(xy 21.245322 -244.916706) (xy 21.244824 -244.943355) (xy 28.077404 -244.943355) (xy 28.077404 -244.890057)
			(xy 28.085347 -244.837353) (xy 28.101057 -244.786423) (xy 28.124183 -244.738402) (xy 28.154207 -244.694365)
			(xy 28.190459 -244.655294) (xy 28.23213 -244.622063) (xy 28.278288 -244.595414) (xy 28.327902 -244.575942)
			(xy 28.379864 -244.564082) (xy 28.433014 -244.560099) (xy 28.486164 -244.564082) (xy 28.538126 -244.575942)
			(xy 28.58774 -244.595414) (xy 28.633898 -244.622063) (xy 28.675569 -244.655294) (xy 28.711821 -244.694365)
			(xy 28.741845 -244.738402) (xy 28.764971 -244.786423) (xy 28.780681 -244.837353) (xy 28.788624 -244.890057)
			(xy 28.789122 -244.916706) (xy 28.788624 -244.943355) (xy 35.621204 -244.943355) (xy 35.621204 -244.890057)
			(xy 35.629147 -244.837353) (xy 35.644857 -244.786423) (xy 35.667983 -244.738402) (xy 35.698007 -244.694365)
			(xy 35.734259 -244.655294) (xy 35.77593 -244.622063) (xy 35.822088 -244.595414) (xy 35.871702 -244.575942)
			(xy 35.923664 -244.564082) (xy 35.976814 -244.560099) (xy 36.029964 -244.564082) (xy 36.081926 -244.575942)
			(xy 36.13154 -244.595414) (xy 36.177698 -244.622063) (xy 36.219369 -244.655294) (xy 36.255621 -244.694365)
			(xy 36.285645 -244.738402) (xy 36.308771 -244.786423) (xy 36.324481 -244.837353) (xy 36.332424 -244.890057)
			(xy 36.332922 -244.916706) (xy 36.332424 -244.943355) (xy 43.165004 -244.943355) (xy 43.165004 -244.890057)
			(xy 43.172947 -244.837353) (xy 43.188657 -244.786423) (xy 43.211783 -244.738402) (xy 43.241807 -244.694365)
			(xy 43.278059 -244.655294) (xy 43.31973 -244.622063) (xy 43.365888 -244.595414) (xy 43.415502 -244.575942)
			(xy 43.467464 -244.564082) (xy 43.520614 -244.560099) (xy 43.573764 -244.564082) (xy 43.625726 -244.575942)
			(xy 43.67534 -244.595414) (xy 43.721498 -244.622063) (xy 43.763169 -244.655294) (xy 43.799421 -244.694365)
			(xy 43.829445 -244.738402) (xy 43.852571 -244.786423) (xy 43.868281 -244.837353) (xy 43.876224 -244.890057)
			(xy 43.876722 -244.916706) (xy 43.876224 -244.943355) (xy 50.708804 -244.943355) (xy 50.708804 -244.890057)
			(xy 50.716747 -244.837353) (xy 50.732457 -244.786423) (xy 50.755583 -244.738402) (xy 50.785607 -244.694365)
			(xy 50.821859 -244.655294) (xy 50.86353 -244.622063) (xy 50.909688 -244.595414) (xy 50.959302 -244.575942)
			(xy 51.011264 -244.564082) (xy 51.064414 -244.560099) (xy 51.117564 -244.564082) (xy 51.169526 -244.575942)
			(xy 51.21914 -244.595414) (xy 51.265298 -244.622063) (xy 51.306969 -244.655294) (xy 51.343221 -244.694365)
			(xy 51.373245 -244.738402) (xy 51.396371 -244.786423) (xy 51.412081 -244.837353) (xy 51.420024 -244.890057)
			(xy 51.420522 -244.916706) (xy 51.420024 -244.943355) (xy 51.412081 -244.996059) (xy 51.396371 -245.046989)
			(xy 51.373245 -245.09501) (xy 51.343221 -245.139047) (xy 51.306969 -245.178118) (xy 51.265298 -245.211349)
			(xy 51.21914 -245.237998) (xy 51.169526 -245.25747) (xy 51.117564 -245.26933) (xy 51.064414 -245.273314)
			(xy 51.011264 -245.26933) (xy 50.959302 -245.25747) (xy 50.909688 -245.237998) (xy 50.86353 -245.211349)
			(xy 50.821859 -245.178118) (xy 50.785607 -245.139047) (xy 50.755583 -245.09501) (xy 50.732457 -245.046989)
			(xy 50.716747 -244.996059) (xy 50.708804 -244.943355) (xy 43.876224 -244.943355) (xy 43.868281 -244.996059)
			(xy 43.852571 -245.046989) (xy 43.829445 -245.09501) (xy 43.799421 -245.139047) (xy 43.763169 -245.178118)
			(xy 43.721498 -245.211349) (xy 43.67534 -245.237998) (xy 43.625726 -245.25747) (xy 43.573764 -245.26933)
			(xy 43.520614 -245.273314) (xy 43.467464 -245.26933) (xy 43.415502 -245.25747) (xy 43.365888 -245.237998)
			(xy 43.31973 -245.211349) (xy 43.278059 -245.178118) (xy 43.241807 -245.139047) (xy 43.211783 -245.09501)
			(xy 43.188657 -245.046989) (xy 43.172947 -244.996059) (xy 43.165004 -244.943355) (xy 36.332424 -244.943355)
			(xy 36.324481 -244.996059) (xy 36.308771 -245.046989) (xy 36.285645 -245.09501) (xy 36.255621 -245.139047)
			(xy 36.219369 -245.178118) (xy 36.177698 -245.211349) (xy 36.13154 -245.237998) (xy 36.081926 -245.25747)
			(xy 36.029964 -245.26933) (xy 35.976814 -245.273314) (xy 35.923664 -245.26933) (xy 35.871702 -245.25747)
			(xy 35.822088 -245.237998) (xy 35.77593 -245.211349) (xy 35.734259 -245.178118) (xy 35.698007 -245.139047)
			(xy 35.667983 -245.09501) (xy 35.644857 -245.046989) (xy 35.629147 -244.996059) (xy 35.621204 -244.943355)
			(xy 28.788624 -244.943355) (xy 28.780681 -244.996059) (xy 28.764971 -245.046989) (xy 28.741845 -245.09501)
			(xy 28.711821 -245.139047) (xy 28.675569 -245.178118) (xy 28.633898 -245.211349) (xy 28.58774 -245.237998)
			(xy 28.538126 -245.25747) (xy 28.486164 -245.26933) (xy 28.433014 -245.273314) (xy 28.379864 -245.26933)
			(xy 28.327902 -245.25747) (xy 28.278288 -245.237998) (xy 28.23213 -245.211349) (xy 28.190459 -245.178118)
			(xy 28.154207 -245.139047) (xy 28.124183 -245.09501) (xy 28.101057 -245.046989) (xy 28.085347 -244.996059)
			(xy 28.077404 -244.943355) (xy 21.244824 -244.943355) (xy 21.236881 -244.996059) (xy 21.221171 -245.046989)
			(xy 21.198045 -245.09501) (xy 21.168021 -245.139047) (xy 21.131769 -245.178118) (xy 21.090098 -245.211349)
			(xy 21.04394 -245.237998) (xy 20.994326 -245.25747) (xy 20.942364 -245.26933) (xy 20.889214 -245.273314)
			(xy 20.836064 -245.26933) (xy 20.784102 -245.25747) (xy 20.734488 -245.237998) (xy 20.68833 -245.211349)
			(xy 20.646659 -245.178118) (xy 20.610407 -245.139047) (xy 20.580383 -245.09501) (xy 20.557257 -245.046989)
			(xy 20.541547 -244.996059) (xy 20.533604 -244.943355) (xy 13.701024 -244.943355) (xy 13.693081 -244.996059)
			(xy 13.677371 -245.046989) (xy 13.654245 -245.09501) (xy 13.624221 -245.139047) (xy 13.587969 -245.178118)
			(xy 13.546298 -245.211349) (xy 13.50014 -245.237998) (xy 13.450526 -245.25747) (xy 13.398564 -245.26933)
			(xy 13.345414 -245.273314) (xy 13.292264 -245.26933) (xy 13.240302 -245.25747) (xy 13.190688 -245.237998)
			(xy 13.14453 -245.211349) (xy 13.102859 -245.178118) (xy 13.066607 -245.139047) (xy 13.036583 -245.09501)
			(xy 13.013457 -245.046989) (xy 12.997747 -244.996059) (xy 12.989804 -244.943355) (xy 9.6774 -244.943355)
			(xy 9.6774 -245.793239) (xy 16.433536 -245.793239) (xy 16.433536 -245.739941) (xy 16.441479 -245.687237)
			(xy 16.457189 -245.636307) (xy 16.480315 -245.588286) (xy 16.510339 -245.544249) (xy 16.546591 -245.505178)
			(xy 16.588262 -245.471947) (xy 16.63442 -245.445298) (xy 16.684034 -245.425826) (xy 16.735996 -245.413966)
			(xy 16.789146 -245.409983) (xy 16.842296 -245.413966) (xy 16.894258 -245.425826) (xy 16.943872 -245.445298)
			(xy 16.99003 -245.471947) (xy 17.031701 -245.505178) (xy 17.067953 -245.544249) (xy 17.097977 -245.588286)
			(xy 17.121103 -245.636307) (xy 17.136813 -245.687237) (xy 17.144756 -245.739941) (xy 17.145254 -245.76659)
			(xy 17.144756 -245.793239) (xy 23.977336 -245.793239) (xy 23.977336 -245.739941) (xy 23.985279 -245.687237)
			(xy 24.000989 -245.636307) (xy 24.024115 -245.588286) (xy 24.054139 -245.544249) (xy 24.090391 -245.505178)
			(xy 24.132062 -245.471947) (xy 24.17822 -245.445298) (xy 24.227834 -245.425826) (xy 24.279796 -245.413966)
			(xy 24.332946 -245.409983) (xy 24.386096 -245.413966) (xy 24.438058 -245.425826) (xy 24.487672 -245.445298)
			(xy 24.53383 -245.471947) (xy 24.575501 -245.505178) (xy 24.611753 -245.544249) (xy 24.641777 -245.588286)
			(xy 24.664903 -245.636307) (xy 24.680613 -245.687237) (xy 24.688556 -245.739941) (xy 24.689054 -245.76659)
			(xy 24.688556 -245.793239) (xy 31.521136 -245.793239) (xy 31.521136 -245.739941) (xy 31.529079 -245.687237)
			(xy 31.544789 -245.636307) (xy 31.567915 -245.588286) (xy 31.597939 -245.544249) (xy 31.634191 -245.505178)
			(xy 31.675862 -245.471947) (xy 31.72202 -245.445298) (xy 31.771634 -245.425826) (xy 31.823596 -245.413966)
			(xy 31.876746 -245.409983) (xy 31.929896 -245.413966) (xy 31.981858 -245.425826) (xy 32.031472 -245.445298)
			(xy 32.07763 -245.471947) (xy 32.119301 -245.505178) (xy 32.155553 -245.544249) (xy 32.185577 -245.588286)
			(xy 32.208703 -245.636307) (xy 32.224413 -245.687237) (xy 32.232356 -245.739941) (xy 32.232854 -245.76659)
			(xy 32.232356 -245.793239) (xy 39.064936 -245.793239) (xy 39.064936 -245.739941) (xy 39.072879 -245.687237)
			(xy 39.088589 -245.636307) (xy 39.111715 -245.588286) (xy 39.141739 -245.544249) (xy 39.177991 -245.505178)
			(xy 39.219662 -245.471947) (xy 39.26582 -245.445298) (xy 39.315434 -245.425826) (xy 39.367396 -245.413966)
			(xy 39.420546 -245.409983) (xy 39.473696 -245.413966) (xy 39.525658 -245.425826) (xy 39.575272 -245.445298)
			(xy 39.62143 -245.471947) (xy 39.663101 -245.505178) (xy 39.699353 -245.544249) (xy 39.729377 -245.588286)
			(xy 39.752503 -245.636307) (xy 39.768213 -245.687237) (xy 39.776156 -245.739941) (xy 39.776654 -245.76659)
			(xy 39.776156 -245.793239) (xy 46.608736 -245.793239) (xy 46.608736 -245.739941) (xy 46.616679 -245.687237)
			(xy 46.632389 -245.636307) (xy 46.655515 -245.588286) (xy 46.685539 -245.544249) (xy 46.721791 -245.505178)
			(xy 46.763462 -245.471947) (xy 46.80962 -245.445298) (xy 46.859234 -245.425826) (xy 46.911196 -245.413966)
			(xy 46.964346 -245.409983) (xy 47.017496 -245.413966) (xy 47.069458 -245.425826) (xy 47.119072 -245.445298)
			(xy 47.16523 -245.471947) (xy 47.206901 -245.505178) (xy 47.243153 -245.544249) (xy 47.273177 -245.588286)
			(xy 47.296303 -245.636307) (xy 47.312013 -245.687237) (xy 47.319956 -245.739941) (xy 47.320454 -245.76659)
			(xy 47.319956 -245.793239) (xy 47.312013 -245.845943) (xy 47.296303 -245.896873) (xy 47.273177 -245.944894)
			(xy 47.243153 -245.988931) (xy 47.206901 -246.028002) (xy 47.16523 -246.061233) (xy 47.119072 -246.087882)
			(xy 47.069458 -246.107354) (xy 47.017496 -246.119214) (xy 46.964346 -246.123198) (xy 46.911196 -246.119214)
			(xy 46.859234 -246.107354) (xy 46.80962 -246.087882) (xy 46.763462 -246.061233) (xy 46.721791 -246.028002)
			(xy 46.685539 -245.988931) (xy 46.655515 -245.944894) (xy 46.632389 -245.896873) (xy 46.616679 -245.845943)
			(xy 46.608736 -245.793239) (xy 39.776156 -245.793239) (xy 39.768213 -245.845943) (xy 39.752503 -245.896873)
			(xy 39.729377 -245.944894) (xy 39.699353 -245.988931) (xy 39.663101 -246.028002) (xy 39.62143 -246.061233)
			(xy 39.575272 -246.087882) (xy 39.525658 -246.107354) (xy 39.473696 -246.119214) (xy 39.420546 -246.123198)
			(xy 39.367396 -246.119214) (xy 39.315434 -246.107354) (xy 39.26582 -246.087882) (xy 39.219662 -246.061233)
			(xy 39.177991 -246.028002) (xy 39.141739 -245.988931) (xy 39.111715 -245.944894) (xy 39.088589 -245.896873)
			(xy 39.072879 -245.845943) (xy 39.064936 -245.793239) (xy 32.232356 -245.793239) (xy 32.224413 -245.845943)
			(xy 32.208703 -245.896873) (xy 32.185577 -245.944894) (xy 32.155553 -245.988931) (xy 32.119301 -246.028002)
			(xy 32.07763 -246.061233) (xy 32.031472 -246.087882) (xy 31.981858 -246.107354) (xy 31.929896 -246.119214)
			(xy 31.876746 -246.123198) (xy 31.823596 -246.119214) (xy 31.771634 -246.107354) (xy 31.72202 -246.087882)
			(xy 31.675862 -246.061233) (xy 31.634191 -246.028002) (xy 31.597939 -245.988931) (xy 31.567915 -245.944894)
			(xy 31.544789 -245.896873) (xy 31.529079 -245.845943) (xy 31.521136 -245.793239) (xy 24.688556 -245.793239)
			(xy 24.680613 -245.845943) (xy 24.664903 -245.896873) (xy 24.641777 -245.944894) (xy 24.611753 -245.988931)
			(xy 24.575501 -246.028002) (xy 24.53383 -246.061233) (xy 24.487672 -246.087882) (xy 24.438058 -246.107354)
			(xy 24.386096 -246.119214) (xy 24.332946 -246.123198) (xy 24.279796 -246.119214) (xy 24.227834 -246.107354)
			(xy 24.17822 -246.087882) (xy 24.132062 -246.061233) (xy 24.090391 -246.028002) (xy 24.054139 -245.988931)
			(xy 24.024115 -245.944894) (xy 24.000989 -245.896873) (xy 23.985279 -245.845943) (xy 23.977336 -245.793239)
			(xy 17.144756 -245.793239) (xy 17.136813 -245.845943) (xy 17.121103 -245.896873) (xy 17.097977 -245.944894)
			(xy 17.067953 -245.988931) (xy 17.031701 -246.028002) (xy 16.99003 -246.061233) (xy 16.943872 -246.087882)
			(xy 16.894258 -246.107354) (xy 16.842296 -246.119214) (xy 16.789146 -246.123198) (xy 16.735996 -246.119214)
			(xy 16.684034 -246.107354) (xy 16.63442 -246.087882) (xy 16.588262 -246.061233) (xy 16.546591 -246.028002)
			(xy 16.510339 -245.988931) (xy 16.480315 -245.944894) (xy 16.457189 -245.896873) (xy 16.441479 -245.845943)
			(xy 16.433536 -245.793239) (xy 9.6774 -245.793239) (xy 9.6774 -246.643377) (xy 20.533604 -246.643377)
			(xy 20.533604 -246.590079) (xy 20.541547 -246.537375) (xy 20.557257 -246.486445) (xy 20.580383 -246.438424)
			(xy 20.610407 -246.394387) (xy 20.646659 -246.355316) (xy 20.68833 -246.322085) (xy 20.734488 -246.295436)
			(xy 20.784102 -246.275964) (xy 20.836064 -246.264104) (xy 20.889214 -246.260121) (xy 20.942364 -246.264104)
			(xy 20.994326 -246.275964) (xy 21.04394 -246.295436) (xy 21.090098 -246.322085) (xy 21.131769 -246.355316)
			(xy 21.168021 -246.394387) (xy 21.198045 -246.438424) (xy 21.221171 -246.486445) (xy 21.236881 -246.537375)
			(xy 21.244824 -246.590079) (xy 21.245322 -246.616728) (xy 21.244824 -246.643377) (xy 35.621204 -246.643377)
			(xy 35.621204 -246.590079) (xy 35.629147 -246.537375) (xy 35.644857 -246.486445) (xy 35.667983 -246.438424)
			(xy 35.698007 -246.394387) (xy 35.734259 -246.355316) (xy 35.77593 -246.322085) (xy 35.822088 -246.295436)
			(xy 35.871702 -246.275964) (xy 35.923664 -246.264104) (xy 35.976814 -246.260121) (xy 36.029964 -246.264104)
			(xy 36.081926 -246.275964) (xy 36.13154 -246.295436) (xy 36.177698 -246.322085) (xy 36.219369 -246.355316)
			(xy 36.255621 -246.394387) (xy 36.285645 -246.438424) (xy 36.308771 -246.486445) (xy 36.324481 -246.537375)
			(xy 36.332424 -246.590079) (xy 36.332922 -246.616728) (xy 36.332424 -246.643377) (xy 50.708804 -246.643377)
			(xy 50.708804 -246.590079) (xy 50.716747 -246.537375) (xy 50.732457 -246.486445) (xy 50.755583 -246.438424)
			(xy 50.785607 -246.394387) (xy 50.821859 -246.355316) (xy 50.86353 -246.322085) (xy 50.909688 -246.295436)
			(xy 50.959302 -246.275964) (xy 51.011264 -246.264104) (xy 51.064414 -246.260121) (xy 51.117564 -246.264104)
			(xy 51.169526 -246.275964) (xy 51.21914 -246.295436) (xy 51.265298 -246.322085) (xy 51.306969 -246.355316)
			(xy 51.343221 -246.394387) (xy 51.373245 -246.438424) (xy 51.396371 -246.486445) (xy 51.412081 -246.537375)
			(xy 51.420024 -246.590079) (xy 51.420522 -246.616728) (xy 51.420024 -246.643377) (xy 51.412081 -246.696081)
			(xy 51.396371 -246.747011) (xy 51.373245 -246.795032) (xy 51.343221 -246.839069) (xy 51.306969 -246.87814)
			(xy 51.265298 -246.911371) (xy 51.21914 -246.93802) (xy 51.169526 -246.957492) (xy 51.117564 -246.969352)
			(xy 51.064414 -246.973336) (xy 51.011264 -246.969352) (xy 50.959302 -246.957492) (xy 50.909688 -246.93802)
			(xy 50.86353 -246.911371) (xy 50.821859 -246.87814) (xy 50.785607 -246.839069) (xy 50.755583 -246.795032)
			(xy 50.732457 -246.747011) (xy 50.716747 -246.696081) (xy 50.708804 -246.643377) (xy 36.332424 -246.643377)
			(xy 36.324481 -246.696081) (xy 36.308771 -246.747011) (xy 36.285645 -246.795032) (xy 36.255621 -246.839069)
			(xy 36.219369 -246.87814) (xy 36.177698 -246.911371) (xy 36.13154 -246.93802) (xy 36.081926 -246.957492)
			(xy 36.029964 -246.969352) (xy 35.976814 -246.973336) (xy 35.923664 -246.969352) (xy 35.871702 -246.957492)
			(xy 35.822088 -246.93802) (xy 35.77593 -246.911371) (xy 35.734259 -246.87814) (xy 35.698007 -246.839069)
			(xy 35.667983 -246.795032) (xy 35.644857 -246.747011) (xy 35.629147 -246.696081) (xy 35.621204 -246.643377)
			(xy 21.244824 -246.643377) (xy 21.236881 -246.696081) (xy 21.221171 -246.747011) (xy 21.198045 -246.795032)
			(xy 21.168021 -246.839069) (xy 21.131769 -246.87814) (xy 21.090098 -246.911371) (xy 21.04394 -246.93802)
			(xy 20.994326 -246.957492) (xy 20.942364 -246.969352) (xy 20.889214 -246.973336) (xy 20.836064 -246.969352)
			(xy 20.784102 -246.957492) (xy 20.734488 -246.93802) (xy 20.68833 -246.911371) (xy 20.646659 -246.87814)
			(xy 20.610407 -246.839069) (xy 20.580383 -246.795032) (xy 20.557257 -246.747011) (xy 20.541547 -246.696081)
			(xy 20.533604 -246.643377) (xy 9.6774 -246.643377) (xy 9.6774 -247.493261) (xy 16.433536 -247.493261)
			(xy 16.433536 -247.439963) (xy 16.441479 -247.387259) (xy 16.457189 -247.336329) (xy 16.480315 -247.288308)
			(xy 16.510339 -247.244271) (xy 16.546591 -247.2052) (xy 16.588262 -247.171969) (xy 16.63442 -247.14532)
			(xy 16.684034 -247.125848) (xy 16.735996 -247.113988) (xy 16.789146 -247.110005) (xy 16.842296 -247.113988)
			(xy 16.894258 -247.125848) (xy 16.943872 -247.14532) (xy 16.99003 -247.171969) (xy 17.031701 -247.2052)
			(xy 17.067953 -247.244271) (xy 17.097977 -247.288308) (xy 17.121103 -247.336329) (xy 17.136813 -247.387259)
			(xy 17.144756 -247.439963) (xy 17.145254 -247.466612) (xy 17.144756 -247.493261) (xy 31.521136 -247.493261)
			(xy 31.521136 -247.439963) (xy 31.529079 -247.387259) (xy 31.544789 -247.336329) (xy 31.567915 -247.288308)
			(xy 31.597939 -247.244271) (xy 31.634191 -247.2052) (xy 31.675862 -247.171969) (xy 31.72202 -247.14532)
			(xy 31.771634 -247.125848) (xy 31.823596 -247.113988) (xy 31.876746 -247.110005) (xy 31.929896 -247.113988)
			(xy 31.981858 -247.125848) (xy 32.031472 -247.14532) (xy 32.07763 -247.171969) (xy 32.119301 -247.2052)
			(xy 32.155553 -247.244271) (xy 32.185577 -247.288308) (xy 32.208703 -247.336329) (xy 32.224413 -247.387259)
			(xy 32.232356 -247.439963) (xy 32.232854 -247.466612) (xy 32.232356 -247.493261) (xy 46.608736 -247.493261)
			(xy 46.608736 -247.439963) (xy 46.616679 -247.387259) (xy 46.632389 -247.336329) (xy 46.655515 -247.288308)
			(xy 46.685539 -247.244271) (xy 46.721791 -247.2052) (xy 46.763462 -247.171969) (xy 46.80962 -247.14532)
			(xy 46.859234 -247.125848) (xy 46.911196 -247.113988) (xy 46.964346 -247.110005) (xy 47.017496 -247.113988)
			(xy 47.069458 -247.125848) (xy 47.119072 -247.14532) (xy 47.16523 -247.171969) (xy 47.206901 -247.2052)
			(xy 47.243153 -247.244271) (xy 47.273177 -247.288308) (xy 47.296303 -247.336329) (xy 47.312013 -247.387259)
			(xy 47.319956 -247.439963) (xy 47.320454 -247.466612) (xy 47.319956 -247.493261) (xy 47.312013 -247.545965)
			(xy 47.296303 -247.596895) (xy 47.273177 -247.644916) (xy 47.243153 -247.688953) (xy 47.206901 -247.728024)
			(xy 47.16523 -247.761255) (xy 47.119072 -247.787904) (xy 47.069458 -247.807376) (xy 47.017496 -247.819236)
			(xy 46.964346 -247.82322) (xy 46.911196 -247.819236) (xy 46.859234 -247.807376) (xy 46.80962 -247.787904)
			(xy 46.763462 -247.761255) (xy 46.721791 -247.728024) (xy 46.685539 -247.688953) (xy 46.655515 -247.644916)
			(xy 46.632389 -247.596895) (xy 46.616679 -247.545965) (xy 46.608736 -247.493261) (xy 32.232356 -247.493261)
			(xy 32.224413 -247.545965) (xy 32.208703 -247.596895) (xy 32.185577 -247.644916) (xy 32.155553 -247.688953)
			(xy 32.119301 -247.728024) (xy 32.07763 -247.761255) (xy 32.031472 -247.787904) (xy 31.981858 -247.807376)
			(xy 31.929896 -247.819236) (xy 31.876746 -247.82322) (xy 31.823596 -247.819236) (xy 31.771634 -247.807376)
			(xy 31.72202 -247.787904) (xy 31.675862 -247.761255) (xy 31.634191 -247.728024) (xy 31.597939 -247.688953)
			(xy 31.567915 -247.644916) (xy 31.544789 -247.596895) (xy 31.529079 -247.545965) (xy 31.521136 -247.493261)
			(xy 17.144756 -247.493261) (xy 17.136813 -247.545965) (xy 17.121103 -247.596895) (xy 17.097977 -247.644916)
			(xy 17.067953 -247.688953) (xy 17.031701 -247.728024) (xy 16.99003 -247.761255) (xy 16.943872 -247.787904)
			(xy 16.894258 -247.807376) (xy 16.842296 -247.819236) (xy 16.789146 -247.82322) (xy 16.735996 -247.819236)
			(xy 16.684034 -247.807376) (xy 16.63442 -247.787904) (xy 16.588262 -247.761255) (xy 16.546591 -247.728024)
			(xy 16.510339 -247.688953) (xy 16.480315 -247.644916) (xy 16.457189 -247.596895) (xy 16.441479 -247.545965)
			(xy 16.433536 -247.493261) (xy 9.6774 -247.493261) (xy 9.6774 -248.343399) (xy 20.533604 -248.343399)
			(xy 20.533604 -248.290101) (xy 20.541547 -248.237397) (xy 20.557257 -248.186467) (xy 20.580383 -248.138446)
			(xy 20.610407 -248.094409) (xy 20.646659 -248.055338) (xy 20.68833 -248.022107) (xy 20.734488 -247.995458)
			(xy 20.784102 -247.975986) (xy 20.836064 -247.964126) (xy 20.889214 -247.960143) (xy 20.942364 -247.964126)
			(xy 20.994326 -247.975986) (xy 21.04394 -247.995458) (xy 21.090098 -248.022107) (xy 21.131769 -248.055338)
			(xy 21.168021 -248.094409) (xy 21.198045 -248.138446) (xy 21.221171 -248.186467) (xy 21.236881 -248.237397)
			(xy 21.244824 -248.290101) (xy 21.245322 -248.31675) (xy 21.244824 -248.343399) (xy 35.621204 -248.343399)
			(xy 35.621204 -248.290101) (xy 35.629147 -248.237397) (xy 35.644857 -248.186467) (xy 35.667983 -248.138446)
			(xy 35.698007 -248.094409) (xy 35.734259 -248.055338) (xy 35.77593 -248.022107) (xy 35.822088 -247.995458)
			(xy 35.871702 -247.975986) (xy 35.923664 -247.964126) (xy 35.976814 -247.960143) (xy 36.029964 -247.964126)
			(xy 36.081926 -247.975986) (xy 36.13154 -247.995458) (xy 36.177698 -248.022107) (xy 36.219369 -248.055338)
			(xy 36.255621 -248.094409) (xy 36.285645 -248.138446) (xy 36.308771 -248.186467) (xy 36.324481 -248.237397)
			(xy 36.332424 -248.290101) (xy 36.332922 -248.31675) (xy 36.332424 -248.343399) (xy 50.708804 -248.343399)
			(xy 50.708804 -248.290101) (xy 50.716747 -248.237397) (xy 50.732457 -248.186467) (xy 50.755583 -248.138446)
			(xy 50.785607 -248.094409) (xy 50.821859 -248.055338) (xy 50.86353 -248.022107) (xy 50.909688 -247.995458)
			(xy 50.959302 -247.975986) (xy 51.011264 -247.964126) (xy 51.064414 -247.960143) (xy 51.117564 -247.964126)
			(xy 51.169526 -247.975986) (xy 51.21914 -247.995458) (xy 51.265298 -248.022107) (xy 51.306969 -248.055338)
			(xy 51.343221 -248.094409) (xy 51.373245 -248.138446) (xy 51.396371 -248.186467) (xy 51.412081 -248.237397)
			(xy 51.420024 -248.290101) (xy 51.420522 -248.31675) (xy 51.420024 -248.343399) (xy 51.412081 -248.396103)
			(xy 51.396371 -248.447033) (xy 51.373245 -248.495054) (xy 51.343221 -248.539091) (xy 51.306969 -248.578162)
			(xy 51.265298 -248.611393) (xy 51.21914 -248.638042) (xy 51.169526 -248.657514) (xy 51.117564 -248.669374)
			(xy 51.064414 -248.673358) (xy 51.011264 -248.669374) (xy 50.959302 -248.657514) (xy 50.909688 -248.638042)
			(xy 50.86353 -248.611393) (xy 50.821859 -248.578162) (xy 50.785607 -248.539091) (xy 50.755583 -248.495054)
			(xy 50.732457 -248.447033) (xy 50.716747 -248.396103) (xy 50.708804 -248.343399) (xy 36.332424 -248.343399)
			(xy 36.324481 -248.396103) (xy 36.308771 -248.447033) (xy 36.285645 -248.495054) (xy 36.255621 -248.539091)
			(xy 36.219369 -248.578162) (xy 36.177698 -248.611393) (xy 36.13154 -248.638042) (xy 36.081926 -248.657514)
			(xy 36.029964 -248.669374) (xy 35.976814 -248.673358) (xy 35.923664 -248.669374) (xy 35.871702 -248.657514)
			(xy 35.822088 -248.638042) (xy 35.77593 -248.611393) (xy 35.734259 -248.578162) (xy 35.698007 -248.539091)
			(xy 35.667983 -248.495054) (xy 35.644857 -248.447033) (xy 35.629147 -248.396103) (xy 35.621204 -248.343399)
			(xy 21.244824 -248.343399) (xy 21.236881 -248.396103) (xy 21.221171 -248.447033) (xy 21.198045 -248.495054)
			(xy 21.168021 -248.539091) (xy 21.131769 -248.578162) (xy 21.090098 -248.611393) (xy 21.04394 -248.638042)
			(xy 20.994326 -248.657514) (xy 20.942364 -248.669374) (xy 20.889214 -248.673358) (xy 20.836064 -248.669374)
			(xy 20.784102 -248.657514) (xy 20.734488 -248.638042) (xy 20.68833 -248.611393) (xy 20.646659 -248.578162)
			(xy 20.610407 -248.539091) (xy 20.580383 -248.495054) (xy 20.557257 -248.447033) (xy 20.541547 -248.396103)
			(xy 20.533604 -248.343399) (xy 9.6774 -248.343399) (xy 9.6774 -249.193283) (xy 16.433536 -249.193283)
			(xy 16.433536 -249.139985) (xy 16.441479 -249.087281) (xy 16.457189 -249.036351) (xy 16.480315 -248.98833)
			(xy 16.510339 -248.944293) (xy 16.546591 -248.905222) (xy 16.588262 -248.871991) (xy 16.63442 -248.845342)
			(xy 16.684034 -248.82587) (xy 16.735996 -248.81401) (xy 16.789146 -248.810027) (xy 16.842296 -248.81401)
			(xy 16.894258 -248.82587) (xy 16.943872 -248.845342) (xy 16.99003 -248.871991) (xy 17.031701 -248.905222)
			(xy 17.067953 -248.944293) (xy 17.097977 -248.98833) (xy 17.121103 -249.036351) (xy 17.136813 -249.087281)
			(xy 17.144756 -249.139985) (xy 17.145254 -249.166634) (xy 17.144756 -249.193283) (xy 31.521136 -249.193283)
			(xy 31.521136 -249.139985) (xy 31.529079 -249.087281) (xy 31.544789 -249.036351) (xy 31.567915 -248.98833)
			(xy 31.597939 -248.944293) (xy 31.634191 -248.905222) (xy 31.675862 -248.871991) (xy 31.72202 -248.845342)
			(xy 31.771634 -248.82587) (xy 31.823596 -248.81401) (xy 31.876746 -248.810027) (xy 31.929896 -248.81401)
			(xy 31.981858 -248.82587) (xy 32.031472 -248.845342) (xy 32.07763 -248.871991) (xy 32.119301 -248.905222)
			(xy 32.155553 -248.944293) (xy 32.185577 -248.98833) (xy 32.208703 -249.036351) (xy 32.224413 -249.087281)
			(xy 32.232356 -249.139985) (xy 32.232854 -249.166634) (xy 32.232356 -249.193283) (xy 46.608736 -249.193283)
			(xy 46.608736 -249.139985) (xy 46.616679 -249.087281) (xy 46.632389 -249.036351) (xy 46.655515 -248.98833)
			(xy 46.685539 -248.944293) (xy 46.721791 -248.905222) (xy 46.763462 -248.871991) (xy 46.80962 -248.845342)
			(xy 46.859234 -248.82587) (xy 46.911196 -248.81401) (xy 46.964346 -248.810027) (xy 47.017496 -248.81401)
			(xy 47.069458 -248.82587) (xy 47.119072 -248.845342) (xy 47.16523 -248.871991) (xy 47.206901 -248.905222)
			(xy 47.243153 -248.944293) (xy 47.273177 -248.98833) (xy 47.296303 -249.036351) (xy 47.312013 -249.087281)
			(xy 47.319956 -249.139985) (xy 47.320454 -249.166634) (xy 47.319956 -249.193283) (xy 47.312013 -249.245987)
			(xy 47.296303 -249.296917) (xy 47.273177 -249.344938) (xy 47.243153 -249.388975) (xy 47.206901 -249.428046)
			(xy 47.16523 -249.461277) (xy 47.119072 -249.487926) (xy 47.069458 -249.507398) (xy 47.017496 -249.519258)
			(xy 46.964346 -249.523242) (xy 46.911196 -249.519258) (xy 46.859234 -249.507398) (xy 46.80962 -249.487926)
			(xy 46.763462 -249.461277) (xy 46.721791 -249.428046) (xy 46.685539 -249.388975) (xy 46.655515 -249.344938)
			(xy 46.632389 -249.296917) (xy 46.616679 -249.245987) (xy 46.608736 -249.193283) (xy 32.232356 -249.193283)
			(xy 32.224413 -249.245987) (xy 32.208703 -249.296917) (xy 32.185577 -249.344938) (xy 32.155553 -249.388975)
			(xy 32.119301 -249.428046) (xy 32.07763 -249.461277) (xy 32.031472 -249.487926) (xy 31.981858 -249.507398)
			(xy 31.929896 -249.519258) (xy 31.876746 -249.523242) (xy 31.823596 -249.519258) (xy 31.771634 -249.507398)
			(xy 31.72202 -249.487926) (xy 31.675862 -249.461277) (xy 31.634191 -249.428046) (xy 31.597939 -249.388975)
			(xy 31.567915 -249.344938) (xy 31.544789 -249.296917) (xy 31.529079 -249.245987) (xy 31.521136 -249.193283)
			(xy 17.144756 -249.193283) (xy 17.136813 -249.245987) (xy 17.121103 -249.296917) (xy 17.097977 -249.344938)
			(xy 17.067953 -249.388975) (xy 17.031701 -249.428046) (xy 16.99003 -249.461277) (xy 16.943872 -249.487926)
			(xy 16.894258 -249.507398) (xy 16.842296 -249.519258) (xy 16.789146 -249.523242) (xy 16.735996 -249.519258)
			(xy 16.684034 -249.507398) (xy 16.63442 -249.487926) (xy 16.588262 -249.461277) (xy 16.546591 -249.428046)
			(xy 16.510339 -249.388975) (xy 16.480315 -249.344938) (xy 16.457189 -249.296917) (xy 16.441479 -249.245987)
			(xy 16.433536 -249.193283) (xy 9.6774 -249.193283) (xy 9.6774 -250.043421) (xy 20.533604 -250.043421)
			(xy 20.533604 -249.990123) (xy 20.541547 -249.937419) (xy 20.557257 -249.886489) (xy 20.580383 -249.838468)
			(xy 20.610407 -249.794431) (xy 20.646659 -249.75536) (xy 20.68833 -249.722129) (xy 20.734488 -249.69548)
			(xy 20.784102 -249.676008) (xy 20.836064 -249.664148) (xy 20.889214 -249.660165) (xy 20.942364 -249.664148)
			(xy 20.994326 -249.676008) (xy 21.04394 -249.69548) (xy 21.090098 -249.722129) (xy 21.131769 -249.75536)
			(xy 21.168021 -249.794431) (xy 21.198045 -249.838468) (xy 21.221171 -249.886489) (xy 21.236881 -249.937419)
			(xy 21.244824 -249.990123) (xy 21.245322 -250.016772) (xy 21.244824 -250.043421) (xy 35.621204 -250.043421)
			(xy 35.621204 -249.990123) (xy 35.629147 -249.937419) (xy 35.644857 -249.886489) (xy 35.667983 -249.838468)
			(xy 35.698007 -249.794431) (xy 35.734259 -249.75536) (xy 35.77593 -249.722129) (xy 35.822088 -249.69548)
			(xy 35.871702 -249.676008) (xy 35.923664 -249.664148) (xy 35.976814 -249.660165) (xy 36.029964 -249.664148)
			(xy 36.081926 -249.676008) (xy 36.13154 -249.69548) (xy 36.177698 -249.722129) (xy 36.219369 -249.75536)
			(xy 36.255621 -249.794431) (xy 36.285645 -249.838468) (xy 36.308771 -249.886489) (xy 36.324481 -249.937419)
			(xy 36.332424 -249.990123) (xy 36.332922 -250.016772) (xy 36.332424 -250.043421) (xy 50.708804 -250.043421)
			(xy 50.708804 -249.990123) (xy 50.716747 -249.937419) (xy 50.732457 -249.886489) (xy 50.755583 -249.838468)
			(xy 50.785607 -249.794431) (xy 50.821859 -249.75536) (xy 50.86353 -249.722129) (xy 50.909688 -249.69548)
			(xy 50.959302 -249.676008) (xy 51.011264 -249.664148) (xy 51.064414 -249.660165) (xy 51.117564 -249.664148)
			(xy 51.169526 -249.676008) (xy 51.21914 -249.69548) (xy 51.265298 -249.722129) (xy 51.306969 -249.75536)
			(xy 51.343221 -249.794431) (xy 51.373245 -249.838468) (xy 51.396371 -249.886489) (xy 51.412081 -249.937419)
			(xy 51.420024 -249.990123) (xy 51.420522 -250.016772) (xy 51.420024 -250.043421) (xy 51.412081 -250.096125)
			(xy 51.396371 -250.147055) (xy 51.373245 -250.195076) (xy 51.343221 -250.239113) (xy 51.306969 -250.278184)
			(xy 51.265298 -250.311415) (xy 51.21914 -250.338064) (xy 51.169526 -250.357536) (xy 51.117564 -250.369396)
			(xy 51.064414 -250.37338) (xy 51.011264 -250.369396) (xy 50.959302 -250.357536) (xy 50.909688 -250.338064)
			(xy 50.86353 -250.311415) (xy 50.821859 -250.278184) (xy 50.785607 -250.239113) (xy 50.755583 -250.195076)
			(xy 50.732457 -250.147055) (xy 50.716747 -250.096125) (xy 50.708804 -250.043421) (xy 36.332424 -250.043421)
			(xy 36.324481 -250.096125) (xy 36.308771 -250.147055) (xy 36.285645 -250.195076) (xy 36.255621 -250.239113)
			(xy 36.219369 -250.278184) (xy 36.177698 -250.311415) (xy 36.13154 -250.338064) (xy 36.081926 -250.357536)
			(xy 36.029964 -250.369396) (xy 35.976814 -250.37338) (xy 35.923664 -250.369396) (xy 35.871702 -250.357536)
			(xy 35.822088 -250.338064) (xy 35.77593 -250.311415) (xy 35.734259 -250.278184) (xy 35.698007 -250.239113)
			(xy 35.667983 -250.195076) (xy 35.644857 -250.147055) (xy 35.629147 -250.096125) (xy 35.621204 -250.043421)
			(xy 21.244824 -250.043421) (xy 21.236881 -250.096125) (xy 21.221171 -250.147055) (xy 21.198045 -250.195076)
			(xy 21.168021 -250.239113) (xy 21.131769 -250.278184) (xy 21.090098 -250.311415) (xy 21.04394 -250.338064)
			(xy 20.994326 -250.357536) (xy 20.942364 -250.369396) (xy 20.889214 -250.37338) (xy 20.836064 -250.369396)
			(xy 20.784102 -250.357536) (xy 20.734488 -250.338064) (xy 20.68833 -250.311415) (xy 20.646659 -250.278184)
			(xy 20.610407 -250.239113) (xy 20.580383 -250.195076) (xy 20.557257 -250.147055) (xy 20.541547 -250.096125)
			(xy 20.533604 -250.043421) (xy 9.6774 -250.043421) (xy 9.6774 -250.893305) (xy 16.433536 -250.893305)
			(xy 16.433536 -250.840007) (xy 16.441479 -250.787303) (xy 16.457189 -250.736373) (xy 16.480315 -250.688352)
			(xy 16.510339 -250.644315) (xy 16.546591 -250.605244) (xy 16.588262 -250.572013) (xy 16.63442 -250.545364)
			(xy 16.684034 -250.525892) (xy 16.735996 -250.514032) (xy 16.789146 -250.510049) (xy 16.842296 -250.514032)
			(xy 16.894258 -250.525892) (xy 16.943872 -250.545364) (xy 16.99003 -250.572013) (xy 17.031701 -250.605244)
			(xy 17.067953 -250.644315) (xy 17.097977 -250.688352) (xy 17.121103 -250.736373) (xy 17.136813 -250.787303)
			(xy 17.144756 -250.840007) (xy 17.145254 -250.866656) (xy 17.144756 -250.893305) (xy 31.521136 -250.893305)
			(xy 31.521136 -250.840007) (xy 31.529079 -250.787303) (xy 31.544789 -250.736373) (xy 31.567915 -250.688352)
			(xy 31.597939 -250.644315) (xy 31.634191 -250.605244) (xy 31.675862 -250.572013) (xy 31.72202 -250.545364)
			(xy 31.771634 -250.525892) (xy 31.823596 -250.514032) (xy 31.876746 -250.510049) (xy 31.929896 -250.514032)
			(xy 31.981858 -250.525892) (xy 32.031472 -250.545364) (xy 32.07763 -250.572013) (xy 32.119301 -250.605244)
			(xy 32.155553 -250.644315) (xy 32.185577 -250.688352) (xy 32.208703 -250.736373) (xy 32.224413 -250.787303)
			(xy 32.232356 -250.840007) (xy 32.232854 -250.866656) (xy 32.232356 -250.893305) (xy 46.608736 -250.893305)
			(xy 46.608736 -250.840007) (xy 46.616679 -250.787303) (xy 46.632389 -250.736373) (xy 46.655515 -250.688352)
			(xy 46.685539 -250.644315) (xy 46.721791 -250.605244) (xy 46.763462 -250.572013) (xy 46.80962 -250.545364)
			(xy 46.859234 -250.525892) (xy 46.911196 -250.514032) (xy 46.964346 -250.510049) (xy 47.017496 -250.514032)
			(xy 47.069458 -250.525892) (xy 47.119072 -250.545364) (xy 47.16523 -250.572013) (xy 47.206901 -250.605244)
			(xy 47.243153 -250.644315) (xy 47.273177 -250.688352) (xy 47.296303 -250.736373) (xy 47.312013 -250.787303)
			(xy 47.319956 -250.840007) (xy 47.320454 -250.866656) (xy 47.319956 -250.893305) (xy 47.312013 -250.946009)
			(xy 47.296303 -250.996939) (xy 47.273177 -251.04496) (xy 47.243153 -251.088997) (xy 47.206901 -251.128068)
			(xy 47.16523 -251.161299) (xy 47.119072 -251.187948) (xy 47.069458 -251.20742) (xy 47.017496 -251.21928)
			(xy 46.964346 -251.223264) (xy 46.911196 -251.21928) (xy 46.859234 -251.20742) (xy 46.80962 -251.187948)
			(xy 46.763462 -251.161299) (xy 46.721791 -251.128068) (xy 46.685539 -251.088997) (xy 46.655515 -251.04496)
			(xy 46.632389 -250.996939) (xy 46.616679 -250.946009) (xy 46.608736 -250.893305) (xy 32.232356 -250.893305)
			(xy 32.224413 -250.946009) (xy 32.208703 -250.996939) (xy 32.185577 -251.04496) (xy 32.155553 -251.088997)
			(xy 32.119301 -251.128068) (xy 32.07763 -251.161299) (xy 32.031472 -251.187948) (xy 31.981858 -251.20742)
			(xy 31.929896 -251.21928) (xy 31.876746 -251.223264) (xy 31.823596 -251.21928) (xy 31.771634 -251.20742)
			(xy 31.72202 -251.187948) (xy 31.675862 -251.161299) (xy 31.634191 -251.128068) (xy 31.597939 -251.088997)
			(xy 31.567915 -251.04496) (xy 31.544789 -250.996939) (xy 31.529079 -250.946009) (xy 31.521136 -250.893305)
			(xy 17.144756 -250.893305) (xy 17.136813 -250.946009) (xy 17.121103 -250.996939) (xy 17.097977 -251.04496)
			(xy 17.067953 -251.088997) (xy 17.031701 -251.128068) (xy 16.99003 -251.161299) (xy 16.943872 -251.187948)
			(xy 16.894258 -251.20742) (xy 16.842296 -251.21928) (xy 16.789146 -251.223264) (xy 16.735996 -251.21928)
			(xy 16.684034 -251.20742) (xy 16.63442 -251.187948) (xy 16.588262 -251.161299) (xy 16.546591 -251.128068)
			(xy 16.510339 -251.088997) (xy 16.480315 -251.04496) (xy 16.457189 -250.996939) (xy 16.441479 -250.946009)
			(xy 16.433536 -250.893305) (xy 9.6774 -250.893305) (xy 9.6774 -251.743443) (xy 20.533604 -251.743443)
			(xy 20.533604 -251.690145) (xy 20.541547 -251.637441) (xy 20.557257 -251.586511) (xy 20.580383 -251.53849)
			(xy 20.610407 -251.494453) (xy 20.646659 -251.455382) (xy 20.68833 -251.422151) (xy 20.734488 -251.395502)
			(xy 20.784102 -251.37603) (xy 20.836064 -251.36417) (xy 20.889214 -251.360187) (xy 20.942364 -251.36417)
			(xy 20.994326 -251.37603) (xy 21.04394 -251.395502) (xy 21.090098 -251.422151) (xy 21.131769 -251.455382)
			(xy 21.168021 -251.494453) (xy 21.198045 -251.53849) (xy 21.221171 -251.586511) (xy 21.236881 -251.637441)
			(xy 21.244824 -251.690145) (xy 21.245322 -251.716794) (xy 21.244824 -251.743443) (xy 35.621204 -251.743443)
			(xy 35.621204 -251.690145) (xy 35.629147 -251.637441) (xy 35.644857 -251.586511) (xy 35.667983 -251.53849)
			(xy 35.698007 -251.494453) (xy 35.734259 -251.455382) (xy 35.77593 -251.422151) (xy 35.822088 -251.395502)
			(xy 35.871702 -251.37603) (xy 35.923664 -251.36417) (xy 35.976814 -251.360187) (xy 36.029964 -251.36417)
			(xy 36.081926 -251.37603) (xy 36.13154 -251.395502) (xy 36.177698 -251.422151) (xy 36.219369 -251.455382)
			(xy 36.255621 -251.494453) (xy 36.285645 -251.53849) (xy 36.308771 -251.586511) (xy 36.324481 -251.637441)
			(xy 36.332424 -251.690145) (xy 36.332922 -251.716794) (xy 36.332424 -251.743443) (xy 50.708804 -251.743443)
			(xy 50.708804 -251.690145) (xy 50.716747 -251.637441) (xy 50.732457 -251.586511) (xy 50.755583 -251.53849)
			(xy 50.785607 -251.494453) (xy 50.821859 -251.455382) (xy 50.86353 -251.422151) (xy 50.909688 -251.395502)
			(xy 50.959302 -251.37603) (xy 51.011264 -251.36417) (xy 51.064414 -251.360187) (xy 51.117564 -251.36417)
			(xy 51.169526 -251.37603) (xy 51.21914 -251.395502) (xy 51.265298 -251.422151) (xy 51.306969 -251.455382)
			(xy 51.343221 -251.494453) (xy 51.373245 -251.53849) (xy 51.396371 -251.586511) (xy 51.412081 -251.637441)
			(xy 51.420024 -251.690145) (xy 51.420522 -251.716794) (xy 51.420024 -251.743443) (xy 51.412081 -251.796147)
			(xy 51.396371 -251.847077) (xy 51.373245 -251.895098) (xy 51.343221 -251.939135) (xy 51.306969 -251.978206)
			(xy 51.265298 -252.011437) (xy 51.21914 -252.038086) (xy 51.169526 -252.057558) (xy 51.117564 -252.069418)
			(xy 51.064414 -252.073402) (xy 51.011264 -252.069418) (xy 50.959302 -252.057558) (xy 50.909688 -252.038086)
			(xy 50.86353 -252.011437) (xy 50.821859 -251.978206) (xy 50.785607 -251.939135) (xy 50.755583 -251.895098)
			(xy 50.732457 -251.847077) (xy 50.716747 -251.796147) (xy 50.708804 -251.743443) (xy 36.332424 -251.743443)
			(xy 36.324481 -251.796147) (xy 36.308771 -251.847077) (xy 36.285645 -251.895098) (xy 36.255621 -251.939135)
			(xy 36.219369 -251.978206) (xy 36.177698 -252.011437) (xy 36.13154 -252.038086) (xy 36.081926 -252.057558)
			(xy 36.029964 -252.069418) (xy 35.976814 -252.073402) (xy 35.923664 -252.069418) (xy 35.871702 -252.057558)
			(xy 35.822088 -252.038086) (xy 35.77593 -252.011437) (xy 35.734259 -251.978206) (xy 35.698007 -251.939135)
			(xy 35.667983 -251.895098) (xy 35.644857 -251.847077) (xy 35.629147 -251.796147) (xy 35.621204 -251.743443)
			(xy 21.244824 -251.743443) (xy 21.236881 -251.796147) (xy 21.221171 -251.847077) (xy 21.198045 -251.895098)
			(xy 21.168021 -251.939135) (xy 21.131769 -251.978206) (xy 21.090098 -252.011437) (xy 21.04394 -252.038086)
			(xy 20.994326 -252.057558) (xy 20.942364 -252.069418) (xy 20.889214 -252.073402) (xy 20.836064 -252.069418)
			(xy 20.784102 -252.057558) (xy 20.734488 -252.038086) (xy 20.68833 -252.011437) (xy 20.646659 -251.978206)
			(xy 20.610407 -251.939135) (xy 20.580383 -251.895098) (xy 20.557257 -251.847077) (xy 20.541547 -251.796147)
			(xy 20.533604 -251.743443) (xy 9.6774 -251.743443) (xy 9.6774 -252.593327) (xy 10.780004 -252.593327)
			(xy 10.780004 -252.540029) (xy 10.787947 -252.487325) (xy 10.803657 -252.436395) (xy 10.826783 -252.388374)
			(xy 10.856807 -252.344337) (xy 10.893059 -252.305266) (xy 10.93473 -252.272035) (xy 10.980888 -252.245386)
			(xy 11.030502 -252.225914) (xy 11.082464 -252.214054) (xy 11.135614 -252.210071) (xy 11.188764 -252.214054)
			(xy 11.240726 -252.225914) (xy 11.29034 -252.245386) (xy 11.336498 -252.272035) (xy 11.378169 -252.305266)
			(xy 11.414421 -252.344337) (xy 11.444445 -252.388374) (xy 11.467571 -252.436395) (xy 11.483281 -252.487325)
			(xy 11.491224 -252.540029) (xy 11.491722 -252.566678) (xy 11.491224 -252.593327) (xy 16.433536 -252.593327)
			(xy 16.433536 -252.540029) (xy 16.441479 -252.487325) (xy 16.457189 -252.436395) (xy 16.480315 -252.388374)
			(xy 16.510339 -252.344337) (xy 16.546591 -252.305266) (xy 16.588262 -252.272035) (xy 16.63442 -252.245386)
			(xy 16.684034 -252.225914) (xy 16.735996 -252.214054) (xy 16.789146 -252.210071) (xy 16.842296 -252.214054)
			(xy 16.894258 -252.225914) (xy 16.943872 -252.245386) (xy 16.99003 -252.272035) (xy 17.031701 -252.305266)
			(xy 17.067953 -252.344337) (xy 17.097977 -252.388374) (xy 17.121103 -252.436395) (xy 17.136813 -252.487325)
			(xy 17.144756 -252.540029) (xy 17.145254 -252.566678) (xy 17.144756 -252.593327) (xy 20.533604 -252.593327)
			(xy 20.533604 -252.540029) (xy 20.541547 -252.487325) (xy 20.557257 -252.436395) (xy 20.580383 -252.388374)
			(xy 20.610407 -252.344337) (xy 20.646659 -252.305266) (xy 20.68833 -252.272035) (xy 20.734488 -252.245386)
			(xy 20.784102 -252.225914) (xy 20.836064 -252.214054) (xy 20.889214 -252.210071) (xy 20.942364 -252.214054)
			(xy 20.994326 -252.225914) (xy 21.04394 -252.245386) (xy 21.090098 -252.272035) (xy 21.131769 -252.305266)
			(xy 21.168021 -252.344337) (xy 21.198045 -252.388374) (xy 21.221171 -252.436395) (xy 21.236881 -252.487325)
			(xy 21.244824 -252.540029) (xy 21.245322 -252.566678) (xy 21.244824 -252.593327) (xy 25.867604 -252.593327)
			(xy 25.867604 -252.540029) (xy 25.875547 -252.487325) (xy 25.891257 -252.436395) (xy 25.914383 -252.388374)
			(xy 25.944407 -252.344337) (xy 25.980659 -252.305266) (xy 26.02233 -252.272035) (xy 26.068488 -252.245386)
			(xy 26.118102 -252.225914) (xy 26.170064 -252.214054) (xy 26.223214 -252.210071) (xy 26.276364 -252.214054)
			(xy 26.328326 -252.225914) (xy 26.37794 -252.245386) (xy 26.424098 -252.272035) (xy 26.465769 -252.305266)
			(xy 26.502021 -252.344337) (xy 26.532045 -252.388374) (xy 26.555171 -252.436395) (xy 26.570881 -252.487325)
			(xy 26.578824 -252.540029) (xy 26.579322 -252.566678) (xy 26.578824 -252.593327) (xy 31.521136 -252.593327)
			(xy 31.521136 -252.540029) (xy 31.529079 -252.487325) (xy 31.544789 -252.436395) (xy 31.567915 -252.388374)
			(xy 31.597939 -252.344337) (xy 31.634191 -252.305266) (xy 31.675862 -252.272035) (xy 31.72202 -252.245386)
			(xy 31.771634 -252.225914) (xy 31.823596 -252.214054) (xy 31.876746 -252.210071) (xy 31.929896 -252.214054)
			(xy 31.981858 -252.225914) (xy 32.031472 -252.245386) (xy 32.07763 -252.272035) (xy 32.119301 -252.305266)
			(xy 32.155553 -252.344337) (xy 32.185577 -252.388374) (xy 32.208703 -252.436395) (xy 32.224413 -252.487325)
			(xy 32.232356 -252.540029) (xy 32.232854 -252.566678) (xy 32.232356 -252.593327) (xy 35.621204 -252.593327)
			(xy 35.621204 -252.540029) (xy 35.629147 -252.487325) (xy 35.644857 -252.436395) (xy 35.667983 -252.388374)
			(xy 35.698007 -252.344337) (xy 35.734259 -252.305266) (xy 35.77593 -252.272035) (xy 35.822088 -252.245386)
			(xy 35.871702 -252.225914) (xy 35.923664 -252.214054) (xy 35.976814 -252.210071) (xy 36.029964 -252.214054)
			(xy 36.081926 -252.225914) (xy 36.13154 -252.245386) (xy 36.177698 -252.272035) (xy 36.219369 -252.305266)
			(xy 36.255621 -252.344337) (xy 36.285645 -252.388374) (xy 36.308771 -252.436395) (xy 36.324481 -252.487325)
			(xy 36.332424 -252.540029) (xy 36.332922 -252.566678) (xy 36.332424 -252.593327) (xy 40.955204 -252.593327)
			(xy 40.955204 -252.540029) (xy 40.963147 -252.487325) (xy 40.978857 -252.436395) (xy 41.001983 -252.388374)
			(xy 41.032007 -252.344337) (xy 41.068259 -252.305266) (xy 41.10993 -252.272035) (xy 41.156088 -252.245386)
			(xy 41.205702 -252.225914) (xy 41.257664 -252.214054) (xy 41.310814 -252.210071) (xy 41.363964 -252.214054)
			(xy 41.415926 -252.225914) (xy 41.46554 -252.245386) (xy 41.511698 -252.272035) (xy 41.553369 -252.305266)
			(xy 41.589621 -252.344337) (xy 41.619645 -252.388374) (xy 41.642771 -252.436395) (xy 41.658481 -252.487325)
			(xy 41.666424 -252.540029) (xy 41.666922 -252.566678) (xy 41.666424 -252.593327) (xy 46.608736 -252.593327)
			(xy 46.608736 -252.540029) (xy 46.616679 -252.487325) (xy 46.632389 -252.436395) (xy 46.655515 -252.388374)
			(xy 46.685539 -252.344337) (xy 46.721791 -252.305266) (xy 46.763462 -252.272035) (xy 46.80962 -252.245386)
			(xy 46.859234 -252.225914) (xy 46.911196 -252.214054) (xy 46.964346 -252.210071) (xy 47.017496 -252.214054)
			(xy 47.069458 -252.225914) (xy 47.119072 -252.245386) (xy 47.16523 -252.272035) (xy 47.206901 -252.305266)
			(xy 47.243153 -252.344337) (xy 47.273177 -252.388374) (xy 47.296303 -252.436395) (xy 47.312013 -252.487325)
			(xy 47.319956 -252.540029) (xy 47.320454 -252.566678) (xy 47.319956 -252.593327) (xy 50.708804 -252.593327)
			(xy 50.708804 -252.540029) (xy 50.716747 -252.487325) (xy 50.732457 -252.436395) (xy 50.755583 -252.388374)
			(xy 50.785607 -252.344337) (xy 50.821859 -252.305266) (xy 50.86353 -252.272035) (xy 50.909688 -252.245386)
			(xy 50.959302 -252.225914) (xy 51.011264 -252.214054) (xy 51.064414 -252.210071) (xy 51.117564 -252.214054)
			(xy 51.169526 -252.225914) (xy 51.21914 -252.245386) (xy 51.265298 -252.272035) (xy 51.306969 -252.305266)
			(xy 51.343221 -252.344337) (xy 51.373245 -252.388374) (xy 51.396371 -252.436395) (xy 51.412081 -252.487325)
			(xy 51.420024 -252.540029) (xy 51.420522 -252.566678) (xy 51.420024 -252.593327) (xy 56.042804 -252.593327)
			(xy 56.042804 -252.540029) (xy 56.050747 -252.487325) (xy 56.066457 -252.436395) (xy 56.089583 -252.388374)
			(xy 56.119607 -252.344337) (xy 56.155859 -252.305266) (xy 56.19753 -252.272035) (xy 56.243688 -252.245386)
			(xy 56.293302 -252.225914) (xy 56.345264 -252.214054) (xy 56.398414 -252.210071) (xy 56.451564 -252.214054)
			(xy 56.503526 -252.225914) (xy 56.55314 -252.245386) (xy 56.599298 -252.272035) (xy 56.640969 -252.305266)
			(xy 56.677221 -252.344337) (xy 56.707245 -252.388374) (xy 56.730371 -252.436395) (xy 56.746081 -252.487325)
			(xy 56.754024 -252.540029) (xy 56.754522 -252.566678) (xy 56.754024 -252.593327) (xy 63.586604 -252.593327)
			(xy 63.586604 -252.540029) (xy 63.594547 -252.487325) (xy 63.610257 -252.436395) (xy 63.633383 -252.388374)
			(xy 63.663407 -252.344337) (xy 63.699659 -252.305266) (xy 63.74133 -252.272035) (xy 63.787488 -252.245386)
			(xy 63.837102 -252.225914) (xy 63.889064 -252.214054) (xy 63.942214 -252.210071) (xy 63.995364 -252.214054)
			(xy 64.047326 -252.225914) (xy 64.09694 -252.245386) (xy 64.143098 -252.272035) (xy 64.184769 -252.305266)
			(xy 64.221021 -252.344337) (xy 64.251045 -252.388374) (xy 64.274171 -252.436395) (xy 64.289881 -252.487325)
			(xy 64.297824 -252.540029) (xy 64.298322 -252.566678) (xy 64.297824 -252.593327) (xy 64.289881 -252.646031)
			(xy 64.274171 -252.696961) (xy 64.251045 -252.744982) (xy 64.221021 -252.789019) (xy 64.184769 -252.82809)
			(xy 64.143098 -252.861321) (xy 64.09694 -252.88797) (xy 64.047326 -252.907442) (xy 63.995364 -252.919302)
			(xy 63.942214 -252.923286) (xy 63.889064 -252.919302) (xy 63.837102 -252.907442) (xy 63.787488 -252.88797)
			(xy 63.74133 -252.861321) (xy 63.699659 -252.82809) (xy 63.663407 -252.789019) (xy 63.633383 -252.744982)
			(xy 63.610257 -252.696961) (xy 63.594547 -252.646031) (xy 63.586604 -252.593327) (xy 56.754024 -252.593327)
			(xy 56.746081 -252.646031) (xy 56.730371 -252.696961) (xy 56.707245 -252.744982) (xy 56.677221 -252.789019)
			(xy 56.640969 -252.82809) (xy 56.599298 -252.861321) (xy 56.55314 -252.88797) (xy 56.503526 -252.907442)
			(xy 56.451564 -252.919302) (xy 56.398414 -252.923286) (xy 56.345264 -252.919302) (xy 56.293302 -252.907442)
			(xy 56.243688 -252.88797) (xy 56.19753 -252.861321) (xy 56.155859 -252.82809) (xy 56.119607 -252.789019)
			(xy 56.089583 -252.744982) (xy 56.066457 -252.696961) (xy 56.050747 -252.646031) (xy 56.042804 -252.593327)
			(xy 51.420024 -252.593327) (xy 51.412081 -252.646031) (xy 51.396371 -252.696961) (xy 51.373245 -252.744982)
			(xy 51.343221 -252.789019) (xy 51.306969 -252.82809) (xy 51.265298 -252.861321) (xy 51.21914 -252.88797)
			(xy 51.169526 -252.907442) (xy 51.117564 -252.919302) (xy 51.064414 -252.923286) (xy 51.011264 -252.919302)
			(xy 50.959302 -252.907442) (xy 50.909688 -252.88797) (xy 50.86353 -252.861321) (xy 50.821859 -252.82809)
			(xy 50.785607 -252.789019) (xy 50.755583 -252.744982) (xy 50.732457 -252.696961) (xy 50.716747 -252.646031)
			(xy 50.708804 -252.593327) (xy 47.319956 -252.593327) (xy 47.312013 -252.646031) (xy 47.296303 -252.696961)
			(xy 47.273177 -252.744982) (xy 47.243153 -252.789019) (xy 47.206901 -252.82809) (xy 47.16523 -252.861321)
			(xy 47.119072 -252.88797) (xy 47.069458 -252.907442) (xy 47.017496 -252.919302) (xy 46.964346 -252.923286)
			(xy 46.911196 -252.919302) (xy 46.859234 -252.907442) (xy 46.80962 -252.88797) (xy 46.763462 -252.861321)
			(xy 46.721791 -252.82809) (xy 46.685539 -252.789019) (xy 46.655515 -252.744982) (xy 46.632389 -252.696961)
			(xy 46.616679 -252.646031) (xy 46.608736 -252.593327) (xy 41.666424 -252.593327) (xy 41.658481 -252.646031)
			(xy 41.642771 -252.696961) (xy 41.619645 -252.744982) (xy 41.589621 -252.789019) (xy 41.553369 -252.82809)
			(xy 41.511698 -252.861321) (xy 41.46554 -252.88797) (xy 41.415926 -252.907442) (xy 41.363964 -252.919302)
			(xy 41.310814 -252.923286) (xy 41.257664 -252.919302) (xy 41.205702 -252.907442) (xy 41.156088 -252.88797)
			(xy 41.10993 -252.861321) (xy 41.068259 -252.82809) (xy 41.032007 -252.789019) (xy 41.001983 -252.744982)
			(xy 40.978857 -252.696961) (xy 40.963147 -252.646031) (xy 40.955204 -252.593327) (xy 36.332424 -252.593327)
			(xy 36.324481 -252.646031) (xy 36.308771 -252.696961) (xy 36.285645 -252.744982) (xy 36.255621 -252.789019)
			(xy 36.219369 -252.82809) (xy 36.177698 -252.861321) (xy 36.13154 -252.88797) (xy 36.081926 -252.907442)
			(xy 36.029964 -252.919302) (xy 35.976814 -252.923286) (xy 35.923664 -252.919302) (xy 35.871702 -252.907442)
			(xy 35.822088 -252.88797) (xy 35.77593 -252.861321) (xy 35.734259 -252.82809) (xy 35.698007 -252.789019)
			(xy 35.667983 -252.744982) (xy 35.644857 -252.696961) (xy 35.629147 -252.646031) (xy 35.621204 -252.593327)
			(xy 32.232356 -252.593327) (xy 32.224413 -252.646031) (xy 32.208703 -252.696961) (xy 32.185577 -252.744982)
			(xy 32.155553 -252.789019) (xy 32.119301 -252.82809) (xy 32.07763 -252.861321) (xy 32.031472 -252.88797)
			(xy 31.981858 -252.907442) (xy 31.929896 -252.919302) (xy 31.876746 -252.923286) (xy 31.823596 -252.919302)
			(xy 31.771634 -252.907442) (xy 31.72202 -252.88797) (xy 31.675862 -252.861321) (xy 31.634191 -252.82809)
			(xy 31.597939 -252.789019) (xy 31.567915 -252.744982) (xy 31.544789 -252.696961) (xy 31.529079 -252.646031)
			(xy 31.521136 -252.593327) (xy 26.578824 -252.593327) (xy 26.570881 -252.646031) (xy 26.555171 -252.696961)
			(xy 26.532045 -252.744982) (xy 26.502021 -252.789019) (xy 26.465769 -252.82809) (xy 26.424098 -252.861321)
			(xy 26.37794 -252.88797) (xy 26.328326 -252.907442) (xy 26.276364 -252.919302) (xy 26.223214 -252.923286)
			(xy 26.170064 -252.919302) (xy 26.118102 -252.907442) (xy 26.068488 -252.88797) (xy 26.02233 -252.861321)
			(xy 25.980659 -252.82809) (xy 25.944407 -252.789019) (xy 25.914383 -252.744982) (xy 25.891257 -252.696961)
			(xy 25.875547 -252.646031) (xy 25.867604 -252.593327) (xy 21.244824 -252.593327) (xy 21.236881 -252.646031)
			(xy 21.221171 -252.696961) (xy 21.198045 -252.744982) (xy 21.168021 -252.789019) (xy 21.131769 -252.82809)
			(xy 21.090098 -252.861321) (xy 21.04394 -252.88797) (xy 20.994326 -252.907442) (xy 20.942364 -252.919302)
			(xy 20.889214 -252.923286) (xy 20.836064 -252.919302) (xy 20.784102 -252.907442) (xy 20.734488 -252.88797)
			(xy 20.68833 -252.861321) (xy 20.646659 -252.82809) (xy 20.610407 -252.789019) (xy 20.580383 -252.744982)
			(xy 20.557257 -252.696961) (xy 20.541547 -252.646031) (xy 20.533604 -252.593327) (xy 17.144756 -252.593327)
			(xy 17.136813 -252.646031) (xy 17.121103 -252.696961) (xy 17.097977 -252.744982) (xy 17.067953 -252.789019)
			(xy 17.031701 -252.82809) (xy 16.99003 -252.861321) (xy 16.943872 -252.88797) (xy 16.894258 -252.907442)
			(xy 16.842296 -252.919302) (xy 16.789146 -252.923286) (xy 16.735996 -252.919302) (xy 16.684034 -252.907442)
			(xy 16.63442 -252.88797) (xy 16.588262 -252.861321) (xy 16.546591 -252.82809) (xy 16.510339 -252.789019)
			(xy 16.480315 -252.744982) (xy 16.457189 -252.696961) (xy 16.441479 -252.646031) (xy 16.433536 -252.593327)
			(xy 11.491224 -252.593327) (xy 11.483281 -252.646031) (xy 11.467571 -252.696961) (xy 11.444445 -252.744982)
			(xy 11.414421 -252.789019) (xy 11.378169 -252.82809) (xy 11.336498 -252.861321) (xy 11.29034 -252.88797)
			(xy 11.240726 -252.907442) (xy 11.188764 -252.919302) (xy 11.135614 -252.923286) (xy 11.082464 -252.919302)
			(xy 11.030502 -252.907442) (xy 10.980888 -252.88797) (xy 10.93473 -252.861321) (xy 10.893059 -252.82809)
			(xy 10.856807 -252.789019) (xy 10.826783 -252.744982) (xy 10.803657 -252.696961) (xy 10.787947 -252.646031)
			(xy 10.780004 -252.593327) (xy 9.6774 -252.593327) (xy 9.6774 -254.6495) (xy 57.781646 -254.6495)
			(xy 57.78563 -254.596342) (xy 57.797492 -254.544372) (xy 57.816968 -254.49475) (xy 57.843622 -254.448585)
			(xy 57.876859 -254.406909) (xy 57.915936 -254.370652) (xy 57.959981 -254.340624) (xy 58.00801 -254.317496)
			(xy 58.058949 -254.301785) (xy 58.111661 -254.293842) (xy 58.138314 -254.29337) (xy 58.165635 -254.293891)
			(xy 58.219636 -254.30223) (xy 58.271732 -254.318712) (xy 58.320703 -254.342949) (xy 58.365403 -254.374375)
			(xy 58.385456 -254.392938) (xy 58.397078 -254.403335) (xy 58.425012 -254.417159) (xy 58.455814 -254.421915)
			(xy 58.486616 -254.417159) (xy 58.51455 -254.403335) (xy 58.526172 -254.392938) (xy 58.54621 -254.374353)
			(xy 58.590896 -254.342892) (xy 58.639868 -254.318636) (xy 58.691975 -254.302158) (xy 58.745989 -254.293846)
			(xy 58.773314 -254.29337) (xy 58.800635 -254.293891) (xy 58.854636 -254.30223) (xy 58.906732 -254.318712)
			(xy 58.955703 -254.342949) (xy 59.000403 -254.374375) (xy 59.020456 -254.392938) (xy 59.032078 -254.403335)
			(xy 59.060012 -254.417159) (xy 59.090814 -254.421915) (xy 59.121616 -254.417159) (xy 59.14955 -254.403335)
			(xy 59.161172 -254.392938) (xy 59.18121 -254.374353) (xy 59.225896 -254.342892) (xy 59.274868 -254.318636)
			(xy 59.326975 -254.302158) (xy 59.380989 -254.293846) (xy 59.408314 -254.29337) (xy 59.435635 -254.293891)
			(xy 59.489636 -254.30223) (xy 59.541732 -254.318712) (xy 59.590703 -254.342949) (xy 59.635403 -254.374375)
			(xy 59.655456 -254.392938) (xy 59.667078 -254.403335) (xy 59.695012 -254.417159) (xy 59.725814 -254.421915)
			(xy 59.756616 -254.417159) (xy 59.78455 -254.403335) (xy 59.796172 -254.392938) (xy 59.815387 -254.37507)
			(xy 59.85811 -254.344611) (xy 59.904846 -254.32076) (xy 59.954579 -254.304037) (xy 59.980322 -254.298958)
			(xy 59.993498 -254.296162) (xy 60.017824 -254.284619) (xy 60.038295 -254.267127) (xy 60.05349 -254.244898)
			(xy 60.062358 -254.219474) (xy 60.064282 -254.192617) (xy 60.06211 -254.179324) (xy 60.059026 -254.162411)
			(xy 60.055715 -254.128189) (xy 60.055506 -254.110998) (xy 60.05601 -254.083012) (xy 60.064767 -254.027729)
			(xy 60.082064 -253.974496) (xy 60.107475 -253.924625) (xy 60.140376 -253.879343) (xy 60.179955 -253.839766)
			(xy 60.225239 -253.806867) (xy 60.275111 -253.781458) (xy 60.328344 -253.764163) (xy 60.383628 -253.755409)
			(xy 60.411614 -253.75489) (xy 60.440947 -253.755474) (xy 60.498821 -253.765086) (xy 60.554333 -253.784064)
			(xy 60.605978 -253.811893) (xy 60.652358 -253.847819) (xy 60.672726 -253.868936) (xy 60.682801 -253.879)
			(xy 60.707161 -253.893713) (xy 60.734638 -253.901124) (xy 60.763093 -253.900655) (xy 60.790311 -253.892342)
			(xy 60.814173 -253.876833) (xy 60.823856 -253.866396) (xy 60.840832 -253.847556) (xy 60.879234 -253.814435)
			(xy 60.921947 -253.787098) (xy 60.968106 -253.766097) (xy 61.016778 -253.751857) (xy 61.066978 -253.744667)
			(xy 61.092334 -253.744222) (xy 61.118984 -253.744662) (xy 61.171688 -253.752611) (xy 61.222618 -253.768325)
			(xy 61.270638 -253.791454) (xy 61.314675 -253.821482) (xy 61.353745 -253.857737) (xy 61.386975 -253.89941)
			(xy 61.413624 -253.94557) (xy 61.433095 -253.995185) (xy 61.444955 -254.047149) (xy 61.448938 -254.1003)
			(xy 61.444955 -254.153451) (xy 61.433095 -254.205415) (xy 61.413624 -254.25503) (xy 61.386975 -254.30119)
			(xy 61.353745 -254.342863) (xy 61.314675 -254.379118) (xy 61.270638 -254.409146) (xy 61.222618 -254.432275)
			(xy 61.171688 -254.447989) (xy 61.118984 -254.455938) (xy 61.092334 -254.456438) (xy 61.063002 -254.455814)
			(xy 61.005131 -254.446211) (xy 60.94962 -254.427242) (xy 60.897974 -254.399422) (xy 60.851592 -254.363505)
			(xy 60.831222 -254.342392) (xy 60.821192 -254.332283) (xy 60.796817 -254.317583) (xy 60.76933 -254.310185)
			(xy 60.740869 -254.310664) (xy 60.713646 -254.318982) (xy 60.689779 -254.334494) (xy 60.680092 -254.344932)
			(xy 60.663963 -254.362833) (xy 60.627712 -254.394575) (xy 60.587509 -254.421134) (xy 60.544089 -254.442025)
			(xy 60.498248 -254.456865) (xy 60.474606 -254.461518) (xy 60.461441 -254.464359) (xy 60.437117 -254.475892)
			(xy 60.416647 -254.493375) (xy 60.401449 -254.515595) (xy 60.392578 -254.541011) (xy 60.390649 -254.567862)
			(xy 60.392818 -254.581152) (xy 60.395913 -254.598063) (xy 60.399217 -254.632287) (xy 60.399422 -254.649478)
			(xy 60.398867 -254.677462) (xy 60.390115 -254.732742) (xy 60.372823 -254.785971) (xy 60.347417 -254.835841)
			(xy 60.314522 -254.881121) (xy 60.274949 -254.920699) (xy 60.229671 -254.953598) (xy 60.179805 -254.979009)
			(xy 60.126577 -254.996307) (xy 60.071298 -255.005064) (xy 60.043314 -255.005586) (xy 60.015993 -255.00506)
			(xy 59.961992 -254.996724) (xy 59.909895 -254.980244) (xy 59.860924 -254.956007) (xy 59.816224 -254.924581)
			(xy 59.796172 -254.906018) (xy 59.78455 -254.895621) (xy 59.756616 -254.881797) (xy 59.725814 -254.877041)
			(xy 59.695012 -254.881797) (xy 59.667078 -254.895621) (xy 59.655456 -254.906018) (xy 59.635457 -254.924647)
			(xy 59.59076 -254.9561) (xy 59.541777 -254.980346) (xy 59.489662 -254.996814) (xy 59.435642 -255.005116)
			(xy 59.408314 -255.005586) (xy 59.380993 -255.00506) (xy 59.326992 -254.996724) (xy 59.274895 -254.980244)
			(xy 59.225924 -254.956007) (xy 59.181224 -254.924581) (xy 59.161172 -254.906018) (xy 59.14955 -254.895621)
			(xy 59.121616 -254.881797) (xy 59.090814 -254.877041) (xy 59.060012 -254.881797) (xy 59.032078 -254.895621)
			(xy 59.020456 -254.906018) (xy 59.000457 -254.924647) (xy 58.95576 -254.9561) (xy 58.906777 -254.980346)
			(xy 58.854662 -254.996814) (xy 58.800642 -255.005116) (xy 58.773314 -255.005586) (xy 58.745993 -255.00506)
			(xy 58.691992 -254.996724) (xy 58.639895 -254.980244) (xy 58.590924 -254.956007) (xy 58.546224 -254.924581)
			(xy 58.526172 -254.906018) (xy 58.51455 -254.895621) (xy 58.486616 -254.881797) (xy 58.455814 -254.877041)
			(xy 58.425012 -254.881797) (xy 58.397078 -254.895621) (xy 58.385456 -254.906018) (xy 58.365457 -254.924647)
			(xy 58.32076 -254.9561) (xy 58.271777 -254.980346) (xy 58.219662 -254.996814) (xy 58.165642 -255.005116)
			(xy 58.138314 -255.005586) (xy 58.111661 -255.005158) (xy 58.058949 -254.997215) (xy 58.00801 -254.981504)
			(xy 57.959981 -254.958376) (xy 57.915936 -254.928348) (xy 57.876859 -254.892091) (xy 57.843622 -254.850415)
			(xy 57.816968 -254.80425) (xy 57.797492 -254.754628) (xy 57.78563 -254.702658) (xy 57.781646 -254.6495)
			(xy 9.6774 -254.6495) (xy 9.6774 -259.393415) (xy 12.989804 -259.393415) (xy 12.989804 -259.340117)
			(xy 12.997747 -259.287413) (xy 13.013457 -259.236483) (xy 13.036583 -259.188462) (xy 13.066607 -259.144425)
			(xy 13.102859 -259.105354) (xy 13.14453 -259.072123) (xy 13.190688 -259.045474) (xy 13.240302 -259.026002)
			(xy 13.292264 -259.014142) (xy 13.345414 -259.010159) (xy 13.398564 -259.014142) (xy 13.450526 -259.026002)
			(xy 13.50014 -259.045474) (xy 13.546298 -259.072123) (xy 13.587969 -259.105354) (xy 13.624221 -259.144425)
			(xy 13.654245 -259.188462) (xy 13.677371 -259.236483) (xy 13.693081 -259.287413) (xy 13.701024 -259.340117)
			(xy 13.701522 -259.366766) (xy 13.701024 -259.393415) (xy 16.433536 -259.393415) (xy 16.433536 -259.340117)
			(xy 16.441479 -259.287413) (xy 16.457189 -259.236483) (xy 16.480315 -259.188462) (xy 16.510339 -259.144425)
			(xy 16.546591 -259.105354) (xy 16.588262 -259.072123) (xy 16.63442 -259.045474) (xy 16.684034 -259.026002)
			(xy 16.735996 -259.014142) (xy 16.789146 -259.010159) (xy 16.842296 -259.014142) (xy 16.894258 -259.026002)
			(xy 16.943872 -259.045474) (xy 16.99003 -259.072123) (xy 17.031701 -259.105354) (xy 17.067953 -259.144425)
			(xy 17.097977 -259.188462) (xy 17.121103 -259.236483) (xy 17.136813 -259.287413) (xy 17.144756 -259.340117)
			(xy 17.145254 -259.366766) (xy 17.144756 -259.393415) (xy 20.533604 -259.393415) (xy 20.533604 -259.340117)
			(xy 20.541547 -259.287413) (xy 20.557257 -259.236483) (xy 20.580383 -259.188462) (xy 20.610407 -259.144425)
			(xy 20.646659 -259.105354) (xy 20.68833 -259.072123) (xy 20.734488 -259.045474) (xy 20.784102 -259.026002)
			(xy 20.836064 -259.014142) (xy 20.889214 -259.010159) (xy 20.942364 -259.014142) (xy 20.994326 -259.026002)
			(xy 21.04394 -259.045474) (xy 21.090098 -259.072123) (xy 21.131769 -259.105354) (xy 21.168021 -259.144425)
			(xy 21.198045 -259.188462) (xy 21.221171 -259.236483) (xy 21.236881 -259.287413) (xy 21.244824 -259.340117)
			(xy 21.245322 -259.366766) (xy 21.244824 -259.393415) (xy 28.077404 -259.393415) (xy 28.077404 -259.340117)
			(xy 28.085347 -259.287413) (xy 28.101057 -259.236483) (xy 28.124183 -259.188462) (xy 28.154207 -259.144425)
			(xy 28.190459 -259.105354) (xy 28.23213 -259.072123) (xy 28.278288 -259.045474) (xy 28.327902 -259.026002)
			(xy 28.379864 -259.014142) (xy 28.433014 -259.010159) (xy 28.486164 -259.014142) (xy 28.538126 -259.026002)
			(xy 28.58774 -259.045474) (xy 28.633898 -259.072123) (xy 28.675569 -259.105354) (xy 28.711821 -259.144425)
			(xy 28.741845 -259.188462) (xy 28.764971 -259.236483) (xy 28.780681 -259.287413) (xy 28.788624 -259.340117)
			(xy 28.789122 -259.366766) (xy 28.788624 -259.393415) (xy 31.521136 -259.393415) (xy 31.521136 -259.340117)
			(xy 31.529079 -259.287413) (xy 31.544789 -259.236483) (xy 31.567915 -259.188462) (xy 31.597939 -259.144425)
			(xy 31.634191 -259.105354) (xy 31.675862 -259.072123) (xy 31.72202 -259.045474) (xy 31.771634 -259.026002)
			(xy 31.823596 -259.014142) (xy 31.876746 -259.010159) (xy 31.929896 -259.014142) (xy 31.981858 -259.026002)
			(xy 32.031472 -259.045474) (xy 32.07763 -259.072123) (xy 32.119301 -259.105354) (xy 32.155553 -259.144425)
			(xy 32.185577 -259.188462) (xy 32.208703 -259.236483) (xy 32.224413 -259.287413) (xy 32.232356 -259.340117)
			(xy 32.232854 -259.366766) (xy 32.232356 -259.393415) (xy 35.621204 -259.393415) (xy 35.621204 -259.340117)
			(xy 35.629147 -259.287413) (xy 35.644857 -259.236483) (xy 35.667983 -259.188462) (xy 35.698007 -259.144425)
			(xy 35.734259 -259.105354) (xy 35.77593 -259.072123) (xy 35.822088 -259.045474) (xy 35.871702 -259.026002)
			(xy 35.923664 -259.014142) (xy 35.976814 -259.010159) (xy 36.029964 -259.014142) (xy 36.081926 -259.026002)
			(xy 36.13154 -259.045474) (xy 36.177698 -259.072123) (xy 36.219369 -259.105354) (xy 36.255621 -259.144425)
			(xy 36.285645 -259.188462) (xy 36.308771 -259.236483) (xy 36.324481 -259.287413) (xy 36.332424 -259.340117)
			(xy 36.332922 -259.366766) (xy 36.332424 -259.393415) (xy 43.165004 -259.393415) (xy 43.165004 -259.340117)
			(xy 43.172947 -259.287413) (xy 43.188657 -259.236483) (xy 43.211783 -259.188462) (xy 43.241807 -259.144425)
			(xy 43.278059 -259.105354) (xy 43.31973 -259.072123) (xy 43.365888 -259.045474) (xy 43.415502 -259.026002)
			(xy 43.467464 -259.014142) (xy 43.520614 -259.010159) (xy 43.573764 -259.014142) (xy 43.625726 -259.026002)
			(xy 43.67534 -259.045474) (xy 43.721498 -259.072123) (xy 43.763169 -259.105354) (xy 43.799421 -259.144425)
			(xy 43.829445 -259.188462) (xy 43.852571 -259.236483) (xy 43.868281 -259.287413) (xy 43.876224 -259.340117)
			(xy 43.876722 -259.366766) (xy 43.876224 -259.393415) (xy 46.608736 -259.393415) (xy 46.608736 -259.340117)
			(xy 46.616679 -259.287413) (xy 46.632389 -259.236483) (xy 46.655515 -259.188462) (xy 46.685539 -259.144425)
			(xy 46.721791 -259.105354) (xy 46.763462 -259.072123) (xy 46.80962 -259.045474) (xy 46.859234 -259.026002)
			(xy 46.911196 -259.014142) (xy 46.964346 -259.010159) (xy 47.017496 -259.014142) (xy 47.069458 -259.026002)
			(xy 47.119072 -259.045474) (xy 47.16523 -259.072123) (xy 47.206901 -259.105354) (xy 47.243153 -259.144425)
			(xy 47.273177 -259.188462) (xy 47.296303 -259.236483) (xy 47.312013 -259.287413) (xy 47.319956 -259.340117)
			(xy 47.320454 -259.366766) (xy 47.319956 -259.393415) (xy 50.734204 -259.393415) (xy 50.734204 -259.340117)
			(xy 50.742147 -259.287413) (xy 50.757857 -259.236483) (xy 50.780983 -259.188462) (xy 50.811007 -259.144425)
			(xy 50.847259 -259.105354) (xy 50.88893 -259.072123) (xy 50.935088 -259.045474) (xy 50.984702 -259.026002)
			(xy 51.036664 -259.014142) (xy 51.089814 -259.010159) (xy 51.142964 -259.014142) (xy 51.194926 -259.026002)
			(xy 51.24454 -259.045474) (xy 51.290698 -259.072123) (xy 51.332369 -259.105354) (xy 51.368621 -259.144425)
			(xy 51.398645 -259.188462) (xy 51.421771 -259.236483) (xy 51.437481 -259.287413) (xy 51.445424 -259.340117)
			(xy 51.445922 -259.366766) (xy 51.445424 -259.393415) (xy 51.437481 -259.446119) (xy 51.421771 -259.497049)
			(xy 51.398645 -259.54507) (xy 51.368621 -259.589107) (xy 51.332369 -259.628178) (xy 51.290698 -259.661409)
			(xy 51.24454 -259.688058) (xy 51.194926 -259.70753) (xy 51.142964 -259.71939) (xy 51.089814 -259.723374)
			(xy 51.036664 -259.71939) (xy 50.984702 -259.70753) (xy 50.935088 -259.688058) (xy 50.88893 -259.661409)
			(xy 50.847259 -259.628178) (xy 50.811007 -259.589107) (xy 50.780983 -259.54507) (xy 50.757857 -259.497049)
			(xy 50.742147 -259.446119) (xy 50.734204 -259.393415) (xy 47.319956 -259.393415) (xy 47.312013 -259.446119)
			(xy 47.296303 -259.497049) (xy 47.273177 -259.54507) (xy 47.243153 -259.589107) (xy 47.206901 -259.628178)
			(xy 47.16523 -259.661409) (xy 47.119072 -259.688058) (xy 47.069458 -259.70753) (xy 47.017496 -259.71939)
			(xy 46.964346 -259.723374) (xy 46.911196 -259.71939) (xy 46.859234 -259.70753) (xy 46.80962 -259.688058)
			(xy 46.763462 -259.661409) (xy 46.721791 -259.628178) (xy 46.685539 -259.589107) (xy 46.655515 -259.54507)
			(xy 46.632389 -259.497049) (xy 46.616679 -259.446119) (xy 46.608736 -259.393415) (xy 43.876224 -259.393415)
			(xy 43.868281 -259.446119) (xy 43.852571 -259.497049) (xy 43.829445 -259.54507) (xy 43.799421 -259.589107)
			(xy 43.763169 -259.628178) (xy 43.721498 -259.661409) (xy 43.67534 -259.688058) (xy 43.625726 -259.70753)
			(xy 43.573764 -259.71939) (xy 43.520614 -259.723374) (xy 43.467464 -259.71939) (xy 43.415502 -259.70753)
			(xy 43.365888 -259.688058) (xy 43.31973 -259.661409) (xy 43.278059 -259.628178) (xy 43.241807 -259.589107)
			(xy 43.211783 -259.54507) (xy 43.188657 -259.497049) (xy 43.172947 -259.446119) (xy 43.165004 -259.393415)
			(xy 36.332424 -259.393415) (xy 36.324481 -259.446119) (xy 36.308771 -259.497049) (xy 36.285645 -259.54507)
			(xy 36.255621 -259.589107) (xy 36.219369 -259.628178) (xy 36.177698 -259.661409) (xy 36.13154 -259.688058)
			(xy 36.081926 -259.70753) (xy 36.029964 -259.71939) (xy 35.976814 -259.723374) (xy 35.923664 -259.71939)
			(xy 35.871702 -259.70753) (xy 35.822088 -259.688058) (xy 35.77593 -259.661409) (xy 35.734259 -259.628178)
			(xy 35.698007 -259.589107) (xy 35.667983 -259.54507) (xy 35.644857 -259.497049) (xy 35.629147 -259.446119)
			(xy 35.621204 -259.393415) (xy 32.232356 -259.393415) (xy 32.224413 -259.446119) (xy 32.208703 -259.497049)
			(xy 32.185577 -259.54507) (xy 32.155553 -259.589107) (xy 32.119301 -259.628178) (xy 32.07763 -259.661409)
			(xy 32.031472 -259.688058) (xy 31.981858 -259.70753) (xy 31.929896 -259.71939) (xy 31.876746 -259.723374)
			(xy 31.823596 -259.71939) (xy 31.771634 -259.70753) (xy 31.72202 -259.688058) (xy 31.675862 -259.661409)
			(xy 31.634191 -259.628178) (xy 31.597939 -259.589107) (xy 31.567915 -259.54507) (xy 31.544789 -259.497049)
			(xy 31.529079 -259.446119) (xy 31.521136 -259.393415) (xy 28.788624 -259.393415) (xy 28.780681 -259.446119)
			(xy 28.764971 -259.497049) (xy 28.741845 -259.54507) (xy 28.711821 -259.589107) (xy 28.675569 -259.628178)
			(xy 28.633898 -259.661409) (xy 28.58774 -259.688058) (xy 28.538126 -259.70753) (xy 28.486164 -259.71939)
			(xy 28.433014 -259.723374) (xy 28.379864 -259.71939) (xy 28.327902 -259.70753) (xy 28.278288 -259.688058)
			(xy 28.23213 -259.661409) (xy 28.190459 -259.628178) (xy 28.154207 -259.589107) (xy 28.124183 -259.54507)
			(xy 28.101057 -259.497049) (xy 28.085347 -259.446119) (xy 28.077404 -259.393415) (xy 21.244824 -259.393415)
			(xy 21.236881 -259.446119) (xy 21.221171 -259.497049) (xy 21.198045 -259.54507) (xy 21.168021 -259.589107)
			(xy 21.131769 -259.628178) (xy 21.090098 -259.661409) (xy 21.04394 -259.688058) (xy 20.994326 -259.70753)
			(xy 20.942364 -259.71939) (xy 20.889214 -259.723374) (xy 20.836064 -259.71939) (xy 20.784102 -259.70753)
			(xy 20.734488 -259.688058) (xy 20.68833 -259.661409) (xy 20.646659 -259.628178) (xy 20.610407 -259.589107)
			(xy 20.580383 -259.54507) (xy 20.557257 -259.497049) (xy 20.541547 -259.446119) (xy 20.533604 -259.393415)
			(xy 17.144756 -259.393415) (xy 17.136813 -259.446119) (xy 17.121103 -259.497049) (xy 17.097977 -259.54507)
			(xy 17.067953 -259.589107) (xy 17.031701 -259.628178) (xy 16.99003 -259.661409) (xy 16.943872 -259.688058)
			(xy 16.894258 -259.70753) (xy 16.842296 -259.71939) (xy 16.789146 -259.723374) (xy 16.735996 -259.71939)
			(xy 16.684034 -259.70753) (xy 16.63442 -259.688058) (xy 16.588262 -259.661409) (xy 16.546591 -259.628178)
			(xy 16.510339 -259.589107) (xy 16.480315 -259.54507) (xy 16.457189 -259.497049) (xy 16.441479 -259.446119)
			(xy 16.433536 -259.393415) (xy 13.701024 -259.393415) (xy 13.693081 -259.446119) (xy 13.677371 -259.497049)
			(xy 13.654245 -259.54507) (xy 13.624221 -259.589107) (xy 13.587969 -259.628178) (xy 13.546298 -259.661409)
			(xy 13.50014 -259.688058) (xy 13.450526 -259.70753) (xy 13.398564 -259.71939) (xy 13.345414 -259.723374)
			(xy 13.292264 -259.71939) (xy 13.240302 -259.70753) (xy 13.190688 -259.688058) (xy 13.14453 -259.661409)
			(xy 13.102859 -259.628178) (xy 13.066607 -259.589107) (xy 13.036583 -259.54507) (xy 13.013457 -259.497049)
			(xy 12.997747 -259.446119) (xy 12.989804 -259.393415) (xy 9.6774 -259.393415) (xy 9.6774 -260.243299)
			(xy 12.989804 -260.243299) (xy 12.989804 -260.190001) (xy 12.997747 -260.137297) (xy 13.013457 -260.086367)
			(xy 13.036583 -260.038346) (xy 13.066607 -259.994309) (xy 13.102859 -259.955238) (xy 13.14453 -259.922007)
			(xy 13.190688 -259.895358) (xy 13.240302 -259.875886) (xy 13.292264 -259.864026) (xy 13.345414 -259.860043)
			(xy 13.398564 -259.864026) (xy 13.450526 -259.875886) (xy 13.50014 -259.895358) (xy 13.546298 -259.922007)
			(xy 13.587969 -259.955238) (xy 13.624221 -259.994309) (xy 13.654245 -260.038346) (xy 13.677371 -260.086367)
			(xy 13.693081 -260.137297) (xy 13.701024 -260.190001) (xy 13.701522 -260.21665) (xy 13.701024 -260.243299)
			(xy 20.533604 -260.243299) (xy 20.533604 -260.190001) (xy 20.541547 -260.137297) (xy 20.557257 -260.086367)
			(xy 20.580383 -260.038346) (xy 20.610407 -259.994309) (xy 20.646659 -259.955238) (xy 20.68833 -259.922007)
			(xy 20.734488 -259.895358) (xy 20.784102 -259.875886) (xy 20.836064 -259.864026) (xy 20.889214 -259.860043)
			(xy 20.942364 -259.864026) (xy 20.994326 -259.875886) (xy 21.04394 -259.895358) (xy 21.090098 -259.922007)
			(xy 21.131769 -259.955238) (xy 21.168021 -259.994309) (xy 21.198045 -260.038346) (xy 21.221171 -260.086367)
			(xy 21.236881 -260.137297) (xy 21.244824 -260.190001) (xy 21.245322 -260.21665) (xy 21.244824 -260.243299)
			(xy 28.077404 -260.243299) (xy 28.077404 -260.190001) (xy 28.085347 -260.137297) (xy 28.101057 -260.086367)
			(xy 28.124183 -260.038346) (xy 28.154207 -259.994309) (xy 28.190459 -259.955238) (xy 28.23213 -259.922007)
			(xy 28.278288 -259.895358) (xy 28.327902 -259.875886) (xy 28.379864 -259.864026) (xy 28.433014 -259.860043)
			(xy 28.486164 -259.864026) (xy 28.538126 -259.875886) (xy 28.58774 -259.895358) (xy 28.633898 -259.922007)
			(xy 28.675569 -259.955238) (xy 28.711821 -259.994309) (xy 28.741845 -260.038346) (xy 28.764971 -260.086367)
			(xy 28.780681 -260.137297) (xy 28.788624 -260.190001) (xy 28.789122 -260.21665) (xy 28.788624 -260.243299)
			(xy 35.621204 -260.243299) (xy 35.621204 -260.190001) (xy 35.629147 -260.137297) (xy 35.644857 -260.086367)
			(xy 35.667983 -260.038346) (xy 35.698007 -259.994309) (xy 35.734259 -259.955238) (xy 35.77593 -259.922007)
			(xy 35.822088 -259.895358) (xy 35.871702 -259.875886) (xy 35.923664 -259.864026) (xy 35.976814 -259.860043)
			(xy 36.029964 -259.864026) (xy 36.081926 -259.875886) (xy 36.13154 -259.895358) (xy 36.177698 -259.922007)
			(xy 36.219369 -259.955238) (xy 36.255621 -259.994309) (xy 36.285645 -260.038346) (xy 36.308771 -260.086367)
			(xy 36.324481 -260.137297) (xy 36.332424 -260.190001) (xy 36.332922 -260.21665) (xy 36.332424 -260.243299)
			(xy 43.165004 -260.243299) (xy 43.165004 -260.190001) (xy 43.172947 -260.137297) (xy 43.188657 -260.086367)
			(xy 43.211783 -260.038346) (xy 43.241807 -259.994309) (xy 43.278059 -259.955238) (xy 43.31973 -259.922007)
			(xy 43.365888 -259.895358) (xy 43.415502 -259.875886) (xy 43.467464 -259.864026) (xy 43.520614 -259.860043)
			(xy 43.573764 -259.864026) (xy 43.625726 -259.875886) (xy 43.67534 -259.895358) (xy 43.721498 -259.922007)
			(xy 43.763169 -259.955238) (xy 43.799421 -259.994309) (xy 43.829445 -260.038346) (xy 43.852571 -260.086367)
			(xy 43.868281 -260.137297) (xy 43.876224 -260.190001) (xy 43.876722 -260.21665) (xy 43.876224 -260.243299)
			(xy 50.734204 -260.243299) (xy 50.734204 -260.190001) (xy 50.742147 -260.137297) (xy 50.757857 -260.086367)
			(xy 50.780983 -260.038346) (xy 50.811007 -259.994309) (xy 50.847259 -259.955238) (xy 50.88893 -259.922007)
			(xy 50.935088 -259.895358) (xy 50.984702 -259.875886) (xy 51.036664 -259.864026) (xy 51.089814 -259.860043)
			(xy 51.142964 -259.864026) (xy 51.194926 -259.875886) (xy 51.24454 -259.895358) (xy 51.290698 -259.922007)
			(xy 51.332369 -259.955238) (xy 51.368621 -259.994309) (xy 51.398645 -260.038346) (xy 51.421771 -260.086367)
			(xy 51.437481 -260.137297) (xy 51.445424 -260.190001) (xy 51.445922 -260.21665) (xy 51.445424 -260.243299)
			(xy 51.437481 -260.296003) (xy 51.421771 -260.346933) (xy 51.398645 -260.394954) (xy 51.368621 -260.438991)
			(xy 51.332369 -260.478062) (xy 51.290698 -260.511293) (xy 51.24454 -260.537942) (xy 51.194926 -260.557414)
			(xy 51.142964 -260.569274) (xy 51.089814 -260.573258) (xy 51.036664 -260.569274) (xy 50.984702 -260.557414)
			(xy 50.935088 -260.537942) (xy 50.88893 -260.511293) (xy 50.847259 -260.478062) (xy 50.811007 -260.438991)
			(xy 50.780983 -260.394954) (xy 50.757857 -260.346933) (xy 50.742147 -260.296003) (xy 50.734204 -260.243299)
			(xy 43.876224 -260.243299) (xy 43.868281 -260.296003) (xy 43.852571 -260.346933) (xy 43.829445 -260.394954)
			(xy 43.799421 -260.438991) (xy 43.763169 -260.478062) (xy 43.721498 -260.511293) (xy 43.67534 -260.537942)
			(xy 43.625726 -260.557414) (xy 43.573764 -260.569274) (xy 43.520614 -260.573258) (xy 43.467464 -260.569274)
			(xy 43.415502 -260.557414) (xy 43.365888 -260.537942) (xy 43.31973 -260.511293) (xy 43.278059 -260.478062)
			(xy 43.241807 -260.438991) (xy 43.211783 -260.394954) (xy 43.188657 -260.346933) (xy 43.172947 -260.296003)
			(xy 43.165004 -260.243299) (xy 36.332424 -260.243299) (xy 36.324481 -260.296003) (xy 36.308771 -260.346933)
			(xy 36.285645 -260.394954) (xy 36.255621 -260.438991) (xy 36.219369 -260.478062) (xy 36.177698 -260.511293)
			(xy 36.13154 -260.537942) (xy 36.081926 -260.557414) (xy 36.029964 -260.569274) (xy 35.976814 -260.573258)
			(xy 35.923664 -260.569274) (xy 35.871702 -260.557414) (xy 35.822088 -260.537942) (xy 35.77593 -260.511293)
			(xy 35.734259 -260.478062) (xy 35.698007 -260.438991) (xy 35.667983 -260.394954) (xy 35.644857 -260.346933)
			(xy 35.629147 -260.296003) (xy 35.621204 -260.243299) (xy 28.788624 -260.243299) (xy 28.780681 -260.296003)
			(xy 28.764971 -260.346933) (xy 28.741845 -260.394954) (xy 28.711821 -260.438991) (xy 28.675569 -260.478062)
			(xy 28.633898 -260.511293) (xy 28.58774 -260.537942) (xy 28.538126 -260.557414) (xy 28.486164 -260.569274)
			(xy 28.433014 -260.573258) (xy 28.379864 -260.569274) (xy 28.327902 -260.557414) (xy 28.278288 -260.537942)
			(xy 28.23213 -260.511293) (xy 28.190459 -260.478062) (xy 28.154207 -260.438991) (xy 28.124183 -260.394954)
			(xy 28.101057 -260.346933) (xy 28.085347 -260.296003) (xy 28.077404 -260.243299) (xy 21.244824 -260.243299)
			(xy 21.236881 -260.296003) (xy 21.221171 -260.346933) (xy 21.198045 -260.394954) (xy 21.168021 -260.438991)
			(xy 21.131769 -260.478062) (xy 21.090098 -260.511293) (xy 21.04394 -260.537942) (xy 20.994326 -260.557414)
			(xy 20.942364 -260.569274) (xy 20.889214 -260.573258) (xy 20.836064 -260.569274) (xy 20.784102 -260.557414)
			(xy 20.734488 -260.537942) (xy 20.68833 -260.511293) (xy 20.646659 -260.478062) (xy 20.610407 -260.438991)
			(xy 20.580383 -260.394954) (xy 20.557257 -260.346933) (xy 20.541547 -260.296003) (xy 20.533604 -260.243299)
			(xy 13.701024 -260.243299) (xy 13.693081 -260.296003) (xy 13.677371 -260.346933) (xy 13.654245 -260.394954)
			(xy 13.624221 -260.438991) (xy 13.587969 -260.478062) (xy 13.546298 -260.511293) (xy 13.50014 -260.537942)
			(xy 13.450526 -260.557414) (xy 13.398564 -260.569274) (xy 13.345414 -260.573258) (xy 13.292264 -260.569274)
			(xy 13.240302 -260.557414) (xy 13.190688 -260.537942) (xy 13.14453 -260.511293) (xy 13.102859 -260.478062)
			(xy 13.066607 -260.438991) (xy 13.036583 -260.394954) (xy 13.013457 -260.346933) (xy 12.997747 -260.296003)
			(xy 12.989804 -260.243299) (xy 9.6774 -260.243299) (xy 9.6774 -261.093437) (xy 16.433536 -261.093437)
			(xy 16.433536 -261.040139) (xy 16.441479 -260.987435) (xy 16.457189 -260.936505) (xy 16.480315 -260.888484)
			(xy 16.510339 -260.844447) (xy 16.546591 -260.805376) (xy 16.588262 -260.772145) (xy 16.63442 -260.745496)
			(xy 16.684034 -260.726024) (xy 16.735996 -260.714164) (xy 16.789146 -260.710181) (xy 16.842296 -260.714164)
			(xy 16.894258 -260.726024) (xy 16.943872 -260.745496) (xy 16.99003 -260.772145) (xy 17.031701 -260.805376)
			(xy 17.067953 -260.844447) (xy 17.097977 -260.888484) (xy 17.121103 -260.936505) (xy 17.136813 -260.987435)
			(xy 17.144756 -261.040139) (xy 17.145254 -261.066788) (xy 17.144756 -261.093437) (xy 31.521136 -261.093437)
			(xy 31.521136 -261.040139) (xy 31.529079 -260.987435) (xy 31.544789 -260.936505) (xy 31.567915 -260.888484)
			(xy 31.597939 -260.844447) (xy 31.634191 -260.805376) (xy 31.675862 -260.772145) (xy 31.72202 -260.745496)
			(xy 31.771634 -260.726024) (xy 31.823596 -260.714164) (xy 31.876746 -260.710181) (xy 31.929896 -260.714164)
			(xy 31.981858 -260.726024) (xy 32.031472 -260.745496) (xy 32.07763 -260.772145) (xy 32.119301 -260.805376)
			(xy 32.155553 -260.844447) (xy 32.185577 -260.888484) (xy 32.208703 -260.936505) (xy 32.224413 -260.987435)
			(xy 32.232356 -261.040139) (xy 32.232854 -261.066788) (xy 32.232356 -261.093437) (xy 46.608736 -261.093437)
			(xy 46.608736 -261.040139) (xy 46.616679 -260.987435) (xy 46.632389 -260.936505) (xy 46.655515 -260.888484)
			(xy 46.685539 -260.844447) (xy 46.721791 -260.805376) (xy 46.763462 -260.772145) (xy 46.80962 -260.745496)
			(xy 46.859234 -260.726024) (xy 46.911196 -260.714164) (xy 46.964346 -260.710181) (xy 47.017496 -260.714164)
			(xy 47.069458 -260.726024) (xy 47.119072 -260.745496) (xy 47.16523 -260.772145) (xy 47.206901 -260.805376)
			(xy 47.243153 -260.844447) (xy 47.273177 -260.888484) (xy 47.296303 -260.936505) (xy 47.312013 -260.987435)
			(xy 47.319956 -261.040139) (xy 47.320454 -261.066788) (xy 47.319956 -261.093437) (xy 47.312013 -261.146141)
			(xy 47.296303 -261.197071) (xy 47.273177 -261.245092) (xy 47.243153 -261.289129) (xy 47.206901 -261.3282)
			(xy 47.16523 -261.361431) (xy 47.119072 -261.38808) (xy 47.069458 -261.407552) (xy 47.017496 -261.419412)
			(xy 46.964346 -261.423396) (xy 46.911196 -261.419412) (xy 46.859234 -261.407552) (xy 46.80962 -261.38808)
			(xy 46.763462 -261.361431) (xy 46.721791 -261.3282) (xy 46.685539 -261.289129) (xy 46.655515 -261.245092)
			(xy 46.632389 -261.197071) (xy 46.616679 -261.146141) (xy 46.608736 -261.093437) (xy 32.232356 -261.093437)
			(xy 32.224413 -261.146141) (xy 32.208703 -261.197071) (xy 32.185577 -261.245092) (xy 32.155553 -261.289129)
			(xy 32.119301 -261.3282) (xy 32.07763 -261.361431) (xy 32.031472 -261.38808) (xy 31.981858 -261.407552)
			(xy 31.929896 -261.419412) (xy 31.876746 -261.423396) (xy 31.823596 -261.419412) (xy 31.771634 -261.407552)
			(xy 31.72202 -261.38808) (xy 31.675862 -261.361431) (xy 31.634191 -261.3282) (xy 31.597939 -261.289129)
			(xy 31.567915 -261.245092) (xy 31.544789 -261.197071) (xy 31.529079 -261.146141) (xy 31.521136 -261.093437)
			(xy 17.144756 -261.093437) (xy 17.136813 -261.146141) (xy 17.121103 -261.197071) (xy 17.097977 -261.245092)
			(xy 17.067953 -261.289129) (xy 17.031701 -261.3282) (xy 16.99003 -261.361431) (xy 16.943872 -261.38808)
			(xy 16.894258 -261.407552) (xy 16.842296 -261.419412) (xy 16.789146 -261.423396) (xy 16.735996 -261.419412)
			(xy 16.684034 -261.407552) (xy 16.63442 -261.38808) (xy 16.588262 -261.361431) (xy 16.546591 -261.3282)
			(xy 16.510339 -261.289129) (xy 16.480315 -261.245092) (xy 16.457189 -261.197071) (xy 16.441479 -261.146141)
			(xy 16.433536 -261.093437) (xy 9.6774 -261.093437) (xy 9.6774 -261.943321) (xy 20.533604 -261.943321)
			(xy 20.533604 -261.890023) (xy 20.541547 -261.837319) (xy 20.557257 -261.786389) (xy 20.580383 -261.738368)
			(xy 20.610407 -261.694331) (xy 20.646659 -261.65526) (xy 20.68833 -261.622029) (xy 20.734488 -261.59538)
			(xy 20.784102 -261.575908) (xy 20.836064 -261.564048) (xy 20.889214 -261.560065) (xy 20.942364 -261.564048)
			(xy 20.994326 -261.575908) (xy 21.04394 -261.59538) (xy 21.090098 -261.622029) (xy 21.131769 -261.65526)
			(xy 21.168021 -261.694331) (xy 21.198045 -261.738368) (xy 21.221171 -261.786389) (xy 21.236881 -261.837319)
			(xy 21.244824 -261.890023) (xy 21.245322 -261.916672) (xy 21.244824 -261.943321) (xy 35.621204 -261.943321)
			(xy 35.621204 -261.890023) (xy 35.629147 -261.837319) (xy 35.644857 -261.786389) (xy 35.667983 -261.738368)
			(xy 35.698007 -261.694331) (xy 35.734259 -261.65526) (xy 35.77593 -261.622029) (xy 35.822088 -261.59538)
			(xy 35.871702 -261.575908) (xy 35.923664 -261.564048) (xy 35.976814 -261.560065) (xy 36.029964 -261.564048)
			(xy 36.081926 -261.575908) (xy 36.13154 -261.59538) (xy 36.177698 -261.622029) (xy 36.219369 -261.65526)
			(xy 36.255621 -261.694331) (xy 36.285645 -261.738368) (xy 36.308771 -261.786389) (xy 36.324481 -261.837319)
			(xy 36.332424 -261.890023) (xy 36.332922 -261.916672) (xy 36.332424 -261.943321) (xy 50.734204 -261.943321)
			(xy 50.734204 -261.890023) (xy 50.742147 -261.837319) (xy 50.757857 -261.786389) (xy 50.780983 -261.738368)
			(xy 50.811007 -261.694331) (xy 50.847259 -261.65526) (xy 50.88893 -261.622029) (xy 50.935088 -261.59538)
			(xy 50.984702 -261.575908) (xy 51.036664 -261.564048) (xy 51.089814 -261.560065) (xy 51.142964 -261.564048)
			(xy 51.194926 -261.575908) (xy 51.24454 -261.59538) (xy 51.290698 -261.622029) (xy 51.332369 -261.65526)
			(xy 51.368621 -261.694331) (xy 51.398645 -261.738368) (xy 51.421771 -261.786389) (xy 51.437481 -261.837319)
			(xy 51.445424 -261.890023) (xy 51.445922 -261.916672) (xy 51.445424 -261.943321) (xy 51.437481 -261.996025)
			(xy 51.421771 -262.046955) (xy 51.398645 -262.094976) (xy 51.368621 -262.139013) (xy 51.332369 -262.178084)
			(xy 51.290698 -262.211315) (xy 51.24454 -262.237964) (xy 51.194926 -262.257436) (xy 51.142964 -262.269296)
			(xy 51.089814 -262.27328) (xy 51.036664 -262.269296) (xy 50.984702 -262.257436) (xy 50.935088 -262.237964)
			(xy 50.88893 -262.211315) (xy 50.847259 -262.178084) (xy 50.811007 -262.139013) (xy 50.780983 -262.094976)
			(xy 50.757857 -262.046955) (xy 50.742147 -261.996025) (xy 50.734204 -261.943321) (xy 36.332424 -261.943321)
			(xy 36.324481 -261.996025) (xy 36.308771 -262.046955) (xy 36.285645 -262.094976) (xy 36.255621 -262.139013)
			(xy 36.219369 -262.178084) (xy 36.177698 -262.211315) (xy 36.13154 -262.237964) (xy 36.081926 -262.257436)
			(xy 36.029964 -262.269296) (xy 35.976814 -262.27328) (xy 35.923664 -262.269296) (xy 35.871702 -262.257436)
			(xy 35.822088 -262.237964) (xy 35.77593 -262.211315) (xy 35.734259 -262.178084) (xy 35.698007 -262.139013)
			(xy 35.667983 -262.094976) (xy 35.644857 -262.046955) (xy 35.629147 -261.996025) (xy 35.621204 -261.943321)
			(xy 21.244824 -261.943321) (xy 21.236881 -261.996025) (xy 21.221171 -262.046955) (xy 21.198045 -262.094976)
			(xy 21.168021 -262.139013) (xy 21.131769 -262.178084) (xy 21.090098 -262.211315) (xy 21.04394 -262.237964)
			(xy 20.994326 -262.257436) (xy 20.942364 -262.269296) (xy 20.889214 -262.27328) (xy 20.836064 -262.269296)
			(xy 20.784102 -262.257436) (xy 20.734488 -262.237964) (xy 20.68833 -262.211315) (xy 20.646659 -262.178084)
			(xy 20.610407 -262.139013) (xy 20.580383 -262.094976) (xy 20.557257 -262.046955) (xy 20.541547 -261.996025)
			(xy 20.533604 -261.943321) (xy 9.6774 -261.943321) (xy 9.6774 -262.793459) (xy 16.433536 -262.793459)
			(xy 16.433536 -262.740161) (xy 16.441479 -262.687457) (xy 16.457189 -262.636527) (xy 16.480315 -262.588506)
			(xy 16.510339 -262.544469) (xy 16.546591 -262.505398) (xy 16.588262 -262.472167) (xy 16.63442 -262.445518)
			(xy 16.684034 -262.426046) (xy 16.735996 -262.414186) (xy 16.789146 -262.410203) (xy 16.842296 -262.414186)
			(xy 16.894258 -262.426046) (xy 16.943872 -262.445518) (xy 16.99003 -262.472167) (xy 17.031701 -262.505398)
			(xy 17.067953 -262.544469) (xy 17.097977 -262.588506) (xy 17.121103 -262.636527) (xy 17.136813 -262.687457)
			(xy 17.144756 -262.740161) (xy 17.145254 -262.76681) (xy 17.144756 -262.793459) (xy 31.521136 -262.793459)
			(xy 31.521136 -262.740161) (xy 31.529079 -262.687457) (xy 31.544789 -262.636527) (xy 31.567915 -262.588506)
			(xy 31.597939 -262.544469) (xy 31.634191 -262.505398) (xy 31.675862 -262.472167) (xy 31.72202 -262.445518)
			(xy 31.771634 -262.426046) (xy 31.823596 -262.414186) (xy 31.876746 -262.410203) (xy 31.929896 -262.414186)
			(xy 31.981858 -262.426046) (xy 32.031472 -262.445518) (xy 32.07763 -262.472167) (xy 32.119301 -262.505398)
			(xy 32.155553 -262.544469) (xy 32.185577 -262.588506) (xy 32.208703 -262.636527) (xy 32.224413 -262.687457)
			(xy 32.232356 -262.740161) (xy 32.232854 -262.76681) (xy 32.232356 -262.793459) (xy 46.608736 -262.793459)
			(xy 46.608736 -262.740161) (xy 46.616679 -262.687457) (xy 46.632389 -262.636527) (xy 46.655515 -262.588506)
			(xy 46.685539 -262.544469) (xy 46.721791 -262.505398) (xy 46.763462 -262.472167) (xy 46.80962 -262.445518)
			(xy 46.859234 -262.426046) (xy 46.911196 -262.414186) (xy 46.964346 -262.410203) (xy 47.017496 -262.414186)
			(xy 47.069458 -262.426046) (xy 47.119072 -262.445518) (xy 47.16523 -262.472167) (xy 47.206901 -262.505398)
			(xy 47.243153 -262.544469) (xy 47.273177 -262.588506) (xy 47.296303 -262.636527) (xy 47.312013 -262.687457)
			(xy 47.319956 -262.740161) (xy 47.320454 -262.76681) (xy 47.319956 -262.793459) (xy 47.312013 -262.846163)
			(xy 47.296303 -262.897093) (xy 47.273177 -262.945114) (xy 47.243153 -262.989151) (xy 47.206901 -263.028222)
			(xy 47.16523 -263.061453) (xy 47.119072 -263.088102) (xy 47.069458 -263.107574) (xy 47.017496 -263.119434)
			(xy 46.964346 -263.123418) (xy 46.911196 -263.119434) (xy 46.859234 -263.107574) (xy 46.80962 -263.088102)
			(xy 46.763462 -263.061453) (xy 46.721791 -263.028222) (xy 46.685539 -262.989151) (xy 46.655515 -262.945114)
			(xy 46.632389 -262.897093) (xy 46.616679 -262.846163) (xy 46.608736 -262.793459) (xy 32.232356 -262.793459)
			(xy 32.224413 -262.846163) (xy 32.208703 -262.897093) (xy 32.185577 -262.945114) (xy 32.155553 -262.989151)
			(xy 32.119301 -263.028222) (xy 32.07763 -263.061453) (xy 32.031472 -263.088102) (xy 31.981858 -263.107574)
			(xy 31.929896 -263.119434) (xy 31.876746 -263.123418) (xy 31.823596 -263.119434) (xy 31.771634 -263.107574)
			(xy 31.72202 -263.088102) (xy 31.675862 -263.061453) (xy 31.634191 -263.028222) (xy 31.597939 -262.989151)
			(xy 31.567915 -262.945114) (xy 31.544789 -262.897093) (xy 31.529079 -262.846163) (xy 31.521136 -262.793459)
			(xy 17.144756 -262.793459) (xy 17.136813 -262.846163) (xy 17.121103 -262.897093) (xy 17.097977 -262.945114)
			(xy 17.067953 -262.989151) (xy 17.031701 -263.028222) (xy 16.99003 -263.061453) (xy 16.943872 -263.088102)
			(xy 16.894258 -263.107574) (xy 16.842296 -263.119434) (xy 16.789146 -263.123418) (xy 16.735996 -263.119434)
			(xy 16.684034 -263.107574) (xy 16.63442 -263.088102) (xy 16.588262 -263.061453) (xy 16.546591 -263.028222)
			(xy 16.510339 -262.989151) (xy 16.480315 -262.945114) (xy 16.457189 -262.897093) (xy 16.441479 -262.846163)
			(xy 16.433536 -262.793459) (xy 9.6774 -262.793459) (xy 9.6774 -263.643343) (xy 20.533604 -263.643343)
			(xy 20.533604 -263.590045) (xy 20.541547 -263.537341) (xy 20.557257 -263.486411) (xy 20.580383 -263.43839)
			(xy 20.610407 -263.394353) (xy 20.646659 -263.355282) (xy 20.68833 -263.322051) (xy 20.734488 -263.295402)
			(xy 20.784102 -263.27593) (xy 20.836064 -263.26407) (xy 20.889214 -263.260087) (xy 20.942364 -263.26407)
			(xy 20.994326 -263.27593) (xy 21.04394 -263.295402) (xy 21.090098 -263.322051) (xy 21.131769 -263.355282)
			(xy 21.168021 -263.394353) (xy 21.198045 -263.43839) (xy 21.221171 -263.486411) (xy 21.236881 -263.537341)
			(xy 21.244824 -263.590045) (xy 21.245322 -263.616694) (xy 21.244824 -263.643343) (xy 35.621204 -263.643343)
			(xy 35.621204 -263.590045) (xy 35.629147 -263.537341) (xy 35.644857 -263.486411) (xy 35.667983 -263.43839)
			(xy 35.698007 -263.394353) (xy 35.734259 -263.355282) (xy 35.77593 -263.322051) (xy 35.822088 -263.295402)
			(xy 35.871702 -263.27593) (xy 35.923664 -263.26407) (xy 35.976814 -263.260087) (xy 36.029964 -263.26407)
			(xy 36.081926 -263.27593) (xy 36.13154 -263.295402) (xy 36.177698 -263.322051) (xy 36.219369 -263.355282)
			(xy 36.255621 -263.394353) (xy 36.285645 -263.43839) (xy 36.308771 -263.486411) (xy 36.324481 -263.537341)
			(xy 36.332424 -263.590045) (xy 36.332922 -263.616694) (xy 36.332424 -263.643343) (xy 50.734204 -263.643343)
			(xy 50.734204 -263.590045) (xy 50.742147 -263.537341) (xy 50.757857 -263.486411) (xy 50.780983 -263.43839)
			(xy 50.811007 -263.394353) (xy 50.847259 -263.355282) (xy 50.88893 -263.322051) (xy 50.935088 -263.295402)
			(xy 50.984702 -263.27593) (xy 51.036664 -263.26407) (xy 51.089814 -263.260087) (xy 51.142964 -263.26407)
			(xy 51.194926 -263.27593) (xy 51.24454 -263.295402) (xy 51.290698 -263.322051) (xy 51.332369 -263.355282)
			(xy 51.368621 -263.394353) (xy 51.398645 -263.43839) (xy 51.421771 -263.486411) (xy 51.437481 -263.537341)
			(xy 51.445424 -263.590045) (xy 51.445922 -263.616694) (xy 51.445424 -263.643343) (xy 51.437481 -263.696047)
			(xy 51.421771 -263.746977) (xy 51.398645 -263.794998) (xy 51.368621 -263.839035) (xy 51.332369 -263.878106)
			(xy 51.290698 -263.911337) (xy 51.24454 -263.937986) (xy 51.194926 -263.957458) (xy 51.142964 -263.969318)
			(xy 51.089814 -263.973302) (xy 51.036664 -263.969318) (xy 50.984702 -263.957458) (xy 50.935088 -263.937986)
			(xy 50.88893 -263.911337) (xy 50.847259 -263.878106) (xy 50.811007 -263.839035) (xy 50.780983 -263.794998)
			(xy 50.757857 -263.746977) (xy 50.742147 -263.696047) (xy 50.734204 -263.643343) (xy 36.332424 -263.643343)
			(xy 36.324481 -263.696047) (xy 36.308771 -263.746977) (xy 36.285645 -263.794998) (xy 36.255621 -263.839035)
			(xy 36.219369 -263.878106) (xy 36.177698 -263.911337) (xy 36.13154 -263.937986) (xy 36.081926 -263.957458)
			(xy 36.029964 -263.969318) (xy 35.976814 -263.973302) (xy 35.923664 -263.969318) (xy 35.871702 -263.957458)
			(xy 35.822088 -263.937986) (xy 35.77593 -263.911337) (xy 35.734259 -263.878106) (xy 35.698007 -263.839035)
			(xy 35.667983 -263.794998) (xy 35.644857 -263.746977) (xy 35.629147 -263.696047) (xy 35.621204 -263.643343)
			(xy 21.244824 -263.643343) (xy 21.236881 -263.696047) (xy 21.221171 -263.746977) (xy 21.198045 -263.794998)
			(xy 21.168021 -263.839035) (xy 21.131769 -263.878106) (xy 21.090098 -263.911337) (xy 21.04394 -263.937986)
			(xy 20.994326 -263.957458) (xy 20.942364 -263.969318) (xy 20.889214 -263.973302) (xy 20.836064 -263.969318)
			(xy 20.784102 -263.957458) (xy 20.734488 -263.937986) (xy 20.68833 -263.911337) (xy 20.646659 -263.878106)
			(xy 20.610407 -263.839035) (xy 20.580383 -263.794998) (xy 20.557257 -263.746977) (xy 20.541547 -263.696047)
			(xy 20.533604 -263.643343) (xy 9.6774 -263.643343) (xy 9.6774 -264.493227) (xy 16.433536 -264.493227)
			(xy 16.433536 -264.439929) (xy 16.441479 -264.387225) (xy 16.457189 -264.336295) (xy 16.480315 -264.288274)
			(xy 16.510339 -264.244237) (xy 16.546591 -264.205166) (xy 16.588262 -264.171935) (xy 16.63442 -264.145286)
			(xy 16.684034 -264.125814) (xy 16.735996 -264.113954) (xy 16.789146 -264.109971) (xy 16.842296 -264.113954)
			(xy 16.894258 -264.125814) (xy 16.943872 -264.145286) (xy 16.99003 -264.171935) (xy 17.031701 -264.205166)
			(xy 17.067953 -264.244237) (xy 17.097977 -264.288274) (xy 17.121103 -264.336295) (xy 17.136813 -264.387225)
			(xy 17.144756 -264.439929) (xy 17.145254 -264.466578) (xy 17.144756 -264.493227) (xy 31.521136 -264.493227)
			(xy 31.521136 -264.439929) (xy 31.529079 -264.387225) (xy 31.544789 -264.336295) (xy 31.567915 -264.288274)
			(xy 31.597939 -264.244237) (xy 31.634191 -264.205166) (xy 31.675862 -264.171935) (xy 31.72202 -264.145286)
			(xy 31.771634 -264.125814) (xy 31.823596 -264.113954) (xy 31.876746 -264.109971) (xy 31.929896 -264.113954)
			(xy 31.981858 -264.125814) (xy 32.031472 -264.145286) (xy 32.07763 -264.171935) (xy 32.119301 -264.205166)
			(xy 32.155553 -264.244237) (xy 32.185577 -264.288274) (xy 32.208703 -264.336295) (xy 32.224413 -264.387225)
			(xy 32.232356 -264.439929) (xy 32.232854 -264.466578) (xy 32.232356 -264.493227) (xy 46.608736 -264.493227)
			(xy 46.608736 -264.439929) (xy 46.616679 -264.387225) (xy 46.632389 -264.336295) (xy 46.655515 -264.288274)
			(xy 46.685539 -264.244237) (xy 46.721791 -264.205166) (xy 46.763462 -264.171935) (xy 46.80962 -264.145286)
			(xy 46.859234 -264.125814) (xy 46.911196 -264.113954) (xy 46.964346 -264.109971) (xy 47.017496 -264.113954)
			(xy 47.069458 -264.125814) (xy 47.119072 -264.145286) (xy 47.16523 -264.171935) (xy 47.206901 -264.205166)
			(xy 47.243153 -264.244237) (xy 47.273177 -264.288274) (xy 47.296303 -264.336295) (xy 47.312013 -264.387225)
			(xy 47.319956 -264.439929) (xy 47.320454 -264.466578) (xy 47.319956 -264.493227) (xy 47.312013 -264.545931)
			(xy 47.296303 -264.596861) (xy 47.273177 -264.644882) (xy 47.243153 -264.688919) (xy 47.206901 -264.72799)
			(xy 47.16523 -264.761221) (xy 47.119072 -264.78787) (xy 47.069458 -264.807342) (xy 47.017496 -264.819202)
			(xy 46.964346 -264.823186) (xy 46.911196 -264.819202) (xy 46.859234 -264.807342) (xy 46.80962 -264.78787)
			(xy 46.763462 -264.761221) (xy 46.721791 -264.72799) (xy 46.685539 -264.688919) (xy 46.655515 -264.644882)
			(xy 46.632389 -264.596861) (xy 46.616679 -264.545931) (xy 46.608736 -264.493227) (xy 32.232356 -264.493227)
			(xy 32.224413 -264.545931) (xy 32.208703 -264.596861) (xy 32.185577 -264.644882) (xy 32.155553 -264.688919)
			(xy 32.119301 -264.72799) (xy 32.07763 -264.761221) (xy 32.031472 -264.78787) (xy 31.981858 -264.807342)
			(xy 31.929896 -264.819202) (xy 31.876746 -264.823186) (xy 31.823596 -264.819202) (xy 31.771634 -264.807342)
			(xy 31.72202 -264.78787) (xy 31.675862 -264.761221) (xy 31.634191 -264.72799) (xy 31.597939 -264.688919)
			(xy 31.567915 -264.644882) (xy 31.544789 -264.596861) (xy 31.529079 -264.545931) (xy 31.521136 -264.493227)
			(xy 17.144756 -264.493227) (xy 17.136813 -264.545931) (xy 17.121103 -264.596861) (xy 17.097977 -264.644882)
			(xy 17.067953 -264.688919) (xy 17.031701 -264.72799) (xy 16.99003 -264.761221) (xy 16.943872 -264.78787)
			(xy 16.894258 -264.807342) (xy 16.842296 -264.819202) (xy 16.789146 -264.823186) (xy 16.735996 -264.819202)
			(xy 16.684034 -264.807342) (xy 16.63442 -264.78787) (xy 16.588262 -264.761221) (xy 16.546591 -264.72799)
			(xy 16.510339 -264.688919) (xy 16.480315 -264.644882) (xy 16.457189 -264.596861) (xy 16.441479 -264.545931)
			(xy 16.433536 -264.493227) (xy 9.6774 -264.493227) (xy 9.6774 -265.343365) (xy 20.533604 -265.343365)
			(xy 20.533604 -265.290067) (xy 20.541547 -265.237363) (xy 20.557257 -265.186433) (xy 20.580383 -265.138412)
			(xy 20.610407 -265.094375) (xy 20.646659 -265.055304) (xy 20.68833 -265.022073) (xy 20.734488 -264.995424)
			(xy 20.784102 -264.975952) (xy 20.836064 -264.964092) (xy 20.889214 -264.960109) (xy 20.942364 -264.964092)
			(xy 20.994326 -264.975952) (xy 21.04394 -264.995424) (xy 21.090098 -265.022073) (xy 21.131769 -265.055304)
			(xy 21.168021 -265.094375) (xy 21.198045 -265.138412) (xy 21.221171 -265.186433) (xy 21.236881 -265.237363)
			(xy 21.244824 -265.290067) (xy 21.245322 -265.316716) (xy 21.244824 -265.343365) (xy 35.621204 -265.343365)
			(xy 35.621204 -265.290067) (xy 35.629147 -265.237363) (xy 35.644857 -265.186433) (xy 35.667983 -265.138412)
			(xy 35.698007 -265.094375) (xy 35.734259 -265.055304) (xy 35.77593 -265.022073) (xy 35.822088 -264.995424)
			(xy 35.871702 -264.975952) (xy 35.923664 -264.964092) (xy 35.976814 -264.960109) (xy 36.029964 -264.964092)
			(xy 36.081926 -264.975952) (xy 36.13154 -264.995424) (xy 36.177698 -265.022073) (xy 36.219369 -265.055304)
			(xy 36.255621 -265.094375) (xy 36.285645 -265.138412) (xy 36.308771 -265.186433) (xy 36.324481 -265.237363)
			(xy 36.332424 -265.290067) (xy 36.332922 -265.316716) (xy 36.332424 -265.343365) (xy 50.734204 -265.343365)
			(xy 50.734204 -265.290067) (xy 50.742147 -265.237363) (xy 50.757857 -265.186433) (xy 50.780983 -265.138412)
			(xy 50.811007 -265.094375) (xy 50.847259 -265.055304) (xy 50.88893 -265.022073) (xy 50.935088 -264.995424)
			(xy 50.984702 -264.975952) (xy 51.036664 -264.964092) (xy 51.089814 -264.960109) (xy 51.142964 -264.964092)
			(xy 51.194926 -264.975952) (xy 51.24454 -264.995424) (xy 51.290698 -265.022073) (xy 51.332369 -265.055304)
			(xy 51.368621 -265.094375) (xy 51.398645 -265.138412) (xy 51.421771 -265.186433) (xy 51.437481 -265.237363)
			(xy 51.445424 -265.290067) (xy 51.445922 -265.316716) (xy 51.445424 -265.343365) (xy 51.437481 -265.396069)
			(xy 51.421771 -265.446999) (xy 51.398645 -265.49502) (xy 51.368621 -265.539057) (xy 51.332369 -265.578128)
			(xy 51.290698 -265.611359) (xy 51.24454 -265.638008) (xy 51.194926 -265.65748) (xy 51.142964 -265.66934)
			(xy 51.089814 -265.673324) (xy 51.036664 -265.66934) (xy 50.984702 -265.65748) (xy 50.935088 -265.638008)
			(xy 50.88893 -265.611359) (xy 50.847259 -265.578128) (xy 50.811007 -265.539057) (xy 50.780983 -265.49502)
			(xy 50.757857 -265.446999) (xy 50.742147 -265.396069) (xy 50.734204 -265.343365) (xy 36.332424 -265.343365)
			(xy 36.324481 -265.396069) (xy 36.308771 -265.446999) (xy 36.285645 -265.49502) (xy 36.255621 -265.539057)
			(xy 36.219369 -265.578128) (xy 36.177698 -265.611359) (xy 36.13154 -265.638008) (xy 36.081926 -265.65748)
			(xy 36.029964 -265.66934) (xy 35.976814 -265.673324) (xy 35.923664 -265.66934) (xy 35.871702 -265.65748)
			(xy 35.822088 -265.638008) (xy 35.77593 -265.611359) (xy 35.734259 -265.578128) (xy 35.698007 -265.539057)
			(xy 35.667983 -265.49502) (xy 35.644857 -265.446999) (xy 35.629147 -265.396069) (xy 35.621204 -265.343365)
			(xy 21.244824 -265.343365) (xy 21.236881 -265.396069) (xy 21.221171 -265.446999) (xy 21.198045 -265.49502)
			(xy 21.168021 -265.539057) (xy 21.131769 -265.578128) (xy 21.090098 -265.611359) (xy 21.04394 -265.638008)
			(xy 20.994326 -265.65748) (xy 20.942364 -265.66934) (xy 20.889214 -265.673324) (xy 20.836064 -265.66934)
			(xy 20.784102 -265.65748) (xy 20.734488 -265.638008) (xy 20.68833 -265.611359) (xy 20.646659 -265.578128)
			(xy 20.610407 -265.539057) (xy 20.580383 -265.49502) (xy 20.557257 -265.446999) (xy 20.541547 -265.396069)
			(xy 20.533604 -265.343365) (xy 9.6774 -265.343365) (xy 9.6774 -266.193249) (xy 16.433536 -266.193249)
			(xy 16.433536 -266.139951) (xy 16.441479 -266.087247) (xy 16.457189 -266.036317) (xy 16.480315 -265.988296)
			(xy 16.510339 -265.944259) (xy 16.546591 -265.905188) (xy 16.588262 -265.871957) (xy 16.63442 -265.845308)
			(xy 16.684034 -265.825836) (xy 16.735996 -265.813976) (xy 16.789146 -265.809993) (xy 16.842296 -265.813976)
			(xy 16.894258 -265.825836) (xy 16.943872 -265.845308) (xy 16.99003 -265.871957) (xy 17.031701 -265.905188)
			(xy 17.067953 -265.944259) (xy 17.097977 -265.988296) (xy 17.121103 -266.036317) (xy 17.136813 -266.087247)
			(xy 17.144756 -266.139951) (xy 17.145254 -266.1666) (xy 17.144756 -266.193249) (xy 31.521136 -266.193249)
			(xy 31.521136 -266.139951) (xy 31.529079 -266.087247) (xy 31.544789 -266.036317) (xy 31.567915 -265.988296)
			(xy 31.597939 -265.944259) (xy 31.634191 -265.905188) (xy 31.675862 -265.871957) (xy 31.72202 -265.845308)
			(xy 31.771634 -265.825836) (xy 31.823596 -265.813976) (xy 31.876746 -265.809993) (xy 31.929896 -265.813976)
			(xy 31.981858 -265.825836) (xy 32.031472 -265.845308) (xy 32.07763 -265.871957) (xy 32.119301 -265.905188)
			(xy 32.155553 -265.944259) (xy 32.185577 -265.988296) (xy 32.208703 -266.036317) (xy 32.224413 -266.087247)
			(xy 32.232356 -266.139951) (xy 32.232854 -266.1666) (xy 32.232356 -266.193249) (xy 46.608736 -266.193249)
			(xy 46.608736 -266.139951) (xy 46.616679 -266.087247) (xy 46.632389 -266.036317) (xy 46.655515 -265.988296)
			(xy 46.685539 -265.944259) (xy 46.721791 -265.905188) (xy 46.763462 -265.871957) (xy 46.80962 -265.845308)
			(xy 46.859234 -265.825836) (xy 46.911196 -265.813976) (xy 46.964346 -265.809993) (xy 47.017496 -265.813976)
			(xy 47.069458 -265.825836) (xy 47.119072 -265.845308) (xy 47.16523 -265.871957) (xy 47.206901 -265.905188)
			(xy 47.243153 -265.944259) (xy 47.273177 -265.988296) (xy 47.296303 -266.036317) (xy 47.312013 -266.087247)
			(xy 47.319956 -266.139951) (xy 47.320454 -266.1666) (xy 47.319956 -266.193249) (xy 47.312013 -266.245953)
			(xy 47.296303 -266.296883) (xy 47.273177 -266.344904) (xy 47.243153 -266.388941) (xy 47.206901 -266.428012)
			(xy 47.16523 -266.461243) (xy 47.119072 -266.487892) (xy 47.069458 -266.507364) (xy 47.017496 -266.519224)
			(xy 46.964346 -266.523208) (xy 46.911196 -266.519224) (xy 46.859234 -266.507364) (xy 46.80962 -266.487892)
			(xy 46.763462 -266.461243) (xy 46.721791 -266.428012) (xy 46.685539 -266.388941) (xy 46.655515 -266.344904)
			(xy 46.632389 -266.296883) (xy 46.616679 -266.245953) (xy 46.608736 -266.193249) (xy 32.232356 -266.193249)
			(xy 32.224413 -266.245953) (xy 32.208703 -266.296883) (xy 32.185577 -266.344904) (xy 32.155553 -266.388941)
			(xy 32.119301 -266.428012) (xy 32.07763 -266.461243) (xy 32.031472 -266.487892) (xy 31.981858 -266.507364)
			(xy 31.929896 -266.519224) (xy 31.876746 -266.523208) (xy 31.823596 -266.519224) (xy 31.771634 -266.507364)
			(xy 31.72202 -266.487892) (xy 31.675862 -266.461243) (xy 31.634191 -266.428012) (xy 31.597939 -266.388941)
			(xy 31.567915 -266.344904) (xy 31.544789 -266.296883) (xy 31.529079 -266.245953) (xy 31.521136 -266.193249)
			(xy 17.144756 -266.193249) (xy 17.136813 -266.245953) (xy 17.121103 -266.296883) (xy 17.097977 -266.344904)
			(xy 17.067953 -266.388941) (xy 17.031701 -266.428012) (xy 16.99003 -266.461243) (xy 16.943872 -266.487892)
			(xy 16.894258 -266.507364) (xy 16.842296 -266.519224) (xy 16.789146 -266.523208) (xy 16.735996 -266.519224)
			(xy 16.684034 -266.507364) (xy 16.63442 -266.487892) (xy 16.588262 -266.461243) (xy 16.546591 -266.428012)
			(xy 16.510339 -266.388941) (xy 16.480315 -266.344904) (xy 16.457189 -266.296883) (xy 16.441479 -266.245953)
			(xy 16.433536 -266.193249) (xy 9.6774 -266.193249) (xy 9.6774 -267.043387) (xy 12.989804 -267.043387)
			(xy 12.989804 -266.990089) (xy 12.997747 -266.937385) (xy 13.013457 -266.886455) (xy 13.036583 -266.838434)
			(xy 13.066607 -266.794397) (xy 13.102859 -266.755326) (xy 13.14453 -266.722095) (xy 13.190688 -266.695446)
			(xy 13.240302 -266.675974) (xy 13.292264 -266.664114) (xy 13.345414 -266.660131) (xy 13.398564 -266.664114)
			(xy 13.450526 -266.675974) (xy 13.50014 -266.695446) (xy 13.546298 -266.722095) (xy 13.587969 -266.755326)
			(xy 13.624221 -266.794397) (xy 13.654245 -266.838434) (xy 13.677371 -266.886455) (xy 13.693081 -266.937385)
			(xy 13.701024 -266.990089) (xy 13.701522 -267.016738) (xy 13.701024 -267.043387) (xy 20.533604 -267.043387)
			(xy 20.533604 -266.990089) (xy 20.541547 -266.937385) (xy 20.557257 -266.886455) (xy 20.580383 -266.838434)
			(xy 20.610407 -266.794397) (xy 20.646659 -266.755326) (xy 20.68833 -266.722095) (xy 20.734488 -266.695446)
			(xy 20.784102 -266.675974) (xy 20.836064 -266.664114) (xy 20.889214 -266.660131) (xy 20.942364 -266.664114)
			(xy 20.994326 -266.675974) (xy 21.04394 -266.695446) (xy 21.090098 -266.722095) (xy 21.131769 -266.755326)
			(xy 21.168021 -266.794397) (xy 21.198045 -266.838434) (xy 21.221171 -266.886455) (xy 21.236881 -266.937385)
			(xy 21.244824 -266.990089) (xy 21.245322 -267.016738) (xy 21.244824 -267.043387) (xy 28.077404 -267.043387)
			(xy 28.077404 -266.990089) (xy 28.085347 -266.937385) (xy 28.101057 -266.886455) (xy 28.124183 -266.838434)
			(xy 28.154207 -266.794397) (xy 28.190459 -266.755326) (xy 28.23213 -266.722095) (xy 28.278288 -266.695446)
			(xy 28.327902 -266.675974) (xy 28.379864 -266.664114) (xy 28.433014 -266.660131) (xy 28.486164 -266.664114)
			(xy 28.538126 -266.675974) (xy 28.58774 -266.695446) (xy 28.633898 -266.722095) (xy 28.675569 -266.755326)
			(xy 28.711821 -266.794397) (xy 28.741845 -266.838434) (xy 28.764971 -266.886455) (xy 28.780681 -266.937385)
			(xy 28.788624 -266.990089) (xy 28.789122 -267.016738) (xy 28.788624 -267.043387) (xy 35.621204 -267.043387)
			(xy 35.621204 -266.990089) (xy 35.629147 -266.937385) (xy 35.644857 -266.886455) (xy 35.667983 -266.838434)
			(xy 35.698007 -266.794397) (xy 35.734259 -266.755326) (xy 35.77593 -266.722095) (xy 35.822088 -266.695446)
			(xy 35.871702 -266.675974) (xy 35.923664 -266.664114) (xy 35.976814 -266.660131) (xy 36.029964 -266.664114)
			(xy 36.081926 -266.675974) (xy 36.13154 -266.695446) (xy 36.177698 -266.722095) (xy 36.219369 -266.755326)
			(xy 36.255621 -266.794397) (xy 36.285645 -266.838434) (xy 36.308771 -266.886455) (xy 36.324481 -266.937385)
			(xy 36.332424 -266.990089) (xy 36.332922 -267.016738) (xy 36.332424 -267.043387) (xy 43.165004 -267.043387)
			(xy 43.165004 -266.990089) (xy 43.172947 -266.937385) (xy 43.188657 -266.886455) (xy 43.211783 -266.838434)
			(xy 43.241807 -266.794397) (xy 43.278059 -266.755326) (xy 43.31973 -266.722095) (xy 43.365888 -266.695446)
			(xy 43.415502 -266.675974) (xy 43.467464 -266.664114) (xy 43.520614 -266.660131) (xy 43.573764 -266.664114)
			(xy 43.625726 -266.675974) (xy 43.67534 -266.695446) (xy 43.721498 -266.722095) (xy 43.763169 -266.755326)
			(xy 43.799421 -266.794397) (xy 43.829445 -266.838434) (xy 43.852571 -266.886455) (xy 43.868281 -266.937385)
			(xy 43.876224 -266.990089) (xy 43.876722 -267.016738) (xy 43.876224 -267.043387) (xy 50.734204 -267.043387)
			(xy 50.734204 -266.990089) (xy 50.742147 -266.937385) (xy 50.757857 -266.886455) (xy 50.780983 -266.838434)
			(xy 50.811007 -266.794397) (xy 50.847259 -266.755326) (xy 50.88893 -266.722095) (xy 50.935088 -266.695446)
			(xy 50.984702 -266.675974) (xy 51.036664 -266.664114) (xy 51.089814 -266.660131) (xy 51.142964 -266.664114)
			(xy 51.194926 -266.675974) (xy 51.24454 -266.695446) (xy 51.290698 -266.722095) (xy 51.332369 -266.755326)
			(xy 51.368621 -266.794397) (xy 51.398645 -266.838434) (xy 51.421771 -266.886455) (xy 51.437481 -266.937385)
			(xy 51.445424 -266.990089) (xy 51.445922 -267.016738) (xy 51.445424 -267.043387) (xy 51.437481 -267.096091)
			(xy 51.421771 -267.147021) (xy 51.398645 -267.195042) (xy 51.368621 -267.239079) (xy 51.332369 -267.27815)
			(xy 51.290698 -267.311381) (xy 51.24454 -267.33803) (xy 51.194926 -267.357502) (xy 51.142964 -267.369362)
			(xy 51.089814 -267.373346) (xy 51.036664 -267.369362) (xy 50.984702 -267.357502) (xy 50.935088 -267.33803)
			(xy 50.88893 -267.311381) (xy 50.847259 -267.27815) (xy 50.811007 -267.239079) (xy 50.780983 -267.195042)
			(xy 50.757857 -267.147021) (xy 50.742147 -267.096091) (xy 50.734204 -267.043387) (xy 43.876224 -267.043387)
			(xy 43.868281 -267.096091) (xy 43.852571 -267.147021) (xy 43.829445 -267.195042) (xy 43.799421 -267.239079)
			(xy 43.763169 -267.27815) (xy 43.721498 -267.311381) (xy 43.67534 -267.33803) (xy 43.625726 -267.357502)
			(xy 43.573764 -267.369362) (xy 43.520614 -267.373346) (xy 43.467464 -267.369362) (xy 43.415502 -267.357502)
			(xy 43.365888 -267.33803) (xy 43.31973 -267.311381) (xy 43.278059 -267.27815) (xy 43.241807 -267.239079)
			(xy 43.211783 -267.195042) (xy 43.188657 -267.147021) (xy 43.172947 -267.096091) (xy 43.165004 -267.043387)
			(xy 36.332424 -267.043387) (xy 36.324481 -267.096091) (xy 36.308771 -267.147021) (xy 36.285645 -267.195042)
			(xy 36.255621 -267.239079) (xy 36.219369 -267.27815) (xy 36.177698 -267.311381) (xy 36.13154 -267.33803)
			(xy 36.081926 -267.357502) (xy 36.029964 -267.369362) (xy 35.976814 -267.373346) (xy 35.923664 -267.369362)
			(xy 35.871702 -267.357502) (xy 35.822088 -267.33803) (xy 35.77593 -267.311381) (xy 35.734259 -267.27815)
			(xy 35.698007 -267.239079) (xy 35.667983 -267.195042) (xy 35.644857 -267.147021) (xy 35.629147 -267.096091)
			(xy 35.621204 -267.043387) (xy 28.788624 -267.043387) (xy 28.780681 -267.096091) (xy 28.764971 -267.147021)
			(xy 28.741845 -267.195042) (xy 28.711821 -267.239079) (xy 28.675569 -267.27815) (xy 28.633898 -267.311381)
			(xy 28.58774 -267.33803) (xy 28.538126 -267.357502) (xy 28.486164 -267.369362) (xy 28.433014 -267.373346)
			(xy 28.379864 -267.369362) (xy 28.327902 -267.357502) (xy 28.278288 -267.33803) (xy 28.23213 -267.311381)
			(xy 28.190459 -267.27815) (xy 28.154207 -267.239079) (xy 28.124183 -267.195042) (xy 28.101057 -267.147021)
			(xy 28.085347 -267.096091) (xy 28.077404 -267.043387) (xy 21.244824 -267.043387) (xy 21.236881 -267.096091)
			(xy 21.221171 -267.147021) (xy 21.198045 -267.195042) (xy 21.168021 -267.239079) (xy 21.131769 -267.27815)
			(xy 21.090098 -267.311381) (xy 21.04394 -267.33803) (xy 20.994326 -267.357502) (xy 20.942364 -267.369362)
			(xy 20.889214 -267.373346) (xy 20.836064 -267.369362) (xy 20.784102 -267.357502) (xy 20.734488 -267.33803)
			(xy 20.68833 -267.311381) (xy 20.646659 -267.27815) (xy 20.610407 -267.239079) (xy 20.580383 -267.195042)
			(xy 20.557257 -267.147021) (xy 20.541547 -267.096091) (xy 20.533604 -267.043387) (xy 13.701024 -267.043387)
			(xy 13.693081 -267.096091) (xy 13.677371 -267.147021) (xy 13.654245 -267.195042) (xy 13.624221 -267.239079)
			(xy 13.587969 -267.27815) (xy 13.546298 -267.311381) (xy 13.50014 -267.33803) (xy 13.450526 -267.357502)
			(xy 13.398564 -267.369362) (xy 13.345414 -267.373346) (xy 13.292264 -267.369362) (xy 13.240302 -267.357502)
			(xy 13.190688 -267.33803) (xy 13.14453 -267.311381) (xy 13.102859 -267.27815) (xy 13.066607 -267.239079)
			(xy 13.036583 -267.195042) (xy 13.013457 -267.147021) (xy 12.997747 -267.096091) (xy 12.989804 -267.043387)
			(xy 9.6774 -267.043387) (xy 9.6774 -267.893271) (xy 16.433536 -267.893271) (xy 16.433536 -267.839973)
			(xy 16.441479 -267.787269) (xy 16.457189 -267.736339) (xy 16.480315 -267.688318) (xy 16.510339 -267.644281)
			(xy 16.546591 -267.60521) (xy 16.588262 -267.571979) (xy 16.63442 -267.54533) (xy 16.684034 -267.525858)
			(xy 16.735996 -267.513998) (xy 16.789146 -267.510015) (xy 16.842296 -267.513998) (xy 16.894258 -267.525858)
			(xy 16.943872 -267.54533) (xy 16.99003 -267.571979) (xy 17.031701 -267.60521) (xy 17.067953 -267.644281)
			(xy 17.097977 -267.688318) (xy 17.121103 -267.736339) (xy 17.136813 -267.787269) (xy 17.144756 -267.839973)
			(xy 17.145254 -267.866622) (xy 17.144756 -267.893271) (xy 23.977336 -267.893271) (xy 23.977336 -267.839973)
			(xy 23.985279 -267.787269) (xy 24.000989 -267.736339) (xy 24.024115 -267.688318) (xy 24.054139 -267.644281)
			(xy 24.090391 -267.60521) (xy 24.132062 -267.571979) (xy 24.17822 -267.54533) (xy 24.227834 -267.525858)
			(xy 24.279796 -267.513998) (xy 24.332946 -267.510015) (xy 24.386096 -267.513998) (xy 24.438058 -267.525858)
			(xy 24.487672 -267.54533) (xy 24.53383 -267.571979) (xy 24.575501 -267.60521) (xy 24.611753 -267.644281)
			(xy 24.641777 -267.688318) (xy 24.664903 -267.736339) (xy 24.680613 -267.787269) (xy 24.688556 -267.839973)
			(xy 24.689054 -267.866622) (xy 24.688556 -267.893271) (xy 31.521136 -267.893271) (xy 31.521136 -267.839973)
			(xy 31.529079 -267.787269) (xy 31.544789 -267.736339) (xy 31.567915 -267.688318) (xy 31.597939 -267.644281)
			(xy 31.634191 -267.60521) (xy 31.675862 -267.571979) (xy 31.72202 -267.54533) (xy 31.771634 -267.525858)
			(xy 31.823596 -267.513998) (xy 31.876746 -267.510015) (xy 31.929896 -267.513998) (xy 31.981858 -267.525858)
			(xy 32.031472 -267.54533) (xy 32.07763 -267.571979) (xy 32.119301 -267.60521) (xy 32.155553 -267.644281)
			(xy 32.185577 -267.688318) (xy 32.208703 -267.736339) (xy 32.224413 -267.787269) (xy 32.232356 -267.839973)
			(xy 32.232854 -267.866622) (xy 32.232356 -267.893271) (xy 39.064936 -267.893271) (xy 39.064936 -267.839973)
			(xy 39.072879 -267.787269) (xy 39.088589 -267.736339) (xy 39.111715 -267.688318) (xy 39.141739 -267.644281)
			(xy 39.177991 -267.60521) (xy 39.219662 -267.571979) (xy 39.26582 -267.54533) (xy 39.315434 -267.525858)
			(xy 39.367396 -267.513998) (xy 39.420546 -267.510015) (xy 39.473696 -267.513998) (xy 39.525658 -267.525858)
			(xy 39.575272 -267.54533) (xy 39.62143 -267.571979) (xy 39.663101 -267.60521) (xy 39.699353 -267.644281)
			(xy 39.729377 -267.688318) (xy 39.752503 -267.736339) (xy 39.768213 -267.787269) (xy 39.776156 -267.839973)
			(xy 39.776654 -267.866622) (xy 39.776156 -267.893271) (xy 46.608736 -267.893271) (xy 46.608736 -267.839973)
			(xy 46.616679 -267.787269) (xy 46.632389 -267.736339) (xy 46.655515 -267.688318) (xy 46.685539 -267.644281)
			(xy 46.721791 -267.60521) (xy 46.763462 -267.571979) (xy 46.80962 -267.54533) (xy 46.859234 -267.525858)
			(xy 46.911196 -267.513998) (xy 46.964346 -267.510015) (xy 47.017496 -267.513998) (xy 47.069458 -267.525858)
			(xy 47.119072 -267.54533) (xy 47.16523 -267.571979) (xy 47.206901 -267.60521) (xy 47.243153 -267.644281)
			(xy 47.273177 -267.688318) (xy 47.296303 -267.736339) (xy 47.312013 -267.787269) (xy 47.319956 -267.839973)
			(xy 47.320454 -267.866622) (xy 47.319956 -267.893271) (xy 47.312013 -267.945975) (xy 47.296303 -267.996905)
			(xy 47.273177 -268.044926) (xy 47.243153 -268.088963) (xy 47.206901 -268.128034) (xy 47.16523 -268.161265)
			(xy 47.119072 -268.187914) (xy 47.069458 -268.207386) (xy 47.017496 -268.219246) (xy 46.964346 -268.22323)
			(xy 46.911196 -268.219246) (xy 46.859234 -268.207386) (xy 46.80962 -268.187914) (xy 46.763462 -268.161265)
			(xy 46.721791 -268.128034) (xy 46.685539 -268.088963) (xy 46.655515 -268.044926) (xy 46.632389 -267.996905)
			(xy 46.616679 -267.945975) (xy 46.608736 -267.893271) (xy 39.776156 -267.893271) (xy 39.768213 -267.945975)
			(xy 39.752503 -267.996905) (xy 39.729377 -268.044926) (xy 39.699353 -268.088963) (xy 39.663101 -268.128034)
			(xy 39.62143 -268.161265) (xy 39.575272 -268.187914) (xy 39.525658 -268.207386) (xy 39.473696 -268.219246)
			(xy 39.420546 -268.22323) (xy 39.367396 -268.219246) (xy 39.315434 -268.207386) (xy 39.26582 -268.187914)
			(xy 39.219662 -268.161265) (xy 39.177991 -268.128034) (xy 39.141739 -268.088963) (xy 39.111715 -268.044926)
			(xy 39.088589 -267.996905) (xy 39.072879 -267.945975) (xy 39.064936 -267.893271) (xy 32.232356 -267.893271)
			(xy 32.224413 -267.945975) (xy 32.208703 -267.996905) (xy 32.185577 -268.044926) (xy 32.155553 -268.088963)
			(xy 32.119301 -268.128034) (xy 32.07763 -268.161265) (xy 32.031472 -268.187914) (xy 31.981858 -268.207386)
			(xy 31.929896 -268.219246) (xy 31.876746 -268.22323) (xy 31.823596 -268.219246) (xy 31.771634 -268.207386)
			(xy 31.72202 -268.187914) (xy 31.675862 -268.161265) (xy 31.634191 -268.128034) (xy 31.597939 -268.088963)
			(xy 31.567915 -268.044926) (xy 31.544789 -267.996905) (xy 31.529079 -267.945975) (xy 31.521136 -267.893271)
			(xy 24.688556 -267.893271) (xy 24.680613 -267.945975) (xy 24.664903 -267.996905) (xy 24.641777 -268.044926)
			(xy 24.611753 -268.088963) (xy 24.575501 -268.128034) (xy 24.53383 -268.161265) (xy 24.487672 -268.187914)
			(xy 24.438058 -268.207386) (xy 24.386096 -268.219246) (xy 24.332946 -268.22323) (xy 24.279796 -268.219246)
			(xy 24.227834 -268.207386) (xy 24.17822 -268.187914) (xy 24.132062 -268.161265) (xy 24.090391 -268.128034)
			(xy 24.054139 -268.088963) (xy 24.024115 -268.044926) (xy 24.000989 -267.996905) (xy 23.985279 -267.945975)
			(xy 23.977336 -267.893271) (xy 17.144756 -267.893271) (xy 17.136813 -267.945975) (xy 17.121103 -267.996905)
			(xy 17.097977 -268.044926) (xy 17.067953 -268.088963) (xy 17.031701 -268.128034) (xy 16.99003 -268.161265)
			(xy 16.943872 -268.187914) (xy 16.894258 -268.207386) (xy 16.842296 -268.219246) (xy 16.789146 -268.22323)
			(xy 16.735996 -268.219246) (xy 16.684034 -268.207386) (xy 16.63442 -268.187914) (xy 16.588262 -268.161265)
			(xy 16.546591 -268.128034) (xy 16.510339 -268.088963) (xy 16.480315 -268.044926) (xy 16.457189 -267.996905)
			(xy 16.441479 -267.945975) (xy 16.433536 -267.893271) (xy 9.6774 -267.893271) (xy 9.6774 -268.743409)
			(xy 35.621204 -268.743409) (xy 35.621204 -268.690111) (xy 35.629147 -268.637407) (xy 35.644857 -268.586477)
			(xy 35.667983 -268.538456) (xy 35.698007 -268.494419) (xy 35.734259 -268.455348) (xy 35.77593 -268.422117)
			(xy 35.822088 -268.395468) (xy 35.871702 -268.375996) (xy 35.923664 -268.364136) (xy 35.976814 -268.360153)
			(xy 36.029964 -268.364136) (xy 36.081926 -268.375996) (xy 36.13154 -268.395468) (xy 36.177698 -268.422117)
			(xy 36.219369 -268.455348) (xy 36.255621 -268.494419) (xy 36.285645 -268.538456) (xy 36.308771 -268.586477)
			(xy 36.324481 -268.637407) (xy 36.332424 -268.690111) (xy 36.332922 -268.71676) (xy 36.332424 -268.743409)
			(xy 36.324481 -268.796113) (xy 36.308771 -268.847043) (xy 36.285645 -268.895064) (xy 36.255621 -268.939101)
			(xy 36.219369 -268.978172) (xy 36.177698 -269.011403) (xy 36.13154 -269.038052) (xy 36.081926 -269.057524)
			(xy 36.029964 -269.069384) (xy 35.976814 -269.073368) (xy 35.923664 -269.069384) (xy 35.871702 -269.057524)
			(xy 35.822088 -269.038052) (xy 35.77593 -269.011403) (xy 35.734259 -268.978172) (xy 35.698007 -268.939101)
			(xy 35.667983 -268.895064) (xy 35.644857 -268.847043) (xy 35.629147 -268.796113) (xy 35.621204 -268.743409)
			(xy 9.6774 -268.743409) (xy 9.6774 -269.593293) (xy 16.433536 -269.593293) (xy 16.433536 -269.539995)
			(xy 16.441479 -269.487291) (xy 16.457189 -269.436361) (xy 16.480315 -269.38834) (xy 16.510339 -269.344303)
			(xy 16.546591 -269.305232) (xy 16.588262 -269.272001) (xy 16.63442 -269.245352) (xy 16.684034 -269.22588)
			(xy 16.735996 -269.21402) (xy 16.789146 -269.210037) (xy 16.842296 -269.21402) (xy 16.894258 -269.22588)
			(xy 16.943872 -269.245352) (xy 16.99003 -269.272001) (xy 17.031701 -269.305232) (xy 17.067953 -269.344303)
			(xy 17.097977 -269.38834) (xy 17.121103 -269.436361) (xy 17.136813 -269.487291) (xy 17.144756 -269.539995)
			(xy 17.145254 -269.566644) (xy 17.144756 -269.593293) (xy 31.521136 -269.593293) (xy 31.521136 -269.539995)
			(xy 31.529079 -269.487291) (xy 31.544789 -269.436361) (xy 31.567915 -269.38834) (xy 31.597939 -269.344303)
			(xy 31.634191 -269.305232) (xy 31.675862 -269.272001) (xy 31.72202 -269.245352) (xy 31.771634 -269.22588)
			(xy 31.823596 -269.21402) (xy 31.876746 -269.210037) (xy 31.929896 -269.21402) (xy 31.981858 -269.22588)
			(xy 32.031472 -269.245352) (xy 32.07763 -269.272001) (xy 32.119301 -269.305232) (xy 32.155553 -269.344303)
			(xy 32.185577 -269.38834) (xy 32.208703 -269.436361) (xy 32.224413 -269.487291) (xy 32.232356 -269.539995)
			(xy 32.232854 -269.566644) (xy 32.232356 -269.593293) (xy 46.608736 -269.593293) (xy 46.608736 -269.539995)
			(xy 46.616679 -269.487291) (xy 46.632389 -269.436361) (xy 46.655515 -269.38834) (xy 46.685539 -269.344303)
			(xy 46.721791 -269.305232) (xy 46.763462 -269.272001) (xy 46.80962 -269.245352) (xy 46.859234 -269.22588)
			(xy 46.911196 -269.21402) (xy 46.964346 -269.210037) (xy 47.017496 -269.21402) (xy 47.069458 -269.22588)
			(xy 47.119072 -269.245352) (xy 47.16523 -269.272001) (xy 47.206901 -269.305232) (xy 47.243153 -269.344303)
			(xy 47.273177 -269.38834) (xy 47.296303 -269.436361) (xy 47.312013 -269.487291) (xy 47.319956 -269.539995)
			(xy 47.320454 -269.566644) (xy 47.319956 -269.593293) (xy 61.696336 -269.593293) (xy 61.696336 -269.539995)
			(xy 61.704279 -269.487291) (xy 61.719989 -269.436361) (xy 61.743115 -269.38834) (xy 61.773139 -269.344303)
			(xy 61.809391 -269.305232) (xy 61.851062 -269.272001) (xy 61.89722 -269.245352) (xy 61.946834 -269.22588)
			(xy 61.998796 -269.21402) (xy 62.051946 -269.210037) (xy 62.105096 -269.21402) (xy 62.157058 -269.22588)
			(xy 62.206672 -269.245352) (xy 62.25283 -269.272001) (xy 62.294501 -269.305232) (xy 62.330753 -269.344303)
			(xy 62.360777 -269.38834) (xy 62.383903 -269.436361) (xy 62.399613 -269.487291) (xy 62.407556 -269.539995)
			(xy 62.408054 -269.566644) (xy 62.407556 -269.593293) (xy 62.399613 -269.645997) (xy 62.383903 -269.696927)
			(xy 62.360777 -269.744948) (xy 62.330753 -269.788985) (xy 62.294501 -269.828056) (xy 62.25283 -269.861287)
			(xy 62.206672 -269.887936) (xy 62.157058 -269.907408) (xy 62.105096 -269.919268) (xy 62.051946 -269.923252)
			(xy 61.998796 -269.919268) (xy 61.946834 -269.907408) (xy 61.89722 -269.887936) (xy 61.851062 -269.861287)
			(xy 61.809391 -269.828056) (xy 61.773139 -269.788985) (xy 61.743115 -269.744948) (xy 61.719989 -269.696927)
			(xy 61.704279 -269.645997) (xy 61.696336 -269.593293) (xy 47.319956 -269.593293) (xy 47.312013 -269.645997)
			(xy 47.296303 -269.696927) (xy 47.273177 -269.744948) (xy 47.243153 -269.788985) (xy 47.206901 -269.828056)
			(xy 47.16523 -269.861287) (xy 47.119072 -269.887936) (xy 47.069458 -269.907408) (xy 47.017496 -269.919268)
			(xy 46.964346 -269.923252) (xy 46.911196 -269.919268) (xy 46.859234 -269.907408) (xy 46.80962 -269.887936)
			(xy 46.763462 -269.861287) (xy 46.721791 -269.828056) (xy 46.685539 -269.788985) (xy 46.655515 -269.744948)
			(xy 46.632389 -269.696927) (xy 46.616679 -269.645997) (xy 46.608736 -269.593293) (xy 32.232356 -269.593293)
			(xy 32.224413 -269.645997) (xy 32.208703 -269.696927) (xy 32.185577 -269.744948) (xy 32.155553 -269.788985)
			(xy 32.119301 -269.828056) (xy 32.07763 -269.861287) (xy 32.031472 -269.887936) (xy 31.981858 -269.907408)
			(xy 31.929896 -269.919268) (xy 31.876746 -269.923252) (xy 31.823596 -269.919268) (xy 31.771634 -269.907408)
			(xy 31.72202 -269.887936) (xy 31.675862 -269.861287) (xy 31.634191 -269.828056) (xy 31.597939 -269.788985)
			(xy 31.567915 -269.744948) (xy 31.544789 -269.696927) (xy 31.529079 -269.645997) (xy 31.521136 -269.593293)
			(xy 17.144756 -269.593293) (xy 17.136813 -269.645997) (xy 17.121103 -269.696927) (xy 17.097977 -269.744948)
			(xy 17.067953 -269.788985) (xy 17.031701 -269.828056) (xy 16.99003 -269.861287) (xy 16.943872 -269.887936)
			(xy 16.894258 -269.907408) (xy 16.842296 -269.919268) (xy 16.789146 -269.923252) (xy 16.735996 -269.919268)
			(xy 16.684034 -269.907408) (xy 16.63442 -269.887936) (xy 16.588262 -269.861287) (xy 16.546591 -269.828056)
			(xy 16.510339 -269.788985) (xy 16.480315 -269.744948) (xy 16.457189 -269.696927) (xy 16.441479 -269.645997)
			(xy 16.433536 -269.593293) (xy 9.6774 -269.593293) (xy 9.6774 -270.443431) (xy 20.533604 -270.443431)
			(xy 20.533604 -270.390133) (xy 20.541547 -270.337429) (xy 20.557257 -270.286499) (xy 20.580383 -270.238478)
			(xy 20.610407 -270.194441) (xy 20.646659 -270.15537) (xy 20.68833 -270.122139) (xy 20.734488 -270.09549)
			(xy 20.784102 -270.076018) (xy 20.836064 -270.064158) (xy 20.889214 -270.060175) (xy 20.942364 -270.064158)
			(xy 20.994326 -270.076018) (xy 21.04394 -270.09549) (xy 21.090098 -270.122139) (xy 21.131769 -270.15537)
			(xy 21.168021 -270.194441) (xy 21.198045 -270.238478) (xy 21.221171 -270.286499) (xy 21.236881 -270.337429)
			(xy 21.244824 -270.390133) (xy 21.245322 -270.416782) (xy 21.244824 -270.443431) (xy 35.621204 -270.443431)
			(xy 35.621204 -270.390133) (xy 35.629147 -270.337429) (xy 35.644857 -270.286499) (xy 35.667983 -270.238478)
			(xy 35.698007 -270.194441) (xy 35.734259 -270.15537) (xy 35.77593 -270.122139) (xy 35.822088 -270.09549)
			(xy 35.871702 -270.076018) (xy 35.923664 -270.064158) (xy 35.976814 -270.060175) (xy 36.029964 -270.064158)
			(xy 36.081926 -270.076018) (xy 36.13154 -270.09549) (xy 36.177698 -270.122139) (xy 36.219369 -270.15537)
			(xy 36.255621 -270.194441) (xy 36.285645 -270.238478) (xy 36.308771 -270.286499) (xy 36.324481 -270.337429)
			(xy 36.332424 -270.390133) (xy 36.332922 -270.416782) (xy 36.332424 -270.443431) (xy 50.734204 -270.443431)
			(xy 50.734204 -270.390133) (xy 50.742147 -270.337429) (xy 50.757857 -270.286499) (xy 50.780983 -270.238478)
			(xy 50.811007 -270.194441) (xy 50.847259 -270.15537) (xy 50.88893 -270.122139) (xy 50.935088 -270.09549)
			(xy 50.984702 -270.076018) (xy 51.036664 -270.064158) (xy 51.089814 -270.060175) (xy 51.142964 -270.064158)
			(xy 51.194926 -270.076018) (xy 51.24454 -270.09549) (xy 51.290698 -270.122139) (xy 51.332369 -270.15537)
			(xy 51.368621 -270.194441) (xy 51.398645 -270.238478) (xy 51.421771 -270.286499) (xy 51.437481 -270.337429)
			(xy 51.445424 -270.390133) (xy 51.445922 -270.416782) (xy 51.445424 -270.443431) (xy 51.437481 -270.496135)
			(xy 51.421771 -270.547065) (xy 51.398645 -270.595086) (xy 51.368621 -270.639123) (xy 51.332369 -270.678194)
			(xy 51.290698 -270.711425) (xy 51.24454 -270.738074) (xy 51.194926 -270.757546) (xy 51.142964 -270.769406)
			(xy 51.089814 -270.77339) (xy 51.036664 -270.769406) (xy 50.984702 -270.757546) (xy 50.935088 -270.738074)
			(xy 50.88893 -270.711425) (xy 50.847259 -270.678194) (xy 50.811007 -270.639123) (xy 50.780983 -270.595086)
			(xy 50.757857 -270.547065) (xy 50.742147 -270.496135) (xy 50.734204 -270.443431) (xy 36.332424 -270.443431)
			(xy 36.324481 -270.496135) (xy 36.308771 -270.547065) (xy 36.285645 -270.595086) (xy 36.255621 -270.639123)
			(xy 36.219369 -270.678194) (xy 36.177698 -270.711425) (xy 36.13154 -270.738074) (xy 36.081926 -270.757546)
			(xy 36.029964 -270.769406) (xy 35.976814 -270.77339) (xy 35.923664 -270.769406) (xy 35.871702 -270.757546)
			(xy 35.822088 -270.738074) (xy 35.77593 -270.711425) (xy 35.734259 -270.678194) (xy 35.698007 -270.639123)
			(xy 35.667983 -270.595086) (xy 35.644857 -270.547065) (xy 35.629147 -270.496135) (xy 35.621204 -270.443431)
			(xy 21.244824 -270.443431) (xy 21.236881 -270.496135) (xy 21.221171 -270.547065) (xy 21.198045 -270.595086)
			(xy 21.168021 -270.639123) (xy 21.131769 -270.678194) (xy 21.090098 -270.711425) (xy 21.04394 -270.738074)
			(xy 20.994326 -270.757546) (xy 20.942364 -270.769406) (xy 20.889214 -270.77339) (xy 20.836064 -270.769406)
			(xy 20.784102 -270.757546) (xy 20.734488 -270.738074) (xy 20.68833 -270.711425) (xy 20.646659 -270.678194)
			(xy 20.610407 -270.639123) (xy 20.580383 -270.595086) (xy 20.557257 -270.547065) (xy 20.541547 -270.496135)
			(xy 20.533604 -270.443431) (xy 9.6774 -270.443431) (xy 9.6774 -271.293315) (xy 16.433536 -271.293315)
			(xy 16.433536 -271.240017) (xy 16.441479 -271.187313) (xy 16.457189 -271.136383) (xy 16.480315 -271.088362)
			(xy 16.510339 -271.044325) (xy 16.546591 -271.005254) (xy 16.588262 -270.972023) (xy 16.63442 -270.945374)
			(xy 16.684034 -270.925902) (xy 16.735996 -270.914042) (xy 16.789146 -270.910059) (xy 16.842296 -270.914042)
			(xy 16.894258 -270.925902) (xy 16.943872 -270.945374) (xy 16.99003 -270.972023) (xy 17.031701 -271.005254)
			(xy 17.067953 -271.044325) (xy 17.097977 -271.088362) (xy 17.121103 -271.136383) (xy 17.136813 -271.187313)
			(xy 17.144756 -271.240017) (xy 17.145254 -271.266666) (xy 17.144756 -271.293315) (xy 31.521136 -271.293315)
			(xy 31.521136 -271.240017) (xy 31.529079 -271.187313) (xy 31.544789 -271.136383) (xy 31.567915 -271.088362)
			(xy 31.597939 -271.044325) (xy 31.634191 -271.005254) (xy 31.675862 -270.972023) (xy 31.72202 -270.945374)
			(xy 31.771634 -270.925902) (xy 31.823596 -270.914042) (xy 31.876746 -270.910059) (xy 31.929896 -270.914042)
			(xy 31.981858 -270.925902) (xy 32.031472 -270.945374) (xy 32.07763 -270.972023) (xy 32.119301 -271.005254)
			(xy 32.155553 -271.044325) (xy 32.185577 -271.088362) (xy 32.208703 -271.136383) (xy 32.224413 -271.187313)
			(xy 32.232356 -271.240017) (xy 32.232854 -271.266666) (xy 32.232356 -271.293315) (xy 46.608736 -271.293315)
			(xy 46.608736 -271.240017) (xy 46.616679 -271.187313) (xy 46.632389 -271.136383) (xy 46.655515 -271.088362)
			(xy 46.685539 -271.044325) (xy 46.721791 -271.005254) (xy 46.763462 -270.972023) (xy 46.80962 -270.945374)
			(xy 46.859234 -270.925902) (xy 46.911196 -270.914042) (xy 46.964346 -270.910059) (xy 47.017496 -270.914042)
			(xy 47.069458 -270.925902) (xy 47.119072 -270.945374) (xy 47.16523 -270.972023) (xy 47.206901 -271.005254)
			(xy 47.243153 -271.044325) (xy 47.273177 -271.088362) (xy 47.296303 -271.136383) (xy 47.312013 -271.187313)
			(xy 47.319956 -271.240017) (xy 47.320454 -271.266666) (xy 47.319956 -271.293315) (xy 47.312013 -271.346019)
			(xy 47.296303 -271.396949) (xy 47.273177 -271.44497) (xy 47.243153 -271.489007) (xy 47.206901 -271.528078)
			(xy 47.16523 -271.561309) (xy 47.119072 -271.587958) (xy 47.069458 -271.60743) (xy 47.017496 -271.61929)
			(xy 46.964346 -271.623274) (xy 46.911196 -271.61929) (xy 46.859234 -271.60743) (xy 46.80962 -271.587958)
			(xy 46.763462 -271.561309) (xy 46.721791 -271.528078) (xy 46.685539 -271.489007) (xy 46.655515 -271.44497)
			(xy 46.632389 -271.396949) (xy 46.616679 -271.346019) (xy 46.608736 -271.293315) (xy 32.232356 -271.293315)
			(xy 32.224413 -271.346019) (xy 32.208703 -271.396949) (xy 32.185577 -271.44497) (xy 32.155553 -271.489007)
			(xy 32.119301 -271.528078) (xy 32.07763 -271.561309) (xy 32.031472 -271.587958) (xy 31.981858 -271.60743)
			(xy 31.929896 -271.61929) (xy 31.876746 -271.623274) (xy 31.823596 -271.61929) (xy 31.771634 -271.60743)
			(xy 31.72202 -271.587958) (xy 31.675862 -271.561309) (xy 31.634191 -271.528078) (xy 31.597939 -271.489007)
			(xy 31.567915 -271.44497) (xy 31.544789 -271.396949) (xy 31.529079 -271.346019) (xy 31.521136 -271.293315)
			(xy 17.144756 -271.293315) (xy 17.136813 -271.346019) (xy 17.121103 -271.396949) (xy 17.097977 -271.44497)
			(xy 17.067953 -271.489007) (xy 17.031701 -271.528078) (xy 16.99003 -271.561309) (xy 16.943872 -271.587958)
			(xy 16.894258 -271.60743) (xy 16.842296 -271.61929) (xy 16.789146 -271.623274) (xy 16.735996 -271.61929)
			(xy 16.684034 -271.60743) (xy 16.63442 -271.587958) (xy 16.588262 -271.561309) (xy 16.546591 -271.528078)
			(xy 16.510339 -271.489007) (xy 16.480315 -271.44497) (xy 16.457189 -271.396949) (xy 16.441479 -271.346019)
			(xy 16.433536 -271.293315) (xy 9.6774 -271.293315) (xy 9.6774 -272.143453) (xy 20.533604 -272.143453)
			(xy 20.533604 -272.090155) (xy 20.541547 -272.037451) (xy 20.557257 -271.986521) (xy 20.580383 -271.9385)
			(xy 20.610407 -271.894463) (xy 20.646659 -271.855392) (xy 20.68833 -271.822161) (xy 20.734488 -271.795512)
			(xy 20.784102 -271.77604) (xy 20.836064 -271.76418) (xy 20.889214 -271.760197) (xy 20.942364 -271.76418)
			(xy 20.994326 -271.77604) (xy 21.04394 -271.795512) (xy 21.090098 -271.822161) (xy 21.131769 -271.855392)
			(xy 21.168021 -271.894463) (xy 21.198045 -271.9385) (xy 21.221171 -271.986521) (xy 21.236881 -272.037451)
			(xy 21.244824 -272.090155) (xy 21.245322 -272.116804) (xy 21.244824 -272.143453) (xy 35.621204 -272.143453)
			(xy 35.621204 -272.090155) (xy 35.629147 -272.037451) (xy 35.644857 -271.986521) (xy 35.667983 -271.9385)
			(xy 35.698007 -271.894463) (xy 35.734259 -271.855392) (xy 35.77593 -271.822161) (xy 35.822088 -271.795512)
			(xy 35.871702 -271.77604) (xy 35.923664 -271.76418) (xy 35.976814 -271.760197) (xy 36.029964 -271.76418)
			(xy 36.081926 -271.77604) (xy 36.13154 -271.795512) (xy 36.177698 -271.822161) (xy 36.219369 -271.855392)
			(xy 36.255621 -271.894463) (xy 36.285645 -271.9385) (xy 36.308771 -271.986521) (xy 36.324481 -272.037451)
			(xy 36.332424 -272.090155) (xy 36.332922 -272.116804) (xy 36.332424 -272.143453) (xy 50.734204 -272.143453)
			(xy 50.734204 -272.090155) (xy 50.742147 -272.037451) (xy 50.757857 -271.986521) (xy 50.780983 -271.9385)
			(xy 50.811007 -271.894463) (xy 50.847259 -271.855392) (xy 50.88893 -271.822161) (xy 50.935088 -271.795512)
			(xy 50.984702 -271.77604) (xy 51.036664 -271.76418) (xy 51.089814 -271.760197) (xy 51.142964 -271.76418)
			(xy 51.194926 -271.77604) (xy 51.24454 -271.795512) (xy 51.290698 -271.822161) (xy 51.332369 -271.855392)
			(xy 51.368621 -271.894463) (xy 51.398645 -271.9385) (xy 51.421771 -271.986521) (xy 51.437481 -272.037451)
			(xy 51.445424 -272.090155) (xy 51.445922 -272.116804) (xy 51.445424 -272.143453) (xy 51.437481 -272.196157)
			(xy 51.421771 -272.247087) (xy 51.398645 -272.295108) (xy 51.368621 -272.339145) (xy 51.332369 -272.378216)
			(xy 51.290698 -272.411447) (xy 51.24454 -272.438096) (xy 51.194926 -272.457568) (xy 51.142964 -272.469428)
			(xy 51.089814 -272.473412) (xy 51.036664 -272.469428) (xy 50.984702 -272.457568) (xy 50.935088 -272.438096)
			(xy 50.88893 -272.411447) (xy 50.847259 -272.378216) (xy 50.811007 -272.339145) (xy 50.780983 -272.295108)
			(xy 50.757857 -272.247087) (xy 50.742147 -272.196157) (xy 50.734204 -272.143453) (xy 36.332424 -272.143453)
			(xy 36.324481 -272.196157) (xy 36.308771 -272.247087) (xy 36.285645 -272.295108) (xy 36.255621 -272.339145)
			(xy 36.219369 -272.378216) (xy 36.177698 -272.411447) (xy 36.13154 -272.438096) (xy 36.081926 -272.457568)
			(xy 36.029964 -272.469428) (xy 35.976814 -272.473412) (xy 35.923664 -272.469428) (xy 35.871702 -272.457568)
			(xy 35.822088 -272.438096) (xy 35.77593 -272.411447) (xy 35.734259 -272.378216) (xy 35.698007 -272.339145)
			(xy 35.667983 -272.295108) (xy 35.644857 -272.247087) (xy 35.629147 -272.196157) (xy 35.621204 -272.143453)
			(xy 21.244824 -272.143453) (xy 21.236881 -272.196157) (xy 21.221171 -272.247087) (xy 21.198045 -272.295108)
			(xy 21.168021 -272.339145) (xy 21.131769 -272.378216) (xy 21.090098 -272.411447) (xy 21.04394 -272.438096)
			(xy 20.994326 -272.457568) (xy 20.942364 -272.469428) (xy 20.889214 -272.473412) (xy 20.836064 -272.469428)
			(xy 20.784102 -272.457568) (xy 20.734488 -272.438096) (xy 20.68833 -272.411447) (xy 20.646659 -272.378216)
			(xy 20.610407 -272.339145) (xy 20.580383 -272.295108) (xy 20.557257 -272.247087) (xy 20.541547 -272.196157)
			(xy 20.533604 -272.143453) (xy 9.6774 -272.143453) (xy 9.6774 -272.993337) (xy 16.433536 -272.993337)
			(xy 16.433536 -272.940039) (xy 16.441479 -272.887335) (xy 16.457189 -272.836405) (xy 16.480315 -272.788384)
			(xy 16.510339 -272.744347) (xy 16.546591 -272.705276) (xy 16.588262 -272.672045) (xy 16.63442 -272.645396)
			(xy 16.684034 -272.625924) (xy 16.735996 -272.614064) (xy 16.789146 -272.610081) (xy 16.842296 -272.614064)
			(xy 16.894258 -272.625924) (xy 16.943872 -272.645396) (xy 16.99003 -272.672045) (xy 17.031701 -272.705276)
			(xy 17.067953 -272.744347) (xy 17.097977 -272.788384) (xy 17.121103 -272.836405) (xy 17.136813 -272.887335)
			(xy 17.144756 -272.940039) (xy 17.145254 -272.966688) (xy 17.144756 -272.993337) (xy 31.521136 -272.993337)
			(xy 31.521136 -272.940039) (xy 31.529079 -272.887335) (xy 31.544789 -272.836405) (xy 31.567915 -272.788384)
			(xy 31.597939 -272.744347) (xy 31.634191 -272.705276) (xy 31.675862 -272.672045) (xy 31.72202 -272.645396)
			(xy 31.771634 -272.625924) (xy 31.823596 -272.614064) (xy 31.876746 -272.610081) (xy 31.929896 -272.614064)
			(xy 31.981858 -272.625924) (xy 32.031472 -272.645396) (xy 32.07763 -272.672045) (xy 32.119301 -272.705276)
			(xy 32.155553 -272.744347) (xy 32.185577 -272.788384) (xy 32.208703 -272.836405) (xy 32.224413 -272.887335)
			(xy 32.232356 -272.940039) (xy 32.232854 -272.966688) (xy 32.232356 -272.993337) (xy 46.608736 -272.993337)
			(xy 46.608736 -272.940039) (xy 46.616679 -272.887335) (xy 46.632389 -272.836405) (xy 46.655515 -272.788384)
			(xy 46.685539 -272.744347) (xy 46.721791 -272.705276) (xy 46.763462 -272.672045) (xy 46.80962 -272.645396)
			(xy 46.859234 -272.625924) (xy 46.911196 -272.614064) (xy 46.964346 -272.610081) (xy 47.017496 -272.614064)
			(xy 47.069458 -272.625924) (xy 47.119072 -272.645396) (xy 47.16523 -272.672045) (xy 47.206901 -272.705276)
			(xy 47.243153 -272.744347) (xy 47.273177 -272.788384) (xy 47.296303 -272.836405) (xy 47.312013 -272.887335)
			(xy 47.319956 -272.940039) (xy 47.320454 -272.966688) (xy 47.319956 -272.993337) (xy 47.312013 -273.046041)
			(xy 47.296303 -273.096971) (xy 47.273177 -273.144992) (xy 47.243153 -273.189029) (xy 47.206901 -273.2281)
			(xy 47.16523 -273.261331) (xy 47.119072 -273.28798) (xy 47.069458 -273.307452) (xy 47.017496 -273.319312)
			(xy 46.964346 -273.323296) (xy 46.911196 -273.319312) (xy 46.859234 -273.307452) (xy 46.80962 -273.28798)
			(xy 46.763462 -273.261331) (xy 46.721791 -273.2281) (xy 46.685539 -273.189029) (xy 46.655515 -273.144992)
			(xy 46.632389 -273.096971) (xy 46.616679 -273.046041) (xy 46.608736 -272.993337) (xy 32.232356 -272.993337)
			(xy 32.224413 -273.046041) (xy 32.208703 -273.096971) (xy 32.185577 -273.144992) (xy 32.155553 -273.189029)
			(xy 32.119301 -273.2281) (xy 32.07763 -273.261331) (xy 32.031472 -273.28798) (xy 31.981858 -273.307452)
			(xy 31.929896 -273.319312) (xy 31.876746 -273.323296) (xy 31.823596 -273.319312) (xy 31.771634 -273.307452)
			(xy 31.72202 -273.28798) (xy 31.675862 -273.261331) (xy 31.634191 -273.2281) (xy 31.597939 -273.189029)
			(xy 31.567915 -273.144992) (xy 31.544789 -273.096971) (xy 31.529079 -273.046041) (xy 31.521136 -272.993337)
			(xy 17.144756 -272.993337) (xy 17.136813 -273.046041) (xy 17.121103 -273.096971) (xy 17.097977 -273.144992)
			(xy 17.067953 -273.189029) (xy 17.031701 -273.2281) (xy 16.99003 -273.261331) (xy 16.943872 -273.28798)
			(xy 16.894258 -273.307452) (xy 16.842296 -273.319312) (xy 16.789146 -273.323296) (xy 16.735996 -273.319312)
			(xy 16.684034 -273.307452) (xy 16.63442 -273.28798) (xy 16.588262 -273.261331) (xy 16.546591 -273.2281)
			(xy 16.510339 -273.189029) (xy 16.480315 -273.144992) (xy 16.457189 -273.096971) (xy 16.441479 -273.046041)
			(xy 16.433536 -272.993337) (xy 9.6774 -272.993337) (xy 9.6774 -273.843221) (xy 20.533604 -273.843221)
			(xy 20.533604 -273.789923) (xy 20.541547 -273.737219) (xy 20.557257 -273.686289) (xy 20.580383 -273.638268)
			(xy 20.610407 -273.594231) (xy 20.646659 -273.55516) (xy 20.68833 -273.521929) (xy 20.734488 -273.49528)
			(xy 20.784102 -273.475808) (xy 20.836064 -273.463948) (xy 20.889214 -273.459965) (xy 20.942364 -273.463948)
			(xy 20.994326 -273.475808) (xy 21.04394 -273.49528) (xy 21.090098 -273.521929) (xy 21.131769 -273.55516)
			(xy 21.168021 -273.594231) (xy 21.198045 -273.638268) (xy 21.221171 -273.686289) (xy 21.236881 -273.737219)
			(xy 21.244824 -273.789923) (xy 21.245322 -273.816572) (xy 21.244824 -273.843221) (xy 35.621204 -273.843221)
			(xy 35.621204 -273.789923) (xy 35.629147 -273.737219) (xy 35.644857 -273.686289) (xy 35.667983 -273.638268)
			(xy 35.698007 -273.594231) (xy 35.734259 -273.55516) (xy 35.77593 -273.521929) (xy 35.822088 -273.49528)
			(xy 35.871702 -273.475808) (xy 35.923664 -273.463948) (xy 35.976814 -273.459965) (xy 36.029964 -273.463948)
			(xy 36.081926 -273.475808) (xy 36.13154 -273.49528) (xy 36.177698 -273.521929) (xy 36.219369 -273.55516)
			(xy 36.255621 -273.594231) (xy 36.285645 -273.638268) (xy 36.308771 -273.686289) (xy 36.324481 -273.737219)
			(xy 36.332424 -273.789923) (xy 36.332922 -273.816572) (xy 36.332424 -273.843221) (xy 50.734204 -273.843221)
			(xy 50.734204 -273.789923) (xy 50.742147 -273.737219) (xy 50.757857 -273.686289) (xy 50.780983 -273.638268)
			(xy 50.811007 -273.594231) (xy 50.847259 -273.55516) (xy 50.88893 -273.521929) (xy 50.935088 -273.49528)
			(xy 50.984702 -273.475808) (xy 51.036664 -273.463948) (xy 51.089814 -273.459965) (xy 51.142964 -273.463948)
			(xy 51.194926 -273.475808) (xy 51.24454 -273.49528) (xy 51.290698 -273.521929) (xy 51.332369 -273.55516)
			(xy 51.368621 -273.594231) (xy 51.398645 -273.638268) (xy 51.421771 -273.686289) (xy 51.437481 -273.737219)
			(xy 51.445424 -273.789923) (xy 51.445922 -273.816572) (xy 51.445424 -273.843221) (xy 51.437481 -273.895925)
			(xy 51.421771 -273.946855) (xy 51.398645 -273.994876) (xy 51.368621 -274.038913) (xy 51.332369 -274.077984)
			(xy 51.290698 -274.111215) (xy 51.24454 -274.137864) (xy 51.194926 -274.157336) (xy 51.142964 -274.169196)
			(xy 51.089814 -274.17318) (xy 51.036664 -274.169196) (xy 50.984702 -274.157336) (xy 50.935088 -274.137864)
			(xy 50.88893 -274.111215) (xy 50.847259 -274.077984) (xy 50.811007 -274.038913) (xy 50.780983 -273.994876)
			(xy 50.757857 -273.946855) (xy 50.742147 -273.895925) (xy 50.734204 -273.843221) (xy 36.332424 -273.843221)
			(xy 36.324481 -273.895925) (xy 36.308771 -273.946855) (xy 36.285645 -273.994876) (xy 36.255621 -274.038913)
			(xy 36.219369 -274.077984) (xy 36.177698 -274.111215) (xy 36.13154 -274.137864) (xy 36.081926 -274.157336)
			(xy 36.029964 -274.169196) (xy 35.976814 -274.17318) (xy 35.923664 -274.169196) (xy 35.871702 -274.157336)
			(xy 35.822088 -274.137864) (xy 35.77593 -274.111215) (xy 35.734259 -274.077984) (xy 35.698007 -274.038913)
			(xy 35.667983 -273.994876) (xy 35.644857 -273.946855) (xy 35.629147 -273.895925) (xy 35.621204 -273.843221)
			(xy 21.244824 -273.843221) (xy 21.236881 -273.895925) (xy 21.221171 -273.946855) (xy 21.198045 -273.994876)
			(xy 21.168021 -274.038913) (xy 21.131769 -274.077984) (xy 21.090098 -274.111215) (xy 21.04394 -274.137864)
			(xy 20.994326 -274.157336) (xy 20.942364 -274.169196) (xy 20.889214 -274.17318) (xy 20.836064 -274.169196)
			(xy 20.784102 -274.157336) (xy 20.734488 -274.137864) (xy 20.68833 -274.111215) (xy 20.646659 -274.077984)
			(xy 20.610407 -274.038913) (xy 20.580383 -273.994876) (xy 20.557257 -273.946855) (xy 20.541547 -273.895925)
			(xy 20.533604 -273.843221) (xy 9.6774 -273.843221) (xy 9.6774 -274.693359) (xy 16.433536 -274.693359)
			(xy 16.433536 -274.640061) (xy 16.441479 -274.587357) (xy 16.457189 -274.536427) (xy 16.480315 -274.488406)
			(xy 16.510339 -274.444369) (xy 16.546591 -274.405298) (xy 16.588262 -274.372067) (xy 16.63442 -274.345418)
			(xy 16.684034 -274.325946) (xy 16.735996 -274.314086) (xy 16.789146 -274.310103) (xy 16.842296 -274.314086)
			(xy 16.894258 -274.325946) (xy 16.943872 -274.345418) (xy 16.99003 -274.372067) (xy 17.031701 -274.405298)
			(xy 17.067953 -274.444369) (xy 17.097977 -274.488406) (xy 17.121103 -274.536427) (xy 17.136813 -274.587357)
			(xy 17.144756 -274.640061) (xy 17.145254 -274.66671) (xy 17.144756 -274.693359) (xy 20.533604 -274.693359)
			(xy 20.533604 -274.640061) (xy 20.541547 -274.587357) (xy 20.557257 -274.536427) (xy 20.580383 -274.488406)
			(xy 20.610407 -274.444369) (xy 20.646659 -274.405298) (xy 20.68833 -274.372067) (xy 20.734488 -274.345418)
			(xy 20.784102 -274.325946) (xy 20.836064 -274.314086) (xy 20.889214 -274.310103) (xy 20.942364 -274.314086)
			(xy 20.994326 -274.325946) (xy 21.04394 -274.345418) (xy 21.090098 -274.372067) (xy 21.131769 -274.405298)
			(xy 21.168021 -274.444369) (xy 21.198045 -274.488406) (xy 21.221171 -274.536427) (xy 21.236881 -274.587357)
			(xy 21.244824 -274.640061) (xy 21.245322 -274.66671) (xy 21.244824 -274.693359) (xy 31.521136 -274.693359)
			(xy 31.521136 -274.640061) (xy 31.529079 -274.587357) (xy 31.544789 -274.536427) (xy 31.567915 -274.488406)
			(xy 31.597939 -274.444369) (xy 31.634191 -274.405298) (xy 31.675862 -274.372067) (xy 31.72202 -274.345418)
			(xy 31.771634 -274.325946) (xy 31.823596 -274.314086) (xy 31.876746 -274.310103) (xy 31.929896 -274.314086)
			(xy 31.981858 -274.325946) (xy 32.031472 -274.345418) (xy 32.07763 -274.372067) (xy 32.119301 -274.405298)
			(xy 32.155553 -274.444369) (xy 32.185577 -274.488406) (xy 32.208703 -274.536427) (xy 32.224413 -274.587357)
			(xy 32.232356 -274.640061) (xy 32.232854 -274.66671) (xy 32.232356 -274.693359) (xy 35.621204 -274.693359)
			(xy 35.621204 -274.640061) (xy 35.629147 -274.587357) (xy 35.644857 -274.536427) (xy 35.667983 -274.488406)
			(xy 35.698007 -274.444369) (xy 35.734259 -274.405298) (xy 35.77593 -274.372067) (xy 35.822088 -274.345418)
			(xy 35.871702 -274.325946) (xy 35.923664 -274.314086) (xy 35.976814 -274.310103) (xy 36.029964 -274.314086)
			(xy 36.081926 -274.325946) (xy 36.13154 -274.345418) (xy 36.177698 -274.372067) (xy 36.219369 -274.405298)
			(xy 36.255621 -274.444369) (xy 36.285645 -274.488406) (xy 36.308771 -274.536427) (xy 36.324481 -274.587357)
			(xy 36.332424 -274.640061) (xy 36.332922 -274.66671) (xy 36.332424 -274.693359) (xy 46.608736 -274.693359)
			(xy 46.608736 -274.640061) (xy 46.616679 -274.587357) (xy 46.632389 -274.536427) (xy 46.655515 -274.488406)
			(xy 46.685539 -274.444369) (xy 46.721791 -274.405298) (xy 46.763462 -274.372067) (xy 46.80962 -274.345418)
			(xy 46.859234 -274.325946) (xy 46.911196 -274.314086) (xy 46.964346 -274.310103) (xy 47.017496 -274.314086)
			(xy 47.069458 -274.325946) (xy 47.119072 -274.345418) (xy 47.16523 -274.372067) (xy 47.206901 -274.405298)
			(xy 47.243153 -274.444369) (xy 47.273177 -274.488406) (xy 47.296303 -274.536427) (xy 47.312013 -274.587357)
			(xy 47.319956 -274.640061) (xy 47.320454 -274.66671) (xy 47.319956 -274.693359) (xy 47.319918 -274.693613)
			(xy 50.734204 -274.693613) (xy 50.734204 -274.640315) (xy 50.742147 -274.587611) (xy 50.757857 -274.536681)
			(xy 50.780983 -274.48866) (xy 50.811007 -274.444623) (xy 50.847259 -274.405552) (xy 50.88893 -274.372321)
			(xy 50.935088 -274.345672) (xy 50.984702 -274.3262) (xy 51.036664 -274.31434) (xy 51.089814 -274.310357)
			(xy 51.142964 -274.31434) (xy 51.194926 -274.3262) (xy 51.24454 -274.345672) (xy 51.290698 -274.372321)
			(xy 51.332369 -274.405552) (xy 51.368621 -274.444623) (xy 51.398645 -274.48866) (xy 51.421771 -274.536681)
			(xy 51.437481 -274.587611) (xy 51.445424 -274.640315) (xy 51.445922 -274.666964) (xy 51.445424 -274.693613)
			(xy 51.437481 -274.746317) (xy 51.421771 -274.797247) (xy 51.398645 -274.845268) (xy 51.368621 -274.889305)
			(xy 51.332369 -274.928376) (xy 51.290698 -274.961607) (xy 51.24454 -274.988256) (xy 51.194926 -275.007728)
			(xy 51.142964 -275.019588) (xy 51.089814 -275.023572) (xy 51.036664 -275.019588) (xy 50.984702 -275.007728)
			(xy 50.935088 -274.988256) (xy 50.88893 -274.961607) (xy 50.847259 -274.928376) (xy 50.811007 -274.889305)
			(xy 50.780983 -274.845268) (xy 50.757857 -274.797247) (xy 50.742147 -274.746317) (xy 50.734204 -274.693613)
			(xy 47.319918 -274.693613) (xy 47.312013 -274.746063) (xy 47.296303 -274.796993) (xy 47.273177 -274.845014)
			(xy 47.243153 -274.889051) (xy 47.206901 -274.928122) (xy 47.16523 -274.961353) (xy 47.119072 -274.988002)
			(xy 47.069458 -275.007474) (xy 47.017496 -275.019334) (xy 46.964346 -275.023318) (xy 46.911196 -275.019334)
			(xy 46.859234 -275.007474) (xy 46.80962 -274.988002) (xy 46.763462 -274.961353) (xy 46.721791 -274.928122)
			(xy 46.685539 -274.889051) (xy 46.655515 -274.845014) (xy 46.632389 -274.796993) (xy 46.616679 -274.746063)
			(xy 46.608736 -274.693359) (xy 36.332424 -274.693359) (xy 36.324481 -274.746063) (xy 36.308771 -274.796993)
			(xy 36.285645 -274.845014) (xy 36.255621 -274.889051) (xy 36.219369 -274.928122) (xy 36.177698 -274.961353)
			(xy 36.13154 -274.988002) (xy 36.081926 -275.007474) (xy 36.029964 -275.019334) (xy 35.976814 -275.023318)
			(xy 35.923664 -275.019334) (xy 35.871702 -275.007474) (xy 35.822088 -274.988002) (xy 35.77593 -274.961353)
			(xy 35.734259 -274.928122) (xy 35.698007 -274.889051) (xy 35.667983 -274.845014) (xy 35.644857 -274.796993)
			(xy 35.629147 -274.746063) (xy 35.621204 -274.693359) (xy 32.232356 -274.693359) (xy 32.224413 -274.746063)
			(xy 32.208703 -274.796993) (xy 32.185577 -274.845014) (xy 32.155553 -274.889051) (xy 32.119301 -274.928122)
			(xy 32.07763 -274.961353) (xy 32.031472 -274.988002) (xy 31.981858 -275.007474) (xy 31.929896 -275.019334)
			(xy 31.876746 -275.023318) (xy 31.823596 -275.019334) (xy 31.771634 -275.007474) (xy 31.72202 -274.988002)
			(xy 31.675862 -274.961353) (xy 31.634191 -274.928122) (xy 31.597939 -274.889051) (xy 31.567915 -274.845014)
			(xy 31.544789 -274.796993) (xy 31.529079 -274.746063) (xy 31.521136 -274.693359) (xy 21.244824 -274.693359)
			(xy 21.236881 -274.746063) (xy 21.221171 -274.796993) (xy 21.198045 -274.845014) (xy 21.168021 -274.889051)
			(xy 21.131769 -274.928122) (xy 21.090098 -274.961353) (xy 21.04394 -274.988002) (xy 20.994326 -275.007474)
			(xy 20.942364 -275.019334) (xy 20.889214 -275.023318) (xy 20.836064 -275.019334) (xy 20.784102 -275.007474)
			(xy 20.734488 -274.988002) (xy 20.68833 -274.961353) (xy 20.646659 -274.928122) (xy 20.610407 -274.889051)
			(xy 20.580383 -274.845014) (xy 20.557257 -274.796993) (xy 20.541547 -274.746063) (xy 20.533604 -274.693359)
			(xy 17.144756 -274.693359) (xy 17.136813 -274.746063) (xy 17.121103 -274.796993) (xy 17.097977 -274.845014)
			(xy 17.067953 -274.889051) (xy 17.031701 -274.928122) (xy 16.99003 -274.961353) (xy 16.943872 -274.988002)
			(xy 16.894258 -275.007474) (xy 16.842296 -275.019334) (xy 16.789146 -275.023318) (xy 16.735996 -275.019334)
			(xy 16.684034 -275.007474) (xy 16.63442 -274.988002) (xy 16.588262 -274.961353) (xy 16.546591 -274.928122)
			(xy 16.510339 -274.889051) (xy 16.480315 -274.845014) (xy 16.457189 -274.796993) (xy 16.441479 -274.746063)
			(xy 16.433536 -274.693359) (xy 9.6774 -274.693359) (xy 9.6774 -275.543243) (xy 16.433536 -275.543243)
			(xy 16.433536 -275.489945) (xy 16.441479 -275.437241) (xy 16.457189 -275.386311) (xy 16.480315 -275.33829)
			(xy 16.510339 -275.294253) (xy 16.546591 -275.255182) (xy 16.588262 -275.221951) (xy 16.63442 -275.195302)
			(xy 16.684034 -275.17583) (xy 16.735996 -275.16397) (xy 16.789146 -275.159987) (xy 16.842296 -275.16397)
			(xy 16.894258 -275.17583) (xy 16.943872 -275.195302) (xy 16.99003 -275.221951) (xy 17.031701 -275.255182)
			(xy 17.067953 -275.294253) (xy 17.097977 -275.33829) (xy 17.121103 -275.386311) (xy 17.136813 -275.437241)
			(xy 17.144756 -275.489945) (xy 17.145254 -275.516594) (xy 17.144756 -275.543243) (xy 31.521136 -275.543243)
			(xy 31.521136 -275.489945) (xy 31.529079 -275.437241) (xy 31.544789 -275.386311) (xy 31.567915 -275.33829)
			(xy 31.597939 -275.294253) (xy 31.634191 -275.255182) (xy 31.675862 -275.221951) (xy 31.72202 -275.195302)
			(xy 31.771634 -275.17583) (xy 31.823596 -275.16397) (xy 31.876746 -275.159987) (xy 31.929896 -275.16397)
			(xy 31.981858 -275.17583) (xy 32.031472 -275.195302) (xy 32.07763 -275.221951) (xy 32.119301 -275.255182)
			(xy 32.155553 -275.294253) (xy 32.185577 -275.33829) (xy 32.208703 -275.386311) (xy 32.224413 -275.437241)
			(xy 32.232356 -275.489945) (xy 32.232854 -275.516594) (xy 32.232356 -275.543243) (xy 46.608736 -275.543243)
			(xy 46.608736 -275.489945) (xy 46.616679 -275.437241) (xy 46.632389 -275.386311) (xy 46.655515 -275.33829)
			(xy 46.685539 -275.294253) (xy 46.721791 -275.255182) (xy 46.763462 -275.221951) (xy 46.80962 -275.195302)
			(xy 46.859234 -275.17583) (xy 46.911196 -275.16397) (xy 46.964346 -275.159987) (xy 47.017496 -275.16397)
			(xy 47.069458 -275.17583) (xy 47.119072 -275.195302) (xy 47.16523 -275.221951) (xy 47.206901 -275.255182)
			(xy 47.243153 -275.294253) (xy 47.273177 -275.33829) (xy 47.296303 -275.386311) (xy 47.312013 -275.437241)
			(xy 47.319956 -275.489945) (xy 47.320454 -275.516594) (xy 47.319956 -275.543243) (xy 47.312013 -275.595947)
			(xy 47.296303 -275.646877) (xy 47.273177 -275.694898) (xy 47.243153 -275.738935) (xy 47.206901 -275.778006)
			(xy 47.16523 -275.811237) (xy 47.119072 -275.837886) (xy 47.069458 -275.857358) (xy 47.017496 -275.869218)
			(xy 46.964346 -275.873202) (xy 46.911196 -275.869218) (xy 46.859234 -275.857358) (xy 46.80962 -275.837886)
			(xy 46.763462 -275.811237) (xy 46.721791 -275.778006) (xy 46.685539 -275.738935) (xy 46.655515 -275.694898)
			(xy 46.632389 -275.646877) (xy 46.616679 -275.595947) (xy 46.608736 -275.543243) (xy 32.232356 -275.543243)
			(xy 32.224413 -275.595947) (xy 32.208703 -275.646877) (xy 32.185577 -275.694898) (xy 32.155553 -275.738935)
			(xy 32.119301 -275.778006) (xy 32.07763 -275.811237) (xy 32.031472 -275.837886) (xy 31.981858 -275.857358)
			(xy 31.929896 -275.869218) (xy 31.876746 -275.873202) (xy 31.823596 -275.869218) (xy 31.771634 -275.857358)
			(xy 31.72202 -275.837886) (xy 31.675862 -275.811237) (xy 31.634191 -275.778006) (xy 31.597939 -275.738935)
			(xy 31.567915 -275.694898) (xy 31.544789 -275.646877) (xy 31.529079 -275.595947) (xy 31.521136 -275.543243)
			(xy 17.144756 -275.543243) (xy 17.136813 -275.595947) (xy 17.121103 -275.646877) (xy 17.097977 -275.694898)
			(xy 17.067953 -275.738935) (xy 17.031701 -275.778006) (xy 16.99003 -275.811237) (xy 16.943872 -275.837886)
			(xy 16.894258 -275.857358) (xy 16.842296 -275.869218) (xy 16.789146 -275.873202) (xy 16.735996 -275.869218)
			(xy 16.684034 -275.857358) (xy 16.63442 -275.837886) (xy 16.588262 -275.811237) (xy 16.546591 -275.778006)
			(xy 16.510339 -275.738935) (xy 16.480315 -275.694898) (xy 16.457189 -275.646877) (xy 16.441479 -275.595947)
			(xy 16.433536 -275.543243) (xy 9.6774 -275.543243) (xy 9.6774 -276.393381) (xy 20.533604 -276.393381)
			(xy 20.533604 -276.340083) (xy 20.541547 -276.287379) (xy 20.557257 -276.236449) (xy 20.580383 -276.188428)
			(xy 20.610407 -276.144391) (xy 20.646659 -276.10532) (xy 20.68833 -276.072089) (xy 20.734488 -276.04544)
			(xy 20.784102 -276.025968) (xy 20.836064 -276.014108) (xy 20.889214 -276.010125) (xy 20.942364 -276.014108)
			(xy 20.994326 -276.025968) (xy 21.04394 -276.04544) (xy 21.090098 -276.072089) (xy 21.131769 -276.10532)
			(xy 21.168021 -276.144391) (xy 21.198045 -276.188428) (xy 21.221171 -276.236449) (xy 21.236881 -276.287379)
			(xy 21.244824 -276.340083) (xy 21.245322 -276.366732) (xy 21.244824 -276.393381) (xy 35.621204 -276.393381)
			(xy 35.621204 -276.340083) (xy 35.629147 -276.287379) (xy 35.644857 -276.236449) (xy 35.667983 -276.188428)
			(xy 35.698007 -276.144391) (xy 35.734259 -276.10532) (xy 35.77593 -276.072089) (xy 35.822088 -276.04544)
			(xy 35.871702 -276.025968) (xy 35.923664 -276.014108) (xy 35.976814 -276.010125) (xy 36.029964 -276.014108)
			(xy 36.081926 -276.025968) (xy 36.13154 -276.04544) (xy 36.177698 -276.072089) (xy 36.219369 -276.10532)
			(xy 36.255621 -276.144391) (xy 36.285645 -276.188428) (xy 36.308771 -276.236449) (xy 36.324481 -276.287379)
			(xy 36.332424 -276.340083) (xy 36.332922 -276.366732) (xy 36.332424 -276.393381) (xy 36.332386 -276.393635)
			(xy 50.734204 -276.393635) (xy 50.734204 -276.340337) (xy 50.742147 -276.287633) (xy 50.757857 -276.236703)
			(xy 50.780983 -276.188682) (xy 50.811007 -276.144645) (xy 50.847259 -276.105574) (xy 50.88893 -276.072343)
			(xy 50.935088 -276.045694) (xy 50.984702 -276.026222) (xy 51.036664 -276.014362) (xy 51.089814 -276.010379)
			(xy 51.142964 -276.014362) (xy 51.194926 -276.026222) (xy 51.24454 -276.045694) (xy 51.290698 -276.072343)
			(xy 51.332369 -276.105574) (xy 51.368621 -276.144645) (xy 51.398645 -276.188682) (xy 51.421771 -276.236703)
			(xy 51.437481 -276.287633) (xy 51.445424 -276.340337) (xy 51.445922 -276.366986) (xy 51.445424 -276.393635)
			(xy 51.437481 -276.446339) (xy 51.421771 -276.497269) (xy 51.398645 -276.54529) (xy 51.368621 -276.589327)
			(xy 51.332369 -276.628398) (xy 51.290698 -276.661629) (xy 51.24454 -276.688278) (xy 51.194926 -276.70775)
			(xy 51.142964 -276.71961) (xy 51.089814 -276.723594) (xy 51.036664 -276.71961) (xy 50.984702 -276.70775)
			(xy 50.935088 -276.688278) (xy 50.88893 -276.661629) (xy 50.847259 -276.628398) (xy 50.811007 -276.589327)
			(xy 50.780983 -276.54529) (xy 50.757857 -276.497269) (xy 50.742147 -276.446339) (xy 50.734204 -276.393635)
			(xy 36.332386 -276.393635) (xy 36.324481 -276.446085) (xy 36.308771 -276.497015) (xy 36.285645 -276.545036)
			(xy 36.255621 -276.589073) (xy 36.219369 -276.628144) (xy 36.177698 -276.661375) (xy 36.13154 -276.688024)
			(xy 36.081926 -276.707496) (xy 36.029964 -276.719356) (xy 35.976814 -276.72334) (xy 35.923664 -276.719356)
			(xy 35.871702 -276.707496) (xy 35.822088 -276.688024) (xy 35.77593 -276.661375) (xy 35.734259 -276.628144)
			(xy 35.698007 -276.589073) (xy 35.667983 -276.545036) (xy 35.644857 -276.497015) (xy 35.629147 -276.446085)
			(xy 35.621204 -276.393381) (xy 21.244824 -276.393381) (xy 21.236881 -276.446085) (xy 21.221171 -276.497015)
			(xy 21.198045 -276.545036) (xy 21.168021 -276.589073) (xy 21.131769 -276.628144) (xy 21.090098 -276.661375)
			(xy 21.04394 -276.688024) (xy 20.994326 -276.707496) (xy 20.942364 -276.719356) (xy 20.889214 -276.72334)
			(xy 20.836064 -276.719356) (xy 20.784102 -276.707496) (xy 20.734488 -276.688024) (xy 20.68833 -276.661375)
			(xy 20.646659 -276.628144) (xy 20.610407 -276.589073) (xy 20.580383 -276.545036) (xy 20.557257 -276.497015)
			(xy 20.541547 -276.446085) (xy 20.533604 -276.393381) (xy 9.6774 -276.393381) (xy 9.6774 -277.243265)
			(xy 16.433536 -277.243265) (xy 16.433536 -277.189967) (xy 16.441479 -277.137263) (xy 16.457189 -277.086333)
			(xy 16.480315 -277.038312) (xy 16.510339 -276.994275) (xy 16.546591 -276.955204) (xy 16.588262 -276.921973)
			(xy 16.63442 -276.895324) (xy 16.684034 -276.875852) (xy 16.735996 -276.863992) (xy 16.789146 -276.860009)
			(xy 16.842296 -276.863992) (xy 16.894258 -276.875852) (xy 16.943872 -276.895324) (xy 16.99003 -276.921973)
			(xy 17.031701 -276.955204) (xy 17.067953 -276.994275) (xy 17.097977 -277.038312) (xy 17.121103 -277.086333)
			(xy 17.136813 -277.137263) (xy 17.144756 -277.189967) (xy 17.145254 -277.216616) (xy 17.144756 -277.243265)
			(xy 31.521136 -277.243265) (xy 31.521136 -277.189967) (xy 31.529079 -277.137263) (xy 31.544789 -277.086333)
			(xy 31.567915 -277.038312) (xy 31.597939 -276.994275) (xy 31.634191 -276.955204) (xy 31.675862 -276.921973)
			(xy 31.72202 -276.895324) (xy 31.771634 -276.875852) (xy 31.823596 -276.863992) (xy 31.876746 -276.860009)
			(xy 31.929896 -276.863992) (xy 31.981858 -276.875852) (xy 32.031472 -276.895324) (xy 32.07763 -276.921973)
			(xy 32.119301 -276.955204) (xy 32.155553 -276.994275) (xy 32.185577 -277.038312) (xy 32.208703 -277.086333)
			(xy 32.224413 -277.137263) (xy 32.232356 -277.189967) (xy 32.232854 -277.216616) (xy 32.232356 -277.243265)
			(xy 46.608736 -277.243265) (xy 46.608736 -277.189967) (xy 46.616679 -277.137263) (xy 46.632389 -277.086333)
			(xy 46.655515 -277.038312) (xy 46.685539 -276.994275) (xy 46.721791 -276.955204) (xy 46.763462 -276.921973)
			(xy 46.80962 -276.895324) (xy 46.859234 -276.875852) (xy 46.911196 -276.863992) (xy 46.964346 -276.860009)
			(xy 47.017496 -276.863992) (xy 47.069458 -276.875852) (xy 47.119072 -276.895324) (xy 47.16523 -276.921973)
			(xy 47.206901 -276.955204) (xy 47.243153 -276.994275) (xy 47.273177 -277.038312) (xy 47.296303 -277.086333)
			(xy 47.312013 -277.137263) (xy 47.319956 -277.189967) (xy 47.320454 -277.216616) (xy 47.319956 -277.243265)
			(xy 47.312013 -277.295969) (xy 47.296303 -277.346899) (xy 47.273177 -277.39492) (xy 47.243153 -277.438957)
			(xy 47.206901 -277.478028) (xy 47.16523 -277.511259) (xy 47.119072 -277.537908) (xy 47.069458 -277.55738)
			(xy 47.017496 -277.56924) (xy 46.964346 -277.573224) (xy 46.911196 -277.56924) (xy 46.859234 -277.55738)
			(xy 46.80962 -277.537908) (xy 46.763462 -277.511259) (xy 46.721791 -277.478028) (xy 46.685539 -277.438957)
			(xy 46.655515 -277.39492) (xy 46.632389 -277.346899) (xy 46.616679 -277.295969) (xy 46.608736 -277.243265)
			(xy 32.232356 -277.243265) (xy 32.224413 -277.295969) (xy 32.208703 -277.346899) (xy 32.185577 -277.39492)
			(xy 32.155553 -277.438957) (xy 32.119301 -277.478028) (xy 32.07763 -277.511259) (xy 32.031472 -277.537908)
			(xy 31.981858 -277.55738) (xy 31.929896 -277.56924) (xy 31.876746 -277.573224) (xy 31.823596 -277.56924)
			(xy 31.771634 -277.55738) (xy 31.72202 -277.537908) (xy 31.675862 -277.511259) (xy 31.634191 -277.478028)
			(xy 31.597939 -277.438957) (xy 31.567915 -277.39492) (xy 31.544789 -277.346899) (xy 31.529079 -277.295969)
			(xy 31.521136 -277.243265) (xy 17.144756 -277.243265) (xy 17.136813 -277.295969) (xy 17.121103 -277.346899)
			(xy 17.097977 -277.39492) (xy 17.067953 -277.438957) (xy 17.031701 -277.478028) (xy 16.99003 -277.511259)
			(xy 16.943872 -277.537908) (xy 16.894258 -277.55738) (xy 16.842296 -277.56924) (xy 16.789146 -277.573224)
			(xy 16.735996 -277.56924) (xy 16.684034 -277.55738) (xy 16.63442 -277.537908) (xy 16.588262 -277.511259)
			(xy 16.546591 -277.478028) (xy 16.510339 -277.438957) (xy 16.480315 -277.39492) (xy 16.457189 -277.346899)
			(xy 16.441479 -277.295969) (xy 16.433536 -277.243265) (xy 9.6774 -277.243265) (xy 9.6774 -278.093403)
			(xy 20.533604 -278.093403) (xy 20.533604 -278.040105) (xy 20.541547 -277.987401) (xy 20.557257 -277.936471)
			(xy 20.580383 -277.88845) (xy 20.610407 -277.844413) (xy 20.646659 -277.805342) (xy 20.68833 -277.772111)
			(xy 20.734488 -277.745462) (xy 20.784102 -277.72599) (xy 20.836064 -277.71413) (xy 20.889214 -277.710147)
			(xy 20.942364 -277.71413) (xy 20.994326 -277.72599) (xy 21.04394 -277.745462) (xy 21.090098 -277.772111)
			(xy 21.131769 -277.805342) (xy 21.168021 -277.844413) (xy 21.198045 -277.88845) (xy 21.221171 -277.936471)
			(xy 21.236881 -277.987401) (xy 21.244824 -278.040105) (xy 21.245322 -278.066754) (xy 21.244824 -278.093403)
			(xy 35.621204 -278.093403) (xy 35.621204 -278.040105) (xy 35.629147 -277.987401) (xy 35.644857 -277.936471)
			(xy 35.667983 -277.88845) (xy 35.698007 -277.844413) (xy 35.734259 -277.805342) (xy 35.77593 -277.772111)
			(xy 35.822088 -277.745462) (xy 35.871702 -277.72599) (xy 35.923664 -277.71413) (xy 35.976814 -277.710147)
			(xy 36.029964 -277.71413) (xy 36.081926 -277.72599) (xy 36.13154 -277.745462) (xy 36.177698 -277.772111)
			(xy 36.219369 -277.805342) (xy 36.255621 -277.844413) (xy 36.285645 -277.88845) (xy 36.308771 -277.936471)
			(xy 36.324481 -277.987401) (xy 36.332424 -278.040105) (xy 36.332922 -278.066754) (xy 36.332424 -278.093403)
			(xy 36.332386 -278.093657) (xy 50.734204 -278.093657) (xy 50.734204 -278.040359) (xy 50.742147 -277.987655)
			(xy 50.757857 -277.936725) (xy 50.780983 -277.888704) (xy 50.811007 -277.844667) (xy 50.847259 -277.805596)
			(xy 50.88893 -277.772365) (xy 50.935088 -277.745716) (xy 50.984702 -277.726244) (xy 51.036664 -277.714384)
			(xy 51.089814 -277.710401) (xy 51.142964 -277.714384) (xy 51.194926 -277.726244) (xy 51.24454 -277.745716)
			(xy 51.290698 -277.772365) (xy 51.332369 -277.805596) (xy 51.368621 -277.844667) (xy 51.398645 -277.888704)
			(xy 51.421771 -277.936725) (xy 51.437481 -277.987655) (xy 51.445424 -278.040359) (xy 51.445922 -278.067008)
			(xy 51.445424 -278.093657) (xy 51.437481 -278.146361) (xy 51.421771 -278.197291) (xy 51.398645 -278.245312)
			(xy 51.368621 -278.289349) (xy 51.332369 -278.32842) (xy 51.290698 -278.361651) (xy 51.24454 -278.3883)
			(xy 51.194926 -278.407772) (xy 51.142964 -278.419632) (xy 51.089814 -278.423616) (xy 51.036664 -278.419632)
			(xy 50.984702 -278.407772) (xy 50.935088 -278.3883) (xy 50.88893 -278.361651) (xy 50.847259 -278.32842)
			(xy 50.811007 -278.289349) (xy 50.780983 -278.245312) (xy 50.757857 -278.197291) (xy 50.742147 -278.146361)
			(xy 50.734204 -278.093657) (xy 36.332386 -278.093657) (xy 36.324481 -278.146107) (xy 36.308771 -278.197037)
			(xy 36.285645 -278.245058) (xy 36.255621 -278.289095) (xy 36.219369 -278.328166) (xy 36.177698 -278.361397)
			(xy 36.13154 -278.388046) (xy 36.081926 -278.407518) (xy 36.029964 -278.419378) (xy 35.976814 -278.423362)
			(xy 35.923664 -278.419378) (xy 35.871702 -278.407518) (xy 35.822088 -278.388046) (xy 35.77593 -278.361397)
			(xy 35.734259 -278.328166) (xy 35.698007 -278.289095) (xy 35.667983 -278.245058) (xy 35.644857 -278.197037)
			(xy 35.629147 -278.146107) (xy 35.621204 -278.093403) (xy 21.244824 -278.093403) (xy 21.236881 -278.146107)
			(xy 21.221171 -278.197037) (xy 21.198045 -278.245058) (xy 21.168021 -278.289095) (xy 21.131769 -278.328166)
			(xy 21.090098 -278.361397) (xy 21.04394 -278.388046) (xy 20.994326 -278.407518) (xy 20.942364 -278.419378)
			(xy 20.889214 -278.423362) (xy 20.836064 -278.419378) (xy 20.784102 -278.407518) (xy 20.734488 -278.388046)
			(xy 20.68833 -278.361397) (xy 20.646659 -278.328166) (xy 20.610407 -278.289095) (xy 20.580383 -278.245058)
			(xy 20.557257 -278.197037) (xy 20.541547 -278.146107) (xy 20.533604 -278.093403) (xy 9.6774 -278.093403)
			(xy 9.6774 -278.943287) (xy 16.433536 -278.943287) (xy 16.433536 -278.889989) (xy 16.441479 -278.837285)
			(xy 16.457189 -278.786355) (xy 16.480315 -278.738334) (xy 16.510339 -278.694297) (xy 16.546591 -278.655226)
			(xy 16.588262 -278.621995) (xy 16.63442 -278.595346) (xy 16.684034 -278.575874) (xy 16.735996 -278.564014)
			(xy 16.789146 -278.560031) (xy 16.842296 -278.564014) (xy 16.894258 -278.575874) (xy 16.943872 -278.595346)
			(xy 16.99003 -278.621995) (xy 17.031701 -278.655226) (xy 17.067953 -278.694297) (xy 17.097977 -278.738334)
			(xy 17.121103 -278.786355) (xy 17.136813 -278.837285) (xy 17.144756 -278.889989) (xy 17.145254 -278.916638)
			(xy 17.144756 -278.943287) (xy 31.521136 -278.943287) (xy 31.521136 -278.889989) (xy 31.529079 -278.837285)
			(xy 31.544789 -278.786355) (xy 31.567915 -278.738334) (xy 31.597939 -278.694297) (xy 31.634191 -278.655226)
			(xy 31.675862 -278.621995) (xy 31.72202 -278.595346) (xy 31.771634 -278.575874) (xy 31.823596 -278.564014)
			(xy 31.876746 -278.560031) (xy 31.929896 -278.564014) (xy 31.981858 -278.575874) (xy 32.031472 -278.595346)
			(xy 32.07763 -278.621995) (xy 32.119301 -278.655226) (xy 32.155553 -278.694297) (xy 32.185577 -278.738334)
			(xy 32.208703 -278.786355) (xy 32.224413 -278.837285) (xy 32.232356 -278.889989) (xy 32.232854 -278.916638)
			(xy 32.232356 -278.943287) (xy 46.608736 -278.943287) (xy 46.608736 -278.889989) (xy 46.616679 -278.837285)
			(xy 46.632389 -278.786355) (xy 46.655515 -278.738334) (xy 46.685539 -278.694297) (xy 46.721791 -278.655226)
			(xy 46.763462 -278.621995) (xy 46.80962 -278.595346) (xy 46.859234 -278.575874) (xy 46.911196 -278.564014)
			(xy 46.964346 -278.560031) (xy 47.017496 -278.564014) (xy 47.069458 -278.575874) (xy 47.119072 -278.595346)
			(xy 47.16523 -278.621995) (xy 47.206901 -278.655226) (xy 47.243153 -278.694297) (xy 47.273177 -278.738334)
			(xy 47.296303 -278.786355) (xy 47.312013 -278.837285) (xy 47.319956 -278.889989) (xy 47.320454 -278.916638)
			(xy 47.319956 -278.943287) (xy 47.312013 -278.995991) (xy 47.296303 -279.046921) (xy 47.273177 -279.094942)
			(xy 47.243153 -279.138979) (xy 47.206901 -279.17805) (xy 47.16523 -279.211281) (xy 47.119072 -279.23793)
			(xy 47.069458 -279.257402) (xy 47.017496 -279.269262) (xy 46.964346 -279.273246) (xy 46.911196 -279.269262)
			(xy 46.859234 -279.257402) (xy 46.80962 -279.23793) (xy 46.763462 -279.211281) (xy 46.721791 -279.17805)
			(xy 46.685539 -279.138979) (xy 46.655515 -279.094942) (xy 46.632389 -279.046921) (xy 46.616679 -278.995991)
			(xy 46.608736 -278.943287) (xy 32.232356 -278.943287) (xy 32.224413 -278.995991) (xy 32.208703 -279.046921)
			(xy 32.185577 -279.094942) (xy 32.155553 -279.138979) (xy 32.119301 -279.17805) (xy 32.07763 -279.211281)
			(xy 32.031472 -279.23793) (xy 31.981858 -279.257402) (xy 31.929896 -279.269262) (xy 31.876746 -279.273246)
			(xy 31.823596 -279.269262) (xy 31.771634 -279.257402) (xy 31.72202 -279.23793) (xy 31.675862 -279.211281)
			(xy 31.634191 -279.17805) (xy 31.597939 -279.138979) (xy 31.567915 -279.094942) (xy 31.544789 -279.046921)
			(xy 31.529079 -278.995991) (xy 31.521136 -278.943287) (xy 17.144756 -278.943287) (xy 17.136813 -278.995991)
			(xy 17.121103 -279.046921) (xy 17.097977 -279.094942) (xy 17.067953 -279.138979) (xy 17.031701 -279.17805)
			(xy 16.99003 -279.211281) (xy 16.943872 -279.23793) (xy 16.894258 -279.257402) (xy 16.842296 -279.269262)
			(xy 16.789146 -279.273246) (xy 16.735996 -279.269262) (xy 16.684034 -279.257402) (xy 16.63442 -279.23793)
			(xy 16.588262 -279.211281) (xy 16.546591 -279.17805) (xy 16.510339 -279.138979) (xy 16.480315 -279.094942)
			(xy 16.457189 -279.046921) (xy 16.441479 -278.995991) (xy 16.433536 -278.943287) (xy 9.6774 -278.943287)
			(xy 9.6774 -279.793425) (xy 20.533604 -279.793425) (xy 20.533604 -279.740127) (xy 20.541547 -279.687423)
			(xy 20.557257 -279.636493) (xy 20.580383 -279.588472) (xy 20.610407 -279.544435) (xy 20.646659 -279.505364)
			(xy 20.68833 -279.472133) (xy 20.734488 -279.445484) (xy 20.784102 -279.426012) (xy 20.836064 -279.414152)
			(xy 20.889214 -279.410169) (xy 20.942364 -279.414152) (xy 20.994326 -279.426012) (xy 21.04394 -279.445484)
			(xy 21.090098 -279.472133) (xy 21.131769 -279.505364) (xy 21.168021 -279.544435) (xy 21.198045 -279.588472)
			(xy 21.221171 -279.636493) (xy 21.236881 -279.687423) (xy 21.244824 -279.740127) (xy 21.245322 -279.766776)
			(xy 21.244824 -279.793425) (xy 35.621204 -279.793425) (xy 35.621204 -279.740127) (xy 35.629147 -279.687423)
			(xy 35.644857 -279.636493) (xy 35.667983 -279.588472) (xy 35.698007 -279.544435) (xy 35.734259 -279.505364)
			(xy 35.77593 -279.472133) (xy 35.822088 -279.445484) (xy 35.871702 -279.426012) (xy 35.923664 -279.414152)
			(xy 35.976814 -279.410169) (xy 36.029964 -279.414152) (xy 36.081926 -279.426012) (xy 36.13154 -279.445484)
			(xy 36.177698 -279.472133) (xy 36.219369 -279.505364) (xy 36.255621 -279.544435) (xy 36.285645 -279.588472)
			(xy 36.308771 -279.636493) (xy 36.324481 -279.687423) (xy 36.332424 -279.740127) (xy 36.332922 -279.766776)
			(xy 36.332424 -279.793425) (xy 50.734204 -279.793425) (xy 50.734204 -279.740127) (xy 50.742147 -279.687423)
			(xy 50.757857 -279.636493) (xy 50.780983 -279.588472) (xy 50.811007 -279.544435) (xy 50.847259 -279.505364)
			(xy 50.88893 -279.472133) (xy 50.935088 -279.445484) (xy 50.984702 -279.426012) (xy 51.036664 -279.414152)
			(xy 51.089814 -279.410169) (xy 51.142964 -279.414152) (xy 51.194926 -279.426012) (xy 51.24454 -279.445484)
			(xy 51.290698 -279.472133) (xy 51.332369 -279.505364) (xy 51.368621 -279.544435) (xy 51.398645 -279.588472)
			(xy 51.421771 -279.636493) (xy 51.437481 -279.687423) (xy 51.445424 -279.740127) (xy 51.445922 -279.766776)
			(xy 51.445424 -279.793425) (xy 51.437481 -279.846129) (xy 51.421771 -279.897059) (xy 51.398645 -279.94508)
			(xy 51.368621 -279.989117) (xy 51.332369 -280.028188) (xy 51.290698 -280.061419) (xy 51.24454 -280.088068)
			(xy 51.194926 -280.10754) (xy 51.142964 -280.1194) (xy 51.089814 -280.123384) (xy 51.036664 -280.1194)
			(xy 50.984702 -280.10754) (xy 50.935088 -280.088068) (xy 50.88893 -280.061419) (xy 50.847259 -280.028188)
			(xy 50.811007 -279.989117) (xy 50.780983 -279.94508) (xy 50.757857 -279.897059) (xy 50.742147 -279.846129)
			(xy 50.734204 -279.793425) (xy 36.332424 -279.793425) (xy 36.324481 -279.846129) (xy 36.308771 -279.897059)
			(xy 36.285645 -279.94508) (xy 36.255621 -279.989117) (xy 36.219369 -280.028188) (xy 36.177698 -280.061419)
			(xy 36.13154 -280.088068) (xy 36.081926 -280.10754) (xy 36.029964 -280.1194) (xy 35.976814 -280.123384)
			(xy 35.923664 -280.1194) (xy 35.871702 -280.10754) (xy 35.822088 -280.088068) (xy 35.77593 -280.061419)
			(xy 35.734259 -280.028188) (xy 35.698007 -279.989117) (xy 35.667983 -279.94508) (xy 35.644857 -279.897059)
			(xy 35.629147 -279.846129) (xy 35.621204 -279.793425) (xy 21.244824 -279.793425) (xy 21.236881 -279.846129)
			(xy 21.221171 -279.897059) (xy 21.198045 -279.94508) (xy 21.168021 -279.989117) (xy 21.131769 -280.028188)
			(xy 21.090098 -280.061419) (xy 21.04394 -280.088068) (xy 20.994326 -280.10754) (xy 20.942364 -280.1194)
			(xy 20.889214 -280.123384) (xy 20.836064 -280.1194) (xy 20.784102 -280.10754) (xy 20.734488 -280.088068)
			(xy 20.68833 -280.061419) (xy 20.646659 -280.028188) (xy 20.610407 -279.989117) (xy 20.580383 -279.94508)
			(xy 20.557257 -279.897059) (xy 20.541547 -279.846129) (xy 20.533604 -279.793425) (xy 9.6774 -279.793425)
			(xy 9.6774 -280.643309) (xy 16.433536 -280.643309) (xy 16.433536 -280.590011) (xy 16.441479 -280.537307)
			(xy 16.457189 -280.486377) (xy 16.480315 -280.438356) (xy 16.510339 -280.394319) (xy 16.546591 -280.355248)
			(xy 16.588262 -280.322017) (xy 16.63442 -280.295368) (xy 16.684034 -280.275896) (xy 16.735996 -280.264036)
			(xy 16.789146 -280.260053) (xy 16.842296 -280.264036) (xy 16.894258 -280.275896) (xy 16.943872 -280.295368)
			(xy 16.99003 -280.322017) (xy 17.031701 -280.355248) (xy 17.067953 -280.394319) (xy 17.097977 -280.438356)
			(xy 17.121103 -280.486377) (xy 17.136813 -280.537307) (xy 17.144756 -280.590011) (xy 17.145254 -280.61666)
			(xy 17.144756 -280.643309) (xy 31.521136 -280.643309) (xy 31.521136 -280.590011) (xy 31.529079 -280.537307)
			(xy 31.544789 -280.486377) (xy 31.567915 -280.438356) (xy 31.597939 -280.394319) (xy 31.634191 -280.355248)
			(xy 31.675862 -280.322017) (xy 31.72202 -280.295368) (xy 31.771634 -280.275896) (xy 31.823596 -280.264036)
			(xy 31.876746 -280.260053) (xy 31.929896 -280.264036) (xy 31.981858 -280.275896) (xy 32.031472 -280.295368)
			(xy 32.07763 -280.322017) (xy 32.119301 -280.355248) (xy 32.155553 -280.394319) (xy 32.185577 -280.438356)
			(xy 32.208703 -280.486377) (xy 32.224413 -280.537307) (xy 32.232356 -280.590011) (xy 32.232854 -280.61666)
			(xy 32.232356 -280.643309) (xy 46.608736 -280.643309) (xy 46.608736 -280.590011) (xy 46.616679 -280.537307)
			(xy 46.632389 -280.486377) (xy 46.655515 -280.438356) (xy 46.685539 -280.394319) (xy 46.721791 -280.355248)
			(xy 46.763462 -280.322017) (xy 46.80962 -280.295368) (xy 46.859234 -280.275896) (xy 46.911196 -280.264036)
			(xy 46.964346 -280.260053) (xy 47.017496 -280.264036) (xy 47.069458 -280.275896) (xy 47.119072 -280.295368)
			(xy 47.16523 -280.322017) (xy 47.206901 -280.355248) (xy 47.243153 -280.394319) (xy 47.273177 -280.438356)
			(xy 47.296303 -280.486377) (xy 47.312013 -280.537307) (xy 47.319956 -280.590011) (xy 47.320454 -280.61666)
			(xy 47.319956 -280.643309) (xy 47.312013 -280.696013) (xy 47.296303 -280.746943) (xy 47.273177 -280.794964)
			(xy 47.243153 -280.839001) (xy 47.206901 -280.878072) (xy 47.16523 -280.911303) (xy 47.119072 -280.937952)
			(xy 47.069458 -280.957424) (xy 47.017496 -280.969284) (xy 46.964346 -280.973268) (xy 46.911196 -280.969284)
			(xy 46.859234 -280.957424) (xy 46.80962 -280.937952) (xy 46.763462 -280.911303) (xy 46.721791 -280.878072)
			(xy 46.685539 -280.839001) (xy 46.655515 -280.794964) (xy 46.632389 -280.746943) (xy 46.616679 -280.696013)
			(xy 46.608736 -280.643309) (xy 32.232356 -280.643309) (xy 32.224413 -280.696013) (xy 32.208703 -280.746943)
			(xy 32.185577 -280.794964) (xy 32.155553 -280.839001) (xy 32.119301 -280.878072) (xy 32.07763 -280.911303)
			(xy 32.031472 -280.937952) (xy 31.981858 -280.957424) (xy 31.929896 -280.969284) (xy 31.876746 -280.973268)
			(xy 31.823596 -280.969284) (xy 31.771634 -280.957424) (xy 31.72202 -280.937952) (xy 31.675862 -280.911303)
			(xy 31.634191 -280.878072) (xy 31.597939 -280.839001) (xy 31.567915 -280.794964) (xy 31.544789 -280.746943)
			(xy 31.529079 -280.696013) (xy 31.521136 -280.643309) (xy 17.144756 -280.643309) (xy 17.136813 -280.696013)
			(xy 17.121103 -280.746943) (xy 17.097977 -280.794964) (xy 17.067953 -280.839001) (xy 17.031701 -280.878072)
			(xy 16.99003 -280.911303) (xy 16.943872 -280.937952) (xy 16.894258 -280.957424) (xy 16.842296 -280.969284)
			(xy 16.789146 -280.973268) (xy 16.735996 -280.969284) (xy 16.684034 -280.957424) (xy 16.63442 -280.937952)
			(xy 16.588262 -280.911303) (xy 16.546591 -280.878072) (xy 16.510339 -280.839001) (xy 16.480315 -280.794964)
			(xy 16.457189 -280.746943) (xy 16.441479 -280.696013) (xy 16.433536 -280.643309) (xy 9.6774 -280.643309)
			(xy 9.6774 -281.493447) (xy 20.533604 -281.493447) (xy 20.533604 -281.440149) (xy 20.541547 -281.387445)
			(xy 20.557257 -281.336515) (xy 20.580383 -281.288494) (xy 20.610407 -281.244457) (xy 20.646659 -281.205386)
			(xy 20.68833 -281.172155) (xy 20.734488 -281.145506) (xy 20.784102 -281.126034) (xy 20.836064 -281.114174)
			(xy 20.889214 -281.110191) (xy 20.942364 -281.114174) (xy 20.994326 -281.126034) (xy 21.04394 -281.145506)
			(xy 21.090098 -281.172155) (xy 21.131769 -281.205386) (xy 21.168021 -281.244457) (xy 21.198045 -281.288494)
			(xy 21.221171 -281.336515) (xy 21.236881 -281.387445) (xy 21.244824 -281.440149) (xy 21.245322 -281.466798)
			(xy 21.244824 -281.493447) (xy 35.621204 -281.493447) (xy 35.621204 -281.440149) (xy 35.629147 -281.387445)
			(xy 35.644857 -281.336515) (xy 35.667983 -281.288494) (xy 35.698007 -281.244457) (xy 35.734259 -281.205386)
			(xy 35.77593 -281.172155) (xy 35.822088 -281.145506) (xy 35.871702 -281.126034) (xy 35.923664 -281.114174)
			(xy 35.976814 -281.110191) (xy 36.029964 -281.114174) (xy 36.081926 -281.126034) (xy 36.13154 -281.145506)
			(xy 36.177698 -281.172155) (xy 36.219369 -281.205386) (xy 36.255621 -281.244457) (xy 36.285645 -281.288494)
			(xy 36.308771 -281.336515) (xy 36.324481 -281.387445) (xy 36.332424 -281.440149) (xy 36.332922 -281.466798)
			(xy 36.332424 -281.493447) (xy 50.734204 -281.493447) (xy 50.734204 -281.440149) (xy 50.742147 -281.387445)
			(xy 50.757857 -281.336515) (xy 50.780983 -281.288494) (xy 50.811007 -281.244457) (xy 50.847259 -281.205386)
			(xy 50.88893 -281.172155) (xy 50.935088 -281.145506) (xy 50.984702 -281.126034) (xy 51.036664 -281.114174)
			(xy 51.089814 -281.110191) (xy 51.142964 -281.114174) (xy 51.194926 -281.126034) (xy 51.24454 -281.145506)
			(xy 51.290698 -281.172155) (xy 51.332369 -281.205386) (xy 51.368621 -281.244457) (xy 51.398645 -281.288494)
			(xy 51.421771 -281.336515) (xy 51.437481 -281.387445) (xy 51.445424 -281.440149) (xy 51.445922 -281.466798)
			(xy 51.445424 -281.493447) (xy 51.437481 -281.546151) (xy 51.421771 -281.597081) (xy 51.398645 -281.645102)
			(xy 51.368621 -281.689139) (xy 51.332369 -281.72821) (xy 51.290698 -281.761441) (xy 51.24454 -281.78809)
			(xy 51.194926 -281.807562) (xy 51.142964 -281.819422) (xy 51.089814 -281.823406) (xy 51.036664 -281.819422)
			(xy 50.984702 -281.807562) (xy 50.935088 -281.78809) (xy 50.88893 -281.761441) (xy 50.847259 -281.72821)
			(xy 50.811007 -281.689139) (xy 50.780983 -281.645102) (xy 50.757857 -281.597081) (xy 50.742147 -281.546151)
			(xy 50.734204 -281.493447) (xy 36.332424 -281.493447) (xy 36.324481 -281.546151) (xy 36.308771 -281.597081)
			(xy 36.285645 -281.645102) (xy 36.255621 -281.689139) (xy 36.219369 -281.72821) (xy 36.177698 -281.761441)
			(xy 36.13154 -281.78809) (xy 36.081926 -281.807562) (xy 36.029964 -281.819422) (xy 35.976814 -281.823406)
			(xy 35.923664 -281.819422) (xy 35.871702 -281.807562) (xy 35.822088 -281.78809) (xy 35.77593 -281.761441)
			(xy 35.734259 -281.72821) (xy 35.698007 -281.689139) (xy 35.667983 -281.645102) (xy 35.644857 -281.597081)
			(xy 35.629147 -281.546151) (xy 35.621204 -281.493447) (xy 21.244824 -281.493447) (xy 21.236881 -281.546151)
			(xy 21.221171 -281.597081) (xy 21.198045 -281.645102) (xy 21.168021 -281.689139) (xy 21.131769 -281.72821)
			(xy 21.090098 -281.761441) (xy 21.04394 -281.78809) (xy 20.994326 -281.807562) (xy 20.942364 -281.819422)
			(xy 20.889214 -281.823406) (xy 20.836064 -281.819422) (xy 20.784102 -281.807562) (xy 20.734488 -281.78809)
			(xy 20.68833 -281.761441) (xy 20.646659 -281.72821) (xy 20.610407 -281.689139) (xy 20.580383 -281.645102)
			(xy 20.557257 -281.597081) (xy 20.541547 -281.546151) (xy 20.533604 -281.493447) (xy 9.6774 -281.493447)
			(xy 9.6774 -282.343331) (xy 16.433536 -282.343331) (xy 16.433536 -282.290033) (xy 16.441479 -282.237329)
			(xy 16.457189 -282.186399) (xy 16.480315 -282.138378) (xy 16.510339 -282.094341) (xy 16.546591 -282.05527)
			(xy 16.588262 -282.022039) (xy 16.63442 -281.99539) (xy 16.684034 -281.975918) (xy 16.735996 -281.964058)
			(xy 16.789146 -281.960075) (xy 16.842296 -281.964058) (xy 16.894258 -281.975918) (xy 16.943872 -281.99539)
			(xy 16.99003 -282.022039) (xy 17.031701 -282.05527) (xy 17.067953 -282.094341) (xy 17.097977 -282.138378)
			(xy 17.121103 -282.186399) (xy 17.136813 -282.237329) (xy 17.144756 -282.290033) (xy 17.145254 -282.316682)
			(xy 17.144756 -282.343331) (xy 31.521136 -282.343331) (xy 31.521136 -282.290033) (xy 31.529079 -282.237329)
			(xy 31.544789 -282.186399) (xy 31.567915 -282.138378) (xy 31.597939 -282.094341) (xy 31.634191 -282.05527)
			(xy 31.675862 -282.022039) (xy 31.72202 -281.99539) (xy 31.771634 -281.975918) (xy 31.823596 -281.964058)
			(xy 31.876746 -281.960075) (xy 31.929896 -281.964058) (xy 31.981858 -281.975918) (xy 32.031472 -281.99539)
			(xy 32.07763 -282.022039) (xy 32.119301 -282.05527) (xy 32.155553 -282.094341) (xy 32.185577 -282.138378)
			(xy 32.208703 -282.186399) (xy 32.224413 -282.237329) (xy 32.232356 -282.290033) (xy 32.232854 -282.316682)
			(xy 32.232356 -282.343331) (xy 46.608736 -282.343331) (xy 46.608736 -282.290033) (xy 46.616679 -282.237329)
			(xy 46.632389 -282.186399) (xy 46.655515 -282.138378) (xy 46.685539 -282.094341) (xy 46.721791 -282.05527)
			(xy 46.763462 -282.022039) (xy 46.80962 -281.99539) (xy 46.859234 -281.975918) (xy 46.911196 -281.964058)
			(xy 46.964346 -281.960075) (xy 47.017496 -281.964058) (xy 47.069458 -281.975918) (xy 47.119072 -281.99539)
			(xy 47.16523 -282.022039) (xy 47.206901 -282.05527) (xy 47.243153 -282.094341) (xy 47.273177 -282.138378)
			(xy 47.296303 -282.186399) (xy 47.312013 -282.237329) (xy 47.319956 -282.290033) (xy 47.320454 -282.316682)
			(xy 47.319956 -282.343331) (xy 47.312013 -282.396035) (xy 47.296303 -282.446965) (xy 47.273177 -282.494986)
			(xy 47.243153 -282.539023) (xy 47.206901 -282.578094) (xy 47.16523 -282.611325) (xy 47.119072 -282.637974)
			(xy 47.069458 -282.657446) (xy 47.017496 -282.669306) (xy 46.964346 -282.67329) (xy 46.911196 -282.669306)
			(xy 46.859234 -282.657446) (xy 46.80962 -282.637974) (xy 46.763462 -282.611325) (xy 46.721791 -282.578094)
			(xy 46.685539 -282.539023) (xy 46.655515 -282.494986) (xy 46.632389 -282.446965) (xy 46.616679 -282.396035)
			(xy 46.608736 -282.343331) (xy 32.232356 -282.343331) (xy 32.224413 -282.396035) (xy 32.208703 -282.446965)
			(xy 32.185577 -282.494986) (xy 32.155553 -282.539023) (xy 32.119301 -282.578094) (xy 32.07763 -282.611325)
			(xy 32.031472 -282.637974) (xy 31.981858 -282.657446) (xy 31.929896 -282.669306) (xy 31.876746 -282.67329)
			(xy 31.823596 -282.669306) (xy 31.771634 -282.657446) (xy 31.72202 -282.637974) (xy 31.675862 -282.611325)
			(xy 31.634191 -282.578094) (xy 31.597939 -282.539023) (xy 31.567915 -282.494986) (xy 31.544789 -282.446965)
			(xy 31.529079 -282.396035) (xy 31.521136 -282.343331) (xy 17.144756 -282.343331) (xy 17.136813 -282.396035)
			(xy 17.121103 -282.446965) (xy 17.097977 -282.494986) (xy 17.067953 -282.539023) (xy 17.031701 -282.578094)
			(xy 16.99003 -282.611325) (xy 16.943872 -282.637974) (xy 16.894258 -282.657446) (xy 16.842296 -282.669306)
			(xy 16.789146 -282.67329) (xy 16.735996 -282.669306) (xy 16.684034 -282.657446) (xy 16.63442 -282.637974)
			(xy 16.588262 -282.611325) (xy 16.546591 -282.578094) (xy 16.510339 -282.539023) (xy 16.480315 -282.494986)
			(xy 16.457189 -282.446965) (xy 16.441479 -282.396035) (xy 16.433536 -282.343331) (xy 9.6774 -282.343331)
			(xy 9.6774 -283.193215) (xy 20.533604 -283.193215) (xy 20.533604 -283.139917) (xy 20.541547 -283.087213)
			(xy 20.557257 -283.036283) (xy 20.580383 -282.988262) (xy 20.610407 -282.944225) (xy 20.646659 -282.905154)
			(xy 20.68833 -282.871923) (xy 20.734488 -282.845274) (xy 20.784102 -282.825802) (xy 20.836064 -282.813942)
			(xy 20.889214 -282.809959) (xy 20.942364 -282.813942) (xy 20.994326 -282.825802) (xy 21.04394 -282.845274)
			(xy 21.090098 -282.871923) (xy 21.131769 -282.905154) (xy 21.168021 -282.944225) (xy 21.198045 -282.988262)
			(xy 21.221171 -283.036283) (xy 21.236881 -283.087213) (xy 21.244824 -283.139917) (xy 21.245322 -283.166566)
			(xy 21.244824 -283.193215) (xy 35.621204 -283.193215) (xy 35.621204 -283.139917) (xy 35.629147 -283.087213)
			(xy 35.644857 -283.036283) (xy 35.667983 -282.988262) (xy 35.698007 -282.944225) (xy 35.734259 -282.905154)
			(xy 35.77593 -282.871923) (xy 35.822088 -282.845274) (xy 35.871702 -282.825802) (xy 35.923664 -282.813942)
			(xy 35.976814 -282.809959) (xy 36.029964 -282.813942) (xy 36.081926 -282.825802) (xy 36.13154 -282.845274)
			(xy 36.177698 -282.871923) (xy 36.219369 -282.905154) (xy 36.255621 -282.944225) (xy 36.285645 -282.988262)
			(xy 36.308771 -283.036283) (xy 36.324481 -283.087213) (xy 36.332424 -283.139917) (xy 36.332922 -283.166566)
			(xy 36.332424 -283.193215) (xy 36.332386 -283.193469) (xy 50.734204 -283.193469) (xy 50.734204 -283.140171)
			(xy 50.742147 -283.087467) (xy 50.757857 -283.036537) (xy 50.780983 -282.988516) (xy 50.811007 -282.944479)
			(xy 50.847259 -282.905408) (xy 50.88893 -282.872177) (xy 50.935088 -282.845528) (xy 50.984702 -282.826056)
			(xy 51.036664 -282.814196) (xy 51.089814 -282.810213) (xy 51.142964 -282.814196) (xy 51.194926 -282.826056)
			(xy 51.24454 -282.845528) (xy 51.290698 -282.872177) (xy 51.332369 -282.905408) (xy 51.368621 -282.944479)
			(xy 51.398645 -282.988516) (xy 51.421771 -283.036537) (xy 51.437481 -283.087467) (xy 51.445424 -283.140171)
			(xy 51.445922 -283.16682) (xy 51.445424 -283.193469) (xy 51.437481 -283.246173) (xy 51.421771 -283.297103)
			(xy 51.398645 -283.345124) (xy 51.368621 -283.389161) (xy 51.332369 -283.428232) (xy 51.290698 -283.461463)
			(xy 51.24454 -283.488112) (xy 51.194926 -283.507584) (xy 51.142964 -283.519444) (xy 51.089814 -283.523428)
			(xy 51.036664 -283.519444) (xy 50.984702 -283.507584) (xy 50.935088 -283.488112) (xy 50.88893 -283.461463)
			(xy 50.847259 -283.428232) (xy 50.811007 -283.389161) (xy 50.780983 -283.345124) (xy 50.757857 -283.297103)
			(xy 50.742147 -283.246173) (xy 50.734204 -283.193469) (xy 36.332386 -283.193469) (xy 36.324481 -283.245919)
			(xy 36.308771 -283.296849) (xy 36.285645 -283.34487) (xy 36.255621 -283.388907) (xy 36.219369 -283.427978)
			(xy 36.177698 -283.461209) (xy 36.13154 -283.487858) (xy 36.081926 -283.50733) (xy 36.029964 -283.51919)
			(xy 35.976814 -283.523174) (xy 35.923664 -283.51919) (xy 35.871702 -283.50733) (xy 35.822088 -283.487858)
			(xy 35.77593 -283.461209) (xy 35.734259 -283.427978) (xy 35.698007 -283.388907) (xy 35.667983 -283.34487)
			(xy 35.644857 -283.296849) (xy 35.629147 -283.245919) (xy 35.621204 -283.193215) (xy 21.244824 -283.193215)
			(xy 21.236881 -283.245919) (xy 21.221171 -283.296849) (xy 21.198045 -283.34487) (xy 21.168021 -283.388907)
			(xy 21.131769 -283.427978) (xy 21.090098 -283.461209) (xy 21.04394 -283.487858) (xy 20.994326 -283.50733)
			(xy 20.942364 -283.51919) (xy 20.889214 -283.523174) (xy 20.836064 -283.51919) (xy 20.784102 -283.50733)
			(xy 20.734488 -283.487858) (xy 20.68833 -283.461209) (xy 20.646659 -283.427978) (xy 20.610407 -283.388907)
			(xy 20.580383 -283.34487) (xy 20.557257 -283.296849) (xy 20.541547 -283.245919) (xy 20.533604 -283.193215)
			(xy 9.6774 -283.193215) (xy 9.6774 -284.043353) (xy 16.433536 -284.043353) (xy 16.433536 -283.990055)
			(xy 16.441479 -283.937351) (xy 16.457189 -283.886421) (xy 16.480315 -283.8384) (xy 16.510339 -283.794363)
			(xy 16.546591 -283.755292) (xy 16.588262 -283.722061) (xy 16.63442 -283.695412) (xy 16.684034 -283.67594)
			(xy 16.735996 -283.66408) (xy 16.789146 -283.660097) (xy 16.842296 -283.66408) (xy 16.894258 -283.67594)
			(xy 16.943872 -283.695412) (xy 16.99003 -283.722061) (xy 17.031701 -283.755292) (xy 17.067953 -283.794363)
			(xy 17.097977 -283.8384) (xy 17.121103 -283.886421) (xy 17.136813 -283.937351) (xy 17.144756 -283.990055)
			(xy 17.145254 -284.016704) (xy 17.144756 -284.043353) (xy 20.533604 -284.043353) (xy 20.533604 -283.990055)
			(xy 20.541547 -283.937351) (xy 20.557257 -283.886421) (xy 20.580383 -283.8384) (xy 20.610407 -283.794363)
			(xy 20.646659 -283.755292) (xy 20.68833 -283.722061) (xy 20.734488 -283.695412) (xy 20.784102 -283.67594)
			(xy 20.836064 -283.66408) (xy 20.889214 -283.660097) (xy 20.942364 -283.66408) (xy 20.994326 -283.67594)
			(xy 21.04394 -283.695412) (xy 21.090098 -283.722061) (xy 21.131769 -283.755292) (xy 21.168021 -283.794363)
			(xy 21.198045 -283.8384) (xy 21.221171 -283.886421) (xy 21.236881 -283.937351) (xy 21.244824 -283.990055)
			(xy 21.245322 -284.016704) (xy 21.244824 -284.043353) (xy 31.521136 -284.043353) (xy 31.521136 -283.990055)
			(xy 31.529079 -283.937351) (xy 31.544789 -283.886421) (xy 31.567915 -283.8384) (xy 31.597939 -283.794363)
			(xy 31.634191 -283.755292) (xy 31.675862 -283.722061) (xy 31.72202 -283.695412) (xy 31.771634 -283.67594)
			(xy 31.823596 -283.66408) (xy 31.876746 -283.660097) (xy 31.929896 -283.66408) (xy 31.981858 -283.67594)
			(xy 32.031472 -283.695412) (xy 32.07763 -283.722061) (xy 32.119301 -283.755292) (xy 32.155553 -283.794363)
			(xy 32.185577 -283.8384) (xy 32.208703 -283.886421) (xy 32.224413 -283.937351) (xy 32.232356 -283.990055)
			(xy 32.232854 -284.016704) (xy 32.232356 -284.043353) (xy 35.621204 -284.043353) (xy 35.621204 -283.990055)
			(xy 35.629147 -283.937351) (xy 35.644857 -283.886421) (xy 35.667983 -283.8384) (xy 35.698007 -283.794363)
			(xy 35.734259 -283.755292) (xy 35.77593 -283.722061) (xy 35.822088 -283.695412) (xy 35.871702 -283.67594)
			(xy 35.923664 -283.66408) (xy 35.976814 -283.660097) (xy 36.029964 -283.66408) (xy 36.081926 -283.67594)
			(xy 36.13154 -283.695412) (xy 36.177698 -283.722061) (xy 36.219369 -283.755292) (xy 36.255621 -283.794363)
			(xy 36.285645 -283.8384) (xy 36.308771 -283.886421) (xy 36.324481 -283.937351) (xy 36.332424 -283.990055)
			(xy 36.332922 -284.016704) (xy 36.332424 -284.043353) (xy 46.608736 -284.043353) (xy 46.608736 -283.990055)
			(xy 46.616679 -283.937351) (xy 46.632389 -283.886421) (xy 46.655515 -283.8384) (xy 46.685539 -283.794363)
			(xy 46.721791 -283.755292) (xy 46.763462 -283.722061) (xy 46.80962 -283.695412) (xy 46.859234 -283.67594)
			(xy 46.911196 -283.66408) (xy 46.964346 -283.660097) (xy 47.017496 -283.66408) (xy 47.069458 -283.67594)
			(xy 47.119072 -283.695412) (xy 47.16523 -283.722061) (xy 47.206901 -283.755292) (xy 47.243153 -283.794363)
			(xy 47.273177 -283.8384) (xy 47.296303 -283.886421) (xy 47.312013 -283.937351) (xy 47.319956 -283.990055)
			(xy 47.320454 -284.016704) (xy 47.319956 -284.043353) (xy 47.319918 -284.043607) (xy 50.734204 -284.043607)
			(xy 50.734204 -283.990309) (xy 50.742147 -283.937605) (xy 50.757857 -283.886675) (xy 50.780983 -283.838654)
			(xy 50.811007 -283.794617) (xy 50.847259 -283.755546) (xy 50.88893 -283.722315) (xy 50.935088 -283.695666)
			(xy 50.984702 -283.676194) (xy 51.036664 -283.664334) (xy 51.089814 -283.660351) (xy 51.142964 -283.664334)
			(xy 51.194926 -283.676194) (xy 51.24454 -283.695666) (xy 51.290698 -283.722315) (xy 51.332369 -283.755546)
			(xy 51.368621 -283.794617) (xy 51.398645 -283.838654) (xy 51.421771 -283.886675) (xy 51.437481 -283.937605)
			(xy 51.445424 -283.990309) (xy 51.445922 -284.016958) (xy 51.445424 -284.043607) (xy 51.437481 -284.096311)
			(xy 51.421771 -284.147241) (xy 51.398645 -284.195262) (xy 51.368621 -284.239299) (xy 51.332369 -284.27837)
			(xy 51.290698 -284.311601) (xy 51.24454 -284.33825) (xy 51.194926 -284.357722) (xy 51.142964 -284.369582)
			(xy 51.089814 -284.373566) (xy 51.036664 -284.369582) (xy 50.984702 -284.357722) (xy 50.935088 -284.33825)
			(xy 50.88893 -284.311601) (xy 50.847259 -284.27837) (xy 50.811007 -284.239299) (xy 50.780983 -284.195262)
			(xy 50.757857 -284.147241) (xy 50.742147 -284.096311) (xy 50.734204 -284.043607) (xy 47.319918 -284.043607)
			(xy 47.312013 -284.096057) (xy 47.296303 -284.146987) (xy 47.273177 -284.195008) (xy 47.243153 -284.239045)
			(xy 47.206901 -284.278116) (xy 47.16523 -284.311347) (xy 47.119072 -284.337996) (xy 47.069458 -284.357468)
			(xy 47.017496 -284.369328) (xy 46.964346 -284.373312) (xy 46.911196 -284.369328) (xy 46.859234 -284.357468)
			(xy 46.80962 -284.337996) (xy 46.763462 -284.311347) (xy 46.721791 -284.278116) (xy 46.685539 -284.239045)
			(xy 46.655515 -284.195008) (xy 46.632389 -284.146987) (xy 46.616679 -284.096057) (xy 46.608736 -284.043353)
			(xy 36.332424 -284.043353) (xy 36.324481 -284.096057) (xy 36.308771 -284.146987) (xy 36.285645 -284.195008)
			(xy 36.255621 -284.239045) (xy 36.219369 -284.278116) (xy 36.177698 -284.311347) (xy 36.13154 -284.337996)
			(xy 36.081926 -284.357468) (xy 36.029964 -284.369328) (xy 35.976814 -284.373312) (xy 35.923664 -284.369328)
			(xy 35.871702 -284.357468) (xy 35.822088 -284.337996) (xy 35.77593 -284.311347) (xy 35.734259 -284.278116)
			(xy 35.698007 -284.239045) (xy 35.667983 -284.195008) (xy 35.644857 -284.146987) (xy 35.629147 -284.096057)
			(xy 35.621204 -284.043353) (xy 32.232356 -284.043353) (xy 32.224413 -284.096057) (xy 32.208703 -284.146987)
			(xy 32.185577 -284.195008) (xy 32.155553 -284.239045) (xy 32.119301 -284.278116) (xy 32.07763 -284.311347)
			(xy 32.031472 -284.337996) (xy 31.981858 -284.357468) (xy 31.929896 -284.369328) (xy 31.876746 -284.373312)
			(xy 31.823596 -284.369328) (xy 31.771634 -284.357468) (xy 31.72202 -284.337996) (xy 31.675862 -284.311347)
			(xy 31.634191 -284.278116) (xy 31.597939 -284.239045) (xy 31.567915 -284.195008) (xy 31.544789 -284.146987)
			(xy 31.529079 -284.096057) (xy 31.521136 -284.043353) (xy 21.244824 -284.043353) (xy 21.236881 -284.096057)
			(xy 21.221171 -284.146987) (xy 21.198045 -284.195008) (xy 21.168021 -284.239045) (xy 21.131769 -284.278116)
			(xy 21.090098 -284.311347) (xy 21.04394 -284.337996) (xy 20.994326 -284.357468) (xy 20.942364 -284.369328)
			(xy 20.889214 -284.373312) (xy 20.836064 -284.369328) (xy 20.784102 -284.357468) (xy 20.734488 -284.337996)
			(xy 20.68833 -284.311347) (xy 20.646659 -284.278116) (xy 20.610407 -284.239045) (xy 20.580383 -284.195008)
			(xy 20.557257 -284.146987) (xy 20.541547 -284.096057) (xy 20.533604 -284.043353) (xy 17.144756 -284.043353)
			(xy 17.136813 -284.096057) (xy 17.121103 -284.146987) (xy 17.097977 -284.195008) (xy 17.067953 -284.239045)
			(xy 17.031701 -284.278116) (xy 16.99003 -284.311347) (xy 16.943872 -284.337996) (xy 16.894258 -284.357468)
			(xy 16.842296 -284.369328) (xy 16.789146 -284.373312) (xy 16.735996 -284.369328) (xy 16.684034 -284.357468)
			(xy 16.63442 -284.337996) (xy 16.588262 -284.311347) (xy 16.546591 -284.278116) (xy 16.510339 -284.239045)
			(xy 16.480315 -284.195008) (xy 16.457189 -284.146987) (xy 16.441479 -284.096057) (xy 16.433536 -284.043353)
			(xy 9.6774 -284.043353) (xy 9.6774 -284.893237) (xy 16.433536 -284.893237) (xy 16.433536 -284.839939)
			(xy 16.441479 -284.787235) (xy 16.457189 -284.736305) (xy 16.480315 -284.688284) (xy 16.510339 -284.644247)
			(xy 16.546591 -284.605176) (xy 16.588262 -284.571945) (xy 16.63442 -284.545296) (xy 16.684034 -284.525824)
			(xy 16.735996 -284.513964) (xy 16.789146 -284.509981) (xy 16.842296 -284.513964) (xy 16.894258 -284.525824)
			(xy 16.943872 -284.545296) (xy 16.99003 -284.571945) (xy 17.031701 -284.605176) (xy 17.067953 -284.644247)
			(xy 17.097977 -284.688284) (xy 17.121103 -284.736305) (xy 17.136813 -284.787235) (xy 17.144756 -284.839939)
			(xy 17.145254 -284.866588) (xy 17.144756 -284.893237) (xy 31.521136 -284.893237) (xy 31.521136 -284.839939)
			(xy 31.529079 -284.787235) (xy 31.544789 -284.736305) (xy 31.567915 -284.688284) (xy 31.597939 -284.644247)
			(xy 31.634191 -284.605176) (xy 31.675862 -284.571945) (xy 31.72202 -284.545296) (xy 31.771634 -284.525824)
			(xy 31.823596 -284.513964) (xy 31.876746 -284.509981) (xy 31.929896 -284.513964) (xy 31.981858 -284.525824)
			(xy 32.031472 -284.545296) (xy 32.07763 -284.571945) (xy 32.119301 -284.605176) (xy 32.155553 -284.644247)
			(xy 32.185577 -284.688284) (xy 32.208703 -284.736305) (xy 32.224413 -284.787235) (xy 32.232356 -284.839939)
			(xy 32.232854 -284.866588) (xy 32.232356 -284.893237) (xy 46.608736 -284.893237) (xy 46.608736 -284.839939)
			(xy 46.616679 -284.787235) (xy 46.632389 -284.736305) (xy 46.655515 -284.688284) (xy 46.685539 -284.644247)
			(xy 46.721791 -284.605176) (xy 46.763462 -284.571945) (xy 46.80962 -284.545296) (xy 46.859234 -284.525824)
			(xy 46.911196 -284.513964) (xy 46.964346 -284.509981) (xy 47.017496 -284.513964) (xy 47.069458 -284.525824)
			(xy 47.119072 -284.545296) (xy 47.16523 -284.571945) (xy 47.206901 -284.605176) (xy 47.243153 -284.644247)
			(xy 47.273177 -284.688284) (xy 47.296303 -284.736305) (xy 47.312013 -284.787235) (xy 47.319956 -284.839939)
			(xy 47.320454 -284.866588) (xy 47.319956 -284.893237) (xy 47.312013 -284.945941) (xy 47.296303 -284.996871)
			(xy 47.273177 -285.044892) (xy 47.243153 -285.088929) (xy 47.206901 -285.128) (xy 47.16523 -285.161231)
			(xy 47.119072 -285.18788) (xy 47.069458 -285.207352) (xy 47.017496 -285.219212) (xy 46.964346 -285.223196)
			(xy 46.911196 -285.219212) (xy 46.859234 -285.207352) (xy 46.80962 -285.18788) (xy 46.763462 -285.161231)
			(xy 46.721791 -285.128) (xy 46.685539 -285.088929) (xy 46.655515 -285.044892) (xy 46.632389 -284.996871)
			(xy 46.616679 -284.945941) (xy 46.608736 -284.893237) (xy 32.232356 -284.893237) (xy 32.224413 -284.945941)
			(xy 32.208703 -284.996871) (xy 32.185577 -285.044892) (xy 32.155553 -285.088929) (xy 32.119301 -285.128)
			(xy 32.07763 -285.161231) (xy 32.031472 -285.18788) (xy 31.981858 -285.207352) (xy 31.929896 -285.219212)
			(xy 31.876746 -285.223196) (xy 31.823596 -285.219212) (xy 31.771634 -285.207352) (xy 31.72202 -285.18788)
			(xy 31.675862 -285.161231) (xy 31.634191 -285.128) (xy 31.597939 -285.088929) (xy 31.567915 -285.044892)
			(xy 31.544789 -284.996871) (xy 31.529079 -284.945941) (xy 31.521136 -284.893237) (xy 17.144756 -284.893237)
			(xy 17.136813 -284.945941) (xy 17.121103 -284.996871) (xy 17.097977 -285.044892) (xy 17.067953 -285.088929)
			(xy 17.031701 -285.128) (xy 16.99003 -285.161231) (xy 16.943872 -285.18788) (xy 16.894258 -285.207352)
			(xy 16.842296 -285.219212) (xy 16.789146 -285.223196) (xy 16.735996 -285.219212) (xy 16.684034 -285.207352)
			(xy 16.63442 -285.18788) (xy 16.588262 -285.161231) (xy 16.546591 -285.128) (xy 16.510339 -285.088929)
			(xy 16.480315 -285.044892) (xy 16.457189 -284.996871) (xy 16.441479 -284.945941) (xy 16.433536 -284.893237)
			(xy 9.6774 -284.893237) (xy 9.6774 -285.743375) (xy 20.533604 -285.743375) (xy 20.533604 -285.690077)
			(xy 20.541547 -285.637373) (xy 20.557257 -285.586443) (xy 20.580383 -285.538422) (xy 20.610407 -285.494385)
			(xy 20.646659 -285.455314) (xy 20.68833 -285.422083) (xy 20.734488 -285.395434) (xy 20.784102 -285.375962)
			(xy 20.836064 -285.364102) (xy 20.889214 -285.360119) (xy 20.942364 -285.364102) (xy 20.994326 -285.375962)
			(xy 21.04394 -285.395434) (xy 21.090098 -285.422083) (xy 21.131769 -285.455314) (xy 21.168021 -285.494385)
			(xy 21.198045 -285.538422) (xy 21.221171 -285.586443) (xy 21.236881 -285.637373) (xy 21.244824 -285.690077)
			(xy 21.245322 -285.716726) (xy 21.244824 -285.743375) (xy 35.621204 -285.743375) (xy 35.621204 -285.690077)
			(xy 35.629147 -285.637373) (xy 35.644857 -285.586443) (xy 35.667983 -285.538422) (xy 35.698007 -285.494385)
			(xy 35.734259 -285.455314) (xy 35.77593 -285.422083) (xy 35.822088 -285.395434) (xy 35.871702 -285.375962)
			(xy 35.923664 -285.364102) (xy 35.976814 -285.360119) (xy 36.029964 -285.364102) (xy 36.081926 -285.375962)
			(xy 36.13154 -285.395434) (xy 36.177698 -285.422083) (xy 36.219369 -285.455314) (xy 36.255621 -285.494385)
			(xy 36.285645 -285.538422) (xy 36.308771 -285.586443) (xy 36.324481 -285.637373) (xy 36.332424 -285.690077)
			(xy 36.332922 -285.716726) (xy 36.332424 -285.743375) (xy 50.708804 -285.743375) (xy 50.708804 -285.690077)
			(xy 50.716747 -285.637373) (xy 50.732457 -285.586443) (xy 50.755583 -285.538422) (xy 50.785607 -285.494385)
			(xy 50.821859 -285.455314) (xy 50.86353 -285.422083) (xy 50.909688 -285.395434) (xy 50.959302 -285.375962)
			(xy 51.011264 -285.364102) (xy 51.064414 -285.360119) (xy 51.117564 -285.364102) (xy 51.169526 -285.375962)
			(xy 51.21914 -285.395434) (xy 51.265298 -285.422083) (xy 51.306969 -285.455314) (xy 51.343221 -285.494385)
			(xy 51.373245 -285.538422) (xy 51.396371 -285.586443) (xy 51.412081 -285.637373) (xy 51.420024 -285.690077)
			(xy 51.420522 -285.716726) (xy 51.420024 -285.743375) (xy 51.412081 -285.796079) (xy 51.396371 -285.847009)
			(xy 51.373245 -285.89503) (xy 51.343221 -285.939067) (xy 51.306969 -285.978138) (xy 51.265298 -286.011369)
			(xy 51.21914 -286.038018) (xy 51.169526 -286.05749) (xy 51.117564 -286.06935) (xy 51.064414 -286.073334)
			(xy 51.011264 -286.06935) (xy 50.959302 -286.05749) (xy 50.909688 -286.038018) (xy 50.86353 -286.011369)
			(xy 50.821859 -285.978138) (xy 50.785607 -285.939067) (xy 50.755583 -285.89503) (xy 50.732457 -285.847009)
			(xy 50.716747 -285.796079) (xy 50.708804 -285.743375) (xy 36.332424 -285.743375) (xy 36.324481 -285.796079)
			(xy 36.308771 -285.847009) (xy 36.285645 -285.89503) (xy 36.255621 -285.939067) (xy 36.219369 -285.978138)
			(xy 36.177698 -286.011369) (xy 36.13154 -286.038018) (xy 36.081926 -286.05749) (xy 36.029964 -286.06935)
			(xy 35.976814 -286.073334) (xy 35.923664 -286.06935) (xy 35.871702 -286.05749) (xy 35.822088 -286.038018)
			(xy 35.77593 -286.011369) (xy 35.734259 -285.978138) (xy 35.698007 -285.939067) (xy 35.667983 -285.89503)
			(xy 35.644857 -285.847009) (xy 35.629147 -285.796079) (xy 35.621204 -285.743375) (xy 21.244824 -285.743375)
			(xy 21.236881 -285.796079) (xy 21.221171 -285.847009) (xy 21.198045 -285.89503) (xy 21.168021 -285.939067)
			(xy 21.131769 -285.978138) (xy 21.090098 -286.011369) (xy 21.04394 -286.038018) (xy 20.994326 -286.05749)
			(xy 20.942364 -286.06935) (xy 20.889214 -286.073334) (xy 20.836064 -286.06935) (xy 20.784102 -286.05749)
			(xy 20.734488 -286.038018) (xy 20.68833 -286.011369) (xy 20.646659 -285.978138) (xy 20.610407 -285.939067)
			(xy 20.580383 -285.89503) (xy 20.557257 -285.847009) (xy 20.541547 -285.796079) (xy 20.533604 -285.743375)
			(xy 9.6774 -285.743375) (xy 9.6774 -286.593259) (xy 16.433536 -286.593259) (xy 16.433536 -286.539961)
			(xy 16.441479 -286.487257) (xy 16.457189 -286.436327) (xy 16.480315 -286.388306) (xy 16.510339 -286.344269)
			(xy 16.546591 -286.305198) (xy 16.588262 -286.271967) (xy 16.63442 -286.245318) (xy 16.684034 -286.225846)
			(xy 16.735996 -286.213986) (xy 16.789146 -286.210003) (xy 16.842296 -286.213986) (xy 16.894258 -286.225846)
			(xy 16.943872 -286.245318) (xy 16.99003 -286.271967) (xy 17.031701 -286.305198) (xy 17.067953 -286.344269)
			(xy 17.097977 -286.388306) (xy 17.121103 -286.436327) (xy 17.136813 -286.487257) (xy 17.144756 -286.539961)
			(xy 17.145254 -286.56661) (xy 17.144756 -286.593259) (xy 31.521136 -286.593259) (xy 31.521136 -286.539961)
			(xy 31.529079 -286.487257) (xy 31.544789 -286.436327) (xy 31.567915 -286.388306) (xy 31.597939 -286.344269)
			(xy 31.634191 -286.305198) (xy 31.675862 -286.271967) (xy 31.72202 -286.245318) (xy 31.771634 -286.225846)
			(xy 31.823596 -286.213986) (xy 31.876746 -286.210003) (xy 31.929896 -286.213986) (xy 31.981858 -286.225846)
			(xy 32.031472 -286.245318) (xy 32.07763 -286.271967) (xy 32.119301 -286.305198) (xy 32.155553 -286.344269)
			(xy 32.185577 -286.388306) (xy 32.208703 -286.436327) (xy 32.224413 -286.487257) (xy 32.232356 -286.539961)
			(xy 32.232854 -286.56661) (xy 32.232356 -286.593259) (xy 46.608736 -286.593259) (xy 46.608736 -286.539961)
			(xy 46.616679 -286.487257) (xy 46.632389 -286.436327) (xy 46.655515 -286.388306) (xy 46.685539 -286.344269)
			(xy 46.721791 -286.305198) (xy 46.763462 -286.271967) (xy 46.80962 -286.245318) (xy 46.859234 -286.225846)
			(xy 46.911196 -286.213986) (xy 46.964346 -286.210003) (xy 47.017496 -286.213986) (xy 47.069458 -286.225846)
			(xy 47.119072 -286.245318) (xy 47.16523 -286.271967) (xy 47.206901 -286.305198) (xy 47.243153 -286.344269)
			(xy 47.273177 -286.388306) (xy 47.296303 -286.436327) (xy 47.312013 -286.487257) (xy 47.319956 -286.539961)
			(xy 47.320454 -286.56661) (xy 47.319956 -286.593259) (xy 47.312013 -286.645963) (xy 47.296303 -286.696893)
			(xy 47.273177 -286.744914) (xy 47.243153 -286.788951) (xy 47.206901 -286.828022) (xy 47.16523 -286.861253)
			(xy 47.119072 -286.887902) (xy 47.069458 -286.907374) (xy 47.017496 -286.919234) (xy 46.964346 -286.923218)
			(xy 46.911196 -286.919234) (xy 46.859234 -286.907374) (xy 46.80962 -286.887902) (xy 46.763462 -286.861253)
			(xy 46.721791 -286.828022) (xy 46.685539 -286.788951) (xy 46.655515 -286.744914) (xy 46.632389 -286.696893)
			(xy 46.616679 -286.645963) (xy 46.608736 -286.593259) (xy 32.232356 -286.593259) (xy 32.224413 -286.645963)
			(xy 32.208703 -286.696893) (xy 32.185577 -286.744914) (xy 32.155553 -286.788951) (xy 32.119301 -286.828022)
			(xy 32.07763 -286.861253) (xy 32.031472 -286.887902) (xy 31.981858 -286.907374) (xy 31.929896 -286.919234)
			(xy 31.876746 -286.923218) (xy 31.823596 -286.919234) (xy 31.771634 -286.907374) (xy 31.72202 -286.887902)
			(xy 31.675862 -286.861253) (xy 31.634191 -286.828022) (xy 31.597939 -286.788951) (xy 31.567915 -286.744914)
			(xy 31.544789 -286.696893) (xy 31.529079 -286.645963) (xy 31.521136 -286.593259) (xy 17.144756 -286.593259)
			(xy 17.136813 -286.645963) (xy 17.121103 -286.696893) (xy 17.097977 -286.744914) (xy 17.067953 -286.788951)
			(xy 17.031701 -286.828022) (xy 16.99003 -286.861253) (xy 16.943872 -286.887902) (xy 16.894258 -286.907374)
			(xy 16.842296 -286.919234) (xy 16.789146 -286.923218) (xy 16.735996 -286.919234) (xy 16.684034 -286.907374)
			(xy 16.63442 -286.887902) (xy 16.588262 -286.861253) (xy 16.546591 -286.828022) (xy 16.510339 -286.788951)
			(xy 16.480315 -286.744914) (xy 16.457189 -286.696893) (xy 16.441479 -286.645963) (xy 16.433536 -286.593259)
			(xy 9.6774 -286.593259) (xy 9.6774 -287.443397) (xy 20.533604 -287.443397) (xy 20.533604 -287.390099)
			(xy 20.541547 -287.337395) (xy 20.557257 -287.286465) (xy 20.580383 -287.238444) (xy 20.610407 -287.194407)
			(xy 20.646659 -287.155336) (xy 20.68833 -287.122105) (xy 20.734488 -287.095456) (xy 20.784102 -287.075984)
			(xy 20.836064 -287.064124) (xy 20.889214 -287.060141) (xy 20.942364 -287.064124) (xy 20.994326 -287.075984)
			(xy 21.04394 -287.095456) (xy 21.090098 -287.122105) (xy 21.131769 -287.155336) (xy 21.168021 -287.194407)
			(xy 21.198045 -287.238444) (xy 21.221171 -287.286465) (xy 21.236881 -287.337395) (xy 21.244824 -287.390099)
			(xy 21.245322 -287.416748) (xy 21.244824 -287.443397) (xy 35.621204 -287.443397) (xy 35.621204 -287.390099)
			(xy 35.629147 -287.337395) (xy 35.644857 -287.286465) (xy 35.667983 -287.238444) (xy 35.698007 -287.194407)
			(xy 35.734259 -287.155336) (xy 35.77593 -287.122105) (xy 35.822088 -287.095456) (xy 35.871702 -287.075984)
			(xy 35.923664 -287.064124) (xy 35.976814 -287.060141) (xy 36.029964 -287.064124) (xy 36.081926 -287.075984)
			(xy 36.13154 -287.095456) (xy 36.177698 -287.122105) (xy 36.219369 -287.155336) (xy 36.255621 -287.194407)
			(xy 36.285645 -287.238444) (xy 36.308771 -287.286465) (xy 36.324481 -287.337395) (xy 36.332424 -287.390099)
			(xy 36.332922 -287.416748) (xy 36.332424 -287.443397) (xy 50.708804 -287.443397) (xy 50.708804 -287.390099)
			(xy 50.716747 -287.337395) (xy 50.732457 -287.286465) (xy 50.755583 -287.238444) (xy 50.785607 -287.194407)
			(xy 50.821859 -287.155336) (xy 50.86353 -287.122105) (xy 50.909688 -287.095456) (xy 50.959302 -287.075984)
			(xy 51.011264 -287.064124) (xy 51.064414 -287.060141) (xy 51.117564 -287.064124) (xy 51.169526 -287.075984)
			(xy 51.21914 -287.095456) (xy 51.265298 -287.122105) (xy 51.306969 -287.155336) (xy 51.343221 -287.194407)
			(xy 51.373245 -287.238444) (xy 51.396371 -287.286465) (xy 51.412081 -287.337395) (xy 51.420024 -287.390099)
			(xy 51.420522 -287.416748) (xy 51.420024 -287.443397) (xy 51.412081 -287.496101) (xy 51.396371 -287.547031)
			(xy 51.373245 -287.595052) (xy 51.343221 -287.639089) (xy 51.306969 -287.67816) (xy 51.265298 -287.711391)
			(xy 51.21914 -287.73804) (xy 51.169526 -287.757512) (xy 51.117564 -287.769372) (xy 51.064414 -287.773356)
			(xy 51.011264 -287.769372) (xy 50.959302 -287.757512) (xy 50.909688 -287.73804) (xy 50.86353 -287.711391)
			(xy 50.821859 -287.67816) (xy 50.785607 -287.639089) (xy 50.755583 -287.595052) (xy 50.732457 -287.547031)
			(xy 50.716747 -287.496101) (xy 50.708804 -287.443397) (xy 36.332424 -287.443397) (xy 36.324481 -287.496101)
			(xy 36.308771 -287.547031) (xy 36.285645 -287.595052) (xy 36.255621 -287.639089) (xy 36.219369 -287.67816)
			(xy 36.177698 -287.711391) (xy 36.13154 -287.73804) (xy 36.081926 -287.757512) (xy 36.029964 -287.769372)
			(xy 35.976814 -287.773356) (xy 35.923664 -287.769372) (xy 35.871702 -287.757512) (xy 35.822088 -287.73804)
			(xy 35.77593 -287.711391) (xy 35.734259 -287.67816) (xy 35.698007 -287.639089) (xy 35.667983 -287.595052)
			(xy 35.644857 -287.547031) (xy 35.629147 -287.496101) (xy 35.621204 -287.443397) (xy 21.244824 -287.443397)
			(xy 21.236881 -287.496101) (xy 21.221171 -287.547031) (xy 21.198045 -287.595052) (xy 21.168021 -287.639089)
			(xy 21.131769 -287.67816) (xy 21.090098 -287.711391) (xy 21.04394 -287.73804) (xy 20.994326 -287.757512)
			(xy 20.942364 -287.769372) (xy 20.889214 -287.773356) (xy 20.836064 -287.769372) (xy 20.784102 -287.757512)
			(xy 20.734488 -287.73804) (xy 20.68833 -287.711391) (xy 20.646659 -287.67816) (xy 20.610407 -287.639089)
			(xy 20.580383 -287.595052) (xy 20.557257 -287.547031) (xy 20.541547 -287.496101) (xy 20.533604 -287.443397)
			(xy 9.6774 -287.443397) (xy 9.6774 -288.293281) (xy 16.433536 -288.293281) (xy 16.433536 -288.239983)
			(xy 16.441479 -288.187279) (xy 16.457189 -288.136349) (xy 16.480315 -288.088328) (xy 16.510339 -288.044291)
			(xy 16.546591 -288.00522) (xy 16.588262 -287.971989) (xy 16.63442 -287.94534) (xy 16.684034 -287.925868)
			(xy 16.735996 -287.914008) (xy 16.789146 -287.910025) (xy 16.842296 -287.914008) (xy 16.894258 -287.925868)
			(xy 16.943872 -287.94534) (xy 16.99003 -287.971989) (xy 17.031701 -288.00522) (xy 17.067953 -288.044291)
			(xy 17.097977 -288.088328) (xy 17.121103 -288.136349) (xy 17.136813 -288.187279) (xy 17.144756 -288.239983)
			(xy 17.145254 -288.266632) (xy 17.144756 -288.293281) (xy 31.521136 -288.293281) (xy 31.521136 -288.239983)
			(xy 31.529079 -288.187279) (xy 31.544789 -288.136349) (xy 31.567915 -288.088328) (xy 31.597939 -288.044291)
			(xy 31.634191 -288.00522) (xy 31.675862 -287.971989) (xy 31.72202 -287.94534) (xy 31.771634 -287.925868)
			(xy 31.823596 -287.914008) (xy 31.876746 -287.910025) (xy 31.929896 -287.914008) (xy 31.981858 -287.925868)
			(xy 32.031472 -287.94534) (xy 32.07763 -287.971989) (xy 32.119301 -288.00522) (xy 32.155553 -288.044291)
			(xy 32.185577 -288.088328) (xy 32.208703 -288.136349) (xy 32.224413 -288.187279) (xy 32.232356 -288.239983)
			(xy 32.232854 -288.266632) (xy 32.232356 -288.293281) (xy 46.608736 -288.293281) (xy 46.608736 -288.239983)
			(xy 46.616679 -288.187279) (xy 46.632389 -288.136349) (xy 46.655515 -288.088328) (xy 46.685539 -288.044291)
			(xy 46.721791 -288.00522) (xy 46.763462 -287.971989) (xy 46.80962 -287.94534) (xy 46.859234 -287.925868)
			(xy 46.911196 -287.914008) (xy 46.964346 -287.910025) (xy 47.017496 -287.914008) (xy 47.069458 -287.925868)
			(xy 47.119072 -287.94534) (xy 47.16523 -287.971989) (xy 47.206901 -288.00522) (xy 47.243153 -288.044291)
			(xy 47.273177 -288.088328) (xy 47.296303 -288.136349) (xy 47.312013 -288.187279) (xy 47.319956 -288.239983)
			(xy 47.320454 -288.266632) (xy 47.319956 -288.293281) (xy 47.312013 -288.345985) (xy 47.296303 -288.396915)
			(xy 47.273177 -288.444936) (xy 47.243153 -288.488973) (xy 47.206901 -288.528044) (xy 47.16523 -288.561275)
			(xy 47.119072 -288.587924) (xy 47.069458 -288.607396) (xy 47.017496 -288.619256) (xy 46.964346 -288.62324)
			(xy 46.911196 -288.619256) (xy 46.859234 -288.607396) (xy 46.80962 -288.587924) (xy 46.763462 -288.561275)
			(xy 46.721791 -288.528044) (xy 46.685539 -288.488973) (xy 46.655515 -288.444936) (xy 46.632389 -288.396915)
			(xy 46.616679 -288.345985) (xy 46.608736 -288.293281) (xy 32.232356 -288.293281) (xy 32.224413 -288.345985)
			(xy 32.208703 -288.396915) (xy 32.185577 -288.444936) (xy 32.155553 -288.488973) (xy 32.119301 -288.528044)
			(xy 32.07763 -288.561275) (xy 32.031472 -288.587924) (xy 31.981858 -288.607396) (xy 31.929896 -288.619256)
			(xy 31.876746 -288.62324) (xy 31.823596 -288.619256) (xy 31.771634 -288.607396) (xy 31.72202 -288.587924)
			(xy 31.675862 -288.561275) (xy 31.634191 -288.528044) (xy 31.597939 -288.488973) (xy 31.567915 -288.444936)
			(xy 31.544789 -288.396915) (xy 31.529079 -288.345985) (xy 31.521136 -288.293281) (xy 17.144756 -288.293281)
			(xy 17.136813 -288.345985) (xy 17.121103 -288.396915) (xy 17.097977 -288.444936) (xy 17.067953 -288.488973)
			(xy 17.031701 -288.528044) (xy 16.99003 -288.561275) (xy 16.943872 -288.587924) (xy 16.894258 -288.607396)
			(xy 16.842296 -288.619256) (xy 16.789146 -288.62324) (xy 16.735996 -288.619256) (xy 16.684034 -288.607396)
			(xy 16.63442 -288.587924) (xy 16.588262 -288.561275) (xy 16.546591 -288.528044) (xy 16.510339 -288.488973)
			(xy 16.480315 -288.444936) (xy 16.457189 -288.396915) (xy 16.441479 -288.345985) (xy 16.433536 -288.293281)
			(xy 9.6774 -288.293281) (xy 9.6774 -289.143419) (xy 20.533604 -289.143419) (xy 20.533604 -289.090121)
			(xy 20.541547 -289.037417) (xy 20.557257 -288.986487) (xy 20.580383 -288.938466) (xy 20.610407 -288.894429)
			(xy 20.646659 -288.855358) (xy 20.68833 -288.822127) (xy 20.734488 -288.795478) (xy 20.784102 -288.776006)
			(xy 20.836064 -288.764146) (xy 20.889214 -288.760163) (xy 20.942364 -288.764146) (xy 20.994326 -288.776006)
			(xy 21.04394 -288.795478) (xy 21.090098 -288.822127) (xy 21.131769 -288.855358) (xy 21.168021 -288.894429)
			(xy 21.198045 -288.938466) (xy 21.221171 -288.986487) (xy 21.236881 -289.037417) (xy 21.244824 -289.090121)
			(xy 21.245322 -289.11677) (xy 21.244824 -289.143419) (xy 35.621204 -289.143419) (xy 35.621204 -289.090121)
			(xy 35.629147 -289.037417) (xy 35.644857 -288.986487) (xy 35.667983 -288.938466) (xy 35.698007 -288.894429)
			(xy 35.734259 -288.855358) (xy 35.77593 -288.822127) (xy 35.822088 -288.795478) (xy 35.871702 -288.776006)
			(xy 35.923664 -288.764146) (xy 35.976814 -288.760163) (xy 36.029964 -288.764146) (xy 36.081926 -288.776006)
			(xy 36.13154 -288.795478) (xy 36.177698 -288.822127) (xy 36.219369 -288.855358) (xy 36.255621 -288.894429)
			(xy 36.285645 -288.938466) (xy 36.308771 -288.986487) (xy 36.324481 -289.037417) (xy 36.332424 -289.090121)
			(xy 36.332922 -289.11677) (xy 36.332424 -289.143419) (xy 50.734204 -289.143419) (xy 50.734204 -289.090121)
			(xy 50.742147 -289.037417) (xy 50.757857 -288.986487) (xy 50.780983 -288.938466) (xy 50.811007 -288.894429)
			(xy 50.847259 -288.855358) (xy 50.88893 -288.822127) (xy 50.935088 -288.795478) (xy 50.984702 -288.776006)
			(xy 51.036664 -288.764146) (xy 51.089814 -288.760163) (xy 51.142964 -288.764146) (xy 51.194926 -288.776006)
			(xy 51.24454 -288.795478) (xy 51.290698 -288.822127) (xy 51.332369 -288.855358) (xy 51.368621 -288.894429)
			(xy 51.398645 -288.938466) (xy 51.421771 -288.986487) (xy 51.437481 -289.037417) (xy 51.445424 -289.090121)
			(xy 51.445922 -289.11677) (xy 51.445424 -289.143419) (xy 51.437481 -289.196123) (xy 51.421771 -289.247053)
			(xy 51.398645 -289.295074) (xy 51.368621 -289.339111) (xy 51.332369 -289.378182) (xy 51.290698 -289.411413)
			(xy 51.24454 -289.438062) (xy 51.194926 -289.457534) (xy 51.142964 -289.469394) (xy 51.089814 -289.473378)
			(xy 51.036664 -289.469394) (xy 50.984702 -289.457534) (xy 50.935088 -289.438062) (xy 50.88893 -289.411413)
			(xy 50.847259 -289.378182) (xy 50.811007 -289.339111) (xy 50.780983 -289.295074) (xy 50.757857 -289.247053)
			(xy 50.742147 -289.196123) (xy 50.734204 -289.143419) (xy 36.332424 -289.143419) (xy 36.324481 -289.196123)
			(xy 36.308771 -289.247053) (xy 36.285645 -289.295074) (xy 36.255621 -289.339111) (xy 36.219369 -289.378182)
			(xy 36.177698 -289.411413) (xy 36.13154 -289.438062) (xy 36.081926 -289.457534) (xy 36.029964 -289.469394)
			(xy 35.976814 -289.473378) (xy 35.923664 -289.469394) (xy 35.871702 -289.457534) (xy 35.822088 -289.438062)
			(xy 35.77593 -289.411413) (xy 35.734259 -289.378182) (xy 35.698007 -289.339111) (xy 35.667983 -289.295074)
			(xy 35.644857 -289.247053) (xy 35.629147 -289.196123) (xy 35.621204 -289.143419) (xy 21.244824 -289.143419)
			(xy 21.236881 -289.196123) (xy 21.221171 -289.247053) (xy 21.198045 -289.295074) (xy 21.168021 -289.339111)
			(xy 21.131769 -289.378182) (xy 21.090098 -289.411413) (xy 21.04394 -289.438062) (xy 20.994326 -289.457534)
			(xy 20.942364 -289.469394) (xy 20.889214 -289.473378) (xy 20.836064 -289.469394) (xy 20.784102 -289.457534)
			(xy 20.734488 -289.438062) (xy 20.68833 -289.411413) (xy 20.646659 -289.378182) (xy 20.610407 -289.339111)
			(xy 20.580383 -289.295074) (xy 20.557257 -289.247053) (xy 20.541547 -289.196123) (xy 20.533604 -289.143419)
			(xy 9.6774 -289.143419) (xy 9.6774 -289.993303) (xy 16.433536 -289.993303) (xy 16.433536 -289.940005)
			(xy 16.441479 -289.887301) (xy 16.457189 -289.836371) (xy 16.480315 -289.78835) (xy 16.510339 -289.744313)
			(xy 16.546591 -289.705242) (xy 16.588262 -289.672011) (xy 16.63442 -289.645362) (xy 16.684034 -289.62589)
			(xy 16.735996 -289.61403) (xy 16.789146 -289.610047) (xy 16.842296 -289.61403) (xy 16.894258 -289.62589)
			(xy 16.943872 -289.645362) (xy 16.99003 -289.672011) (xy 17.031701 -289.705242) (xy 17.067953 -289.744313)
			(xy 17.097977 -289.78835) (xy 17.121103 -289.836371) (xy 17.136813 -289.887301) (xy 17.144756 -289.940005)
			(xy 17.145254 -289.966654) (xy 17.144756 -289.993303) (xy 31.521136 -289.993303) (xy 31.521136 -289.940005)
			(xy 31.529079 -289.887301) (xy 31.544789 -289.836371) (xy 31.567915 -289.78835) (xy 31.597939 -289.744313)
			(xy 31.634191 -289.705242) (xy 31.675862 -289.672011) (xy 31.72202 -289.645362) (xy 31.771634 -289.62589)
			(xy 31.823596 -289.61403) (xy 31.876746 -289.610047) (xy 31.929896 -289.61403) (xy 31.981858 -289.62589)
			(xy 32.031472 -289.645362) (xy 32.07763 -289.672011) (xy 32.119301 -289.705242) (xy 32.155553 -289.744313)
			(xy 32.185577 -289.78835) (xy 32.208703 -289.836371) (xy 32.224413 -289.887301) (xy 32.232356 -289.940005)
			(xy 32.232854 -289.966654) (xy 32.232356 -289.993303) (xy 46.608736 -289.993303) (xy 46.608736 -289.940005)
			(xy 46.616679 -289.887301) (xy 46.632389 -289.836371) (xy 46.655515 -289.78835) (xy 46.685539 -289.744313)
			(xy 46.721791 -289.705242) (xy 46.763462 -289.672011) (xy 46.80962 -289.645362) (xy 46.859234 -289.62589)
			(xy 46.911196 -289.61403) (xy 46.964346 -289.610047) (xy 47.017496 -289.61403) (xy 47.069458 -289.62589)
			(xy 47.119072 -289.645362) (xy 47.16523 -289.672011) (xy 47.206901 -289.705242) (xy 47.243153 -289.744313)
			(xy 47.273177 -289.78835) (xy 47.296303 -289.836371) (xy 47.312013 -289.887301) (xy 47.319956 -289.940005)
			(xy 47.320454 -289.966654) (xy 47.319956 -289.993303) (xy 47.312013 -290.046007) (xy 47.296303 -290.096937)
			(xy 47.273177 -290.144958) (xy 47.243153 -290.188995) (xy 47.206901 -290.228066) (xy 47.16523 -290.261297)
			(xy 47.119072 -290.287946) (xy 47.069458 -290.307418) (xy 47.017496 -290.319278) (xy 46.964346 -290.323262)
			(xy 46.911196 -290.319278) (xy 46.859234 -290.307418) (xy 46.80962 -290.287946) (xy 46.763462 -290.261297)
			(xy 46.721791 -290.228066) (xy 46.685539 -290.188995) (xy 46.655515 -290.144958) (xy 46.632389 -290.096937)
			(xy 46.616679 -290.046007) (xy 46.608736 -289.993303) (xy 32.232356 -289.993303) (xy 32.224413 -290.046007)
			(xy 32.208703 -290.096937) (xy 32.185577 -290.144958) (xy 32.155553 -290.188995) (xy 32.119301 -290.228066)
			(xy 32.07763 -290.261297) (xy 32.031472 -290.287946) (xy 31.981858 -290.307418) (xy 31.929896 -290.319278)
			(xy 31.876746 -290.323262) (xy 31.823596 -290.319278) (xy 31.771634 -290.307418) (xy 31.72202 -290.287946)
			(xy 31.675862 -290.261297) (xy 31.634191 -290.228066) (xy 31.597939 -290.188995) (xy 31.567915 -290.144958)
			(xy 31.544789 -290.096937) (xy 31.529079 -290.046007) (xy 31.521136 -289.993303) (xy 17.144756 -289.993303)
			(xy 17.136813 -290.046007) (xy 17.121103 -290.096937) (xy 17.097977 -290.144958) (xy 17.067953 -290.188995)
			(xy 17.031701 -290.228066) (xy 16.99003 -290.261297) (xy 16.943872 -290.287946) (xy 16.894258 -290.307418)
			(xy 16.842296 -290.319278) (xy 16.789146 -290.323262) (xy 16.735996 -290.319278) (xy 16.684034 -290.307418)
			(xy 16.63442 -290.287946) (xy 16.588262 -290.261297) (xy 16.546591 -290.228066) (xy 16.510339 -290.188995)
			(xy 16.480315 -290.144958) (xy 16.457189 -290.096937) (xy 16.441479 -290.046007) (xy 16.433536 -289.993303)
			(xy 9.6774 -289.993303) (xy 9.6774 -290.843441) (xy 20.533604 -290.843441) (xy 20.533604 -290.790143)
			(xy 20.541547 -290.737439) (xy 20.557257 -290.686509) (xy 20.580383 -290.638488) (xy 20.610407 -290.594451)
			(xy 20.646659 -290.55538) (xy 20.68833 -290.522149) (xy 20.734488 -290.4955) (xy 20.784102 -290.476028)
			(xy 20.836064 -290.464168) (xy 20.889214 -290.460185) (xy 20.942364 -290.464168) (xy 20.994326 -290.476028)
			(xy 21.04394 -290.4955) (xy 21.090098 -290.522149) (xy 21.131769 -290.55538) (xy 21.168021 -290.594451)
			(xy 21.198045 -290.638488) (xy 21.221171 -290.686509) (xy 21.236881 -290.737439) (xy 21.244824 -290.790143)
			(xy 21.245322 -290.816792) (xy 21.244824 -290.843441) (xy 35.621204 -290.843441) (xy 35.621204 -290.790143)
			(xy 35.629147 -290.737439) (xy 35.644857 -290.686509) (xy 35.667983 -290.638488) (xy 35.698007 -290.594451)
			(xy 35.734259 -290.55538) (xy 35.77593 -290.522149) (xy 35.822088 -290.4955) (xy 35.871702 -290.476028)
			(xy 35.923664 -290.464168) (xy 35.976814 -290.460185) (xy 36.029964 -290.464168) (xy 36.081926 -290.476028)
			(xy 36.13154 -290.4955) (xy 36.177698 -290.522149) (xy 36.219369 -290.55538) (xy 36.255621 -290.594451)
			(xy 36.285645 -290.638488) (xy 36.308771 -290.686509) (xy 36.324481 -290.737439) (xy 36.332424 -290.790143)
			(xy 36.332922 -290.816792) (xy 36.332424 -290.843441) (xy 50.734204 -290.843441) (xy 50.734204 -290.790143)
			(xy 50.742147 -290.737439) (xy 50.757857 -290.686509) (xy 50.780983 -290.638488) (xy 50.811007 -290.594451)
			(xy 50.847259 -290.55538) (xy 50.88893 -290.522149) (xy 50.935088 -290.4955) (xy 50.984702 -290.476028)
			(xy 51.036664 -290.464168) (xy 51.089814 -290.460185) (xy 51.142964 -290.464168) (xy 51.194926 -290.476028)
			(xy 51.24454 -290.4955) (xy 51.290698 -290.522149) (xy 51.332369 -290.55538) (xy 51.368621 -290.594451)
			(xy 51.398645 -290.638488) (xy 51.421771 -290.686509) (xy 51.437481 -290.737439) (xy 51.445424 -290.790143)
			(xy 51.445922 -290.816792) (xy 51.445424 -290.843441) (xy 51.437481 -290.896145) (xy 51.421771 -290.947075)
			(xy 51.398645 -290.995096) (xy 51.368621 -291.039133) (xy 51.332369 -291.078204) (xy 51.290698 -291.111435)
			(xy 51.24454 -291.138084) (xy 51.194926 -291.157556) (xy 51.142964 -291.169416) (xy 51.089814 -291.1734)
			(xy 51.036664 -291.169416) (xy 50.984702 -291.157556) (xy 50.935088 -291.138084) (xy 50.88893 -291.111435)
			(xy 50.847259 -291.078204) (xy 50.811007 -291.039133) (xy 50.780983 -290.995096) (xy 50.757857 -290.947075)
			(xy 50.742147 -290.896145) (xy 50.734204 -290.843441) (xy 36.332424 -290.843441) (xy 36.324481 -290.896145)
			(xy 36.308771 -290.947075) (xy 36.285645 -290.995096) (xy 36.255621 -291.039133) (xy 36.219369 -291.078204)
			(xy 36.177698 -291.111435) (xy 36.13154 -291.138084) (xy 36.081926 -291.157556) (xy 36.029964 -291.169416)
			(xy 35.976814 -291.1734) (xy 35.923664 -291.169416) (xy 35.871702 -291.157556) (xy 35.822088 -291.138084)
			(xy 35.77593 -291.111435) (xy 35.734259 -291.078204) (xy 35.698007 -291.039133) (xy 35.667983 -290.995096)
			(xy 35.644857 -290.947075) (xy 35.629147 -290.896145) (xy 35.621204 -290.843441) (xy 21.244824 -290.843441)
			(xy 21.236881 -290.896145) (xy 21.221171 -290.947075) (xy 21.198045 -290.995096) (xy 21.168021 -291.039133)
			(xy 21.131769 -291.078204) (xy 21.090098 -291.111435) (xy 21.04394 -291.138084) (xy 20.994326 -291.157556)
			(xy 20.942364 -291.169416) (xy 20.889214 -291.1734) (xy 20.836064 -291.169416) (xy 20.784102 -291.157556)
			(xy 20.734488 -291.138084) (xy 20.68833 -291.111435) (xy 20.646659 -291.078204) (xy 20.610407 -291.039133)
			(xy 20.580383 -290.995096) (xy 20.557257 -290.947075) (xy 20.541547 -290.896145) (xy 20.533604 -290.843441)
			(xy 9.6774 -290.843441) (xy 9.6774 -291.693325) (xy 16.433536 -291.693325) (xy 16.433536 -291.640027)
			(xy 16.441479 -291.587323) (xy 16.457189 -291.536393) (xy 16.480315 -291.488372) (xy 16.510339 -291.444335)
			(xy 16.546591 -291.405264) (xy 16.588262 -291.372033) (xy 16.63442 -291.345384) (xy 16.684034 -291.325912)
			(xy 16.735996 -291.314052) (xy 16.789146 -291.310069) (xy 16.842296 -291.314052) (xy 16.894258 -291.325912)
			(xy 16.943872 -291.345384) (xy 16.99003 -291.372033) (xy 17.031701 -291.405264) (xy 17.067953 -291.444335)
			(xy 17.097977 -291.488372) (xy 17.121103 -291.536393) (xy 17.136813 -291.587323) (xy 17.144756 -291.640027)
			(xy 17.145254 -291.666676) (xy 17.144756 -291.693325) (xy 31.521136 -291.693325) (xy 31.521136 -291.640027)
			(xy 31.529079 -291.587323) (xy 31.544789 -291.536393) (xy 31.567915 -291.488372) (xy 31.597939 -291.444335)
			(xy 31.634191 -291.405264) (xy 31.675862 -291.372033) (xy 31.72202 -291.345384) (xy 31.771634 -291.325912)
			(xy 31.823596 -291.314052) (xy 31.876746 -291.310069) (xy 31.929896 -291.314052) (xy 31.981858 -291.325912)
			(xy 32.031472 -291.345384) (xy 32.07763 -291.372033) (xy 32.119301 -291.405264) (xy 32.155553 -291.444335)
			(xy 32.185577 -291.488372) (xy 32.208703 -291.536393) (xy 32.224413 -291.587323) (xy 32.232356 -291.640027)
			(xy 32.232854 -291.666676) (xy 32.232356 -291.693325) (xy 46.608736 -291.693325) (xy 46.608736 -291.640027)
			(xy 46.616679 -291.587323) (xy 46.632389 -291.536393) (xy 46.655515 -291.488372) (xy 46.685539 -291.444335)
			(xy 46.721791 -291.405264) (xy 46.763462 -291.372033) (xy 46.80962 -291.345384) (xy 46.859234 -291.325912)
			(xy 46.911196 -291.314052) (xy 46.964346 -291.310069) (xy 47.017496 -291.314052) (xy 47.069458 -291.325912)
			(xy 47.119072 -291.345384) (xy 47.16523 -291.372033) (xy 47.206901 -291.405264) (xy 47.243153 -291.444335)
			(xy 47.273177 -291.488372) (xy 47.296303 -291.536393) (xy 47.312013 -291.587323) (xy 47.319956 -291.640027)
			(xy 47.320454 -291.666676) (xy 47.319956 -291.693325) (xy 47.312013 -291.746029) (xy 47.296303 -291.796959)
			(xy 47.273177 -291.84498) (xy 47.243153 -291.889017) (xy 47.206901 -291.928088) (xy 47.16523 -291.961319)
			(xy 47.119072 -291.987968) (xy 47.069458 -292.00744) (xy 47.017496 -292.0193) (xy 46.964346 -292.023284)
			(xy 46.911196 -292.0193) (xy 46.859234 -292.00744) (xy 46.80962 -291.987968) (xy 46.763462 -291.961319)
			(xy 46.721791 -291.928088) (xy 46.685539 -291.889017) (xy 46.655515 -291.84498) (xy 46.632389 -291.796959)
			(xy 46.616679 -291.746029) (xy 46.608736 -291.693325) (xy 32.232356 -291.693325) (xy 32.224413 -291.746029)
			(xy 32.208703 -291.796959) (xy 32.185577 -291.84498) (xy 32.155553 -291.889017) (xy 32.119301 -291.928088)
			(xy 32.07763 -291.961319) (xy 32.031472 -291.987968) (xy 31.981858 -292.00744) (xy 31.929896 -292.0193)
			(xy 31.876746 -292.023284) (xy 31.823596 -292.0193) (xy 31.771634 -292.00744) (xy 31.72202 -291.987968)
			(xy 31.675862 -291.961319) (xy 31.634191 -291.928088) (xy 31.597939 -291.889017) (xy 31.567915 -291.84498)
			(xy 31.544789 -291.796959) (xy 31.529079 -291.746029) (xy 31.521136 -291.693325) (xy 17.144756 -291.693325)
			(xy 17.136813 -291.746029) (xy 17.121103 -291.796959) (xy 17.097977 -291.84498) (xy 17.067953 -291.889017)
			(xy 17.031701 -291.928088) (xy 16.99003 -291.961319) (xy 16.943872 -291.987968) (xy 16.894258 -292.00744)
			(xy 16.842296 -292.0193) (xy 16.789146 -292.023284) (xy 16.735996 -292.0193) (xy 16.684034 -292.00744)
			(xy 16.63442 -291.987968) (xy 16.588262 -291.961319) (xy 16.546591 -291.928088) (xy 16.510339 -291.889017)
			(xy 16.480315 -291.84498) (xy 16.457189 -291.796959) (xy 16.441479 -291.746029) (xy 16.433536 -291.693325)
			(xy 9.6774 -291.693325) (xy 9.6774 -292.543463) (xy 20.533604 -292.543463) (xy 20.533604 -292.490165)
			(xy 20.541547 -292.437461) (xy 20.557257 -292.386531) (xy 20.580383 -292.33851) (xy 20.610407 -292.294473)
			(xy 20.646659 -292.255402) (xy 20.68833 -292.222171) (xy 20.734488 -292.195522) (xy 20.784102 -292.17605)
			(xy 20.836064 -292.16419) (xy 20.889214 -292.160207) (xy 20.942364 -292.16419) (xy 20.994326 -292.17605)
			(xy 21.04394 -292.195522) (xy 21.090098 -292.222171) (xy 21.131769 -292.255402) (xy 21.168021 -292.294473)
			(xy 21.198045 -292.33851) (xy 21.221171 -292.386531) (xy 21.236881 -292.437461) (xy 21.244824 -292.490165)
			(xy 21.245322 -292.516814) (xy 21.244824 -292.543463) (xy 35.621204 -292.543463) (xy 35.621204 -292.490165)
			(xy 35.629147 -292.437461) (xy 35.644857 -292.386531) (xy 35.667983 -292.33851) (xy 35.698007 -292.294473)
			(xy 35.734259 -292.255402) (xy 35.77593 -292.222171) (xy 35.822088 -292.195522) (xy 35.871702 -292.17605)
			(xy 35.923664 -292.16419) (xy 35.976814 -292.160207) (xy 36.029964 -292.16419) (xy 36.081926 -292.17605)
			(xy 36.13154 -292.195522) (xy 36.177698 -292.222171) (xy 36.219369 -292.255402) (xy 36.255621 -292.294473)
			(xy 36.285645 -292.33851) (xy 36.308771 -292.386531) (xy 36.324481 -292.437461) (xy 36.332424 -292.490165)
			(xy 36.332922 -292.516814) (xy 36.332424 -292.543463) (xy 50.734204 -292.543463) (xy 50.734204 -292.490165)
			(xy 50.742147 -292.437461) (xy 50.757857 -292.386531) (xy 50.780983 -292.33851) (xy 50.811007 -292.294473)
			(xy 50.847259 -292.255402) (xy 50.88893 -292.222171) (xy 50.935088 -292.195522) (xy 50.984702 -292.17605)
			(xy 51.036664 -292.16419) (xy 51.089814 -292.160207) (xy 51.142964 -292.16419) (xy 51.194926 -292.17605)
			(xy 51.24454 -292.195522) (xy 51.290698 -292.222171) (xy 51.332369 -292.255402) (xy 51.368621 -292.294473)
			(xy 51.398645 -292.33851) (xy 51.421771 -292.386531) (xy 51.437481 -292.437461) (xy 51.445424 -292.490165)
			(xy 51.445922 -292.516814) (xy 51.445424 -292.543463) (xy 51.437481 -292.596167) (xy 51.421771 -292.647097)
			(xy 51.398645 -292.695118) (xy 51.368621 -292.739155) (xy 51.332369 -292.778226) (xy 51.290698 -292.811457)
			(xy 51.24454 -292.838106) (xy 51.194926 -292.857578) (xy 51.142964 -292.869438) (xy 51.089814 -292.873422)
			(xy 51.036664 -292.869438) (xy 50.984702 -292.857578) (xy 50.935088 -292.838106) (xy 50.88893 -292.811457)
			(xy 50.847259 -292.778226) (xy 50.811007 -292.739155) (xy 50.780983 -292.695118) (xy 50.757857 -292.647097)
			(xy 50.742147 -292.596167) (xy 50.734204 -292.543463) (xy 36.332424 -292.543463) (xy 36.324481 -292.596167)
			(xy 36.308771 -292.647097) (xy 36.285645 -292.695118) (xy 36.255621 -292.739155) (xy 36.219369 -292.778226)
			(xy 36.177698 -292.811457) (xy 36.13154 -292.838106) (xy 36.081926 -292.857578) (xy 36.029964 -292.869438)
			(xy 35.976814 -292.873422) (xy 35.923664 -292.869438) (xy 35.871702 -292.857578) (xy 35.822088 -292.838106)
			(xy 35.77593 -292.811457) (xy 35.734259 -292.778226) (xy 35.698007 -292.739155) (xy 35.667983 -292.695118)
			(xy 35.644857 -292.647097) (xy 35.629147 -292.596167) (xy 35.621204 -292.543463) (xy 21.244824 -292.543463)
			(xy 21.236881 -292.596167) (xy 21.221171 -292.647097) (xy 21.198045 -292.695118) (xy 21.168021 -292.739155)
			(xy 21.131769 -292.778226) (xy 21.090098 -292.811457) (xy 21.04394 -292.838106) (xy 20.994326 -292.857578)
			(xy 20.942364 -292.869438) (xy 20.889214 -292.873422) (xy 20.836064 -292.869438) (xy 20.784102 -292.857578)
			(xy 20.734488 -292.838106) (xy 20.68833 -292.811457) (xy 20.646659 -292.778226) (xy 20.610407 -292.739155)
			(xy 20.580383 -292.695118) (xy 20.557257 -292.647097) (xy 20.541547 -292.596167) (xy 20.533604 -292.543463)
			(xy 9.6774 -292.543463) (xy 9.6774 -293.393347) (xy 16.433536 -293.393347) (xy 16.433536 -293.340049)
			(xy 16.441479 -293.287345) (xy 16.457189 -293.236415) (xy 16.480315 -293.188394) (xy 16.510339 -293.144357)
			(xy 16.546591 -293.105286) (xy 16.588262 -293.072055) (xy 16.63442 -293.045406) (xy 16.684034 -293.025934)
			(xy 16.735996 -293.014074) (xy 16.789146 -293.010091) (xy 16.842296 -293.014074) (xy 16.894258 -293.025934)
			(xy 16.943872 -293.045406) (xy 16.99003 -293.072055) (xy 17.031701 -293.105286) (xy 17.067953 -293.144357)
			(xy 17.097977 -293.188394) (xy 17.121103 -293.236415) (xy 17.136813 -293.287345) (xy 17.144756 -293.340049)
			(xy 17.145254 -293.366698) (xy 17.144756 -293.393347) (xy 20.533604 -293.393347) (xy 20.533604 -293.340049)
			(xy 20.541547 -293.287345) (xy 20.557257 -293.236415) (xy 20.580383 -293.188394) (xy 20.610407 -293.144357)
			(xy 20.646659 -293.105286) (xy 20.68833 -293.072055) (xy 20.734488 -293.045406) (xy 20.784102 -293.025934)
			(xy 20.836064 -293.014074) (xy 20.889214 -293.010091) (xy 20.942364 -293.014074) (xy 20.994326 -293.025934)
			(xy 21.04394 -293.045406) (xy 21.090098 -293.072055) (xy 21.131769 -293.105286) (xy 21.168021 -293.144357)
			(xy 21.198045 -293.188394) (xy 21.221171 -293.236415) (xy 21.236881 -293.287345) (xy 21.244824 -293.340049)
			(xy 21.245322 -293.366698) (xy 21.244824 -293.393347) (xy 31.521136 -293.393347) (xy 31.521136 -293.340049)
			(xy 31.529079 -293.287345) (xy 31.544789 -293.236415) (xy 31.567915 -293.188394) (xy 31.597939 -293.144357)
			(xy 31.634191 -293.105286) (xy 31.675862 -293.072055) (xy 31.72202 -293.045406) (xy 31.771634 -293.025934)
			(xy 31.823596 -293.014074) (xy 31.876746 -293.010091) (xy 31.929896 -293.014074) (xy 31.981858 -293.025934)
			(xy 32.031472 -293.045406) (xy 32.07763 -293.072055) (xy 32.119301 -293.105286) (xy 32.155553 -293.144357)
			(xy 32.185577 -293.188394) (xy 32.208703 -293.236415) (xy 32.224413 -293.287345) (xy 32.232356 -293.340049)
			(xy 32.232854 -293.366698) (xy 32.232356 -293.393347) (xy 35.621204 -293.393347) (xy 35.621204 -293.340049)
			(xy 35.629147 -293.287345) (xy 35.644857 -293.236415) (xy 35.667983 -293.188394) (xy 35.698007 -293.144357)
			(xy 35.734259 -293.105286) (xy 35.77593 -293.072055) (xy 35.822088 -293.045406) (xy 35.871702 -293.025934)
			(xy 35.923664 -293.014074) (xy 35.976814 -293.010091) (xy 36.029964 -293.014074) (xy 36.081926 -293.025934)
			(xy 36.13154 -293.045406) (xy 36.177698 -293.072055) (xy 36.219369 -293.105286) (xy 36.255621 -293.144357)
			(xy 36.285645 -293.188394) (xy 36.308771 -293.236415) (xy 36.324481 -293.287345) (xy 36.332424 -293.340049)
			(xy 36.332922 -293.366698) (xy 36.332424 -293.393347) (xy 46.608736 -293.393347) (xy 46.608736 -293.340049)
			(xy 46.616679 -293.287345) (xy 46.632389 -293.236415) (xy 46.655515 -293.188394) (xy 46.685539 -293.144357)
			(xy 46.721791 -293.105286) (xy 46.763462 -293.072055) (xy 46.80962 -293.045406) (xy 46.859234 -293.025934)
			(xy 46.911196 -293.014074) (xy 46.964346 -293.010091) (xy 47.017496 -293.014074) (xy 47.069458 -293.025934)
			(xy 47.119072 -293.045406) (xy 47.16523 -293.072055) (xy 47.206901 -293.105286) (xy 47.243153 -293.144357)
			(xy 47.273177 -293.188394) (xy 47.296303 -293.236415) (xy 47.312013 -293.287345) (xy 47.319956 -293.340049)
			(xy 47.320454 -293.366698) (xy 47.319956 -293.393347) (xy 47.319918 -293.393601) (xy 50.734204 -293.393601)
			(xy 50.734204 -293.340303) (xy 50.742147 -293.287599) (xy 50.757857 -293.236669) (xy 50.780983 -293.188648)
			(xy 50.811007 -293.144611) (xy 50.847259 -293.10554) (xy 50.88893 -293.072309) (xy 50.935088 -293.04566)
			(xy 50.984702 -293.026188) (xy 51.036664 -293.014328) (xy 51.089814 -293.010345) (xy 51.142964 -293.014328)
			(xy 51.194926 -293.026188) (xy 51.24454 -293.04566) (xy 51.290698 -293.072309) (xy 51.332369 -293.10554)
			(xy 51.368621 -293.144611) (xy 51.398645 -293.188648) (xy 51.421771 -293.236669) (xy 51.437481 -293.287599)
			(xy 51.445424 -293.340303) (xy 51.445922 -293.366952) (xy 51.445424 -293.393601) (xy 51.437481 -293.446305)
			(xy 51.421771 -293.497235) (xy 51.398645 -293.545256) (xy 51.368621 -293.589293) (xy 51.332369 -293.628364)
			(xy 51.290698 -293.661595) (xy 51.24454 -293.688244) (xy 51.194926 -293.707716) (xy 51.142964 -293.719576)
			(xy 51.089814 -293.72356) (xy 51.036664 -293.719576) (xy 50.984702 -293.707716) (xy 50.935088 -293.688244)
			(xy 50.88893 -293.661595) (xy 50.847259 -293.628364) (xy 50.811007 -293.589293) (xy 50.780983 -293.545256)
			(xy 50.757857 -293.497235) (xy 50.742147 -293.446305) (xy 50.734204 -293.393601) (xy 47.319918 -293.393601)
			(xy 47.312013 -293.446051) (xy 47.296303 -293.496981) (xy 47.273177 -293.545002) (xy 47.243153 -293.589039)
			(xy 47.206901 -293.62811) (xy 47.16523 -293.661341) (xy 47.119072 -293.68799) (xy 47.069458 -293.707462)
			(xy 47.017496 -293.719322) (xy 46.964346 -293.723306) (xy 46.911196 -293.719322) (xy 46.859234 -293.707462)
			(xy 46.80962 -293.68799) (xy 46.763462 -293.661341) (xy 46.721791 -293.62811) (xy 46.685539 -293.589039)
			(xy 46.655515 -293.545002) (xy 46.632389 -293.496981) (xy 46.616679 -293.446051) (xy 46.608736 -293.393347)
			(xy 36.332424 -293.393347) (xy 36.324481 -293.446051) (xy 36.308771 -293.496981) (xy 36.285645 -293.545002)
			(xy 36.255621 -293.589039) (xy 36.219369 -293.62811) (xy 36.177698 -293.661341) (xy 36.13154 -293.68799)
			(xy 36.081926 -293.707462) (xy 36.029964 -293.719322) (xy 35.976814 -293.723306) (xy 35.923664 -293.719322)
			(xy 35.871702 -293.707462) (xy 35.822088 -293.68799) (xy 35.77593 -293.661341) (xy 35.734259 -293.62811)
			(xy 35.698007 -293.589039) (xy 35.667983 -293.545002) (xy 35.644857 -293.496981) (xy 35.629147 -293.446051)
			(xy 35.621204 -293.393347) (xy 32.232356 -293.393347) (xy 32.224413 -293.446051) (xy 32.208703 -293.496981)
			(xy 32.185577 -293.545002) (xy 32.155553 -293.589039) (xy 32.119301 -293.62811) (xy 32.07763 -293.661341)
			(xy 32.031472 -293.68799) (xy 31.981858 -293.707462) (xy 31.929896 -293.719322) (xy 31.876746 -293.723306)
			(xy 31.823596 -293.719322) (xy 31.771634 -293.707462) (xy 31.72202 -293.68799) (xy 31.675862 -293.661341)
			(xy 31.634191 -293.62811) (xy 31.597939 -293.589039) (xy 31.567915 -293.545002) (xy 31.544789 -293.496981)
			(xy 31.529079 -293.446051) (xy 31.521136 -293.393347) (xy 21.244824 -293.393347) (xy 21.236881 -293.446051)
			(xy 21.221171 -293.496981) (xy 21.198045 -293.545002) (xy 21.168021 -293.589039) (xy 21.131769 -293.62811)
			(xy 21.090098 -293.661341) (xy 21.04394 -293.68799) (xy 20.994326 -293.707462) (xy 20.942364 -293.719322)
			(xy 20.889214 -293.723306) (xy 20.836064 -293.719322) (xy 20.784102 -293.707462) (xy 20.734488 -293.68799)
			(xy 20.68833 -293.661341) (xy 20.646659 -293.62811) (xy 20.610407 -293.589039) (xy 20.580383 -293.545002)
			(xy 20.557257 -293.496981) (xy 20.541547 -293.446051) (xy 20.533604 -293.393347) (xy 17.144756 -293.393347)
			(xy 17.136813 -293.446051) (xy 17.121103 -293.496981) (xy 17.097977 -293.545002) (xy 17.067953 -293.589039)
			(xy 17.031701 -293.62811) (xy 16.99003 -293.661341) (xy 16.943872 -293.68799) (xy 16.894258 -293.707462)
			(xy 16.842296 -293.719322) (xy 16.789146 -293.723306) (xy 16.735996 -293.719322) (xy 16.684034 -293.707462)
			(xy 16.63442 -293.68799) (xy 16.588262 -293.661341) (xy 16.546591 -293.62811) (xy 16.510339 -293.589039)
			(xy 16.480315 -293.545002) (xy 16.457189 -293.496981) (xy 16.441479 -293.446051) (xy 16.433536 -293.393347)
			(xy 9.6774 -293.393347) (xy 9.6774 -294.243231) (xy 16.433536 -294.243231) (xy 16.433536 -294.189933)
			(xy 16.441479 -294.137229) (xy 16.457189 -294.086299) (xy 16.480315 -294.038278) (xy 16.510339 -293.994241)
			(xy 16.546591 -293.95517) (xy 16.588262 -293.921939) (xy 16.63442 -293.89529) (xy 16.684034 -293.875818)
			(xy 16.735996 -293.863958) (xy 16.789146 -293.859975) (xy 16.842296 -293.863958) (xy 16.894258 -293.875818)
			(xy 16.943872 -293.89529) (xy 16.99003 -293.921939) (xy 17.031701 -293.95517) (xy 17.067953 -293.994241)
			(xy 17.097977 -294.038278) (xy 17.121103 -294.086299) (xy 17.136813 -294.137229) (xy 17.144756 -294.189933)
			(xy 17.145254 -294.216582) (xy 17.144756 -294.243231) (xy 31.521136 -294.243231) (xy 31.521136 -294.189933)
			(xy 31.529079 -294.137229) (xy 31.544789 -294.086299) (xy 31.567915 -294.038278) (xy 31.597939 -293.994241)
			(xy 31.634191 -293.95517) (xy 31.675862 -293.921939) (xy 31.72202 -293.89529) (xy 31.771634 -293.875818)
			(xy 31.823596 -293.863958) (xy 31.876746 -293.859975) (xy 31.929896 -293.863958) (xy 31.981858 -293.875818)
			(xy 32.031472 -293.89529) (xy 32.07763 -293.921939) (xy 32.119301 -293.95517) (xy 32.155553 -293.994241)
			(xy 32.185577 -294.038278) (xy 32.208703 -294.086299) (xy 32.224413 -294.137229) (xy 32.232356 -294.189933)
			(xy 32.232854 -294.216582) (xy 32.232356 -294.243231) (xy 46.608736 -294.243231) (xy 46.608736 -294.189933)
			(xy 46.616679 -294.137229) (xy 46.632389 -294.086299) (xy 46.655515 -294.038278) (xy 46.685539 -293.994241)
			(xy 46.721791 -293.95517) (xy 46.763462 -293.921939) (xy 46.80962 -293.89529) (xy 46.859234 -293.875818)
			(xy 46.911196 -293.863958) (xy 46.964346 -293.859975) (xy 47.017496 -293.863958) (xy 47.069458 -293.875818)
			(xy 47.119072 -293.89529) (xy 47.16523 -293.921939) (xy 47.206901 -293.95517) (xy 47.243153 -293.994241)
			(xy 47.273177 -294.038278) (xy 47.296303 -294.086299) (xy 47.312013 -294.137229) (xy 47.319956 -294.189933)
			(xy 47.320454 -294.216582) (xy 47.319956 -294.243231) (xy 47.312013 -294.295935) (xy 47.296303 -294.346865)
			(xy 47.273177 -294.394886) (xy 47.243153 -294.438923) (xy 47.206901 -294.477994) (xy 47.16523 -294.511225)
			(xy 47.119072 -294.537874) (xy 47.069458 -294.557346) (xy 47.017496 -294.569206) (xy 46.964346 -294.57319)
			(xy 46.911196 -294.569206) (xy 46.859234 -294.557346) (xy 46.80962 -294.537874) (xy 46.763462 -294.511225)
			(xy 46.721791 -294.477994) (xy 46.685539 -294.438923) (xy 46.655515 -294.394886) (xy 46.632389 -294.346865)
			(xy 46.616679 -294.295935) (xy 46.608736 -294.243231) (xy 32.232356 -294.243231) (xy 32.224413 -294.295935)
			(xy 32.208703 -294.346865) (xy 32.185577 -294.394886) (xy 32.155553 -294.438923) (xy 32.119301 -294.477994)
			(xy 32.07763 -294.511225) (xy 32.031472 -294.537874) (xy 31.981858 -294.557346) (xy 31.929896 -294.569206)
			(xy 31.876746 -294.57319) (xy 31.823596 -294.569206) (xy 31.771634 -294.557346) (xy 31.72202 -294.537874)
			(xy 31.675862 -294.511225) (xy 31.634191 -294.477994) (xy 31.597939 -294.438923) (xy 31.567915 -294.394886)
			(xy 31.544789 -294.346865) (xy 31.529079 -294.295935) (xy 31.521136 -294.243231) (xy 17.144756 -294.243231)
			(xy 17.136813 -294.295935) (xy 17.121103 -294.346865) (xy 17.097977 -294.394886) (xy 17.067953 -294.438923)
			(xy 17.031701 -294.477994) (xy 16.99003 -294.511225) (xy 16.943872 -294.537874) (xy 16.894258 -294.557346)
			(xy 16.842296 -294.569206) (xy 16.789146 -294.57319) (xy 16.735996 -294.569206) (xy 16.684034 -294.557346)
			(xy 16.63442 -294.537874) (xy 16.588262 -294.511225) (xy 16.546591 -294.477994) (xy 16.510339 -294.438923)
			(xy 16.480315 -294.394886) (xy 16.457189 -294.346865) (xy 16.441479 -294.295935) (xy 16.433536 -294.243231)
			(xy 9.6774 -294.243231) (xy 9.6774 -295.093369) (xy 20.533604 -295.093369) (xy 20.533604 -295.040071)
			(xy 20.541547 -294.987367) (xy 20.557257 -294.936437) (xy 20.580383 -294.888416) (xy 20.610407 -294.844379)
			(xy 20.646659 -294.805308) (xy 20.68833 -294.772077) (xy 20.734488 -294.745428) (xy 20.784102 -294.725956)
			(xy 20.836064 -294.714096) (xy 20.889214 -294.710113) (xy 20.942364 -294.714096) (xy 20.994326 -294.725956)
			(xy 21.04394 -294.745428) (xy 21.090098 -294.772077) (xy 21.131769 -294.805308) (xy 21.168021 -294.844379)
			(xy 21.198045 -294.888416) (xy 21.221171 -294.936437) (xy 21.236881 -294.987367) (xy 21.244824 -295.040071)
			(xy 21.245322 -295.06672) (xy 21.244824 -295.093369) (xy 35.621204 -295.093369) (xy 35.621204 -295.040071)
			(xy 35.629147 -294.987367) (xy 35.644857 -294.936437) (xy 35.667983 -294.888416) (xy 35.698007 -294.844379)
			(xy 35.734259 -294.805308) (xy 35.77593 -294.772077) (xy 35.822088 -294.745428) (xy 35.871702 -294.725956)
			(xy 35.923664 -294.714096) (xy 35.976814 -294.710113) (xy 36.029964 -294.714096) (xy 36.081926 -294.725956)
			(xy 36.13154 -294.745428) (xy 36.177698 -294.772077) (xy 36.219369 -294.805308) (xy 36.255621 -294.844379)
			(xy 36.285645 -294.888416) (xy 36.308771 -294.936437) (xy 36.324481 -294.987367) (xy 36.332424 -295.040071)
			(xy 36.332922 -295.06672) (xy 36.332424 -295.093369) (xy 50.734204 -295.093369) (xy 50.734204 -295.040071)
			(xy 50.742147 -294.987367) (xy 50.757857 -294.936437) (xy 50.780983 -294.888416) (xy 50.811007 -294.844379)
			(xy 50.847259 -294.805308) (xy 50.88893 -294.772077) (xy 50.935088 -294.745428) (xy 50.984702 -294.725956)
			(xy 51.036664 -294.714096) (xy 51.089814 -294.710113) (xy 51.142964 -294.714096) (xy 51.194926 -294.725956)
			(xy 51.24454 -294.745428) (xy 51.290698 -294.772077) (xy 51.332369 -294.805308) (xy 51.368621 -294.844379)
			(xy 51.398645 -294.888416) (xy 51.421771 -294.936437) (xy 51.437481 -294.987367) (xy 51.445424 -295.040071)
			(xy 51.445922 -295.06672) (xy 51.445424 -295.093369) (xy 51.437481 -295.146073) (xy 51.421771 -295.197003)
			(xy 51.398645 -295.245024) (xy 51.368621 -295.289061) (xy 51.332369 -295.328132) (xy 51.290698 -295.361363)
			(xy 51.24454 -295.388012) (xy 51.194926 -295.407484) (xy 51.142964 -295.419344) (xy 51.089814 -295.423328)
			(xy 51.036664 -295.419344) (xy 50.984702 -295.407484) (xy 50.935088 -295.388012) (xy 50.88893 -295.361363)
			(xy 50.847259 -295.328132) (xy 50.811007 -295.289061) (xy 50.780983 -295.245024) (xy 50.757857 -295.197003)
			(xy 50.742147 -295.146073) (xy 50.734204 -295.093369) (xy 36.332424 -295.093369) (xy 36.324481 -295.146073)
			(xy 36.308771 -295.197003) (xy 36.285645 -295.245024) (xy 36.255621 -295.289061) (xy 36.219369 -295.328132)
			(xy 36.177698 -295.361363) (xy 36.13154 -295.388012) (xy 36.081926 -295.407484) (xy 36.029964 -295.419344)
			(xy 35.976814 -295.423328) (xy 35.923664 -295.419344) (xy 35.871702 -295.407484) (xy 35.822088 -295.388012)
			(xy 35.77593 -295.361363) (xy 35.734259 -295.328132) (xy 35.698007 -295.289061) (xy 35.667983 -295.245024)
			(xy 35.644857 -295.197003) (xy 35.629147 -295.146073) (xy 35.621204 -295.093369) (xy 21.244824 -295.093369)
			(xy 21.236881 -295.146073) (xy 21.221171 -295.197003) (xy 21.198045 -295.245024) (xy 21.168021 -295.289061)
			(xy 21.131769 -295.328132) (xy 21.090098 -295.361363) (xy 21.04394 -295.388012) (xy 20.994326 -295.407484)
			(xy 20.942364 -295.419344) (xy 20.889214 -295.423328) (xy 20.836064 -295.419344) (xy 20.784102 -295.407484)
			(xy 20.734488 -295.388012) (xy 20.68833 -295.361363) (xy 20.646659 -295.328132) (xy 20.610407 -295.289061)
			(xy 20.580383 -295.245024) (xy 20.557257 -295.197003) (xy 20.541547 -295.146073) (xy 20.533604 -295.093369)
			(xy 9.6774 -295.093369) (xy 9.6774 -295.943253) (xy 16.433536 -295.943253) (xy 16.433536 -295.889955)
			(xy 16.441479 -295.837251) (xy 16.457189 -295.786321) (xy 16.480315 -295.7383) (xy 16.510339 -295.694263)
			(xy 16.546591 -295.655192) (xy 16.588262 -295.621961) (xy 16.63442 -295.595312) (xy 16.684034 -295.57584)
			(xy 16.735996 -295.56398) (xy 16.789146 -295.559997) (xy 16.842296 -295.56398) (xy 16.894258 -295.57584)
			(xy 16.943872 -295.595312) (xy 16.99003 -295.621961) (xy 17.031701 -295.655192) (xy 17.067953 -295.694263)
			(xy 17.097977 -295.7383) (xy 17.121103 -295.786321) (xy 17.136813 -295.837251) (xy 17.144756 -295.889955)
			(xy 17.145254 -295.916604) (xy 17.144756 -295.943253) (xy 31.521136 -295.943253) (xy 31.521136 -295.889955)
			(xy 31.529079 -295.837251) (xy 31.544789 -295.786321) (xy 31.567915 -295.7383) (xy 31.597939 -295.694263)
			(xy 31.634191 -295.655192) (xy 31.675862 -295.621961) (xy 31.72202 -295.595312) (xy 31.771634 -295.57584)
			(xy 31.823596 -295.56398) (xy 31.876746 -295.559997) (xy 31.929896 -295.56398) (xy 31.981858 -295.57584)
			(xy 32.031472 -295.595312) (xy 32.07763 -295.621961) (xy 32.119301 -295.655192) (xy 32.155553 -295.694263)
			(xy 32.185577 -295.7383) (xy 32.208703 -295.786321) (xy 32.224413 -295.837251) (xy 32.232356 -295.889955)
			(xy 32.232854 -295.916604) (xy 32.232356 -295.943253) (xy 46.608736 -295.943253) (xy 46.608736 -295.889955)
			(xy 46.616679 -295.837251) (xy 46.632389 -295.786321) (xy 46.655515 -295.7383) (xy 46.685539 -295.694263)
			(xy 46.721791 -295.655192) (xy 46.763462 -295.621961) (xy 46.80962 -295.595312) (xy 46.859234 -295.57584)
			(xy 46.911196 -295.56398) (xy 46.964346 -295.559997) (xy 47.017496 -295.56398) (xy 47.069458 -295.57584)
			(xy 47.119072 -295.595312) (xy 47.16523 -295.621961) (xy 47.206901 -295.655192) (xy 47.243153 -295.694263)
			(xy 47.273177 -295.7383) (xy 47.296303 -295.786321) (xy 47.312013 -295.837251) (xy 47.319956 -295.889955)
			(xy 47.320454 -295.916604) (xy 47.319956 -295.943253) (xy 47.312013 -295.995957) (xy 47.296303 -296.046887)
			(xy 47.273177 -296.094908) (xy 47.243153 -296.138945) (xy 47.206901 -296.178016) (xy 47.16523 -296.211247)
			(xy 47.119072 -296.237896) (xy 47.069458 -296.257368) (xy 47.017496 -296.269228) (xy 46.964346 -296.273212)
			(xy 46.911196 -296.269228) (xy 46.859234 -296.257368) (xy 46.80962 -296.237896) (xy 46.763462 -296.211247)
			(xy 46.721791 -296.178016) (xy 46.685539 -296.138945) (xy 46.655515 -296.094908) (xy 46.632389 -296.046887)
			(xy 46.616679 -295.995957) (xy 46.608736 -295.943253) (xy 32.232356 -295.943253) (xy 32.224413 -295.995957)
			(xy 32.208703 -296.046887) (xy 32.185577 -296.094908) (xy 32.155553 -296.138945) (xy 32.119301 -296.178016)
			(xy 32.07763 -296.211247) (xy 32.031472 -296.237896) (xy 31.981858 -296.257368) (xy 31.929896 -296.269228)
			(xy 31.876746 -296.273212) (xy 31.823596 -296.269228) (xy 31.771634 -296.257368) (xy 31.72202 -296.237896)
			(xy 31.675862 -296.211247) (xy 31.634191 -296.178016) (xy 31.597939 -296.138945) (xy 31.567915 -296.094908)
			(xy 31.544789 -296.046887) (xy 31.529079 -295.995957) (xy 31.521136 -295.943253) (xy 17.144756 -295.943253)
			(xy 17.136813 -295.995957) (xy 17.121103 -296.046887) (xy 17.097977 -296.094908) (xy 17.067953 -296.138945)
			(xy 17.031701 -296.178016) (xy 16.99003 -296.211247) (xy 16.943872 -296.237896) (xy 16.894258 -296.257368)
			(xy 16.842296 -296.269228) (xy 16.789146 -296.273212) (xy 16.735996 -296.269228) (xy 16.684034 -296.257368)
			(xy 16.63442 -296.237896) (xy 16.588262 -296.211247) (xy 16.546591 -296.178016) (xy 16.510339 -296.138945)
			(xy 16.480315 -296.094908) (xy 16.457189 -296.046887) (xy 16.441479 -295.995957) (xy 16.433536 -295.943253)
			(xy 9.6774 -295.943253) (xy 9.6774 -296.793391) (xy 20.533604 -296.793391) (xy 20.533604 -296.740093)
			(xy 20.541547 -296.687389) (xy 20.557257 -296.636459) (xy 20.580383 -296.588438) (xy 20.610407 -296.544401)
			(xy 20.646659 -296.50533) (xy 20.68833 -296.472099) (xy 20.734488 -296.44545) (xy 20.784102 -296.425978)
			(xy 20.836064 -296.414118) (xy 20.889214 -296.410135) (xy 20.942364 -296.414118) (xy 20.994326 -296.425978)
			(xy 21.04394 -296.44545) (xy 21.090098 -296.472099) (xy 21.131769 -296.50533) (xy 21.168021 -296.544401)
			(xy 21.198045 -296.588438) (xy 21.221171 -296.636459) (xy 21.236881 -296.687389) (xy 21.244824 -296.740093)
			(xy 21.245322 -296.766742) (xy 21.244824 -296.793391) (xy 35.621204 -296.793391) (xy 35.621204 -296.740093)
			(xy 35.629147 -296.687389) (xy 35.644857 -296.636459) (xy 35.667983 -296.588438) (xy 35.698007 -296.544401)
			(xy 35.734259 -296.50533) (xy 35.77593 -296.472099) (xy 35.822088 -296.44545) (xy 35.871702 -296.425978)
			(xy 35.923664 -296.414118) (xy 35.976814 -296.410135) (xy 36.029964 -296.414118) (xy 36.081926 -296.425978)
			(xy 36.13154 -296.44545) (xy 36.177698 -296.472099) (xy 36.219369 -296.50533) (xy 36.255621 -296.544401)
			(xy 36.285645 -296.588438) (xy 36.308771 -296.636459) (xy 36.324481 -296.687389) (xy 36.332424 -296.740093)
			(xy 36.332922 -296.766742) (xy 36.332424 -296.793391) (xy 50.734204 -296.793391) (xy 50.734204 -296.740093)
			(xy 50.742147 -296.687389) (xy 50.757857 -296.636459) (xy 50.780983 -296.588438) (xy 50.811007 -296.544401)
			(xy 50.847259 -296.50533) (xy 50.88893 -296.472099) (xy 50.935088 -296.44545) (xy 50.984702 -296.425978)
			(xy 51.036664 -296.414118) (xy 51.089814 -296.410135) (xy 51.142964 -296.414118) (xy 51.194926 -296.425978)
			(xy 51.24454 -296.44545) (xy 51.290698 -296.472099) (xy 51.332369 -296.50533) (xy 51.368621 -296.544401)
			(xy 51.398645 -296.588438) (xy 51.421771 -296.636459) (xy 51.437481 -296.687389) (xy 51.445424 -296.740093)
			(xy 51.445922 -296.766742) (xy 51.445424 -296.793391) (xy 51.437481 -296.846095) (xy 51.421771 -296.897025)
			(xy 51.398645 -296.945046) (xy 51.368621 -296.989083) (xy 51.332369 -297.028154) (xy 51.290698 -297.061385)
			(xy 51.24454 -297.088034) (xy 51.194926 -297.107506) (xy 51.142964 -297.119366) (xy 51.089814 -297.12335)
			(xy 51.036664 -297.119366) (xy 50.984702 -297.107506) (xy 50.935088 -297.088034) (xy 50.88893 -297.061385)
			(xy 50.847259 -297.028154) (xy 50.811007 -296.989083) (xy 50.780983 -296.945046) (xy 50.757857 -296.897025)
			(xy 50.742147 -296.846095) (xy 50.734204 -296.793391) (xy 36.332424 -296.793391) (xy 36.324481 -296.846095)
			(xy 36.308771 -296.897025) (xy 36.285645 -296.945046) (xy 36.255621 -296.989083) (xy 36.219369 -297.028154)
			(xy 36.177698 -297.061385) (xy 36.13154 -297.088034) (xy 36.081926 -297.107506) (xy 36.029964 -297.119366)
			(xy 35.976814 -297.12335) (xy 35.923664 -297.119366) (xy 35.871702 -297.107506) (xy 35.822088 -297.088034)
			(xy 35.77593 -297.061385) (xy 35.734259 -297.028154) (xy 35.698007 -296.989083) (xy 35.667983 -296.945046)
			(xy 35.644857 -296.897025) (xy 35.629147 -296.846095) (xy 35.621204 -296.793391) (xy 21.244824 -296.793391)
			(xy 21.236881 -296.846095) (xy 21.221171 -296.897025) (xy 21.198045 -296.945046) (xy 21.168021 -296.989083)
			(xy 21.131769 -297.028154) (xy 21.090098 -297.061385) (xy 21.04394 -297.088034) (xy 20.994326 -297.107506)
			(xy 20.942364 -297.119366) (xy 20.889214 -297.12335) (xy 20.836064 -297.119366) (xy 20.784102 -297.107506)
			(xy 20.734488 -297.088034) (xy 20.68833 -297.061385) (xy 20.646659 -297.028154) (xy 20.610407 -296.989083)
			(xy 20.580383 -296.945046) (xy 20.557257 -296.897025) (xy 20.541547 -296.846095) (xy 20.533604 -296.793391)
			(xy 9.6774 -296.793391) (xy 9.6774 -297.643275) (xy 16.433536 -297.643275) (xy 16.433536 -297.589977)
			(xy 16.441479 -297.537273) (xy 16.457189 -297.486343) (xy 16.480315 -297.438322) (xy 16.510339 -297.394285)
			(xy 16.546591 -297.355214) (xy 16.588262 -297.321983) (xy 16.63442 -297.295334) (xy 16.684034 -297.275862)
			(xy 16.735996 -297.264002) (xy 16.789146 -297.260019) (xy 16.842296 -297.264002) (xy 16.894258 -297.275862)
			(xy 16.943872 -297.295334) (xy 16.99003 -297.321983) (xy 17.031701 -297.355214) (xy 17.067953 -297.394285)
			(xy 17.097977 -297.438322) (xy 17.121103 -297.486343) (xy 17.136813 -297.537273) (xy 17.144756 -297.589977)
			(xy 17.145254 -297.616626) (xy 17.144756 -297.643275) (xy 31.521136 -297.643275) (xy 31.521136 -297.589977)
			(xy 31.529079 -297.537273) (xy 31.544789 -297.486343) (xy 31.567915 -297.438322) (xy 31.597939 -297.394285)
			(xy 31.634191 -297.355214) (xy 31.675862 -297.321983) (xy 31.72202 -297.295334) (xy 31.771634 -297.275862)
			(xy 31.823596 -297.264002) (xy 31.876746 -297.260019) (xy 31.929896 -297.264002) (xy 31.981858 -297.275862)
			(xy 32.031472 -297.295334) (xy 32.07763 -297.321983) (xy 32.119301 -297.355214) (xy 32.155553 -297.394285)
			(xy 32.185577 -297.438322) (xy 32.208703 -297.486343) (xy 32.224413 -297.537273) (xy 32.232356 -297.589977)
			(xy 32.232854 -297.616626) (xy 32.232356 -297.643275) (xy 46.608736 -297.643275) (xy 46.608736 -297.589977)
			(xy 46.616679 -297.537273) (xy 46.632389 -297.486343) (xy 46.655515 -297.438322) (xy 46.685539 -297.394285)
			(xy 46.721791 -297.355214) (xy 46.763462 -297.321983) (xy 46.80962 -297.295334) (xy 46.859234 -297.275862)
			(xy 46.911196 -297.264002) (xy 46.964346 -297.260019) (xy 47.017496 -297.264002) (xy 47.069458 -297.275862)
			(xy 47.119072 -297.295334) (xy 47.16523 -297.321983) (xy 47.206901 -297.355214) (xy 47.243153 -297.394285)
			(xy 47.273177 -297.438322) (xy 47.296303 -297.486343) (xy 47.312013 -297.537273) (xy 47.319956 -297.589977)
			(xy 47.320454 -297.616626) (xy 47.319956 -297.643275) (xy 47.312013 -297.695979) (xy 47.296303 -297.746909)
			(xy 47.273177 -297.79493) (xy 47.243153 -297.838967) (xy 47.206901 -297.878038) (xy 47.16523 -297.911269)
			(xy 47.119072 -297.937918) (xy 47.069458 -297.95739) (xy 47.017496 -297.96925) (xy 46.964346 -297.973234)
			(xy 46.911196 -297.96925) (xy 46.859234 -297.95739) (xy 46.80962 -297.937918) (xy 46.763462 -297.911269)
			(xy 46.721791 -297.878038) (xy 46.685539 -297.838967) (xy 46.655515 -297.79493) (xy 46.632389 -297.746909)
			(xy 46.616679 -297.695979) (xy 46.608736 -297.643275) (xy 32.232356 -297.643275) (xy 32.224413 -297.695979)
			(xy 32.208703 -297.746909) (xy 32.185577 -297.79493) (xy 32.155553 -297.838967) (xy 32.119301 -297.878038)
			(xy 32.07763 -297.911269) (xy 32.031472 -297.937918) (xy 31.981858 -297.95739) (xy 31.929896 -297.96925)
			(xy 31.876746 -297.973234) (xy 31.823596 -297.96925) (xy 31.771634 -297.95739) (xy 31.72202 -297.937918)
			(xy 31.675862 -297.911269) (xy 31.634191 -297.878038) (xy 31.597939 -297.838967) (xy 31.567915 -297.79493)
			(xy 31.544789 -297.746909) (xy 31.529079 -297.695979) (xy 31.521136 -297.643275) (xy 17.144756 -297.643275)
			(xy 17.136813 -297.695979) (xy 17.121103 -297.746909) (xy 17.097977 -297.79493) (xy 17.067953 -297.838967)
			(xy 17.031701 -297.878038) (xy 16.99003 -297.911269) (xy 16.943872 -297.937918) (xy 16.894258 -297.95739)
			(xy 16.842296 -297.96925) (xy 16.789146 -297.973234) (xy 16.735996 -297.96925) (xy 16.684034 -297.95739)
			(xy 16.63442 -297.937918) (xy 16.588262 -297.911269) (xy 16.546591 -297.878038) (xy 16.510339 -297.838967)
			(xy 16.480315 -297.79493) (xy 16.457189 -297.746909) (xy 16.441479 -297.695979) (xy 16.433536 -297.643275)
			(xy 9.6774 -297.643275) (xy 9.6774 -298.493413) (xy 20.533604 -298.493413) (xy 20.533604 -298.440115)
			(xy 20.541547 -298.387411) (xy 20.557257 -298.336481) (xy 20.580383 -298.28846) (xy 20.610407 -298.244423)
			(xy 20.646659 -298.205352) (xy 20.68833 -298.172121) (xy 20.734488 -298.145472) (xy 20.784102 -298.126)
			(xy 20.836064 -298.11414) (xy 20.889214 -298.110157) (xy 20.942364 -298.11414) (xy 20.994326 -298.126)
			(xy 21.04394 -298.145472) (xy 21.090098 -298.172121) (xy 21.131769 -298.205352) (xy 21.168021 -298.244423)
			(xy 21.198045 -298.28846) (xy 21.221171 -298.336481) (xy 21.236881 -298.387411) (xy 21.244824 -298.440115)
			(xy 21.245322 -298.466764) (xy 21.244824 -298.493413) (xy 35.621204 -298.493413) (xy 35.621204 -298.440115)
			(xy 35.629147 -298.387411) (xy 35.644857 -298.336481) (xy 35.667983 -298.28846) (xy 35.698007 -298.244423)
			(xy 35.734259 -298.205352) (xy 35.77593 -298.172121) (xy 35.822088 -298.145472) (xy 35.871702 -298.126)
			(xy 35.923664 -298.11414) (xy 35.976814 -298.110157) (xy 36.029964 -298.11414) (xy 36.081926 -298.126)
			(xy 36.13154 -298.145472) (xy 36.177698 -298.172121) (xy 36.219369 -298.205352) (xy 36.255621 -298.244423)
			(xy 36.285645 -298.28846) (xy 36.308771 -298.336481) (xy 36.324481 -298.387411) (xy 36.332424 -298.440115)
			(xy 36.332922 -298.466764) (xy 36.332424 -298.493413) (xy 50.734204 -298.493413) (xy 50.734204 -298.440115)
			(xy 50.742147 -298.387411) (xy 50.757857 -298.336481) (xy 50.780983 -298.28846) (xy 50.811007 -298.244423)
			(xy 50.847259 -298.205352) (xy 50.88893 -298.172121) (xy 50.935088 -298.145472) (xy 50.984702 -298.126)
			(xy 51.036664 -298.11414) (xy 51.089814 -298.110157) (xy 51.142964 -298.11414) (xy 51.194926 -298.126)
			(xy 51.24454 -298.145472) (xy 51.290698 -298.172121) (xy 51.332369 -298.205352) (xy 51.368621 -298.244423)
			(xy 51.398645 -298.28846) (xy 51.421771 -298.336481) (xy 51.437481 -298.387411) (xy 51.445424 -298.440115)
			(xy 51.445922 -298.466764) (xy 51.445424 -298.493413) (xy 51.437481 -298.546117) (xy 51.421771 -298.597047)
			(xy 51.398645 -298.645068) (xy 51.368621 -298.689105) (xy 51.332369 -298.728176) (xy 51.290698 -298.761407)
			(xy 51.24454 -298.788056) (xy 51.194926 -298.807528) (xy 51.142964 -298.819388) (xy 51.089814 -298.823372)
			(xy 51.036664 -298.819388) (xy 50.984702 -298.807528) (xy 50.935088 -298.788056) (xy 50.88893 -298.761407)
			(xy 50.847259 -298.728176) (xy 50.811007 -298.689105) (xy 50.780983 -298.645068) (xy 50.757857 -298.597047)
			(xy 50.742147 -298.546117) (xy 50.734204 -298.493413) (xy 36.332424 -298.493413) (xy 36.324481 -298.546117)
			(xy 36.308771 -298.597047) (xy 36.285645 -298.645068) (xy 36.255621 -298.689105) (xy 36.219369 -298.728176)
			(xy 36.177698 -298.761407) (xy 36.13154 -298.788056) (xy 36.081926 -298.807528) (xy 36.029964 -298.819388)
			(xy 35.976814 -298.823372) (xy 35.923664 -298.819388) (xy 35.871702 -298.807528) (xy 35.822088 -298.788056)
			(xy 35.77593 -298.761407) (xy 35.734259 -298.728176) (xy 35.698007 -298.689105) (xy 35.667983 -298.645068)
			(xy 35.644857 -298.597047) (xy 35.629147 -298.546117) (xy 35.621204 -298.493413) (xy 21.244824 -298.493413)
			(xy 21.236881 -298.546117) (xy 21.221171 -298.597047) (xy 21.198045 -298.645068) (xy 21.168021 -298.689105)
			(xy 21.131769 -298.728176) (xy 21.090098 -298.761407) (xy 21.04394 -298.788056) (xy 20.994326 -298.807528)
			(xy 20.942364 -298.819388) (xy 20.889214 -298.823372) (xy 20.836064 -298.819388) (xy 20.784102 -298.807528)
			(xy 20.734488 -298.788056) (xy 20.68833 -298.761407) (xy 20.646659 -298.728176) (xy 20.610407 -298.689105)
			(xy 20.580383 -298.645068) (xy 20.557257 -298.597047) (xy 20.541547 -298.546117) (xy 20.533604 -298.493413)
			(xy 9.6774 -298.493413) (xy 9.6774 -299.343297) (xy 16.433536 -299.343297) (xy 16.433536 -299.289999)
			(xy 16.441479 -299.237295) (xy 16.457189 -299.186365) (xy 16.480315 -299.138344) (xy 16.510339 -299.094307)
			(xy 16.546591 -299.055236) (xy 16.588262 -299.022005) (xy 16.63442 -298.995356) (xy 16.684034 -298.975884)
			(xy 16.735996 -298.964024) (xy 16.789146 -298.960041) (xy 16.842296 -298.964024) (xy 16.894258 -298.975884)
			(xy 16.943872 -298.995356) (xy 16.99003 -299.022005) (xy 17.031701 -299.055236) (xy 17.067953 -299.094307)
			(xy 17.097977 -299.138344) (xy 17.121103 -299.186365) (xy 17.136813 -299.237295) (xy 17.144756 -299.289999)
			(xy 17.145254 -299.316648) (xy 17.144756 -299.343297) (xy 31.521136 -299.343297) (xy 31.521136 -299.289999)
			(xy 31.529079 -299.237295) (xy 31.544789 -299.186365) (xy 31.567915 -299.138344) (xy 31.597939 -299.094307)
			(xy 31.634191 -299.055236) (xy 31.675862 -299.022005) (xy 31.72202 -298.995356) (xy 31.771634 -298.975884)
			(xy 31.823596 -298.964024) (xy 31.876746 -298.960041) (xy 31.929896 -298.964024) (xy 31.981858 -298.975884)
			(xy 32.031472 -298.995356) (xy 32.07763 -299.022005) (xy 32.119301 -299.055236) (xy 32.155553 -299.094307)
			(xy 32.185577 -299.138344) (xy 32.208703 -299.186365) (xy 32.224413 -299.237295) (xy 32.232356 -299.289999)
			(xy 32.232854 -299.316648) (xy 32.232356 -299.343297) (xy 46.608736 -299.343297) (xy 46.608736 -299.289999)
			(xy 46.616679 -299.237295) (xy 46.632389 -299.186365) (xy 46.655515 -299.138344) (xy 46.685539 -299.094307)
			(xy 46.721791 -299.055236) (xy 46.763462 -299.022005) (xy 46.80962 -298.995356) (xy 46.859234 -298.975884)
			(xy 46.911196 -298.964024) (xy 46.964346 -298.960041) (xy 47.017496 -298.964024) (xy 47.069458 -298.975884)
			(xy 47.119072 -298.995356) (xy 47.16523 -299.022005) (xy 47.206901 -299.055236) (xy 47.243153 -299.094307)
			(xy 47.273177 -299.138344) (xy 47.296303 -299.186365) (xy 47.312013 -299.237295) (xy 47.319956 -299.289999)
			(xy 47.320454 -299.316648) (xy 47.319956 -299.343297) (xy 61.696336 -299.343297) (xy 61.696336 -299.289999)
			(xy 61.704279 -299.237295) (xy 61.719989 -299.186365) (xy 61.743115 -299.138344) (xy 61.773139 -299.094307)
			(xy 61.809391 -299.055236) (xy 61.851062 -299.022005) (xy 61.89722 -298.995356) (xy 61.946834 -298.975884)
			(xy 61.998796 -298.964024) (xy 62.051946 -298.960041) (xy 62.105096 -298.964024) (xy 62.157058 -298.975884)
			(xy 62.206672 -298.995356) (xy 62.25283 -299.022005) (xy 62.294501 -299.055236) (xy 62.330753 -299.094307)
			(xy 62.360777 -299.138344) (xy 62.383903 -299.186365) (xy 62.399613 -299.237295) (xy 62.407556 -299.289999)
			(xy 62.408054 -299.316648) (xy 62.407556 -299.343297) (xy 62.399613 -299.396001) (xy 62.383903 -299.446931)
			(xy 62.360777 -299.494952) (xy 62.330753 -299.538989) (xy 62.294501 -299.57806) (xy 62.25283 -299.611291)
			(xy 62.206672 -299.63794) (xy 62.157058 -299.657412) (xy 62.105096 -299.669272) (xy 62.051946 -299.673256)
			(xy 61.998796 -299.669272) (xy 61.946834 -299.657412) (xy 61.89722 -299.63794) (xy 61.851062 -299.611291)
			(xy 61.809391 -299.57806) (xy 61.773139 -299.538989) (xy 61.743115 -299.494952) (xy 61.719989 -299.446931)
			(xy 61.704279 -299.396001) (xy 61.696336 -299.343297) (xy 47.319956 -299.343297) (xy 47.312013 -299.396001)
			(xy 47.296303 -299.446931) (xy 47.273177 -299.494952) (xy 47.243153 -299.538989) (xy 47.206901 -299.57806)
			(xy 47.16523 -299.611291) (xy 47.119072 -299.63794) (xy 47.069458 -299.657412) (xy 47.017496 -299.669272)
			(xy 46.964346 -299.673256) (xy 46.911196 -299.669272) (xy 46.859234 -299.657412) (xy 46.80962 -299.63794)
			(xy 46.763462 -299.611291) (xy 46.721791 -299.57806) (xy 46.685539 -299.538989) (xy 46.655515 -299.494952)
			(xy 46.632389 -299.446931) (xy 46.616679 -299.396001) (xy 46.608736 -299.343297) (xy 32.232356 -299.343297)
			(xy 32.224413 -299.396001) (xy 32.208703 -299.446931) (xy 32.185577 -299.494952) (xy 32.155553 -299.538989)
			(xy 32.119301 -299.57806) (xy 32.07763 -299.611291) (xy 32.031472 -299.63794) (xy 31.981858 -299.657412)
			(xy 31.929896 -299.669272) (xy 31.876746 -299.673256) (xy 31.823596 -299.669272) (xy 31.771634 -299.657412)
			(xy 31.72202 -299.63794) (xy 31.675862 -299.611291) (xy 31.634191 -299.57806) (xy 31.597939 -299.538989)
			(xy 31.567915 -299.494952) (xy 31.544789 -299.446931) (xy 31.529079 -299.396001) (xy 31.521136 -299.343297)
			(xy 17.144756 -299.343297) (xy 17.136813 -299.396001) (xy 17.121103 -299.446931) (xy 17.097977 -299.494952)
			(xy 17.067953 -299.538989) (xy 17.031701 -299.57806) (xy 16.99003 -299.611291) (xy 16.943872 -299.63794)
			(xy 16.894258 -299.657412) (xy 16.842296 -299.669272) (xy 16.789146 -299.673256) (xy 16.735996 -299.669272)
			(xy 16.684034 -299.657412) (xy 16.63442 -299.63794) (xy 16.588262 -299.611291) (xy 16.546591 -299.57806)
			(xy 16.510339 -299.538989) (xy 16.480315 -299.494952) (xy 16.457189 -299.446931) (xy 16.441479 -299.396001)
			(xy 16.433536 -299.343297) (xy 9.6774 -299.343297) (xy 9.6774 -300.193435) (xy 20.533604 -300.193435)
			(xy 20.533604 -300.140137) (xy 20.541547 -300.087433) (xy 20.557257 -300.036503) (xy 20.580383 -299.988482)
			(xy 20.610407 -299.944445) (xy 20.646659 -299.905374) (xy 20.68833 -299.872143) (xy 20.734488 -299.845494)
			(xy 20.784102 -299.826022) (xy 20.836064 -299.814162) (xy 20.889214 -299.810179) (xy 20.942364 -299.814162)
			(xy 20.994326 -299.826022) (xy 21.04394 -299.845494) (xy 21.090098 -299.872143) (xy 21.131769 -299.905374)
			(xy 21.168021 -299.944445) (xy 21.198045 -299.988482) (xy 21.221171 -300.036503) (xy 21.236881 -300.087433)
			(xy 21.244824 -300.140137) (xy 21.245322 -300.166786) (xy 21.244824 -300.193435) (xy 35.621204 -300.193435)
			(xy 35.621204 -300.140137) (xy 35.629147 -300.087433) (xy 35.644857 -300.036503) (xy 35.667983 -299.988482)
			(xy 35.698007 -299.944445) (xy 35.734259 -299.905374) (xy 35.77593 -299.872143) (xy 35.822088 -299.845494)
			(xy 35.871702 -299.826022) (xy 35.923664 -299.814162) (xy 35.976814 -299.810179) (xy 36.029964 -299.814162)
			(xy 36.081926 -299.826022) (xy 36.13154 -299.845494) (xy 36.177698 -299.872143) (xy 36.219369 -299.905374)
			(xy 36.255621 -299.944445) (xy 36.285645 -299.988482) (xy 36.308771 -300.036503) (xy 36.324481 -300.087433)
			(xy 36.332424 -300.140137) (xy 36.332922 -300.166786) (xy 36.332424 -300.193435) (xy 50.734204 -300.193435)
			(xy 50.734204 -300.140137) (xy 50.742147 -300.087433) (xy 50.757857 -300.036503) (xy 50.780983 -299.988482)
			(xy 50.811007 -299.944445) (xy 50.847259 -299.905374) (xy 50.88893 -299.872143) (xy 50.935088 -299.845494)
			(xy 50.984702 -299.826022) (xy 51.036664 -299.814162) (xy 51.089814 -299.810179) (xy 51.142964 -299.814162)
			(xy 51.194926 -299.826022) (xy 51.24454 -299.845494) (xy 51.290698 -299.872143) (xy 51.332369 -299.905374)
			(xy 51.368621 -299.944445) (xy 51.398645 -299.988482) (xy 51.421771 -300.036503) (xy 51.437481 -300.087433)
			(xy 51.445424 -300.140137) (xy 51.445922 -300.166786) (xy 51.445424 -300.193435) (xy 51.437481 -300.246139)
			(xy 51.421771 -300.297069) (xy 51.398645 -300.34509) (xy 51.368621 -300.389127) (xy 51.332369 -300.428198)
			(xy 51.290698 -300.461429) (xy 51.24454 -300.488078) (xy 51.194926 -300.50755) (xy 51.142964 -300.51941)
			(xy 51.089814 -300.523394) (xy 51.036664 -300.51941) (xy 50.984702 -300.50755) (xy 50.935088 -300.488078)
			(xy 50.88893 -300.461429) (xy 50.847259 -300.428198) (xy 50.811007 -300.389127) (xy 50.780983 -300.34509)
			(xy 50.757857 -300.297069) (xy 50.742147 -300.246139) (xy 50.734204 -300.193435) (xy 36.332424 -300.193435)
			(xy 36.324481 -300.246139) (xy 36.308771 -300.297069) (xy 36.285645 -300.34509) (xy 36.255621 -300.389127)
			(xy 36.219369 -300.428198) (xy 36.177698 -300.461429) (xy 36.13154 -300.488078) (xy 36.081926 -300.50755)
			(xy 36.029964 -300.51941) (xy 35.976814 -300.523394) (xy 35.923664 -300.51941) (xy 35.871702 -300.50755)
			(xy 35.822088 -300.488078) (xy 35.77593 -300.461429) (xy 35.734259 -300.428198) (xy 35.698007 -300.389127)
			(xy 35.667983 -300.34509) (xy 35.644857 -300.297069) (xy 35.629147 -300.246139) (xy 35.621204 -300.193435)
			(xy 21.244824 -300.193435) (xy 21.236881 -300.246139) (xy 21.221171 -300.297069) (xy 21.198045 -300.34509)
			(xy 21.168021 -300.389127) (xy 21.131769 -300.428198) (xy 21.090098 -300.461429) (xy 21.04394 -300.488078)
			(xy 20.994326 -300.50755) (xy 20.942364 -300.51941) (xy 20.889214 -300.523394) (xy 20.836064 -300.51941)
			(xy 20.784102 -300.50755) (xy 20.734488 -300.488078) (xy 20.68833 -300.461429) (xy 20.646659 -300.428198)
			(xy 20.610407 -300.389127) (xy 20.580383 -300.34509) (xy 20.557257 -300.297069) (xy 20.541547 -300.246139)
			(xy 20.533604 -300.193435) (xy 9.6774 -300.193435) (xy 9.6774 -301.043319) (xy 16.433536 -301.043319)
			(xy 16.433536 -300.990021) (xy 16.441479 -300.937317) (xy 16.457189 -300.886387) (xy 16.480315 -300.838366)
			(xy 16.510339 -300.794329) (xy 16.546591 -300.755258) (xy 16.588262 -300.722027) (xy 16.63442 -300.695378)
			(xy 16.684034 -300.675906) (xy 16.735996 -300.664046) (xy 16.789146 -300.660063) (xy 16.842296 -300.664046)
			(xy 16.894258 -300.675906) (xy 16.943872 -300.695378) (xy 16.99003 -300.722027) (xy 17.031701 -300.755258)
			(xy 17.067953 -300.794329) (xy 17.097977 -300.838366) (xy 17.121103 -300.886387) (xy 17.136813 -300.937317)
			(xy 17.144756 -300.990021) (xy 17.145254 -301.01667) (xy 17.144756 -301.043319) (xy 31.521136 -301.043319)
			(xy 31.521136 -300.990021) (xy 31.529079 -300.937317) (xy 31.544789 -300.886387) (xy 31.567915 -300.838366)
			(xy 31.597939 -300.794329) (xy 31.634191 -300.755258) (xy 31.675862 -300.722027) (xy 31.72202 -300.695378)
			(xy 31.771634 -300.675906) (xy 31.823596 -300.664046) (xy 31.876746 -300.660063) (xy 31.929896 -300.664046)
			(xy 31.981858 -300.675906) (xy 32.031472 -300.695378) (xy 32.07763 -300.722027) (xy 32.119301 -300.755258)
			(xy 32.155553 -300.794329) (xy 32.185577 -300.838366) (xy 32.208703 -300.886387) (xy 32.224413 -300.937317)
			(xy 32.232356 -300.990021) (xy 32.232854 -301.01667) (xy 32.232356 -301.043319) (xy 46.608736 -301.043319)
			(xy 46.608736 -300.990021) (xy 46.616679 -300.937317) (xy 46.632389 -300.886387) (xy 46.655515 -300.838366)
			(xy 46.685539 -300.794329) (xy 46.721791 -300.755258) (xy 46.763462 -300.722027) (xy 46.80962 -300.695378)
			(xy 46.859234 -300.675906) (xy 46.911196 -300.664046) (xy 46.964346 -300.660063) (xy 47.017496 -300.664046)
			(xy 47.069458 -300.675906) (xy 47.119072 -300.695378) (xy 47.16523 -300.722027) (xy 47.206901 -300.755258)
			(xy 47.243153 -300.794329) (xy 47.273177 -300.838366) (xy 47.296303 -300.886387) (xy 47.312013 -300.937317)
			(xy 47.319956 -300.990021) (xy 47.320454 -301.01667) (xy 47.319956 -301.043319) (xy 61.696336 -301.043319)
			(xy 61.696336 -300.990021) (xy 61.704279 -300.937317) (xy 61.719989 -300.886387) (xy 61.743115 -300.838366)
			(xy 61.773139 -300.794329) (xy 61.809391 -300.755258) (xy 61.851062 -300.722027) (xy 61.89722 -300.695378)
			(xy 61.946834 -300.675906) (xy 61.998796 -300.664046) (xy 62.051946 -300.660063) (xy 62.105096 -300.664046)
			(xy 62.157058 -300.675906) (xy 62.206672 -300.695378) (xy 62.25283 -300.722027) (xy 62.294501 -300.755258)
			(xy 62.330753 -300.794329) (xy 62.360777 -300.838366) (xy 62.383903 -300.886387) (xy 62.399613 -300.937317)
			(xy 62.407556 -300.990021) (xy 62.408054 -301.01667) (xy 62.407556 -301.043319) (xy 62.399613 -301.096023)
			(xy 62.383903 -301.146953) (xy 62.360777 -301.194974) (xy 62.330753 -301.239011) (xy 62.294501 -301.278082)
			(xy 62.25283 -301.311313) (xy 62.206672 -301.337962) (xy 62.157058 -301.357434) (xy 62.105096 -301.369294)
			(xy 62.051946 -301.373278) (xy 61.998796 -301.369294) (xy 61.946834 -301.357434) (xy 61.89722 -301.337962)
			(xy 61.851062 -301.311313) (xy 61.809391 -301.278082) (xy 61.773139 -301.239011) (xy 61.743115 -301.194974)
			(xy 61.719989 -301.146953) (xy 61.704279 -301.096023) (xy 61.696336 -301.043319) (xy 47.319956 -301.043319)
			(xy 47.312013 -301.096023) (xy 47.296303 -301.146953) (xy 47.273177 -301.194974) (xy 47.243153 -301.239011)
			(xy 47.206901 -301.278082) (xy 47.16523 -301.311313) (xy 47.119072 -301.337962) (xy 47.069458 -301.357434)
			(xy 47.017496 -301.369294) (xy 46.964346 -301.373278) (xy 46.911196 -301.369294) (xy 46.859234 -301.357434)
			(xy 46.80962 -301.337962) (xy 46.763462 -301.311313) (xy 46.721791 -301.278082) (xy 46.685539 -301.239011)
			(xy 46.655515 -301.194974) (xy 46.632389 -301.146953) (xy 46.616679 -301.096023) (xy 46.608736 -301.043319)
			(xy 32.232356 -301.043319) (xy 32.224413 -301.096023) (xy 32.208703 -301.146953) (xy 32.185577 -301.194974)
			(xy 32.155553 -301.239011) (xy 32.119301 -301.278082) (xy 32.07763 -301.311313) (xy 32.031472 -301.337962)
			(xy 31.981858 -301.357434) (xy 31.929896 -301.369294) (xy 31.876746 -301.373278) (xy 31.823596 -301.369294)
			(xy 31.771634 -301.357434) (xy 31.72202 -301.337962) (xy 31.675862 -301.311313) (xy 31.634191 -301.278082)
			(xy 31.597939 -301.239011) (xy 31.567915 -301.194974) (xy 31.544789 -301.146953) (xy 31.529079 -301.096023)
			(xy 31.521136 -301.043319) (xy 17.144756 -301.043319) (xy 17.136813 -301.096023) (xy 17.121103 -301.146953)
			(xy 17.097977 -301.194974) (xy 17.067953 -301.239011) (xy 17.031701 -301.278082) (xy 16.99003 -301.311313)
			(xy 16.943872 -301.337962) (xy 16.894258 -301.357434) (xy 16.842296 -301.369294) (xy 16.789146 -301.373278)
			(xy 16.735996 -301.369294) (xy 16.684034 -301.357434) (xy 16.63442 -301.337962) (xy 16.588262 -301.311313)
			(xy 16.546591 -301.278082) (xy 16.510339 -301.239011) (xy 16.480315 -301.194974) (xy 16.457189 -301.146953)
			(xy 16.441479 -301.096023) (xy 16.433536 -301.043319) (xy 9.6774 -301.043319) (xy 9.6774 -301.893457)
			(xy 20.533604 -301.893457) (xy 20.533604 -301.840159) (xy 20.541547 -301.787455) (xy 20.557257 -301.736525)
			(xy 20.580383 -301.688504) (xy 20.610407 -301.644467) (xy 20.646659 -301.605396) (xy 20.68833 -301.572165)
			(xy 20.734488 -301.545516) (xy 20.784102 -301.526044) (xy 20.836064 -301.514184) (xy 20.889214 -301.510201)
			(xy 20.942364 -301.514184) (xy 20.994326 -301.526044) (xy 21.04394 -301.545516) (xy 21.090098 -301.572165)
			(xy 21.131769 -301.605396) (xy 21.168021 -301.644467) (xy 21.198045 -301.688504) (xy 21.221171 -301.736525)
			(xy 21.236881 -301.787455) (xy 21.244824 -301.840159) (xy 21.245322 -301.866808) (xy 21.244824 -301.893457)
			(xy 35.621204 -301.893457) (xy 35.621204 -301.840159) (xy 35.629147 -301.787455) (xy 35.644857 -301.736525)
			(xy 35.667983 -301.688504) (xy 35.698007 -301.644467) (xy 35.734259 -301.605396) (xy 35.77593 -301.572165)
			(xy 35.822088 -301.545516) (xy 35.871702 -301.526044) (xy 35.923664 -301.514184) (xy 35.976814 -301.510201)
			(xy 36.029964 -301.514184) (xy 36.081926 -301.526044) (xy 36.13154 -301.545516) (xy 36.177698 -301.572165)
			(xy 36.219369 -301.605396) (xy 36.255621 -301.644467) (xy 36.285645 -301.688504) (xy 36.308771 -301.736525)
			(xy 36.324481 -301.787455) (xy 36.332424 -301.840159) (xy 36.332922 -301.866808) (xy 36.332424 -301.893457)
			(xy 50.734204 -301.893457) (xy 50.734204 -301.840159) (xy 50.742147 -301.787455) (xy 50.757857 -301.736525)
			(xy 50.780983 -301.688504) (xy 50.811007 -301.644467) (xy 50.847259 -301.605396) (xy 50.88893 -301.572165)
			(xy 50.935088 -301.545516) (xy 50.984702 -301.526044) (xy 51.036664 -301.514184) (xy 51.089814 -301.510201)
			(xy 51.142964 -301.514184) (xy 51.194926 -301.526044) (xy 51.24454 -301.545516) (xy 51.290698 -301.572165)
			(xy 51.332369 -301.605396) (xy 51.368621 -301.644467) (xy 51.398645 -301.688504) (xy 51.421771 -301.736525)
			(xy 51.437481 -301.787455) (xy 51.445424 -301.840159) (xy 51.445922 -301.866808) (xy 51.445424 -301.893457)
			(xy 51.437481 -301.946161) (xy 51.421771 -301.997091) (xy 51.398645 -302.045112) (xy 51.368621 -302.089149)
			(xy 51.332369 -302.12822) (xy 51.290698 -302.161451) (xy 51.24454 -302.1881) (xy 51.194926 -302.207572)
			(xy 51.142964 -302.219432) (xy 51.089814 -302.223416) (xy 51.036664 -302.219432) (xy 50.984702 -302.207572)
			(xy 50.935088 -302.1881) (xy 50.88893 -302.161451) (xy 50.847259 -302.12822) (xy 50.811007 -302.089149)
			(xy 50.780983 -302.045112) (xy 50.757857 -301.997091) (xy 50.742147 -301.946161) (xy 50.734204 -301.893457)
			(xy 36.332424 -301.893457) (xy 36.324481 -301.946161) (xy 36.308771 -301.997091) (xy 36.285645 -302.045112)
			(xy 36.255621 -302.089149) (xy 36.219369 -302.12822) (xy 36.177698 -302.161451) (xy 36.13154 -302.1881)
			(xy 36.081926 -302.207572) (xy 36.029964 -302.219432) (xy 35.976814 -302.223416) (xy 35.923664 -302.219432)
			(xy 35.871702 -302.207572) (xy 35.822088 -302.1881) (xy 35.77593 -302.161451) (xy 35.734259 -302.12822)
			(xy 35.698007 -302.089149) (xy 35.667983 -302.045112) (xy 35.644857 -301.997091) (xy 35.629147 -301.946161)
			(xy 35.621204 -301.893457) (xy 21.244824 -301.893457) (xy 21.236881 -301.946161) (xy 21.221171 -301.997091)
			(xy 21.198045 -302.045112) (xy 21.168021 -302.089149) (xy 21.131769 -302.12822) (xy 21.090098 -302.161451)
			(xy 21.04394 -302.1881) (xy 20.994326 -302.207572) (xy 20.942364 -302.219432) (xy 20.889214 -302.223416)
			(xy 20.836064 -302.219432) (xy 20.784102 -302.207572) (xy 20.734488 -302.1881) (xy 20.68833 -302.161451)
			(xy 20.646659 -302.12822) (xy 20.610407 -302.089149) (xy 20.580383 -302.045112) (xy 20.557257 -301.997091)
			(xy 20.541547 -301.946161) (xy 20.533604 -301.893457) (xy 9.6774 -301.893457) (xy 9.6774 -302.743341)
			(xy 16.433536 -302.743341) (xy 16.433536 -302.690043) (xy 16.441479 -302.637339) (xy 16.457189 -302.586409)
			(xy 16.480315 -302.538388) (xy 16.510339 -302.494351) (xy 16.546591 -302.45528) (xy 16.588262 -302.422049)
			(xy 16.63442 -302.3954) (xy 16.684034 -302.375928) (xy 16.735996 -302.364068) (xy 16.789146 -302.360085)
			(xy 16.842296 -302.364068) (xy 16.894258 -302.375928) (xy 16.943872 -302.3954) (xy 16.99003 -302.422049)
			(xy 17.031701 -302.45528) (xy 17.067953 -302.494351) (xy 17.097977 -302.538388) (xy 17.121103 -302.586409)
			(xy 17.136813 -302.637339) (xy 17.144756 -302.690043) (xy 17.145254 -302.716692) (xy 17.144756 -302.743341)
			(xy 20.533604 -302.743341) (xy 20.533604 -302.690043) (xy 20.541547 -302.637339) (xy 20.557257 -302.586409)
			(xy 20.580383 -302.538388) (xy 20.610407 -302.494351) (xy 20.646659 -302.45528) (xy 20.68833 -302.422049)
			(xy 20.734488 -302.3954) (xy 20.784102 -302.375928) (xy 20.836064 -302.364068) (xy 20.889214 -302.360085)
			(xy 20.942364 -302.364068) (xy 20.994326 -302.375928) (xy 21.04394 -302.3954) (xy 21.090098 -302.422049)
			(xy 21.131769 -302.45528) (xy 21.168021 -302.494351) (xy 21.198045 -302.538388) (xy 21.221171 -302.586409)
			(xy 21.236881 -302.637339) (xy 21.244824 -302.690043) (xy 21.245322 -302.716692) (xy 21.244824 -302.743341)
			(xy 31.521136 -302.743341) (xy 31.521136 -302.690043) (xy 31.529079 -302.637339) (xy 31.544789 -302.586409)
			(xy 31.567915 -302.538388) (xy 31.597939 -302.494351) (xy 31.634191 -302.45528) (xy 31.675862 -302.422049)
			(xy 31.72202 -302.3954) (xy 31.771634 -302.375928) (xy 31.823596 -302.364068) (xy 31.876746 -302.360085)
			(xy 31.929896 -302.364068) (xy 31.981858 -302.375928) (xy 32.031472 -302.3954) (xy 32.07763 -302.422049)
			(xy 32.119301 -302.45528) (xy 32.155553 -302.494351) (xy 32.185577 -302.538388) (xy 32.208703 -302.586409)
			(xy 32.224413 -302.637339) (xy 32.232356 -302.690043) (xy 32.232854 -302.716692) (xy 32.232356 -302.743341)
			(xy 35.621204 -302.743341) (xy 35.621204 -302.690043) (xy 35.629147 -302.637339) (xy 35.644857 -302.586409)
			(xy 35.667983 -302.538388) (xy 35.698007 -302.494351) (xy 35.734259 -302.45528) (xy 35.77593 -302.422049)
			(xy 35.822088 -302.3954) (xy 35.871702 -302.375928) (xy 35.923664 -302.364068) (xy 35.976814 -302.360085)
			(xy 36.029964 -302.364068) (xy 36.081926 -302.375928) (xy 36.13154 -302.3954) (xy 36.177698 -302.422049)
			(xy 36.219369 -302.45528) (xy 36.255621 -302.494351) (xy 36.285645 -302.538388) (xy 36.308771 -302.586409)
			(xy 36.324481 -302.637339) (xy 36.332424 -302.690043) (xy 36.332922 -302.716692) (xy 36.332424 -302.743341)
			(xy 46.608736 -302.743341) (xy 46.608736 -302.690043) (xy 46.616679 -302.637339) (xy 46.632389 -302.586409)
			(xy 46.655515 -302.538388) (xy 46.685539 -302.494351) (xy 46.721791 -302.45528) (xy 46.763462 -302.422049)
			(xy 46.80962 -302.3954) (xy 46.859234 -302.375928) (xy 46.911196 -302.364068) (xy 46.964346 -302.360085)
			(xy 47.017496 -302.364068) (xy 47.069458 -302.375928) (xy 47.119072 -302.3954) (xy 47.16523 -302.422049)
			(xy 47.206901 -302.45528) (xy 47.243153 -302.494351) (xy 47.273177 -302.538388) (xy 47.296303 -302.586409)
			(xy 47.312013 -302.637339) (xy 47.319956 -302.690043) (xy 47.320454 -302.716692) (xy 47.319956 -302.743341)
			(xy 47.319918 -302.743595) (xy 50.734204 -302.743595) (xy 50.734204 -302.690297) (xy 50.742147 -302.637593)
			(xy 50.757857 -302.586663) (xy 50.780983 -302.538642) (xy 50.811007 -302.494605) (xy 50.847259 -302.455534)
			(xy 50.88893 -302.422303) (xy 50.935088 -302.395654) (xy 50.984702 -302.376182) (xy 51.036664 -302.364322)
			(xy 51.089814 -302.360339) (xy 51.142964 -302.364322) (xy 51.194926 -302.376182) (xy 51.24454 -302.395654)
			(xy 51.290698 -302.422303) (xy 51.332369 -302.455534) (xy 51.368621 -302.494605) (xy 51.398645 -302.538642)
			(xy 51.421771 -302.586663) (xy 51.437481 -302.637593) (xy 51.445424 -302.690297) (xy 51.445922 -302.716946)
			(xy 51.445429 -302.743341) (xy 61.696336 -302.743341) (xy 61.696336 -302.690043) (xy 61.704279 -302.637339)
			(xy 61.719989 -302.586409) (xy 61.743115 -302.538388) (xy 61.773139 -302.494351) (xy 61.809391 -302.45528)
			(xy 61.851062 -302.422049) (xy 61.89722 -302.3954) (xy 61.946834 -302.375928) (xy 61.998796 -302.364068)
			(xy 62.051946 -302.360085) (xy 62.105096 -302.364068) (xy 62.157058 -302.375928) (xy 62.206672 -302.3954)
			(xy 62.25283 -302.422049) (xy 62.294501 -302.45528) (xy 62.330753 -302.494351) (xy 62.360777 -302.538388)
			(xy 62.383903 -302.586409) (xy 62.399613 -302.637339) (xy 62.407556 -302.690043) (xy 62.408054 -302.716692)
			(xy 62.407556 -302.743341) (xy 62.399613 -302.796045) (xy 62.383903 -302.846975) (xy 62.360777 -302.894996)
			(xy 62.330753 -302.939033) (xy 62.294501 -302.978104) (xy 62.25283 -303.011335) (xy 62.206672 -303.037984)
			(xy 62.157058 -303.057456) (xy 62.105096 -303.069316) (xy 62.051946 -303.0733) (xy 61.998796 -303.069316)
			(xy 61.946834 -303.057456) (xy 61.89722 -303.037984) (xy 61.851062 -303.011335) (xy 61.809391 -302.978104)
			(xy 61.773139 -302.939033) (xy 61.743115 -302.894996) (xy 61.719989 -302.846975) (xy 61.704279 -302.796045)
			(xy 61.696336 -302.743341) (xy 51.445429 -302.743341) (xy 51.445424 -302.743595) (xy 51.437481 -302.796299)
			(xy 51.421771 -302.847229) (xy 51.398645 -302.89525) (xy 51.368621 -302.939287) (xy 51.332369 -302.978358)
			(xy 51.290698 -303.011589) (xy 51.24454 -303.038238) (xy 51.194926 -303.05771) (xy 51.142964 -303.06957)
			(xy 51.089814 -303.073554) (xy 51.036664 -303.06957) (xy 50.984702 -303.05771) (xy 50.935088 -303.038238)
			(xy 50.88893 -303.011589) (xy 50.847259 -302.978358) (xy 50.811007 -302.939287) (xy 50.780983 -302.89525)
			(xy 50.757857 -302.847229) (xy 50.742147 -302.796299) (xy 50.734204 -302.743595) (xy 47.319918 -302.743595)
			(xy 47.312013 -302.796045) (xy 47.296303 -302.846975) (xy 47.273177 -302.894996) (xy 47.243153 -302.939033)
			(xy 47.206901 -302.978104) (xy 47.16523 -303.011335) (xy 47.119072 -303.037984) (xy 47.069458 -303.057456)
			(xy 47.017496 -303.069316) (xy 46.964346 -303.0733) (xy 46.911196 -303.069316) (xy 46.859234 -303.057456)
			(xy 46.80962 -303.037984) (xy 46.763462 -303.011335) (xy 46.721791 -302.978104) (xy 46.685539 -302.939033)
			(xy 46.655515 -302.894996) (xy 46.632389 -302.846975) (xy 46.616679 -302.796045) (xy 46.608736 -302.743341)
			(xy 36.332424 -302.743341) (xy 36.324481 -302.796045) (xy 36.308771 -302.846975) (xy 36.285645 -302.894996)
			(xy 36.255621 -302.939033) (xy 36.219369 -302.978104) (xy 36.177698 -303.011335) (xy 36.13154 -303.037984)
			(xy 36.081926 -303.057456) (xy 36.029964 -303.069316) (xy 35.976814 -303.0733) (xy 35.923664 -303.069316)
			(xy 35.871702 -303.057456) (xy 35.822088 -303.037984) (xy 35.77593 -303.011335) (xy 35.734259 -302.978104)
			(xy 35.698007 -302.939033) (xy 35.667983 -302.894996) (xy 35.644857 -302.846975) (xy 35.629147 -302.796045)
			(xy 35.621204 -302.743341) (xy 32.232356 -302.743341) (xy 32.224413 -302.796045) (xy 32.208703 -302.846975)
			(xy 32.185577 -302.894996) (xy 32.155553 -302.939033) (xy 32.119301 -302.978104) (xy 32.07763 -303.011335)
			(xy 32.031472 -303.037984) (xy 31.981858 -303.057456) (xy 31.929896 -303.069316) (xy 31.876746 -303.0733)
			(xy 31.823596 -303.069316) (xy 31.771634 -303.057456) (xy 31.72202 -303.037984) (xy 31.675862 -303.011335)
			(xy 31.634191 -302.978104) (xy 31.597939 -302.939033) (xy 31.567915 -302.894996) (xy 31.544789 -302.846975)
			(xy 31.529079 -302.796045) (xy 31.521136 -302.743341) (xy 21.244824 -302.743341) (xy 21.236881 -302.796045)
			(xy 21.221171 -302.846975) (xy 21.198045 -302.894996) (xy 21.168021 -302.939033) (xy 21.131769 -302.978104)
			(xy 21.090098 -303.011335) (xy 21.04394 -303.037984) (xy 20.994326 -303.057456) (xy 20.942364 -303.069316)
			(xy 20.889214 -303.0733) (xy 20.836064 -303.069316) (xy 20.784102 -303.057456) (xy 20.734488 -303.037984)
			(xy 20.68833 -303.011335) (xy 20.646659 -302.978104) (xy 20.610407 -302.939033) (xy 20.580383 -302.894996)
			(xy 20.557257 -302.846975) (xy 20.541547 -302.796045) (xy 20.533604 -302.743341) (xy 17.144756 -302.743341)
			(xy 17.136813 -302.796045) (xy 17.121103 -302.846975) (xy 17.097977 -302.894996) (xy 17.067953 -302.939033)
			(xy 17.031701 -302.978104) (xy 16.99003 -303.011335) (xy 16.943872 -303.037984) (xy 16.894258 -303.057456)
			(xy 16.842296 -303.069316) (xy 16.789146 -303.0733) (xy 16.735996 -303.069316) (xy 16.684034 -303.057456)
			(xy 16.63442 -303.037984) (xy 16.588262 -303.011335) (xy 16.546591 -302.978104) (xy 16.510339 -302.939033)
			(xy 16.480315 -302.894996) (xy 16.457189 -302.846975) (xy 16.441479 -302.796045) (xy 16.433536 -302.743341)
			(xy 9.6774 -302.743341) (xy 9.6774 -303.593225) (xy 16.433536 -303.593225) (xy 16.433536 -303.539927)
			(xy 16.441479 -303.487223) (xy 16.457189 -303.436293) (xy 16.480315 -303.388272) (xy 16.510339 -303.344235)
			(xy 16.546591 -303.305164) (xy 16.588262 -303.271933) (xy 16.63442 -303.245284) (xy 16.684034 -303.225812)
			(xy 16.735996 -303.213952) (xy 16.789146 -303.209969) (xy 16.842296 -303.213952) (xy 16.894258 -303.225812)
			(xy 16.943872 -303.245284) (xy 16.99003 -303.271933) (xy 17.031701 -303.305164) (xy 17.067953 -303.344235)
			(xy 17.097977 -303.388272) (xy 17.121103 -303.436293) (xy 17.136813 -303.487223) (xy 17.144756 -303.539927)
			(xy 17.145254 -303.566576) (xy 17.144756 -303.593225) (xy 31.521136 -303.593225) (xy 31.521136 -303.539927)
			(xy 31.529079 -303.487223) (xy 31.544789 -303.436293) (xy 31.567915 -303.388272) (xy 31.597939 -303.344235)
			(xy 31.634191 -303.305164) (xy 31.675862 -303.271933) (xy 31.72202 -303.245284) (xy 31.771634 -303.225812)
			(xy 31.823596 -303.213952) (xy 31.876746 -303.209969) (xy 31.929896 -303.213952) (xy 31.981858 -303.225812)
			(xy 32.031472 -303.245284) (xy 32.07763 -303.271933) (xy 32.119301 -303.305164) (xy 32.155553 -303.344235)
			(xy 32.185577 -303.388272) (xy 32.208703 -303.436293) (xy 32.224413 -303.487223) (xy 32.232356 -303.539927)
			(xy 32.232854 -303.566576) (xy 32.232356 -303.593225) (xy 46.608736 -303.593225) (xy 46.608736 -303.539927)
			(xy 46.616679 -303.487223) (xy 46.632389 -303.436293) (xy 46.655515 -303.388272) (xy 46.685539 -303.344235)
			(xy 46.721791 -303.305164) (xy 46.763462 -303.271933) (xy 46.80962 -303.245284) (xy 46.859234 -303.225812)
			(xy 46.911196 -303.213952) (xy 46.964346 -303.209969) (xy 47.017496 -303.213952) (xy 47.069458 -303.225812)
			(xy 47.119072 -303.245284) (xy 47.16523 -303.271933) (xy 47.206901 -303.305164) (xy 47.243153 -303.344235)
			(xy 47.273177 -303.388272) (xy 47.296303 -303.436293) (xy 47.312013 -303.487223) (xy 47.319956 -303.539927)
			(xy 47.320454 -303.566576) (xy 47.319956 -303.593225) (xy 61.696336 -303.593225) (xy 61.696336 -303.539927)
			(xy 61.704279 -303.487223) (xy 61.719989 -303.436293) (xy 61.743115 -303.388272) (xy 61.773139 -303.344235)
			(xy 61.809391 -303.305164) (xy 61.851062 -303.271933) (xy 61.89722 -303.245284) (xy 61.946834 -303.225812)
			(xy 61.998796 -303.213952) (xy 62.051946 -303.209969) (xy 62.105096 -303.213952) (xy 62.157058 -303.225812)
			(xy 62.206672 -303.245284) (xy 62.25283 -303.271933) (xy 62.294501 -303.305164) (xy 62.330753 -303.344235)
			(xy 62.360777 -303.388272) (xy 62.383903 -303.436293) (xy 62.399613 -303.487223) (xy 62.407556 -303.539927)
			(xy 62.408054 -303.566576) (xy 62.407556 -303.593225) (xy 62.399613 -303.645929) (xy 62.383903 -303.696859)
			(xy 62.360777 -303.74488) (xy 62.330753 -303.788917) (xy 62.294501 -303.827988) (xy 62.25283 -303.861219)
			(xy 62.206672 -303.887868) (xy 62.157058 -303.90734) (xy 62.105096 -303.9192) (xy 62.051946 -303.923184)
			(xy 61.998796 -303.9192) (xy 61.946834 -303.90734) (xy 61.89722 -303.887868) (xy 61.851062 -303.861219)
			(xy 61.809391 -303.827988) (xy 61.773139 -303.788917) (xy 61.743115 -303.74488) (xy 61.719989 -303.696859)
			(xy 61.704279 -303.645929) (xy 61.696336 -303.593225) (xy 47.319956 -303.593225) (xy 47.312013 -303.645929)
			(xy 47.296303 -303.696859) (xy 47.273177 -303.74488) (xy 47.243153 -303.788917) (xy 47.206901 -303.827988)
			(xy 47.16523 -303.861219) (xy 47.119072 -303.887868) (xy 47.069458 -303.90734) (xy 47.017496 -303.9192)
			(xy 46.964346 -303.923184) (xy 46.911196 -303.9192) (xy 46.859234 -303.90734) (xy 46.80962 -303.887868)
			(xy 46.763462 -303.861219) (xy 46.721791 -303.827988) (xy 46.685539 -303.788917) (xy 46.655515 -303.74488)
			(xy 46.632389 -303.696859) (xy 46.616679 -303.645929) (xy 46.608736 -303.593225) (xy 32.232356 -303.593225)
			(xy 32.224413 -303.645929) (xy 32.208703 -303.696859) (xy 32.185577 -303.74488) (xy 32.155553 -303.788917)
			(xy 32.119301 -303.827988) (xy 32.07763 -303.861219) (xy 32.031472 -303.887868) (xy 31.981858 -303.90734)
			(xy 31.929896 -303.9192) (xy 31.876746 -303.923184) (xy 31.823596 -303.9192) (xy 31.771634 -303.90734)
			(xy 31.72202 -303.887868) (xy 31.675862 -303.861219) (xy 31.634191 -303.827988) (xy 31.597939 -303.788917)
			(xy 31.567915 -303.74488) (xy 31.544789 -303.696859) (xy 31.529079 -303.645929) (xy 31.521136 -303.593225)
			(xy 17.144756 -303.593225) (xy 17.136813 -303.645929) (xy 17.121103 -303.696859) (xy 17.097977 -303.74488)
			(xy 17.067953 -303.788917) (xy 17.031701 -303.827988) (xy 16.99003 -303.861219) (xy 16.943872 -303.887868)
			(xy 16.894258 -303.90734) (xy 16.842296 -303.9192) (xy 16.789146 -303.923184) (xy 16.735996 -303.9192)
			(xy 16.684034 -303.90734) (xy 16.63442 -303.887868) (xy 16.588262 -303.861219) (xy 16.546591 -303.827988)
			(xy 16.510339 -303.788917) (xy 16.480315 -303.74488) (xy 16.457189 -303.696859) (xy 16.441479 -303.645929)
			(xy 16.433536 -303.593225) (xy 9.6774 -303.593225) (xy 9.6774 -304.443363) (xy 20.533604 -304.443363)
			(xy 20.533604 -304.390065) (xy 20.541547 -304.337361) (xy 20.557257 -304.286431) (xy 20.580383 -304.23841)
			(xy 20.610407 -304.194373) (xy 20.646659 -304.155302) (xy 20.68833 -304.122071) (xy 20.734488 -304.095422)
			(xy 20.784102 -304.07595) (xy 20.836064 -304.06409) (xy 20.889214 -304.060107) (xy 20.942364 -304.06409)
			(xy 20.994326 -304.07595) (xy 21.04394 -304.095422) (xy 21.090098 -304.122071) (xy 21.131769 -304.155302)
			(xy 21.168021 -304.194373) (xy 21.198045 -304.23841) (xy 21.221171 -304.286431) (xy 21.236881 -304.337361)
			(xy 21.244824 -304.390065) (xy 21.245322 -304.416714) (xy 21.244824 -304.443363) (xy 35.621204 -304.443363)
			(xy 35.621204 -304.390065) (xy 35.629147 -304.337361) (xy 35.644857 -304.286431) (xy 35.667983 -304.23841)
			(xy 35.698007 -304.194373) (xy 35.734259 -304.155302) (xy 35.77593 -304.122071) (xy 35.822088 -304.095422)
			(xy 35.871702 -304.07595) (xy 35.923664 -304.06409) (xy 35.976814 -304.060107) (xy 36.029964 -304.06409)
			(xy 36.081926 -304.07595) (xy 36.13154 -304.095422) (xy 36.177698 -304.122071) (xy 36.219369 -304.155302)
			(xy 36.255621 -304.194373) (xy 36.285645 -304.23841) (xy 36.308771 -304.286431) (xy 36.324481 -304.337361)
			(xy 36.332424 -304.390065) (xy 36.332922 -304.416714) (xy 36.332424 -304.443363) (xy 50.734204 -304.443363)
			(xy 50.734204 -304.390065) (xy 50.742147 -304.337361) (xy 50.757857 -304.286431) (xy 50.780983 -304.23841)
			(xy 50.811007 -304.194373) (xy 50.847259 -304.155302) (xy 50.88893 -304.122071) (xy 50.935088 -304.095422)
			(xy 50.984702 -304.07595) (xy 51.036664 -304.06409) (xy 51.089814 -304.060107) (xy 51.142964 -304.06409)
			(xy 51.194926 -304.07595) (xy 51.24454 -304.095422) (xy 51.290698 -304.122071) (xy 51.332369 -304.155302)
			(xy 51.368621 -304.194373) (xy 51.398645 -304.23841) (xy 51.421771 -304.286431) (xy 51.437481 -304.337361)
			(xy 51.445424 -304.390065) (xy 51.445922 -304.416714) (xy 51.445424 -304.443363) (xy 51.437481 -304.496067)
			(xy 51.421771 -304.546997) (xy 51.398645 -304.595018) (xy 51.368621 -304.639055) (xy 51.332369 -304.678126)
			(xy 51.290698 -304.711357) (xy 51.24454 -304.738006) (xy 51.194926 -304.757478) (xy 51.142964 -304.769338)
			(xy 51.089814 -304.773322) (xy 51.036664 -304.769338) (xy 50.984702 -304.757478) (xy 50.935088 -304.738006)
			(xy 50.88893 -304.711357) (xy 50.847259 -304.678126) (xy 50.811007 -304.639055) (xy 50.780983 -304.595018)
			(xy 50.757857 -304.546997) (xy 50.742147 -304.496067) (xy 50.734204 -304.443363) (xy 36.332424 -304.443363)
			(xy 36.324481 -304.496067) (xy 36.308771 -304.546997) (xy 36.285645 -304.595018) (xy 36.255621 -304.639055)
			(xy 36.219369 -304.678126) (xy 36.177698 -304.711357) (xy 36.13154 -304.738006) (xy 36.081926 -304.757478)
			(xy 36.029964 -304.769338) (xy 35.976814 -304.773322) (xy 35.923664 -304.769338) (xy 35.871702 -304.757478)
			(xy 35.822088 -304.738006) (xy 35.77593 -304.711357) (xy 35.734259 -304.678126) (xy 35.698007 -304.639055)
			(xy 35.667983 -304.595018) (xy 35.644857 -304.546997) (xy 35.629147 -304.496067) (xy 35.621204 -304.443363)
			(xy 21.244824 -304.443363) (xy 21.236881 -304.496067) (xy 21.221171 -304.546997) (xy 21.198045 -304.595018)
			(xy 21.168021 -304.639055) (xy 21.131769 -304.678126) (xy 21.090098 -304.711357) (xy 21.04394 -304.738006)
			(xy 20.994326 -304.757478) (xy 20.942364 -304.769338) (xy 20.889214 -304.773322) (xy 20.836064 -304.769338)
			(xy 20.784102 -304.757478) (xy 20.734488 -304.738006) (xy 20.68833 -304.711357) (xy 20.646659 -304.678126)
			(xy 20.610407 -304.639055) (xy 20.580383 -304.595018) (xy 20.557257 -304.546997) (xy 20.541547 -304.496067)
			(xy 20.533604 -304.443363) (xy 9.6774 -304.443363) (xy 9.6774 -305.293247) (xy 16.433536 -305.293247)
			(xy 16.433536 -305.239949) (xy 16.441479 -305.187245) (xy 16.457189 -305.136315) (xy 16.480315 -305.088294)
			(xy 16.510339 -305.044257) (xy 16.546591 -305.005186) (xy 16.588262 -304.971955) (xy 16.63442 -304.945306)
			(xy 16.684034 -304.925834) (xy 16.735996 -304.913974) (xy 16.789146 -304.909991) (xy 16.842296 -304.913974)
			(xy 16.894258 -304.925834) (xy 16.943872 -304.945306) (xy 16.99003 -304.971955) (xy 17.031701 -305.005186)
			(xy 17.067953 -305.044257) (xy 17.097977 -305.088294) (xy 17.121103 -305.136315) (xy 17.136813 -305.187245)
			(xy 17.144756 -305.239949) (xy 17.145254 -305.266598) (xy 17.144756 -305.293247) (xy 31.521136 -305.293247)
			(xy 31.521136 -305.239949) (xy 31.529079 -305.187245) (xy 31.544789 -305.136315) (xy 31.567915 -305.088294)
			(xy 31.597939 -305.044257) (xy 31.634191 -305.005186) (xy 31.675862 -304.971955) (xy 31.72202 -304.945306)
			(xy 31.771634 -304.925834) (xy 31.823596 -304.913974) (xy 31.876746 -304.909991) (xy 31.929896 -304.913974)
			(xy 31.981858 -304.925834) (xy 32.031472 -304.945306) (xy 32.07763 -304.971955) (xy 32.119301 -305.005186)
			(xy 32.155553 -305.044257) (xy 32.185577 -305.088294) (xy 32.208703 -305.136315) (xy 32.224413 -305.187245)
			(xy 32.232356 -305.239949) (xy 32.232854 -305.266598) (xy 32.232356 -305.293247) (xy 46.608736 -305.293247)
			(xy 46.608736 -305.239949) (xy 46.616679 -305.187245) (xy 46.632389 -305.136315) (xy 46.655515 -305.088294)
			(xy 46.685539 -305.044257) (xy 46.721791 -305.005186) (xy 46.763462 -304.971955) (xy 46.80962 -304.945306)
			(xy 46.859234 -304.925834) (xy 46.911196 -304.913974) (xy 46.964346 -304.909991) (xy 47.017496 -304.913974)
			(xy 47.069458 -304.925834) (xy 47.119072 -304.945306) (xy 47.16523 -304.971955) (xy 47.206901 -305.005186)
			(xy 47.243153 -305.044257) (xy 47.273177 -305.088294) (xy 47.296303 -305.136315) (xy 47.312013 -305.187245)
			(xy 47.319956 -305.239949) (xy 47.320454 -305.266598) (xy 47.319956 -305.293247) (xy 61.696336 -305.293247)
			(xy 61.696336 -305.239949) (xy 61.704279 -305.187245) (xy 61.719989 -305.136315) (xy 61.743115 -305.088294)
			(xy 61.773139 -305.044257) (xy 61.809391 -305.005186) (xy 61.851062 -304.971955) (xy 61.89722 -304.945306)
			(xy 61.946834 -304.925834) (xy 61.998796 -304.913974) (xy 62.051946 -304.909991) (xy 62.105096 -304.913974)
			(xy 62.157058 -304.925834) (xy 62.206672 -304.945306) (xy 62.25283 -304.971955) (xy 62.294501 -305.005186)
			(xy 62.330753 -305.044257) (xy 62.360777 -305.088294) (xy 62.383903 -305.136315) (xy 62.399613 -305.187245)
			(xy 62.407556 -305.239949) (xy 62.408054 -305.266598) (xy 62.407556 -305.293247) (xy 62.399613 -305.345951)
			(xy 62.383903 -305.396881) (xy 62.360777 -305.444902) (xy 62.330753 -305.488939) (xy 62.294501 -305.52801)
			(xy 62.25283 -305.561241) (xy 62.206672 -305.58789) (xy 62.157058 -305.607362) (xy 62.105096 -305.619222)
			(xy 62.051946 -305.623206) (xy 61.998796 -305.619222) (xy 61.946834 -305.607362) (xy 61.89722 -305.58789)
			(xy 61.851062 -305.561241) (xy 61.809391 -305.52801) (xy 61.773139 -305.488939) (xy 61.743115 -305.444902)
			(xy 61.719989 -305.396881) (xy 61.704279 -305.345951) (xy 61.696336 -305.293247) (xy 47.319956 -305.293247)
			(xy 47.312013 -305.345951) (xy 47.296303 -305.396881) (xy 47.273177 -305.444902) (xy 47.243153 -305.488939)
			(xy 47.206901 -305.52801) (xy 47.16523 -305.561241) (xy 47.119072 -305.58789) (xy 47.069458 -305.607362)
			(xy 47.017496 -305.619222) (xy 46.964346 -305.623206) (xy 46.911196 -305.619222) (xy 46.859234 -305.607362)
			(xy 46.80962 -305.58789) (xy 46.763462 -305.561241) (xy 46.721791 -305.52801) (xy 46.685539 -305.488939)
			(xy 46.655515 -305.444902) (xy 46.632389 -305.396881) (xy 46.616679 -305.345951) (xy 46.608736 -305.293247)
			(xy 32.232356 -305.293247) (xy 32.224413 -305.345951) (xy 32.208703 -305.396881) (xy 32.185577 -305.444902)
			(xy 32.155553 -305.488939) (xy 32.119301 -305.52801) (xy 32.07763 -305.561241) (xy 32.031472 -305.58789)
			(xy 31.981858 -305.607362) (xy 31.929896 -305.619222) (xy 31.876746 -305.623206) (xy 31.823596 -305.619222)
			(xy 31.771634 -305.607362) (xy 31.72202 -305.58789) (xy 31.675862 -305.561241) (xy 31.634191 -305.52801)
			(xy 31.597939 -305.488939) (xy 31.567915 -305.444902) (xy 31.544789 -305.396881) (xy 31.529079 -305.345951)
			(xy 31.521136 -305.293247) (xy 17.144756 -305.293247) (xy 17.136813 -305.345951) (xy 17.121103 -305.396881)
			(xy 17.097977 -305.444902) (xy 17.067953 -305.488939) (xy 17.031701 -305.52801) (xy 16.99003 -305.561241)
			(xy 16.943872 -305.58789) (xy 16.894258 -305.607362) (xy 16.842296 -305.619222) (xy 16.789146 -305.623206)
			(xy 16.735996 -305.619222) (xy 16.684034 -305.607362) (xy 16.63442 -305.58789) (xy 16.588262 -305.561241)
			(xy 16.546591 -305.52801) (xy 16.510339 -305.488939) (xy 16.480315 -305.444902) (xy 16.457189 -305.396881)
			(xy 16.441479 -305.345951) (xy 16.433536 -305.293247) (xy 9.6774 -305.293247) (xy 9.6774 -306.143385)
			(xy 20.533604 -306.143385) (xy 20.533604 -306.090087) (xy 20.541547 -306.037383) (xy 20.557257 -305.986453)
			(xy 20.580383 -305.938432) (xy 20.610407 -305.894395) (xy 20.646659 -305.855324) (xy 20.68833 -305.822093)
			(xy 20.734488 -305.795444) (xy 20.784102 -305.775972) (xy 20.836064 -305.764112) (xy 20.889214 -305.760129)
			(xy 20.942364 -305.764112) (xy 20.994326 -305.775972) (xy 21.04394 -305.795444) (xy 21.090098 -305.822093)
			(xy 21.131769 -305.855324) (xy 21.168021 -305.894395) (xy 21.198045 -305.938432) (xy 21.221171 -305.986453)
			(xy 21.236881 -306.037383) (xy 21.244824 -306.090087) (xy 21.245322 -306.116736) (xy 21.244824 -306.143385)
			(xy 35.621204 -306.143385) (xy 35.621204 -306.090087) (xy 35.629147 -306.037383) (xy 35.644857 -305.986453)
			(xy 35.667983 -305.938432) (xy 35.698007 -305.894395) (xy 35.734259 -305.855324) (xy 35.77593 -305.822093)
			(xy 35.822088 -305.795444) (xy 35.871702 -305.775972) (xy 35.923664 -305.764112) (xy 35.976814 -305.760129)
			(xy 36.029964 -305.764112) (xy 36.081926 -305.775972) (xy 36.13154 -305.795444) (xy 36.177698 -305.822093)
			(xy 36.219369 -305.855324) (xy 36.255621 -305.894395) (xy 36.285645 -305.938432) (xy 36.308771 -305.986453)
			(xy 36.324481 -306.037383) (xy 36.332424 -306.090087) (xy 36.332922 -306.116736) (xy 36.332424 -306.143385)
			(xy 50.734204 -306.143385) (xy 50.734204 -306.090087) (xy 50.742147 -306.037383) (xy 50.757857 -305.986453)
			(xy 50.780983 -305.938432) (xy 50.811007 -305.894395) (xy 50.847259 -305.855324) (xy 50.88893 -305.822093)
			(xy 50.935088 -305.795444) (xy 50.984702 -305.775972) (xy 51.036664 -305.764112) (xy 51.089814 -305.760129)
			(xy 51.142964 -305.764112) (xy 51.194926 -305.775972) (xy 51.24454 -305.795444) (xy 51.290698 -305.822093)
			(xy 51.332369 -305.855324) (xy 51.368621 -305.894395) (xy 51.398645 -305.938432) (xy 51.421771 -305.986453)
			(xy 51.437481 -306.037383) (xy 51.445424 -306.090087) (xy 51.445922 -306.116736) (xy 51.445424 -306.143385)
			(xy 51.437481 -306.196089) (xy 51.421771 -306.247019) (xy 51.398645 -306.29504) (xy 51.368621 -306.339077)
			(xy 51.332369 -306.378148) (xy 51.290698 -306.411379) (xy 51.24454 -306.438028) (xy 51.194926 -306.4575)
			(xy 51.142964 -306.46936) (xy 51.089814 -306.473344) (xy 51.036664 -306.46936) (xy 50.984702 -306.4575)
			(xy 50.935088 -306.438028) (xy 50.88893 -306.411379) (xy 50.847259 -306.378148) (xy 50.811007 -306.339077)
			(xy 50.780983 -306.29504) (xy 50.757857 -306.247019) (xy 50.742147 -306.196089) (xy 50.734204 -306.143385)
			(xy 36.332424 -306.143385) (xy 36.324481 -306.196089) (xy 36.308771 -306.247019) (xy 36.285645 -306.29504)
			(xy 36.255621 -306.339077) (xy 36.219369 -306.378148) (xy 36.177698 -306.411379) (xy 36.13154 -306.438028)
			(xy 36.081926 -306.4575) (xy 36.029964 -306.46936) (xy 35.976814 -306.473344) (xy 35.923664 -306.46936)
			(xy 35.871702 -306.4575) (xy 35.822088 -306.438028) (xy 35.77593 -306.411379) (xy 35.734259 -306.378148)
			(xy 35.698007 -306.339077) (xy 35.667983 -306.29504) (xy 35.644857 -306.247019) (xy 35.629147 -306.196089)
			(xy 35.621204 -306.143385) (xy 21.244824 -306.143385) (xy 21.236881 -306.196089) (xy 21.221171 -306.247019)
			(xy 21.198045 -306.29504) (xy 21.168021 -306.339077) (xy 21.131769 -306.378148) (xy 21.090098 -306.411379)
			(xy 21.04394 -306.438028) (xy 20.994326 -306.4575) (xy 20.942364 -306.46936) (xy 20.889214 -306.473344)
			(xy 20.836064 -306.46936) (xy 20.784102 -306.4575) (xy 20.734488 -306.438028) (xy 20.68833 -306.411379)
			(xy 20.646659 -306.378148) (xy 20.610407 -306.339077) (xy 20.580383 -306.29504) (xy 20.557257 -306.247019)
			(xy 20.541547 -306.196089) (xy 20.533604 -306.143385) (xy 9.6774 -306.143385) (xy 9.6774 -306.993269)
			(xy 16.433536 -306.993269) (xy 16.433536 -306.939971) (xy 16.441479 -306.887267) (xy 16.457189 -306.836337)
			(xy 16.480315 -306.788316) (xy 16.510339 -306.744279) (xy 16.546591 -306.705208) (xy 16.588262 -306.671977)
			(xy 16.63442 -306.645328) (xy 16.684034 -306.625856) (xy 16.735996 -306.613996) (xy 16.789146 -306.610013)
			(xy 16.842296 -306.613996) (xy 16.894258 -306.625856) (xy 16.943872 -306.645328) (xy 16.99003 -306.671977)
			(xy 17.031701 -306.705208) (xy 17.067953 -306.744279) (xy 17.097977 -306.788316) (xy 17.121103 -306.836337)
			(xy 17.136813 -306.887267) (xy 17.144756 -306.939971) (xy 17.145254 -306.96662) (xy 17.144756 -306.993269)
			(xy 31.521136 -306.993269) (xy 31.521136 -306.939971) (xy 31.529079 -306.887267) (xy 31.544789 -306.836337)
			(xy 31.567915 -306.788316) (xy 31.597939 -306.744279) (xy 31.634191 -306.705208) (xy 31.675862 -306.671977)
			(xy 31.72202 -306.645328) (xy 31.771634 -306.625856) (xy 31.823596 -306.613996) (xy 31.876746 -306.610013)
			(xy 31.929896 -306.613996) (xy 31.981858 -306.625856) (xy 32.031472 -306.645328) (xy 32.07763 -306.671977)
			(xy 32.119301 -306.705208) (xy 32.155553 -306.744279) (xy 32.185577 -306.788316) (xy 32.208703 -306.836337)
			(xy 32.224413 -306.887267) (xy 32.232356 -306.939971) (xy 32.232854 -306.96662) (xy 32.232356 -306.993269)
			(xy 46.608736 -306.993269) (xy 46.608736 -306.939971) (xy 46.616679 -306.887267) (xy 46.632389 -306.836337)
			(xy 46.655515 -306.788316) (xy 46.685539 -306.744279) (xy 46.721791 -306.705208) (xy 46.763462 -306.671977)
			(xy 46.80962 -306.645328) (xy 46.859234 -306.625856) (xy 46.911196 -306.613996) (xy 46.964346 -306.610013)
			(xy 47.017496 -306.613996) (xy 47.069458 -306.625856) (xy 47.119072 -306.645328) (xy 47.16523 -306.671977)
			(xy 47.206901 -306.705208) (xy 47.243153 -306.744279) (xy 47.273177 -306.788316) (xy 47.296303 -306.836337)
			(xy 47.312013 -306.887267) (xy 47.319956 -306.939971) (xy 47.320454 -306.96662) (xy 47.319956 -306.993269)
			(xy 61.696336 -306.993269) (xy 61.696336 -306.939971) (xy 61.704279 -306.887267) (xy 61.719989 -306.836337)
			(xy 61.743115 -306.788316) (xy 61.773139 -306.744279) (xy 61.809391 -306.705208) (xy 61.851062 -306.671977)
			(xy 61.89722 -306.645328) (xy 61.946834 -306.625856) (xy 61.998796 -306.613996) (xy 62.051946 -306.610013)
			(xy 62.105096 -306.613996) (xy 62.157058 -306.625856) (xy 62.206672 -306.645328) (xy 62.25283 -306.671977)
			(xy 62.294501 -306.705208) (xy 62.330753 -306.744279) (xy 62.360777 -306.788316) (xy 62.383903 -306.836337)
			(xy 62.399613 -306.887267) (xy 62.407556 -306.939971) (xy 62.408054 -306.96662) (xy 62.407556 -306.993269)
			(xy 62.399613 -307.045973) (xy 62.383903 -307.096903) (xy 62.360777 -307.144924) (xy 62.330753 -307.188961)
			(xy 62.294501 -307.228032) (xy 62.25283 -307.261263) (xy 62.206672 -307.287912) (xy 62.157058 -307.307384)
			(xy 62.105096 -307.319244) (xy 62.051946 -307.323228) (xy 61.998796 -307.319244) (xy 61.946834 -307.307384)
			(xy 61.89722 -307.287912) (xy 61.851062 -307.261263) (xy 61.809391 -307.228032) (xy 61.773139 -307.188961)
			(xy 61.743115 -307.144924) (xy 61.719989 -307.096903) (xy 61.704279 -307.045973) (xy 61.696336 -306.993269)
			(xy 47.319956 -306.993269) (xy 47.312013 -307.045973) (xy 47.296303 -307.096903) (xy 47.273177 -307.144924)
			(xy 47.243153 -307.188961) (xy 47.206901 -307.228032) (xy 47.16523 -307.261263) (xy 47.119072 -307.287912)
			(xy 47.069458 -307.307384) (xy 47.017496 -307.319244) (xy 46.964346 -307.323228) (xy 46.911196 -307.319244)
			(xy 46.859234 -307.307384) (xy 46.80962 -307.287912) (xy 46.763462 -307.261263) (xy 46.721791 -307.228032)
			(xy 46.685539 -307.188961) (xy 46.655515 -307.144924) (xy 46.632389 -307.096903) (xy 46.616679 -307.045973)
			(xy 46.608736 -306.993269) (xy 32.232356 -306.993269) (xy 32.224413 -307.045973) (xy 32.208703 -307.096903)
			(xy 32.185577 -307.144924) (xy 32.155553 -307.188961) (xy 32.119301 -307.228032) (xy 32.07763 -307.261263)
			(xy 32.031472 -307.287912) (xy 31.981858 -307.307384) (xy 31.929896 -307.319244) (xy 31.876746 -307.323228)
			(xy 31.823596 -307.319244) (xy 31.771634 -307.307384) (xy 31.72202 -307.287912) (xy 31.675862 -307.261263)
			(xy 31.634191 -307.228032) (xy 31.597939 -307.188961) (xy 31.567915 -307.144924) (xy 31.544789 -307.096903)
			(xy 31.529079 -307.045973) (xy 31.521136 -306.993269) (xy 17.144756 -306.993269) (xy 17.136813 -307.045973)
			(xy 17.121103 -307.096903) (xy 17.097977 -307.144924) (xy 17.067953 -307.188961) (xy 17.031701 -307.228032)
			(xy 16.99003 -307.261263) (xy 16.943872 -307.287912) (xy 16.894258 -307.307384) (xy 16.842296 -307.319244)
			(xy 16.789146 -307.323228) (xy 16.735996 -307.319244) (xy 16.684034 -307.307384) (xy 16.63442 -307.287912)
			(xy 16.588262 -307.261263) (xy 16.546591 -307.228032) (xy 16.510339 -307.188961) (xy 16.480315 -307.144924)
			(xy 16.457189 -307.096903) (xy 16.441479 -307.045973) (xy 16.433536 -306.993269) (xy 9.6774 -306.993269)
			(xy 9.6774 -307.843407) (xy 20.533604 -307.843407) (xy 20.533604 -307.790109) (xy 20.541547 -307.737405)
			(xy 20.557257 -307.686475) (xy 20.580383 -307.638454) (xy 20.610407 -307.594417) (xy 20.646659 -307.555346)
			(xy 20.68833 -307.522115) (xy 20.734488 -307.495466) (xy 20.784102 -307.475994) (xy 20.836064 -307.464134)
			(xy 20.889214 -307.460151) (xy 20.942364 -307.464134) (xy 20.994326 -307.475994) (xy 21.04394 -307.495466)
			(xy 21.090098 -307.522115) (xy 21.131769 -307.555346) (xy 21.168021 -307.594417) (xy 21.198045 -307.638454)
			(xy 21.221171 -307.686475) (xy 21.236881 -307.737405) (xy 21.244824 -307.790109) (xy 21.245322 -307.816758)
			(xy 21.244824 -307.843407) (xy 35.621204 -307.843407) (xy 35.621204 -307.790109) (xy 35.629147 -307.737405)
			(xy 35.644857 -307.686475) (xy 35.667983 -307.638454) (xy 35.698007 -307.594417) (xy 35.734259 -307.555346)
			(xy 35.77593 -307.522115) (xy 35.822088 -307.495466) (xy 35.871702 -307.475994) (xy 35.923664 -307.464134)
			(xy 35.976814 -307.460151) (xy 36.029964 -307.464134) (xy 36.081926 -307.475994) (xy 36.13154 -307.495466)
			(xy 36.177698 -307.522115) (xy 36.219369 -307.555346) (xy 36.255621 -307.594417) (xy 36.285645 -307.638454)
			(xy 36.308771 -307.686475) (xy 36.324481 -307.737405) (xy 36.332424 -307.790109) (xy 36.332922 -307.816758)
			(xy 36.332424 -307.843407) (xy 50.734204 -307.843407) (xy 50.734204 -307.790109) (xy 50.742147 -307.737405)
			(xy 50.757857 -307.686475) (xy 50.780983 -307.638454) (xy 50.811007 -307.594417) (xy 50.847259 -307.555346)
			(xy 50.88893 -307.522115) (xy 50.935088 -307.495466) (xy 50.984702 -307.475994) (xy 51.036664 -307.464134)
			(xy 51.089814 -307.460151) (xy 51.142964 -307.464134) (xy 51.194926 -307.475994) (xy 51.24454 -307.495466)
			(xy 51.290698 -307.522115) (xy 51.332369 -307.555346) (xy 51.368621 -307.594417) (xy 51.398645 -307.638454)
			(xy 51.421771 -307.686475) (xy 51.437481 -307.737405) (xy 51.445424 -307.790109) (xy 51.445922 -307.816758)
			(xy 51.445424 -307.843407) (xy 51.437481 -307.896111) (xy 51.421771 -307.947041) (xy 51.398645 -307.995062)
			(xy 51.368621 -308.039099) (xy 51.332369 -308.07817) (xy 51.290698 -308.111401) (xy 51.24454 -308.13805)
			(xy 51.194926 -308.157522) (xy 51.142964 -308.169382) (xy 51.089814 -308.173366) (xy 51.036664 -308.169382)
			(xy 50.984702 -308.157522) (xy 50.935088 -308.13805) (xy 50.88893 -308.111401) (xy 50.847259 -308.07817)
			(xy 50.811007 -308.039099) (xy 50.780983 -307.995062) (xy 50.757857 -307.947041) (xy 50.742147 -307.896111)
			(xy 50.734204 -307.843407) (xy 36.332424 -307.843407) (xy 36.324481 -307.896111) (xy 36.308771 -307.947041)
			(xy 36.285645 -307.995062) (xy 36.255621 -308.039099) (xy 36.219369 -308.07817) (xy 36.177698 -308.111401)
			(xy 36.13154 -308.13805) (xy 36.081926 -308.157522) (xy 36.029964 -308.169382) (xy 35.976814 -308.173366)
			(xy 35.923664 -308.169382) (xy 35.871702 -308.157522) (xy 35.822088 -308.13805) (xy 35.77593 -308.111401)
			(xy 35.734259 -308.07817) (xy 35.698007 -308.039099) (xy 35.667983 -307.995062) (xy 35.644857 -307.947041)
			(xy 35.629147 -307.896111) (xy 35.621204 -307.843407) (xy 21.244824 -307.843407) (xy 21.236881 -307.896111)
			(xy 21.221171 -307.947041) (xy 21.198045 -307.995062) (xy 21.168021 -308.039099) (xy 21.131769 -308.07817)
			(xy 21.090098 -308.111401) (xy 21.04394 -308.13805) (xy 20.994326 -308.157522) (xy 20.942364 -308.169382)
			(xy 20.889214 -308.173366) (xy 20.836064 -308.169382) (xy 20.784102 -308.157522) (xy 20.734488 -308.13805)
			(xy 20.68833 -308.111401) (xy 20.646659 -308.07817) (xy 20.610407 -308.039099) (xy 20.580383 -307.995062)
			(xy 20.557257 -307.947041) (xy 20.541547 -307.896111) (xy 20.533604 -307.843407) (xy 9.6774 -307.843407)
			(xy 9.6774 -308.693291) (xy 16.433536 -308.693291) (xy 16.433536 -308.639993) (xy 16.441479 -308.587289)
			(xy 16.457189 -308.536359) (xy 16.480315 -308.488338) (xy 16.510339 -308.444301) (xy 16.546591 -308.40523)
			(xy 16.588262 -308.371999) (xy 16.63442 -308.34535) (xy 16.684034 -308.325878) (xy 16.735996 -308.314018)
			(xy 16.789146 -308.310035) (xy 16.842296 -308.314018) (xy 16.894258 -308.325878) (xy 16.943872 -308.34535)
			(xy 16.99003 -308.371999) (xy 17.031701 -308.40523) (xy 17.067953 -308.444301) (xy 17.097977 -308.488338)
			(xy 17.121103 -308.536359) (xy 17.136813 -308.587289) (xy 17.144756 -308.639993) (xy 17.145254 -308.666642)
			(xy 17.144756 -308.693291) (xy 31.521136 -308.693291) (xy 31.521136 -308.639993) (xy 31.529079 -308.587289)
			(xy 31.544789 -308.536359) (xy 31.567915 -308.488338) (xy 31.597939 -308.444301) (xy 31.634191 -308.40523)
			(xy 31.675862 -308.371999) (xy 31.72202 -308.34535) (xy 31.771634 -308.325878) (xy 31.823596 -308.314018)
			(xy 31.876746 -308.310035) (xy 31.929896 -308.314018) (xy 31.981858 -308.325878) (xy 32.031472 -308.34535)
			(xy 32.07763 -308.371999) (xy 32.119301 -308.40523) (xy 32.155553 -308.444301) (xy 32.185577 -308.488338)
			(xy 32.208703 -308.536359) (xy 32.224413 -308.587289) (xy 32.232356 -308.639993) (xy 32.232854 -308.666642)
			(xy 32.232356 -308.693291) (xy 46.608736 -308.693291) (xy 46.608736 -308.639993) (xy 46.616679 -308.587289)
			(xy 46.632389 -308.536359) (xy 46.655515 -308.488338) (xy 46.685539 -308.444301) (xy 46.721791 -308.40523)
			(xy 46.763462 -308.371999) (xy 46.80962 -308.34535) (xy 46.859234 -308.325878) (xy 46.911196 -308.314018)
			(xy 46.964346 -308.310035) (xy 47.017496 -308.314018) (xy 47.069458 -308.325878) (xy 47.119072 -308.34535)
			(xy 47.16523 -308.371999) (xy 47.206901 -308.40523) (xy 47.243153 -308.444301) (xy 47.273177 -308.488338)
			(xy 47.296303 -308.536359) (xy 47.312013 -308.587289) (xy 47.319956 -308.639993) (xy 47.320454 -308.666642)
			(xy 47.319956 -308.693291) (xy 47.312013 -308.745995) (xy 47.296303 -308.796925) (xy 47.273177 -308.844946)
			(xy 47.243153 -308.888983) (xy 47.206901 -308.928054) (xy 47.16523 -308.961285) (xy 47.119072 -308.987934)
			(xy 47.069458 -309.007406) (xy 47.017496 -309.019266) (xy 46.964346 -309.02325) (xy 46.911196 -309.019266)
			(xy 46.859234 -309.007406) (xy 46.80962 -308.987934) (xy 46.763462 -308.961285) (xy 46.721791 -308.928054)
			(xy 46.685539 -308.888983) (xy 46.655515 -308.844946) (xy 46.632389 -308.796925) (xy 46.616679 -308.745995)
			(xy 46.608736 -308.693291) (xy 32.232356 -308.693291) (xy 32.224413 -308.745995) (xy 32.208703 -308.796925)
			(xy 32.185577 -308.844946) (xy 32.155553 -308.888983) (xy 32.119301 -308.928054) (xy 32.07763 -308.961285)
			(xy 32.031472 -308.987934) (xy 31.981858 -309.007406) (xy 31.929896 -309.019266) (xy 31.876746 -309.02325)
			(xy 31.823596 -309.019266) (xy 31.771634 -309.007406) (xy 31.72202 -308.987934) (xy 31.675862 -308.961285)
			(xy 31.634191 -308.928054) (xy 31.597939 -308.888983) (xy 31.567915 -308.844946) (xy 31.544789 -308.796925)
			(xy 31.529079 -308.745995) (xy 31.521136 -308.693291) (xy 17.144756 -308.693291) (xy 17.136813 -308.745995)
			(xy 17.121103 -308.796925) (xy 17.097977 -308.844946) (xy 17.067953 -308.888983) (xy 17.031701 -308.928054)
			(xy 16.99003 -308.961285) (xy 16.943872 -308.987934) (xy 16.894258 -309.007406) (xy 16.842296 -309.019266)
			(xy 16.789146 -309.02325) (xy 16.735996 -309.019266) (xy 16.684034 -309.007406) (xy 16.63442 -308.987934)
			(xy 16.588262 -308.961285) (xy 16.546591 -308.928054) (xy 16.510339 -308.888983) (xy 16.480315 -308.844946)
			(xy 16.457189 -308.796925) (xy 16.441479 -308.745995) (xy 16.433536 -308.693291) (xy 9.6774 -308.693291)
			(xy 9.6774 -309.543429) (xy 20.533604 -309.543429) (xy 20.533604 -309.490131) (xy 20.541547 -309.437427)
			(xy 20.557257 -309.386497) (xy 20.580383 -309.338476) (xy 20.610407 -309.294439) (xy 20.646659 -309.255368)
			(xy 20.68833 -309.222137) (xy 20.734488 -309.195488) (xy 20.784102 -309.176016) (xy 20.836064 -309.164156)
			(xy 20.889214 -309.160173) (xy 20.942364 -309.164156) (xy 20.994326 -309.176016) (xy 21.04394 -309.195488)
			(xy 21.090098 -309.222137) (xy 21.131769 -309.255368) (xy 21.168021 -309.294439) (xy 21.198045 -309.338476)
			(xy 21.221171 -309.386497) (xy 21.236881 -309.437427) (xy 21.244824 -309.490131) (xy 21.245322 -309.51678)
			(xy 21.244824 -309.543429) (xy 35.621204 -309.543429) (xy 35.621204 -309.490131) (xy 35.629147 -309.437427)
			(xy 35.644857 -309.386497) (xy 35.667983 -309.338476) (xy 35.698007 -309.294439) (xy 35.734259 -309.255368)
			(xy 35.77593 -309.222137) (xy 35.822088 -309.195488) (xy 35.871702 -309.176016) (xy 35.923664 -309.164156)
			(xy 35.976814 -309.160173) (xy 36.029964 -309.164156) (xy 36.081926 -309.176016) (xy 36.13154 -309.195488)
			(xy 36.177698 -309.222137) (xy 36.219369 -309.255368) (xy 36.255621 -309.294439) (xy 36.285645 -309.338476)
			(xy 36.308771 -309.386497) (xy 36.324481 -309.437427) (xy 36.332424 -309.490131) (xy 36.332922 -309.51678)
			(xy 36.332424 -309.543429) (xy 50.734204 -309.543429) (xy 50.734204 -309.490131) (xy 50.742147 -309.437427)
			(xy 50.757857 -309.386497) (xy 50.780983 -309.338476) (xy 50.811007 -309.294439) (xy 50.847259 -309.255368)
			(xy 50.88893 -309.222137) (xy 50.935088 -309.195488) (xy 50.984702 -309.176016) (xy 51.036664 -309.164156)
			(xy 51.089814 -309.160173) (xy 51.142964 -309.164156) (xy 51.194926 -309.176016) (xy 51.24454 -309.195488)
			(xy 51.290698 -309.222137) (xy 51.332369 -309.255368) (xy 51.368621 -309.294439) (xy 51.398645 -309.338476)
			(xy 51.421771 -309.386497) (xy 51.437481 -309.437427) (xy 51.445424 -309.490131) (xy 51.445922 -309.51678)
			(xy 51.445424 -309.543429) (xy 51.437481 -309.596133) (xy 51.421771 -309.647063) (xy 51.398645 -309.695084)
			(xy 51.368621 -309.739121) (xy 51.332369 -309.778192) (xy 51.290698 -309.811423) (xy 51.24454 -309.838072)
			(xy 51.194926 -309.857544) (xy 51.142964 -309.869404) (xy 51.089814 -309.873388) (xy 51.036664 -309.869404)
			(xy 50.984702 -309.857544) (xy 50.935088 -309.838072) (xy 50.88893 -309.811423) (xy 50.847259 -309.778192)
			(xy 50.811007 -309.739121) (xy 50.780983 -309.695084) (xy 50.757857 -309.647063) (xy 50.742147 -309.596133)
			(xy 50.734204 -309.543429) (xy 36.332424 -309.543429) (xy 36.324481 -309.596133) (xy 36.308771 -309.647063)
			(xy 36.285645 -309.695084) (xy 36.255621 -309.739121) (xy 36.219369 -309.778192) (xy 36.177698 -309.811423)
			(xy 36.13154 -309.838072) (xy 36.081926 -309.857544) (xy 36.029964 -309.869404) (xy 35.976814 -309.873388)
			(xy 35.923664 -309.869404) (xy 35.871702 -309.857544) (xy 35.822088 -309.838072) (xy 35.77593 -309.811423)
			(xy 35.734259 -309.778192) (xy 35.698007 -309.739121) (xy 35.667983 -309.695084) (xy 35.644857 -309.647063)
			(xy 35.629147 -309.596133) (xy 35.621204 -309.543429) (xy 21.244824 -309.543429) (xy 21.236881 -309.596133)
			(xy 21.221171 -309.647063) (xy 21.198045 -309.695084) (xy 21.168021 -309.739121) (xy 21.131769 -309.778192)
			(xy 21.090098 -309.811423) (xy 21.04394 -309.838072) (xy 20.994326 -309.857544) (xy 20.942364 -309.869404)
			(xy 20.889214 -309.873388) (xy 20.836064 -309.869404) (xy 20.784102 -309.857544) (xy 20.734488 -309.838072)
			(xy 20.68833 -309.811423) (xy 20.646659 -309.778192) (xy 20.610407 -309.739121) (xy 20.580383 -309.695084)
			(xy 20.557257 -309.647063) (xy 20.541547 -309.596133) (xy 20.533604 -309.543429) (xy 9.6774 -309.543429)
			(xy 9.6774 -310.393313) (xy 16.433536 -310.393313) (xy 16.433536 -310.340015) (xy 16.441479 -310.287311)
			(xy 16.457189 -310.236381) (xy 16.480315 -310.18836) (xy 16.510339 -310.144323) (xy 16.546591 -310.105252)
			(xy 16.588262 -310.072021) (xy 16.63442 -310.045372) (xy 16.684034 -310.0259) (xy 16.735996 -310.01404)
			(xy 16.789146 -310.010057) (xy 16.842296 -310.01404) (xy 16.894258 -310.0259) (xy 16.943872 -310.045372)
			(xy 16.99003 -310.072021) (xy 17.031701 -310.105252) (xy 17.067953 -310.144323) (xy 17.097977 -310.18836)
			(xy 17.121103 -310.236381) (xy 17.136813 -310.287311) (xy 17.144756 -310.340015) (xy 17.145254 -310.366664)
			(xy 17.144756 -310.393313) (xy 31.521136 -310.393313) (xy 31.521136 -310.340015) (xy 31.529079 -310.287311)
			(xy 31.544789 -310.236381) (xy 31.567915 -310.18836) (xy 31.597939 -310.144323) (xy 31.634191 -310.105252)
			(xy 31.675862 -310.072021) (xy 31.72202 -310.045372) (xy 31.771634 -310.0259) (xy 31.823596 -310.01404)
			(xy 31.876746 -310.010057) (xy 31.929896 -310.01404) (xy 31.981858 -310.0259) (xy 32.031472 -310.045372)
			(xy 32.07763 -310.072021) (xy 32.119301 -310.105252) (xy 32.155553 -310.144323) (xy 32.185577 -310.18836)
			(xy 32.208703 -310.236381) (xy 32.224413 -310.287311) (xy 32.232356 -310.340015) (xy 32.232854 -310.366664)
			(xy 32.232356 -310.393313) (xy 46.608736 -310.393313) (xy 46.608736 -310.340015) (xy 46.616679 -310.287311)
			(xy 46.632389 -310.236381) (xy 46.655515 -310.18836) (xy 46.685539 -310.144323) (xy 46.721791 -310.105252)
			(xy 46.763462 -310.072021) (xy 46.80962 -310.045372) (xy 46.859234 -310.0259) (xy 46.911196 -310.01404)
			(xy 46.964346 -310.010057) (xy 47.017496 -310.01404) (xy 47.069458 -310.0259) (xy 47.119072 -310.045372)
			(xy 47.16523 -310.072021) (xy 47.206901 -310.105252) (xy 47.243153 -310.144323) (xy 47.273177 -310.18836)
			(xy 47.296303 -310.236381) (xy 47.312013 -310.287311) (xy 47.319956 -310.340015) (xy 47.320454 -310.366664)
			(xy 47.319956 -310.393313) (xy 47.312013 -310.446017) (xy 47.296303 -310.496947) (xy 47.273177 -310.544968)
			(xy 47.243153 -310.589005) (xy 47.206901 -310.628076) (xy 47.16523 -310.661307) (xy 47.119072 -310.687956)
			(xy 47.069458 -310.707428) (xy 47.017496 -310.719288) (xy 46.964346 -310.723272) (xy 46.911196 -310.719288)
			(xy 46.859234 -310.707428) (xy 46.80962 -310.687956) (xy 46.763462 -310.661307) (xy 46.721791 -310.628076)
			(xy 46.685539 -310.589005) (xy 46.655515 -310.544968) (xy 46.632389 -310.496947) (xy 46.616679 -310.446017)
			(xy 46.608736 -310.393313) (xy 32.232356 -310.393313) (xy 32.224413 -310.446017) (xy 32.208703 -310.496947)
			(xy 32.185577 -310.544968) (xy 32.155553 -310.589005) (xy 32.119301 -310.628076) (xy 32.07763 -310.661307)
			(xy 32.031472 -310.687956) (xy 31.981858 -310.707428) (xy 31.929896 -310.719288) (xy 31.876746 -310.723272)
			(xy 31.823596 -310.719288) (xy 31.771634 -310.707428) (xy 31.72202 -310.687956) (xy 31.675862 -310.661307)
			(xy 31.634191 -310.628076) (xy 31.597939 -310.589005) (xy 31.567915 -310.544968) (xy 31.544789 -310.496947)
			(xy 31.529079 -310.446017) (xy 31.521136 -310.393313) (xy 17.144756 -310.393313) (xy 17.136813 -310.446017)
			(xy 17.121103 -310.496947) (xy 17.097977 -310.544968) (xy 17.067953 -310.589005) (xy 17.031701 -310.628076)
			(xy 16.99003 -310.661307) (xy 16.943872 -310.687956) (xy 16.894258 -310.707428) (xy 16.842296 -310.719288)
			(xy 16.789146 -310.723272) (xy 16.735996 -310.719288) (xy 16.684034 -310.707428) (xy 16.63442 -310.687956)
			(xy 16.588262 -310.661307) (xy 16.546591 -310.628076) (xy 16.510339 -310.589005) (xy 16.480315 -310.544968)
			(xy 16.457189 -310.496947) (xy 16.441479 -310.446017) (xy 16.433536 -310.393313) (xy 9.6774 -310.393313)
			(xy 9.6774 -311.243451) (xy 20.533604 -311.243451) (xy 20.533604 -311.190153) (xy 20.541547 -311.137449)
			(xy 20.557257 -311.086519) (xy 20.580383 -311.038498) (xy 20.610407 -310.994461) (xy 20.646659 -310.95539)
			(xy 20.68833 -310.922159) (xy 20.734488 -310.89551) (xy 20.784102 -310.876038) (xy 20.836064 -310.864178)
			(xy 20.889214 -310.860195) (xy 20.942364 -310.864178) (xy 20.994326 -310.876038) (xy 21.04394 -310.89551)
			(xy 21.090098 -310.922159) (xy 21.131769 -310.95539) (xy 21.168021 -310.994461) (xy 21.198045 -311.038498)
			(xy 21.221171 -311.086519) (xy 21.236881 -311.137449) (xy 21.244824 -311.190153) (xy 21.245322 -311.216802)
			(xy 21.244824 -311.243451) (xy 35.621204 -311.243451) (xy 35.621204 -311.190153) (xy 35.629147 -311.137449)
			(xy 35.644857 -311.086519) (xy 35.667983 -311.038498) (xy 35.698007 -310.994461) (xy 35.734259 -310.95539)
			(xy 35.77593 -310.922159) (xy 35.822088 -310.89551) (xy 35.871702 -310.876038) (xy 35.923664 -310.864178)
			(xy 35.976814 -310.860195) (xy 36.029964 -310.864178) (xy 36.081926 -310.876038) (xy 36.13154 -310.89551)
			(xy 36.177698 -310.922159) (xy 36.219369 -310.95539) (xy 36.255621 -310.994461) (xy 36.285645 -311.038498)
			(xy 36.308771 -311.086519) (xy 36.324481 -311.137449) (xy 36.332424 -311.190153) (xy 36.332922 -311.216802)
			(xy 36.332424 -311.243451) (xy 50.734204 -311.243451) (xy 50.734204 -311.190153) (xy 50.742147 -311.137449)
			(xy 50.757857 -311.086519) (xy 50.780983 -311.038498) (xy 50.811007 -310.994461) (xy 50.847259 -310.95539)
			(xy 50.88893 -310.922159) (xy 50.935088 -310.89551) (xy 50.984702 -310.876038) (xy 51.036664 -310.864178)
			(xy 51.089814 -310.860195) (xy 51.142964 -310.864178) (xy 51.194926 -310.876038) (xy 51.24454 -310.89551)
			(xy 51.290698 -310.922159) (xy 51.332369 -310.95539) (xy 51.368621 -310.994461) (xy 51.398645 -311.038498)
			(xy 51.421771 -311.086519) (xy 51.437481 -311.137449) (xy 51.445424 -311.190153) (xy 51.445922 -311.216802)
			(xy 51.445424 -311.243451) (xy 51.437481 -311.296155) (xy 51.421771 -311.347085) (xy 51.398645 -311.395106)
			(xy 51.368621 -311.439143) (xy 51.332369 -311.478214) (xy 51.290698 -311.511445) (xy 51.24454 -311.538094)
			(xy 51.194926 -311.557566) (xy 51.142964 -311.569426) (xy 51.089814 -311.57341) (xy 51.036664 -311.569426)
			(xy 50.984702 -311.557566) (xy 50.935088 -311.538094) (xy 50.88893 -311.511445) (xy 50.847259 -311.478214)
			(xy 50.811007 -311.439143) (xy 50.780983 -311.395106) (xy 50.757857 -311.347085) (xy 50.742147 -311.296155)
			(xy 50.734204 -311.243451) (xy 36.332424 -311.243451) (xy 36.324481 -311.296155) (xy 36.308771 -311.347085)
			(xy 36.285645 -311.395106) (xy 36.255621 -311.439143) (xy 36.219369 -311.478214) (xy 36.177698 -311.511445)
			(xy 36.13154 -311.538094) (xy 36.081926 -311.557566) (xy 36.029964 -311.569426) (xy 35.976814 -311.57341)
			(xy 35.923664 -311.569426) (xy 35.871702 -311.557566) (xy 35.822088 -311.538094) (xy 35.77593 -311.511445)
			(xy 35.734259 -311.478214) (xy 35.698007 -311.439143) (xy 35.667983 -311.395106) (xy 35.644857 -311.347085)
			(xy 35.629147 -311.296155) (xy 35.621204 -311.243451) (xy 21.244824 -311.243451) (xy 21.236881 -311.296155)
			(xy 21.221171 -311.347085) (xy 21.198045 -311.395106) (xy 21.168021 -311.439143) (xy 21.131769 -311.478214)
			(xy 21.090098 -311.511445) (xy 21.04394 -311.538094) (xy 20.994326 -311.557566) (xy 20.942364 -311.569426)
			(xy 20.889214 -311.57341) (xy 20.836064 -311.569426) (xy 20.784102 -311.557566) (xy 20.734488 -311.538094)
			(xy 20.68833 -311.511445) (xy 20.646659 -311.478214) (xy 20.610407 -311.439143) (xy 20.580383 -311.395106)
			(xy 20.557257 -311.347085) (xy 20.541547 -311.296155) (xy 20.533604 -311.243451) (xy 9.6774 -311.243451)
			(xy 9.6774 -312.093335) (xy 16.433536 -312.093335) (xy 16.433536 -312.040037) (xy 16.441479 -311.987333)
			(xy 16.457189 -311.936403) (xy 16.480315 -311.888382) (xy 16.510339 -311.844345) (xy 16.546591 -311.805274)
			(xy 16.588262 -311.772043) (xy 16.63442 -311.745394) (xy 16.684034 -311.725922) (xy 16.735996 -311.714062)
			(xy 16.789146 -311.710079) (xy 16.842296 -311.714062) (xy 16.894258 -311.725922) (xy 16.943872 -311.745394)
			(xy 16.99003 -311.772043) (xy 17.031701 -311.805274) (xy 17.067953 -311.844345) (xy 17.097977 -311.888382)
			(xy 17.121103 -311.936403) (xy 17.136813 -311.987333) (xy 17.144756 -312.040037) (xy 17.145254 -312.066686)
			(xy 17.144756 -312.093335) (xy 20.533604 -312.093335) (xy 20.533604 -312.040037) (xy 20.541547 -311.987333)
			(xy 20.557257 -311.936403) (xy 20.580383 -311.888382) (xy 20.610407 -311.844345) (xy 20.646659 -311.805274)
			(xy 20.68833 -311.772043) (xy 20.734488 -311.745394) (xy 20.784102 -311.725922) (xy 20.836064 -311.714062)
			(xy 20.889214 -311.710079) (xy 20.942364 -311.714062) (xy 20.994326 -311.725922) (xy 21.04394 -311.745394)
			(xy 21.090098 -311.772043) (xy 21.131769 -311.805274) (xy 21.168021 -311.844345) (xy 21.198045 -311.888382)
			(xy 21.221171 -311.936403) (xy 21.236881 -311.987333) (xy 21.244824 -312.040037) (xy 21.245322 -312.066686)
			(xy 21.244824 -312.093335) (xy 31.521136 -312.093335) (xy 31.521136 -312.040037) (xy 31.529079 -311.987333)
			(xy 31.544789 -311.936403) (xy 31.567915 -311.888382) (xy 31.597939 -311.844345) (xy 31.634191 -311.805274)
			(xy 31.675862 -311.772043) (xy 31.72202 -311.745394) (xy 31.771634 -311.725922) (xy 31.823596 -311.714062)
			(xy 31.876746 -311.710079) (xy 31.929896 -311.714062) (xy 31.981858 -311.725922) (xy 32.031472 -311.745394)
			(xy 32.07763 -311.772043) (xy 32.119301 -311.805274) (xy 32.155553 -311.844345) (xy 32.185577 -311.888382)
			(xy 32.208703 -311.936403) (xy 32.224413 -311.987333) (xy 32.232356 -312.040037) (xy 32.232854 -312.066686)
			(xy 32.232356 -312.093335) (xy 35.621204 -312.093335) (xy 35.621204 -312.040037) (xy 35.629147 -311.987333)
			(xy 35.644857 -311.936403) (xy 35.667983 -311.888382) (xy 35.698007 -311.844345) (xy 35.734259 -311.805274)
			(xy 35.77593 -311.772043) (xy 35.822088 -311.745394) (xy 35.871702 -311.725922) (xy 35.923664 -311.714062)
			(xy 35.976814 -311.710079) (xy 36.029964 -311.714062) (xy 36.081926 -311.725922) (xy 36.13154 -311.745394)
			(xy 36.177698 -311.772043) (xy 36.219369 -311.805274) (xy 36.255621 -311.844345) (xy 36.285645 -311.888382)
			(xy 36.308771 -311.936403) (xy 36.324481 -311.987333) (xy 36.332424 -312.040037) (xy 36.332922 -312.066686)
			(xy 36.332424 -312.093335) (xy 46.608736 -312.093335) (xy 46.608736 -312.040037) (xy 46.616679 -311.987333)
			(xy 46.632389 -311.936403) (xy 46.655515 -311.888382) (xy 46.685539 -311.844345) (xy 46.721791 -311.805274)
			(xy 46.763462 -311.772043) (xy 46.80962 -311.745394) (xy 46.859234 -311.725922) (xy 46.911196 -311.714062)
			(xy 46.964346 -311.710079) (xy 47.017496 -311.714062) (xy 47.069458 -311.725922) (xy 47.119072 -311.745394)
			(xy 47.16523 -311.772043) (xy 47.206901 -311.805274) (xy 47.243153 -311.844345) (xy 47.273177 -311.888382)
			(xy 47.296303 -311.936403) (xy 47.312013 -311.987333) (xy 47.319956 -312.040037) (xy 47.320454 -312.066686)
			(xy 47.319956 -312.093335) (xy 50.734204 -312.093335) (xy 50.734204 -312.040037) (xy 50.742147 -311.987333)
			(xy 50.757857 -311.936403) (xy 50.780983 -311.888382) (xy 50.811007 -311.844345) (xy 50.847259 -311.805274)
			(xy 50.88893 -311.772043) (xy 50.935088 -311.745394) (xy 50.984702 -311.725922) (xy 51.036664 -311.714062)
			(xy 51.089814 -311.710079) (xy 51.142964 -311.714062) (xy 51.194926 -311.725922) (xy 51.24454 -311.745394)
			(xy 51.290698 -311.772043) (xy 51.332369 -311.805274) (xy 51.368621 -311.844345) (xy 51.398645 -311.888382)
			(xy 51.421771 -311.936403) (xy 51.437481 -311.987333) (xy 51.445424 -312.040037) (xy 51.445922 -312.066686)
			(xy 51.445424 -312.093335) (xy 51.437481 -312.146039) (xy 51.421771 -312.196969) (xy 51.398645 -312.24499)
			(xy 51.368621 -312.289027) (xy 51.332369 -312.328098) (xy 51.290698 -312.361329) (xy 51.24454 -312.387978)
			(xy 51.194926 -312.40745) (xy 51.142964 -312.41931) (xy 51.089814 -312.423294) (xy 51.036664 -312.41931)
			(xy 50.984702 -312.40745) (xy 50.935088 -312.387978) (xy 50.88893 -312.361329) (xy 50.847259 -312.328098)
			(xy 50.811007 -312.289027) (xy 50.780983 -312.24499) (xy 50.757857 -312.196969) (xy 50.742147 -312.146039)
			(xy 50.734204 -312.093335) (xy 47.319956 -312.093335) (xy 47.312013 -312.146039) (xy 47.296303 -312.196969)
			(xy 47.273177 -312.24499) (xy 47.243153 -312.289027) (xy 47.206901 -312.328098) (xy 47.16523 -312.361329)
			(xy 47.119072 -312.387978) (xy 47.069458 -312.40745) (xy 47.017496 -312.41931) (xy 46.964346 -312.423294)
			(xy 46.911196 -312.41931) (xy 46.859234 -312.40745) (xy 46.80962 -312.387978) (xy 46.763462 -312.361329)
			(xy 46.721791 -312.328098) (xy 46.685539 -312.289027) (xy 46.655515 -312.24499) (xy 46.632389 -312.196969)
			(xy 46.616679 -312.146039) (xy 46.608736 -312.093335) (xy 36.332424 -312.093335) (xy 36.324481 -312.146039)
			(xy 36.308771 -312.196969) (xy 36.285645 -312.24499) (xy 36.255621 -312.289027) (xy 36.219369 -312.328098)
			(xy 36.177698 -312.361329) (xy 36.13154 -312.387978) (xy 36.081926 -312.40745) (xy 36.029964 -312.41931)
			(xy 35.976814 -312.423294) (xy 35.923664 -312.41931) (xy 35.871702 -312.40745) (xy 35.822088 -312.387978)
			(xy 35.77593 -312.361329) (xy 35.734259 -312.328098) (xy 35.698007 -312.289027) (xy 35.667983 -312.24499)
			(xy 35.644857 -312.196969) (xy 35.629147 -312.146039) (xy 35.621204 -312.093335) (xy 32.232356 -312.093335)
			(xy 32.224413 -312.146039) (xy 32.208703 -312.196969) (xy 32.185577 -312.24499) (xy 32.155553 -312.289027)
			(xy 32.119301 -312.328098) (xy 32.07763 -312.361329) (xy 32.031472 -312.387978) (xy 31.981858 -312.40745)
			(xy 31.929896 -312.41931) (xy 31.876746 -312.423294) (xy 31.823596 -312.41931) (xy 31.771634 -312.40745)
			(xy 31.72202 -312.387978) (xy 31.675862 -312.361329) (xy 31.634191 -312.328098) (xy 31.597939 -312.289027)
			(xy 31.567915 -312.24499) (xy 31.544789 -312.196969) (xy 31.529079 -312.146039) (xy 31.521136 -312.093335)
			(xy 21.244824 -312.093335) (xy 21.236881 -312.146039) (xy 21.221171 -312.196969) (xy 21.198045 -312.24499)
			(xy 21.168021 -312.289027) (xy 21.131769 -312.328098) (xy 21.090098 -312.361329) (xy 21.04394 -312.387978)
			(xy 20.994326 -312.40745) (xy 20.942364 -312.41931) (xy 20.889214 -312.423294) (xy 20.836064 -312.41931)
			(xy 20.784102 -312.40745) (xy 20.734488 -312.387978) (xy 20.68833 -312.361329) (xy 20.646659 -312.328098)
			(xy 20.610407 -312.289027) (xy 20.580383 -312.24499) (xy 20.557257 -312.196969) (xy 20.541547 -312.146039)
			(xy 20.533604 -312.093335) (xy 17.144756 -312.093335) (xy 17.136813 -312.146039) (xy 17.121103 -312.196969)
			(xy 17.097977 -312.24499) (xy 17.067953 -312.289027) (xy 17.031701 -312.328098) (xy 16.99003 -312.361329)
			(xy 16.943872 -312.387978) (xy 16.894258 -312.40745) (xy 16.842296 -312.41931) (xy 16.789146 -312.423294)
			(xy 16.735996 -312.41931) (xy 16.684034 -312.40745) (xy 16.63442 -312.387978) (xy 16.588262 -312.361329)
			(xy 16.546591 -312.328098) (xy 16.510339 -312.289027) (xy 16.480315 -312.24499) (xy 16.457189 -312.196969)
			(xy 16.441479 -312.146039) (xy 16.433536 -312.093335) (xy 9.6774 -312.093335) (xy 9.6774 -312.943219)
			(xy 16.433536 -312.943219) (xy 16.433536 -312.889921) (xy 16.441479 -312.837217) (xy 16.457189 -312.786287)
			(xy 16.480315 -312.738266) (xy 16.510339 -312.694229) (xy 16.546591 -312.655158) (xy 16.588262 -312.621927)
			(xy 16.63442 -312.595278) (xy 16.684034 -312.575806) (xy 16.735996 -312.563946) (xy 16.789146 -312.559963)
			(xy 16.842296 -312.563946) (xy 16.894258 -312.575806) (xy 16.943872 -312.595278) (xy 16.99003 -312.621927)
			(xy 17.031701 -312.655158) (xy 17.067953 -312.694229) (xy 17.097977 -312.738266) (xy 17.121103 -312.786287)
			(xy 17.136813 -312.837217) (xy 17.144756 -312.889921) (xy 17.145254 -312.91657) (xy 17.144756 -312.943219)
			(xy 31.521136 -312.943219) (xy 31.521136 -312.889921) (xy 31.529079 -312.837217) (xy 31.544789 -312.786287)
			(xy 31.567915 -312.738266) (xy 31.597939 -312.694229) (xy 31.634191 -312.655158) (xy 31.675862 -312.621927)
			(xy 31.72202 -312.595278) (xy 31.771634 -312.575806) (xy 31.823596 -312.563946) (xy 31.876746 -312.559963)
			(xy 31.929896 -312.563946) (xy 31.981858 -312.575806) (xy 32.031472 -312.595278) (xy 32.07763 -312.621927)
			(xy 32.119301 -312.655158) (xy 32.155553 -312.694229) (xy 32.185577 -312.738266) (xy 32.208703 -312.786287)
			(xy 32.224413 -312.837217) (xy 32.232356 -312.889921) (xy 32.232854 -312.91657) (xy 32.232356 -312.943219)
			(xy 46.608736 -312.943219) (xy 46.608736 -312.889921) (xy 46.616679 -312.837217) (xy 46.632389 -312.786287)
			(xy 46.655515 -312.738266) (xy 46.685539 -312.694229) (xy 46.721791 -312.655158) (xy 46.763462 -312.621927)
			(xy 46.80962 -312.595278) (xy 46.859234 -312.575806) (xy 46.911196 -312.563946) (xy 46.964346 -312.559963)
			(xy 47.017496 -312.563946) (xy 47.069458 -312.575806) (xy 47.119072 -312.595278) (xy 47.16523 -312.621927)
			(xy 47.206901 -312.655158) (xy 47.243153 -312.694229) (xy 47.273177 -312.738266) (xy 47.296303 -312.786287)
			(xy 47.312013 -312.837217) (xy 47.319956 -312.889921) (xy 47.320454 -312.91657) (xy 47.319956 -312.943219)
			(xy 47.312013 -312.995923) (xy 47.296303 -313.046853) (xy 47.273177 -313.094874) (xy 47.243153 -313.138911)
			(xy 47.206901 -313.177982) (xy 47.16523 -313.211213) (xy 47.119072 -313.237862) (xy 47.069458 -313.257334)
			(xy 47.017496 -313.269194) (xy 46.964346 -313.273178) (xy 46.911196 -313.269194) (xy 46.859234 -313.257334)
			(xy 46.80962 -313.237862) (xy 46.763462 -313.211213) (xy 46.721791 -313.177982) (xy 46.685539 -313.138911)
			(xy 46.655515 -313.094874) (xy 46.632389 -313.046853) (xy 46.616679 -312.995923) (xy 46.608736 -312.943219)
			(xy 32.232356 -312.943219) (xy 32.224413 -312.995923) (xy 32.208703 -313.046853) (xy 32.185577 -313.094874)
			(xy 32.155553 -313.138911) (xy 32.119301 -313.177982) (xy 32.07763 -313.211213) (xy 32.031472 -313.237862)
			(xy 31.981858 -313.257334) (xy 31.929896 -313.269194) (xy 31.876746 -313.273178) (xy 31.823596 -313.269194)
			(xy 31.771634 -313.257334) (xy 31.72202 -313.237862) (xy 31.675862 -313.211213) (xy 31.634191 -313.177982)
			(xy 31.597939 -313.138911) (xy 31.567915 -313.094874) (xy 31.544789 -313.046853) (xy 31.529079 -312.995923)
			(xy 31.521136 -312.943219) (xy 17.144756 -312.943219) (xy 17.136813 -312.995923) (xy 17.121103 -313.046853)
			(xy 17.097977 -313.094874) (xy 17.067953 -313.138911) (xy 17.031701 -313.177982) (xy 16.99003 -313.211213)
			(xy 16.943872 -313.237862) (xy 16.894258 -313.257334) (xy 16.842296 -313.269194) (xy 16.789146 -313.273178)
			(xy 16.735996 -313.269194) (xy 16.684034 -313.257334) (xy 16.63442 -313.237862) (xy 16.588262 -313.211213)
			(xy 16.546591 -313.177982) (xy 16.510339 -313.138911) (xy 16.480315 -313.094874) (xy 16.457189 -313.046853)
			(xy 16.441479 -312.995923) (xy 16.433536 -312.943219) (xy 9.6774 -312.943219) (xy 9.6774 -313.793357)
			(xy 20.533604 -313.793357) (xy 20.533604 -313.740059) (xy 20.541547 -313.687355) (xy 20.557257 -313.636425)
			(xy 20.580383 -313.588404) (xy 20.610407 -313.544367) (xy 20.646659 -313.505296) (xy 20.68833 -313.472065)
			(xy 20.734488 -313.445416) (xy 20.784102 -313.425944) (xy 20.836064 -313.414084) (xy 20.889214 -313.410101)
			(xy 20.942364 -313.414084) (xy 20.994326 -313.425944) (xy 21.04394 -313.445416) (xy 21.090098 -313.472065)
			(xy 21.131769 -313.505296) (xy 21.168021 -313.544367) (xy 21.198045 -313.588404) (xy 21.221171 -313.636425)
			(xy 21.236881 -313.687355) (xy 21.244824 -313.740059) (xy 21.245322 -313.766708) (xy 21.244824 -313.793357)
			(xy 35.621204 -313.793357) (xy 35.621204 -313.740059) (xy 35.629147 -313.687355) (xy 35.644857 -313.636425)
			(xy 35.667983 -313.588404) (xy 35.698007 -313.544367) (xy 35.734259 -313.505296) (xy 35.77593 -313.472065)
			(xy 35.822088 -313.445416) (xy 35.871702 -313.425944) (xy 35.923664 -313.414084) (xy 35.976814 -313.410101)
			(xy 36.029964 -313.414084) (xy 36.081926 -313.425944) (xy 36.13154 -313.445416) (xy 36.177698 -313.472065)
			(xy 36.219369 -313.505296) (xy 36.255621 -313.544367) (xy 36.285645 -313.588404) (xy 36.308771 -313.636425)
			(xy 36.324481 -313.687355) (xy 36.332424 -313.740059) (xy 36.332922 -313.766708) (xy 36.332424 -313.793357)
			(xy 50.734204 -313.793357) (xy 50.734204 -313.740059) (xy 50.742147 -313.687355) (xy 50.757857 -313.636425)
			(xy 50.780983 -313.588404) (xy 50.811007 -313.544367) (xy 50.847259 -313.505296) (xy 50.88893 -313.472065)
			(xy 50.935088 -313.445416) (xy 50.984702 -313.425944) (xy 51.036664 -313.414084) (xy 51.089814 -313.410101)
			(xy 51.142964 -313.414084) (xy 51.194926 -313.425944) (xy 51.24454 -313.445416) (xy 51.290698 -313.472065)
			(xy 51.332369 -313.505296) (xy 51.368621 -313.544367) (xy 51.398645 -313.588404) (xy 51.421771 -313.636425)
			(xy 51.437481 -313.687355) (xy 51.445424 -313.740059) (xy 51.445922 -313.766708) (xy 51.445424 -313.793357)
			(xy 51.437481 -313.846061) (xy 51.421771 -313.896991) (xy 51.398645 -313.945012) (xy 51.368621 -313.989049)
			(xy 51.332369 -314.02812) (xy 51.290698 -314.061351) (xy 51.24454 -314.088) (xy 51.194926 -314.107472)
			(xy 51.142964 -314.119332) (xy 51.089814 -314.123316) (xy 51.036664 -314.119332) (xy 50.984702 -314.107472)
			(xy 50.935088 -314.088) (xy 50.88893 -314.061351) (xy 50.847259 -314.02812) (xy 50.811007 -313.989049)
			(xy 50.780983 -313.945012) (xy 50.757857 -313.896991) (xy 50.742147 -313.846061) (xy 50.734204 -313.793357)
			(xy 36.332424 -313.793357) (xy 36.324481 -313.846061) (xy 36.308771 -313.896991) (xy 36.285645 -313.945012)
			(xy 36.255621 -313.989049) (xy 36.219369 -314.02812) (xy 36.177698 -314.061351) (xy 36.13154 -314.088)
			(xy 36.081926 -314.107472) (xy 36.029964 -314.119332) (xy 35.976814 -314.123316) (xy 35.923664 -314.119332)
			(xy 35.871702 -314.107472) (xy 35.822088 -314.088) (xy 35.77593 -314.061351) (xy 35.734259 -314.02812)
			(xy 35.698007 -313.989049) (xy 35.667983 -313.945012) (xy 35.644857 -313.896991) (xy 35.629147 -313.846061)
			(xy 35.621204 -313.793357) (xy 21.244824 -313.793357) (xy 21.236881 -313.846061) (xy 21.221171 -313.896991)
			(xy 21.198045 -313.945012) (xy 21.168021 -313.989049) (xy 21.131769 -314.02812) (xy 21.090098 -314.061351)
			(xy 21.04394 -314.088) (xy 20.994326 -314.107472) (xy 20.942364 -314.119332) (xy 20.889214 -314.123316)
			(xy 20.836064 -314.119332) (xy 20.784102 -314.107472) (xy 20.734488 -314.088) (xy 20.68833 -314.061351)
			(xy 20.646659 -314.02812) (xy 20.610407 -313.989049) (xy 20.580383 -313.945012) (xy 20.557257 -313.896991)
			(xy 20.541547 -313.846061) (xy 20.533604 -313.793357) (xy 9.6774 -313.793357) (xy 9.6774 -314.643241)
			(xy 16.433536 -314.643241) (xy 16.433536 -314.589943) (xy 16.441479 -314.537239) (xy 16.457189 -314.486309)
			(xy 16.480315 -314.438288) (xy 16.510339 -314.394251) (xy 16.546591 -314.35518) (xy 16.588262 -314.321949)
			(xy 16.63442 -314.2953) (xy 16.684034 -314.275828) (xy 16.735996 -314.263968) (xy 16.789146 -314.259985)
			(xy 16.842296 -314.263968) (xy 16.894258 -314.275828) (xy 16.943872 -314.2953) (xy 16.99003 -314.321949)
			(xy 17.031701 -314.35518) (xy 17.067953 -314.394251) (xy 17.097977 -314.438288) (xy 17.121103 -314.486309)
			(xy 17.136813 -314.537239) (xy 17.144756 -314.589943) (xy 17.145254 -314.616592) (xy 17.144756 -314.643241)
			(xy 31.521136 -314.643241) (xy 31.521136 -314.589943) (xy 31.529079 -314.537239) (xy 31.544789 -314.486309)
			(xy 31.567915 -314.438288) (xy 31.597939 -314.394251) (xy 31.634191 -314.35518) (xy 31.675862 -314.321949)
			(xy 31.72202 -314.2953) (xy 31.771634 -314.275828) (xy 31.823596 -314.263968) (xy 31.876746 -314.259985)
			(xy 31.929896 -314.263968) (xy 31.981858 -314.275828) (xy 32.031472 -314.2953) (xy 32.07763 -314.321949)
			(xy 32.119301 -314.35518) (xy 32.155553 -314.394251) (xy 32.185577 -314.438288) (xy 32.208703 -314.486309)
			(xy 32.224413 -314.537239) (xy 32.232356 -314.589943) (xy 32.232854 -314.616592) (xy 32.232356 -314.643241)
			(xy 32.224413 -314.695945) (xy 32.208703 -314.746875) (xy 32.185577 -314.794896) (xy 32.155553 -314.838933)
			(xy 32.119301 -314.878004) (xy 32.07763 -314.911235) (xy 32.031472 -314.937884) (xy 31.981858 -314.957356)
			(xy 31.929896 -314.969216) (xy 31.876746 -314.9732) (xy 31.823596 -314.969216) (xy 31.771634 -314.957356)
			(xy 31.72202 -314.937884) (xy 31.675862 -314.911235) (xy 31.634191 -314.878004) (xy 31.597939 -314.838933)
			(xy 31.567915 -314.794896) (xy 31.544789 -314.746875) (xy 31.529079 -314.695945) (xy 31.521136 -314.643241)
			(xy 17.144756 -314.643241) (xy 17.136813 -314.695945) (xy 17.121103 -314.746875) (xy 17.097977 -314.794896)
			(xy 17.067953 -314.838933) (xy 17.031701 -314.878004) (xy 16.99003 -314.911235) (xy 16.943872 -314.937884)
			(xy 16.894258 -314.957356) (xy 16.842296 -314.969216) (xy 16.789146 -314.9732) (xy 16.735996 -314.969216)
			(xy 16.684034 -314.957356) (xy 16.63442 -314.937884) (xy 16.588262 -314.911235) (xy 16.546591 -314.878004)
			(xy 16.510339 -314.838933) (xy 16.480315 -314.794896) (xy 16.457189 -314.746875) (xy 16.441479 -314.695945)
			(xy 16.433536 -314.643241) (xy 9.6774 -314.643241) (xy 9.6774 -315.493379) (xy 20.533604 -315.493379)
			(xy 20.533604 -315.440081) (xy 20.541547 -315.387377) (xy 20.557257 -315.336447) (xy 20.580383 -315.288426)
			(xy 20.610407 -315.244389) (xy 20.646659 -315.205318) (xy 20.68833 -315.172087) (xy 20.734488 -315.145438)
			(xy 20.784102 -315.125966) (xy 20.836064 -315.114106) (xy 20.889214 -315.110123) (xy 20.942364 -315.114106)
			(xy 20.994326 -315.125966) (xy 21.04394 -315.145438) (xy 21.090098 -315.172087) (xy 21.131769 -315.205318)
			(xy 21.168021 -315.244389) (xy 21.198045 -315.288426) (xy 21.221171 -315.336447) (xy 21.236881 -315.387377)
			(xy 21.244824 -315.440081) (xy 21.245322 -315.46673) (xy 21.244824 -315.493379) (xy 21.236881 -315.546083)
			(xy 21.221171 -315.597013) (xy 21.198045 -315.645034) (xy 21.168021 -315.689071) (xy 21.131769 -315.728142)
			(xy 21.090098 -315.761373) (xy 21.04394 -315.788022) (xy 20.994326 -315.807494) (xy 20.942364 -315.819354)
			(xy 20.889214 -315.823338) (xy 20.836064 -315.819354) (xy 20.784102 -315.807494) (xy 20.734488 -315.788022)
			(xy 20.68833 -315.761373) (xy 20.646659 -315.728142) (xy 20.610407 -315.689071) (xy 20.580383 -315.645034)
			(xy 20.557257 -315.597013) (xy 20.541547 -315.546083) (xy 20.533604 -315.493379) (xy 9.6774 -315.493379)
			(xy 9.6774 -316.343263) (xy 16.433536 -316.343263) (xy 16.433536 -316.289965) (xy 16.441479 -316.237261)
			(xy 16.457189 -316.186331) (xy 16.480315 -316.13831) (xy 16.510339 -316.094273) (xy 16.546591 -316.055202)
			(xy 16.588262 -316.021971) (xy 16.63442 -315.995322) (xy 16.684034 -315.97585) (xy 16.735996 -315.96399)
			(xy 16.789146 -315.960007) (xy 16.842296 -315.96399) (xy 16.894258 -315.97585) (xy 16.943872 -315.995322)
			(xy 16.99003 -316.021971) (xy 17.031701 -316.055202) (xy 17.067953 -316.094273) (xy 17.097977 -316.13831)
			(xy 17.121103 -316.186331) (xy 17.136813 -316.237261) (xy 17.144756 -316.289965) (xy 17.145254 -316.316614)
			(xy 17.144756 -316.343263) (xy 31.521136 -316.343263) (xy 31.521136 -316.289965) (xy 31.529079 -316.237261)
			(xy 31.544789 -316.186331) (xy 31.567915 -316.13831) (xy 31.597939 -316.094273) (xy 31.634191 -316.055202)
			(xy 31.675862 -316.021971) (xy 31.72202 -315.995322) (xy 31.771634 -315.97585) (xy 31.823596 -315.96399)
			(xy 31.876746 -315.960007) (xy 31.929896 -315.96399) (xy 31.981858 -315.97585) (xy 32.031472 -315.995322)
			(xy 32.07763 -316.021971) (xy 32.119301 -316.055202) (xy 32.155553 -316.094273) (xy 32.185577 -316.13831)
			(xy 32.208703 -316.186331) (xy 32.224413 -316.237261) (xy 32.232356 -316.289965) (xy 32.232854 -316.316614)
			(xy 32.232356 -316.343263) (xy 32.224413 -316.395967) (xy 32.208703 -316.446897) (xy 32.185577 -316.494918)
			(xy 32.155553 -316.538955) (xy 32.119301 -316.578026) (xy 32.07763 -316.611257) (xy 32.031472 -316.637906)
			(xy 31.981858 -316.657378) (xy 31.929896 -316.669238) (xy 31.876746 -316.673222) (xy 31.823596 -316.669238)
			(xy 31.771634 -316.657378) (xy 31.72202 -316.637906) (xy 31.675862 -316.611257) (xy 31.634191 -316.578026)
			(xy 31.597939 -316.538955) (xy 31.567915 -316.494918) (xy 31.544789 -316.446897) (xy 31.529079 -316.395967)
			(xy 31.521136 -316.343263) (xy 17.144756 -316.343263) (xy 17.136813 -316.395967) (xy 17.121103 -316.446897)
			(xy 17.097977 -316.494918) (xy 17.067953 -316.538955) (xy 17.031701 -316.578026) (xy 16.99003 -316.611257)
			(xy 16.943872 -316.637906) (xy 16.894258 -316.657378) (xy 16.842296 -316.669238) (xy 16.789146 -316.673222)
			(xy 16.735996 -316.669238) (xy 16.684034 -316.657378) (xy 16.63442 -316.637906) (xy 16.588262 -316.611257)
			(xy 16.546591 -316.578026) (xy 16.510339 -316.538955) (xy 16.480315 -316.494918) (xy 16.457189 -316.446897)
			(xy 16.441479 -316.395967) (xy 16.433536 -316.343263) (xy 9.6774 -316.343263) (xy 9.6774 -317.166752)
			(xy 10.753596 -317.166752) (xy 10.757667 -317.11113) (xy 10.769793 -317.056693) (xy 10.789716 -317.004602)
			(xy 10.817012 -316.955967) (xy 10.851098 -316.911824) (xy 10.891247 -316.873115) (xy 10.936605 -316.840664)
			(xy 10.986205 -316.815163) (xy 11.038989 -316.797156) (xy 11.093832 -316.787026) (xy 11.149566 -316.784989)
			(xy 11.205003 -316.791089) (xy 11.25896 -316.805195) (xy 11.310289 -316.827007) (xy 11.357895 -316.856061)
			(xy 11.400763 -316.891736) (xy 11.43798 -316.933273) (xy 11.468753 -316.979786) (xy 11.492425 -317.030283)
			(xy 11.508493 -317.08369) (xy 11.516613 -317.138866) (xy 11.517122 -317.166752) (xy 11.516636 -317.193401)
			(xy 20.533604 -317.193401) (xy 20.533604 -317.140103) (xy 20.541547 -317.087399) (xy 20.557257 -317.036469)
			(xy 20.580383 -316.988448) (xy 20.610407 -316.944411) (xy 20.646659 -316.90534) (xy 20.68833 -316.872109)
			(xy 20.734488 -316.84546) (xy 20.784102 -316.825988) (xy 20.836064 -316.814128) (xy 20.889214 -316.810145)
			(xy 20.942364 -316.814128) (xy 20.994326 -316.825988) (xy 21.04394 -316.84546) (xy 21.090098 -316.872109)
			(xy 21.131769 -316.90534) (xy 21.168021 -316.944411) (xy 21.198045 -316.988448) (xy 21.221171 -317.036469)
			(xy 21.236881 -317.087399) (xy 21.244824 -317.140103) (xy 21.245322 -317.166752) (xy 21.244824 -317.193401)
			(xy 28.077404 -317.193401) (xy 28.077404 -317.140103) (xy 28.085347 -317.087399) (xy 28.101057 -317.036469)
			(xy 28.124183 -316.988448) (xy 28.154207 -316.944411) (xy 28.190459 -316.90534) (xy 28.23213 -316.872109)
			(xy 28.278288 -316.84546) (xy 28.327902 -316.825988) (xy 28.379864 -316.814128) (xy 28.433014 -316.810145)
			(xy 28.486164 -316.814128) (xy 28.538126 -316.825988) (xy 28.58774 -316.84546) (xy 28.633898 -316.872109)
			(xy 28.675569 -316.90534) (xy 28.711821 -316.944411) (xy 28.741845 -316.988448) (xy 28.764971 -317.036469)
			(xy 28.780681 -317.087399) (xy 28.788624 -317.140103) (xy 28.789122 -317.166752) (xy 28.788624 -317.193401)
			(xy 28.780681 -317.246105) (xy 28.764971 -317.297035) (xy 28.741845 -317.345056) (xy 28.711821 -317.389093)
			(xy 28.675569 -317.428164) (xy 28.633898 -317.461395) (xy 28.58774 -317.488044) (xy 28.538126 -317.507516)
			(xy 28.486164 -317.519376) (xy 28.433014 -317.52336) (xy 28.379864 -317.519376) (xy 28.327902 -317.507516)
			(xy 28.278288 -317.488044) (xy 28.23213 -317.461395) (xy 28.190459 -317.428164) (xy 28.154207 -317.389093)
			(xy 28.124183 -317.345056) (xy 28.101057 -317.297035) (xy 28.085347 -317.246105) (xy 28.077404 -317.193401)
			(xy 21.244824 -317.193401) (xy 21.236881 -317.246105) (xy 21.221171 -317.297035) (xy 21.198045 -317.345056)
			(xy 21.168021 -317.389093) (xy 21.131769 -317.428164) (xy 21.090098 -317.461395) (xy 21.04394 -317.488044)
			(xy 20.994326 -317.507516) (xy 20.942364 -317.519376) (xy 20.889214 -317.52336) (xy 20.836064 -317.519376)
			(xy 20.784102 -317.507516) (xy 20.734488 -317.488044) (xy 20.68833 -317.461395) (xy 20.646659 -317.428164)
			(xy 20.610407 -317.389093) (xy 20.580383 -317.345056) (xy 20.557257 -317.297035) (xy 20.541547 -317.246105)
			(xy 20.533604 -317.193401) (xy 11.516636 -317.193401) (xy 11.516613 -317.194638) (xy 11.508493 -317.249814)
			(xy 11.492425 -317.303221) (xy 11.468753 -317.353718) (xy 11.43798 -317.400231) (xy 11.400763 -317.441768)
			(xy 11.357895 -317.477443) (xy 11.310289 -317.506497) (xy 11.25896 -317.528309) (xy 11.205003 -317.542415)
			(xy 11.149566 -317.548515) (xy 11.093832 -317.546478) (xy 11.038989 -317.536348) (xy 10.986205 -317.518341)
			(xy 10.936605 -317.49284) (xy 10.891247 -317.460389) (xy 10.851098 -317.42168) (xy 10.817012 -317.377537)
			(xy 10.789716 -317.328902) (xy 10.769793 -317.276811) (xy 10.757667 -317.222374) (xy 10.753596 -317.166752)
			(xy 9.6774 -317.166752) (xy 9.6774 -317.515748) (xy 9.9822 -317.820548)
		)
		(stroke
			(width 0)
			(type solid)
		)
		(fill yes)
		(layer "In13.Cu")
		(net "GND")
	)
	(gr_poly
		(pts
			(xy 267.30706 -327.802748) (xy 267.327757 -327.786043) (xy 267.372902 -327.757923) (xy 267.421514 -327.736342)
			(xy 267.472651 -327.721718) (xy 267.525323 -327.714334) (xy 267.578509 -327.714334) (xy 267.631181 -327.721718)
			(xy 267.682318 -327.736342) (xy 267.73093 -327.757923) (xy 267.776075 -327.786043) (xy 267.796772 -327.802748)
			(xy 268.57706 -327.802748) (xy 268.597757 -327.786043) (xy 268.642902 -327.757923) (xy 268.691514 -327.736342)
			(xy 268.742651 -327.721718) (xy 268.795323 -327.714334) (xy 268.848509 -327.714334) (xy 268.901181 -327.721718)
			(xy 268.952318 -327.736342) (xy 269.00093 -327.757923) (xy 269.046075 -327.786043) (xy 269.066772 -327.802748)
			(xy 269.84706 -327.802748) (xy 269.867757 -327.786043) (xy 269.912902 -327.757923) (xy 269.961514 -327.736342)
			(xy 270.012651 -327.721718) (xy 270.065323 -327.714334) (xy 270.118509 -327.714334) (xy 270.171181 -327.721718)
			(xy 270.222318 -327.736342) (xy 270.27093 -327.757923) (xy 270.316075 -327.786043) (xy 270.336772 -327.802748)
			(xy 274.910296 -327.802748) (xy 274.92452 -327.775316) (xy 274.937566 -327.751147) (xy 274.969532 -327.706486)
			(xy 275.00756 -327.666859) (xy 275.028914 -327.649586) (xy 275.040713 -327.639687) (xy 275.058219 -327.614365)
			(xy 275.067386 -327.584977) (xy 275.067381 -327.554193) (xy 275.058206 -327.524808) (xy 275.040692 -327.499491)
			(xy 275.028914 -327.489566) (xy 275.008135 -327.472811) (xy 274.971012 -327.434457) (xy 274.939597 -327.391302)
			(xy 274.914505 -327.34419) (xy 274.896223 -327.294041) (xy 274.885111 -327.241833) (xy 274.881384 -327.188585)
			(xy 274.885115 -327.135338) (xy 274.896232 -327.083131) (xy 274.914517 -327.032983) (xy 274.939613 -326.985873)
			(xy 274.971031 -326.942721) (xy 275.008157 -326.904369) (xy 275.028914 -326.887586) (xy 275.040713 -326.877687)
			(xy 275.058219 -326.852365) (xy 275.067386 -326.822977) (xy 275.067381 -326.792193) (xy 275.058206 -326.762808)
			(xy 275.040692 -326.737491) (xy 275.028914 -326.727566) (xy 275.006428 -326.709377) (xy 274.966685 -326.667361)
			(xy 274.933741 -326.619827) (xy 274.908349 -326.567865) (xy 274.891092 -326.512665) (xy 274.882365 -326.455493)
			(xy 274.881848 -326.426576) (xy 274.882334 -326.399325) (xy 274.89009 -326.345377) (xy 274.905445 -326.293082)
			(xy 274.928087 -326.243505) (xy 274.957553 -326.197655) (xy 274.993244 -326.156464) (xy 275.034435 -326.120773)
			(xy 275.080285 -326.091307) (xy 275.129862 -326.068665) (xy 275.182157 -326.05331) (xy 275.236105 -326.045554)
			(xy 275.290607 -326.045554) (xy 275.344555 -326.05331) (xy 275.39685 -326.068665) (xy 275.446427 -326.091307)
			(xy 275.492277 -326.120773) (xy 275.533468 -326.156464) (xy 275.569159 -326.197655) (xy 275.598625 -326.243505)
			(xy 275.621267 -326.293082) (xy 275.636622 -326.345377) (xy 275.644378 -326.399325) (xy 275.644864 -326.426576)
			(xy 276.405338 -326.426576) (xy 276.409409 -326.370954) (xy 276.421535 -326.316517) (xy 276.441458 -326.264426)
			(xy 276.468754 -326.215791) (xy 276.50284 -326.171648) (xy 276.542989 -326.132939) (xy 276.588347 -326.100488)
			(xy 276.637947 -326.074987) (xy 276.690731 -326.05698) (xy 276.745574 -326.04685) (xy 276.801308 -326.044813)
			(xy 276.856745 -326.050913) (xy 276.910702 -326.065019) (xy 276.962031 -326.086831) (xy 277.009637 -326.115885)
			(xy 277.052505 -326.15156) (xy 277.089722 -326.193097) (xy 277.120495 -326.23961) (xy 277.144167 -326.290107)
			(xy 277.160235 -326.343514) (xy 277.168355 -326.39869) (xy 277.168864 -326.426576) (xy 277.168355 -326.454462)
			(xy 277.160235 -326.509638) (xy 277.144167 -326.563045) (xy 277.120495 -326.613542) (xy 277.089722 -326.660055)
			(xy 277.052505 -326.701592) (xy 277.009637 -326.737267) (xy 276.962031 -326.766321) (xy 276.910702 -326.788133)
			(xy 276.856745 -326.802239) (xy 276.801308 -326.808339) (xy 276.745574 -326.806302) (xy 276.690731 -326.796172)
			(xy 276.637947 -326.778165) (xy 276.588347 -326.752664) (xy 276.542989 -326.720213) (xy 276.50284 -326.681504)
			(xy 276.468754 -326.637361) (xy 276.441458 -326.588726) (xy 276.421535 -326.536635) (xy 276.409409 -326.482198)
			(xy 276.405338 -326.426576) (xy 275.644864 -326.426576) (xy 275.644332 -326.455493) (xy 275.635607 -326.512665)
			(xy 275.618355 -326.567866) (xy 275.592969 -326.619831) (xy 275.560032 -326.66737) (xy 275.520297 -326.709394)
			(xy 275.497798 -326.727566) (xy 275.485991 -326.737464) (xy 275.468469 -326.76279) (xy 275.459288 -326.792187)
			(xy 275.459284 -326.822984) (xy 275.468456 -326.852383) (xy 275.48597 -326.877714) (xy 275.497798 -326.887586)
			(xy 275.518585 -326.904338) (xy 275.555722 -326.94269) (xy 275.587151 -326.985845) (xy 275.612256 -327.03296)
			(xy 275.619357 -327.052432) (xy 289.857178 -327.052432) (xy 289.861249 -326.99681) (xy 289.873375 -326.942373)
			(xy 289.893298 -326.890282) (xy 289.920594 -326.841647) (xy 289.95468 -326.797504) (xy 289.994829 -326.758795)
			(xy 290.040187 -326.726344) (xy 290.089787 -326.700843) (xy 290.142571 -326.682836) (xy 290.197414 -326.672706)
			(xy 290.253148 -326.670669) (xy 290.308585 -326.676769) (xy 290.362542 -326.690875) (xy 290.413871 -326.712687)
			(xy 290.461477 -326.741741) (xy 290.504345 -326.777416) (xy 290.540699 -326.81799) (xy 293.396668 -326.81799)
			(xy 293.400739 -326.762368) (xy 293.412865 -326.707931) (xy 293.432788 -326.65584) (xy 293.460084 -326.607205)
			(xy 293.49417 -326.563062) (xy 293.534319 -326.524353) (xy 293.579677 -326.491902) (xy 293.629277 -326.466401)
			(xy 293.682061 -326.448394) (xy 293.736904 -326.438264) (xy 293.792638 -326.436227) (xy 293.848075 -326.442327)
			(xy 293.902032 -326.456433) (xy 293.953361 -326.478245) (xy 294.000967 -326.507299) (xy 294.043835 -326.542974)
			(xy 294.081052 -326.584511) (xy 294.111825 -326.631024) (xy 294.135497 -326.681521) (xy 294.151565 -326.734928)
			(xy 294.159685 -326.790104) (xy 294.160194 -326.81799) (xy 294.159685 -326.845876) (xy 294.151565 -326.901052)
			(xy 294.135497 -326.954459) (xy 294.111825 -327.004956) (xy 294.081052 -327.051469) (xy 294.043835 -327.093006)
			(xy 294.000967 -327.128681) (xy 293.953361 -327.157735) (xy 293.902032 -327.179547) (xy 293.848075 -327.193653)
			(xy 293.792638 -327.199753) (xy 293.736904 -327.197716) (xy 293.682061 -327.187586) (xy 293.629277 -327.169579)
			(xy 293.579677 -327.144078) (xy 293.534319 -327.111627) (xy 293.49417 -327.072918) (xy 293.460084 -327.028775)
			(xy 293.432788 -326.98014) (xy 293.412865 -326.928049) (xy 293.400739 -326.873612) (xy 293.396668 -326.81799)
			(xy 290.540699 -326.81799) (xy 290.541562 -326.818953) (xy 290.572335 -326.865466) (xy 290.596007 -326.915963)
			(xy 290.612075 -326.96937) (xy 290.620195 -327.024546) (xy 290.620704 -327.052432) (xy 290.620195 -327.080318)
			(xy 290.612075 -327.135494) (xy 290.596007 -327.188901) (xy 290.572335 -327.239398) (xy 290.541562 -327.285911)
			(xy 290.504345 -327.327448) (xy 290.461477 -327.363123) (xy 290.413871 -327.392177) (xy 290.362542 -327.413989)
			(xy 290.308585 -327.428095) (xy 290.253148 -327.434195) (xy 290.197414 -327.432158) (xy 290.142571 -327.422028)
			(xy 290.089787 -327.404021) (xy 290.040187 -327.37852) (xy 289.994829 -327.346069) (xy 289.95468 -327.30736)
			(xy 289.920594 -327.263217) (xy 289.893298 -327.214582) (xy 289.873375 -327.162491) (xy 289.861249 -327.108054)
			(xy 289.857178 -327.052432) (xy 275.619357 -327.052432) (xy 275.630547 -327.083115) (xy 275.641668 -327.13533)
			(xy 275.6454 -327.188585) (xy 275.641672 -327.241841) (xy 275.630555 -327.294057) (xy 275.612268 -327.344213)
			(xy 275.587166 -327.39133) (xy 275.555741 -327.434487) (xy 275.518607 -327.472842) (xy 275.497798 -327.489566)
			(xy 275.485991 -327.499464) (xy 275.468469 -327.52479) (xy 275.459288 -327.554187) (xy 275.459284 -327.584984)
			(xy 275.468456 -327.614383) (xy 275.48597 -327.639714) (xy 275.497798 -327.649586) (xy 275.519172 -327.666837)
			(xy 275.557213 -327.706458) (xy 275.589162 -327.751136) (xy 275.602192 -327.775316) (xy 275.616416 -327.802748)
			(xy 296.8244 -327.802748) (xy 297.54068 -327.086468) (xy 297.517312 -327.05167) (xy 297.501896 -327.027911)
			(xy 297.4775 -326.9768) (xy 297.460936 -326.922641) (xy 297.452569 -326.866628) (xy 297.452034 -326.83831)
			(xy 297.452497 -326.811058) (xy 297.460253 -326.757108) (xy 297.475608 -326.704811) (xy 297.498251 -326.655233)
			(xy 297.527719 -326.609381) (xy 297.563414 -326.568191) (xy 297.604607 -326.5325) (xy 297.650461 -326.503035)
			(xy 297.700041 -326.480397) (xy 297.752339 -326.465046) (xy 297.80629 -326.457294) (xy 297.833542 -326.456802)
			(xy 297.861859 -326.457322) (xy 297.917871 -326.465703) (xy 297.972027 -326.482275) (xy 298.023137 -326.506673)
			(xy 298.046902 -326.52208) (xy 298.0817 -326.545448) (xy 303.441354 -321.185794) (xy 303.45118 -321.175243)
			(xy 303.465039 -321.149976) (xy 303.471301 -321.121846) (xy 303.469471 -321.093086) (xy 303.459692 -321.065977)
			(xy 303.442742 -321.042671) (xy 303.431702 -321.033394) (xy 303.410563 -321.01643) (xy 303.373182 -320.977186)
			(xy 303.342184 -320.932728) (xy 303.318286 -320.884084) (xy 303.302039 -320.832378) (xy 303.29382 -320.778807)
			(xy 303.293272 -320.751708) (xy 303.29382 -320.723724) (xy 303.302574 -320.668445) (xy 303.319868 -320.615215)
			(xy 303.345275 -320.565346) (xy 303.378171 -320.520066) (xy 303.417745 -320.480489) (xy 303.463023 -320.44759)
			(xy 303.512889 -320.422179) (xy 303.566117 -320.404881) (xy 303.621396 -320.396123) (xy 303.64938 -320.3956)
			(xy 303.677836 -320.396186) (xy 303.734018 -320.405286) (xy 303.788041 -320.423193) (xy 303.838534 -320.449455)
			(xy 303.861724 -320.465958) (xy 303.874171 -320.474481) (xy 303.902589 -320.484553) (xy 303.932709 -320.485909)
			(xy 303.961917 -320.478429) (xy 303.987679 -320.462764) (xy 304.007758 -320.440272) (xy 304.014632 -320.426842)
			(xy 304.025677 -320.404057) (xy 304.053251 -320.361591) (xy 304.086559 -320.323456) (xy 304.124931 -320.290421)
			(xy 304.167594 -320.263151) (xy 304.213688 -320.242197) (xy 304.262284 -320.227979) (xy 304.312404 -320.220785)
			(xy 304.33772 -320.22034) (xy 304.347712 -320.220427) (xy 304.367662 -320.221571) (xy 304.377598 -320.222626)
			(xy 304.401728 -320.22542) (xy 307.450998 -317.17615) (xy 307.45176 -317.156084) (xy 307.453019 -317.131201)
			(xy 307.462087 -317.082211) (xy 307.478404 -317.035137) (xy 307.501598 -316.991044) (xy 307.531147 -316.950931)
			(xy 307.566379 -316.915705) (xy 307.606499 -316.886164) (xy 307.650596 -316.862978) (xy 307.697673 -316.846671)
			(xy 307.746665 -316.837612) (xy 307.771546 -316.836298) (xy 307.791612 -316.835536) (xy 312.4962 -312.130948)
			(xy 312.4962 -254.216154) (xy 312.474006 -254.202255) (xy 312.433579 -254.168972) (xy 312.398464 -254.130126)
			(xy 312.369417 -254.086556) (xy 312.347065 -254.039201) (xy 312.33189 -253.989083) (xy 312.32422 -253.937283)
			(xy 312.32422 -253.884917) (xy 312.33189 -253.833117) (xy 312.347065 -253.782999) (xy 312.369417 -253.735644)
			(xy 312.398464 -253.692074) (xy 312.433579 -253.653228) (xy 312.474006 -253.619945) (xy 312.4962 -253.606046)
			(xy 312.4962 -196.129148) (xy 311.4294 -195.062348) (xy 307.955188 -195.062348) (xy 307.933069 -195.076611)
			(xy 307.885524 -195.09918) (xy 307.83518 -195.114519) (xy 307.783128 -195.122296) (xy 307.756814 -195.1228)
			(xy 307.730496 -195.122332) (xy 307.678433 -195.114583) (xy 307.628084 -195.099238) (xy 307.580549 -195.076633)
			(xy 307.55844 -195.062348) (xy 306.696872 -195.062348) (xy 306.686712 -195.06692) (xy 306.664914 -195.076534)
			(xy 306.619245 -195.090104) (xy 306.572102 -195.09698) (xy 306.548282 -195.0974) (xy 306.524461 -195.096969)
			(xy 306.477317 -195.090104) (xy 306.431645 -195.076546) (xy 306.409852 -195.06692) (xy 306.399692 -195.062348)
			(xy 304.487072 -195.062348) (xy 304.476912 -195.06692) (xy 304.455114 -195.076534) (xy 304.409445 -195.090104)
			(xy 304.362302 -195.09698) (xy 304.338482 -195.0974) (xy 304.314661 -195.096969) (xy 304.267517 -195.090104)
			(xy 304.221845 -195.076546) (xy 304.200052 -195.06692) (xy 304.189892 -195.062348) (xy 300.411388 -195.062348)
			(xy 300.389269 -195.076611) (xy 300.341724 -195.09918) (xy 300.29138 -195.114519) (xy 300.239328 -195.122296)
			(xy 300.213014 -195.1228) (xy 300.186696 -195.122332) (xy 300.134633 -195.114583) (xy 300.084284 -195.099238)
			(xy 300.036749 -195.076633) (xy 300.01464 -195.062348) (xy 299.6946 -195.062348) (xy 299.0342 -194.401948)
			(xy 293.04361 -194.401948) (xy 293.029724 -194.402418) (xy 293.002981 -194.409905) (xy 292.979246 -194.424325)
			(xy 292.96028 -194.444612) (xy 292.947487 -194.469261) (xy 292.941815 -194.496448) (xy 292.943683 -194.524156)
			(xy 292.952955 -194.550335) (xy 292.960552 -194.561968) (xy 292.97584 -194.584568) (xy 293.000046 -194.633466)
			(xy 293.0165 -194.685487) (xy 293.024818 -194.739411) (xy 293.025322 -194.766692) (xy 293.024824 -194.793341)
			(xy 293.016881 -194.846045) (xy 293.001171 -194.896975) (xy 292.978045 -194.944996) (xy 292.948021 -194.989033)
			(xy 292.911769 -195.028104) (xy 292.870098 -195.061335) (xy 292.82394 -195.087984) (xy 292.774326 -195.107456)
			(xy 292.722364 -195.119316) (xy 292.669214 -195.1233) (xy 292.616064 -195.119316) (xy 292.564102 -195.107456)
			(xy 292.514488 -195.087984) (xy 292.46833 -195.061335) (xy 292.426659 -195.028104) (xy 292.390407 -194.989033)
			(xy 292.360383 -194.944996) (xy 292.337257 -194.896975) (xy 292.321547 -194.846045) (xy 292.313604 -194.793341)
			(xy 292.313106 -194.766692) (xy 292.313628 -194.739413) (xy 292.321953 -194.685494) (xy 292.338409 -194.633477)
			(xy 292.362608 -194.58458) (xy 292.377876 -194.561968) (xy 292.385483 -194.550339) (xy 292.394754 -194.524156)
			(xy 292.396621 -194.496443) (xy 292.390948 -194.469252) (xy 292.378154 -194.444598) (xy 292.359187 -194.424306)
			(xy 292.335452 -194.40988) (xy 292.308706 -194.402386) (xy 292.294818 -194.401948) (xy 285.49981 -194.401948)
			(xy 285.485924 -194.402418) (xy 285.459181 -194.409905) (xy 285.435446 -194.424325) (xy 285.41648 -194.444612)
			(xy 285.403687 -194.469261) (xy 285.398015 -194.496448) (xy 285.399883 -194.524156) (xy 285.409155 -194.550335)
			(xy 285.416752 -194.561968) (xy 285.43204 -194.584568) (xy 285.456246 -194.633466) (xy 285.4727 -194.685487)
			(xy 285.481018 -194.739411) (xy 285.481522 -194.766692) (xy 285.481024 -194.793341) (xy 285.473081 -194.846045)
			(xy 285.457371 -194.896975) (xy 285.434245 -194.944996) (xy 285.404221 -194.989033) (xy 285.367969 -195.028104)
			(xy 285.326298 -195.061335) (xy 285.28014 -195.087984) (xy 285.230526 -195.107456) (xy 285.178564 -195.119316)
			(xy 285.125414 -195.1233) (xy 285.072264 -195.119316) (xy 285.020302 -195.107456) (xy 284.970688 -195.087984)
			(xy 284.92453 -195.061335) (xy 284.882859 -195.028104) (xy 284.846607 -194.989033) (xy 284.816583 -194.944996)
			(xy 284.793457 -194.896975) (xy 284.777747 -194.846045) (xy 284.769804 -194.793341) (xy 284.769306 -194.766692)
			(xy 284.769828 -194.739413) (xy 284.778153 -194.685494) (xy 284.794609 -194.633477) (xy 284.818808 -194.58458)
			(xy 284.834076 -194.561968) (xy 284.841683 -194.550339) (xy 284.850954 -194.524156) (xy 284.852821 -194.496443)
			(xy 284.847148 -194.469252) (xy 284.834354 -194.444598) (xy 284.815387 -194.424306) (xy 284.791652 -194.40988)
			(xy 284.764906 -194.402386) (xy 284.751018 -194.401948) (xy 277.926546 -194.401948) (xy 277.912759 -194.402412)
			(xy 277.886194 -194.409803) (xy 277.862574 -194.424031) (xy 277.843621 -194.44406) (xy 277.830717 -194.468428)
			(xy 277.824803 -194.495361) (xy 277.826309 -194.522894) (xy 277.835126 -194.549021) (xy 277.842472 -194.560698)
			(xy 277.857027 -194.582953) (xy 277.880082 -194.63087) (xy 277.895751 -194.681683) (xy 277.903685 -194.734263)
			(xy 277.904194 -194.76085) (xy 277.903696 -194.787499) (xy 277.895753 -194.840203) (xy 277.880043 -194.891133)
			(xy 277.856917 -194.939154) (xy 277.826893 -194.983191) (xy 277.790641 -195.022262) (xy 277.74897 -195.055493)
			(xy 277.702812 -195.082142) (xy 277.653198 -195.101614) (xy 277.601236 -195.113474) (xy 277.548086 -195.117458)
			(xy 277.494936 -195.113474) (xy 277.442974 -195.101614) (xy 277.39336 -195.082142) (xy 277.347202 -195.055493)
			(xy 277.305531 -195.022262) (xy 277.269279 -194.983191) (xy 277.239255 -194.939154) (xy 277.216129 -194.891133)
			(xy 277.200419 -194.840203) (xy 277.192476 -194.787499) (xy 277.191978 -194.76085) (xy 277.192489 -194.734263)
			(xy 277.200428 -194.681684) (xy 277.216093 -194.630869) (xy 277.239135 -194.582946) (xy 277.2537 -194.560698)
			(xy 277.261072 -194.549037) (xy 277.269902 -194.522912) (xy 277.271414 -194.495377) (xy 277.265499 -194.468443)
			(xy 277.252587 -194.444076) (xy 277.233622 -194.424055) (xy 277.20999 -194.409844) (xy 277.183415 -194.40248)
			(xy 277.169626 -194.401948) (xy 270.41221 -194.401948) (xy 270.398324 -194.402418) (xy 270.371581 -194.409905)
			(xy 270.347846 -194.424325) (xy 270.32888 -194.444612) (xy 270.316087 -194.469261) (xy 270.310415 -194.496448)
			(xy 270.312283 -194.524156) (xy 270.321555 -194.550335) (xy 270.329152 -194.561968) (xy 270.34444 -194.584568)
			(xy 270.368646 -194.633466) (xy 270.3851 -194.685487) (xy 270.393418 -194.739411) (xy 270.393922 -194.766692)
			(xy 270.393424 -194.793341) (xy 270.385481 -194.846045) (xy 270.369771 -194.896975) (xy 270.346645 -194.944996)
			(xy 270.316621 -194.989033) (xy 270.280369 -195.028104) (xy 270.238698 -195.061335) (xy 270.19254 -195.087984)
			(xy 270.142926 -195.107456) (xy 270.090964 -195.119316) (xy 270.037814 -195.1233) (xy 269.984664 -195.119316)
			(xy 269.932702 -195.107456) (xy 269.883088 -195.087984) (xy 269.83693 -195.061335) (xy 269.795259 -195.028104)
			(xy 269.759007 -194.989033) (xy 269.728983 -194.944996) (xy 269.705857 -194.896975) (xy 269.690147 -194.846045)
			(xy 269.682204 -194.793341) (xy 269.681706 -194.766692) (xy 269.682228 -194.739413) (xy 269.690553 -194.685494)
			(xy 269.707009 -194.633477) (xy 269.731208 -194.58458) (xy 269.746476 -194.561968) (xy 269.754083 -194.550339)
			(xy 269.763354 -194.524156) (xy 269.765221 -194.496443) (xy 269.759548 -194.469252) (xy 269.746754 -194.444598)
			(xy 269.727787 -194.424306) (xy 269.704052 -194.40988) (xy 269.677306 -194.402386) (xy 269.663418 -194.401948)
			(xy 262.86841 -194.401948) (xy 262.854524 -194.402418) (xy 262.827781 -194.409905) (xy 262.804046 -194.424325)
			(xy 262.78508 -194.444612) (xy 262.772287 -194.469261) (xy 262.766615 -194.496448) (xy 262.768483 -194.524156)
			(xy 262.777755 -194.550335) (xy 262.785352 -194.561968) (xy 262.80064 -194.584568) (xy 262.824846 -194.633466)
			(xy 262.8413 -194.685487) (xy 262.849618 -194.739411) (xy 262.850122 -194.766692) (xy 262.849624 -194.793341)
			(xy 262.841681 -194.846045) (xy 262.825971 -194.896975) (xy 262.802845 -194.944996) (xy 262.772821 -194.989033)
			(xy 262.736569 -195.028104) (xy 262.694898 -195.061335) (xy 262.64874 -195.087984) (xy 262.599126 -195.107456)
			(xy 262.547164 -195.119316) (xy 262.494014 -195.1233) (xy 262.440864 -195.119316) (xy 262.388902 -195.107456)
			(xy 262.339288 -195.087984) (xy 262.29313 -195.061335) (xy 262.251459 -195.028104) (xy 262.215207 -194.989033)
			(xy 262.185183 -194.944996) (xy 262.162057 -194.896975) (xy 262.146347 -194.846045) (xy 262.138404 -194.793341)
			(xy 262.137906 -194.766692) (xy 262.138428 -194.739413) (xy 262.146753 -194.685494) (xy 262.163209 -194.633477)
			(xy 262.187408 -194.58458) (xy 262.202676 -194.561968) (xy 262.210283 -194.550339) (xy 262.219554 -194.524156)
			(xy 262.221421 -194.496443) (xy 262.215748 -194.469252) (xy 262.202954 -194.444598) (xy 262.183987 -194.424306)
			(xy 262.160252 -194.40988) (xy 262.133506 -194.402386) (xy 262.119618 -194.401948) (xy 257.617722 -194.401948)
			(xy 257.603835 -194.402417) (xy 257.577088 -194.409901) (xy 257.553351 -194.424321) (xy 257.534382 -194.444609)
			(xy 257.521587 -194.46926) (xy 257.515914 -194.496449) (xy 257.517784 -194.52416) (xy 257.527058 -194.55034)
			(xy 257.534664 -194.561968) (xy 257.549952 -194.584568) (xy 257.574156 -194.633467) (xy 257.59061 -194.685488)
			(xy 257.598928 -194.739411) (xy 257.599434 -194.766692) (xy 257.598936 -194.793341) (xy 257.590993 -194.846045)
			(xy 257.575283 -194.896975) (xy 257.552157 -194.944996) (xy 257.522133 -194.989033) (xy 257.485881 -195.028104)
			(xy 257.44421 -195.061335) (xy 257.398052 -195.087984) (xy 257.348438 -195.107456) (xy 257.296476 -195.119316)
			(xy 257.243326 -195.1233) (xy 257.190176 -195.119316) (xy 257.138214 -195.107456) (xy 257.0886 -195.087984)
			(xy 257.042442 -195.061335) (xy 257.000771 -195.028104) (xy 256.964519 -194.989033) (xy 256.934495 -194.944996)
			(xy 256.911369 -194.896975) (xy 256.895659 -194.846045) (xy 256.887716 -194.793341) (xy 256.887218 -194.766692)
			(xy 256.88774 -194.739413) (xy 256.896066 -194.685494) (xy 256.912521 -194.633478) (xy 256.936721 -194.584581)
			(xy 256.951988 -194.561968) (xy 256.959595 -194.550339) (xy 256.968864 -194.524155) (xy 256.970731 -194.496441)
			(xy 256.965058 -194.46925) (xy 256.952265 -194.444596) (xy 256.933298 -194.424303) (xy 256.909564 -194.409874)
			(xy 256.882818 -194.402378) (xy 256.86893 -194.401948) (xy 255.1176 -194.401948) (xy 254 -195.519548)
			(xy 254 -195.643225) (xy 268.473672 -195.643225) (xy 268.473672 -195.589927) (xy 268.481615 -195.537223)
			(xy 268.497325 -195.486293) (xy 268.520451 -195.438272) (xy 268.550475 -195.394235) (xy 268.586727 -195.355164)
			(xy 268.628398 -195.321933) (xy 268.674556 -195.295284) (xy 268.72417 -195.275812) (xy 268.776132 -195.263952)
			(xy 268.829282 -195.259969) (xy 268.882432 -195.263952) (xy 268.934394 -195.275812) (xy 268.984008 -195.295284)
			(xy 269.030166 -195.321933) (xy 269.071837 -195.355164) (xy 269.108089 -195.394235) (xy 269.138113 -195.438272)
			(xy 269.161239 -195.486293) (xy 269.176949 -195.537223) (xy 269.184892 -195.589927) (xy 269.18539 -195.616576)
			(xy 269.184892 -195.643225) (xy 283.561272 -195.643225) (xy 283.561272 -195.589927) (xy 283.569215 -195.537223)
			(xy 283.584925 -195.486293) (xy 283.608051 -195.438272) (xy 283.638075 -195.394235) (xy 283.674327 -195.355164)
			(xy 283.715998 -195.321933) (xy 283.762156 -195.295284) (xy 283.81177 -195.275812) (xy 283.863732 -195.263952)
			(xy 283.916882 -195.259969) (xy 283.970032 -195.263952) (xy 284.021994 -195.275812) (xy 284.071608 -195.295284)
			(xy 284.117766 -195.321933) (xy 284.159437 -195.355164) (xy 284.195689 -195.394235) (xy 284.225713 -195.438272)
			(xy 284.248839 -195.486293) (xy 284.264549 -195.537223) (xy 284.272492 -195.589927) (xy 284.27299 -195.616576)
			(xy 284.272492 -195.643225) (xy 298.648872 -195.643225) (xy 298.648872 -195.589927) (xy 298.656815 -195.537223)
			(xy 298.672525 -195.486293) (xy 298.695651 -195.438272) (xy 298.725675 -195.394235) (xy 298.761927 -195.355164)
			(xy 298.803598 -195.321933) (xy 298.849756 -195.295284) (xy 298.89937 -195.275812) (xy 298.951332 -195.263952)
			(xy 299.004482 -195.259969) (xy 299.057632 -195.263952) (xy 299.109594 -195.275812) (xy 299.159208 -195.295284)
			(xy 299.205366 -195.321933) (xy 299.247037 -195.355164) (xy 299.283289 -195.394235) (xy 299.313313 -195.438272)
			(xy 299.336439 -195.486293) (xy 299.352149 -195.537223) (xy 299.360092 -195.589927) (xy 299.36059 -195.616576)
			(xy 299.360092 -195.643225) (xy 299.352149 -195.695929) (xy 299.336439 -195.746859) (xy 299.313313 -195.79488)
			(xy 299.283289 -195.838917) (xy 299.247037 -195.877988) (xy 299.205366 -195.911219) (xy 299.159208 -195.937868)
			(xy 299.109594 -195.95734) (xy 299.057632 -195.9692) (xy 299.004482 -195.973184) (xy 298.951332 -195.9692)
			(xy 298.89937 -195.95734) (xy 298.849756 -195.937868) (xy 298.803598 -195.911219) (xy 298.761927 -195.877988)
			(xy 298.725675 -195.838917) (xy 298.695651 -195.79488) (xy 298.672525 -195.746859) (xy 298.656815 -195.695929)
			(xy 298.648872 -195.643225) (xy 284.272492 -195.643225) (xy 284.264549 -195.695929) (xy 284.248839 -195.746859)
			(xy 284.225713 -195.79488) (xy 284.195689 -195.838917) (xy 284.159437 -195.877988) (xy 284.117766 -195.911219)
			(xy 284.071608 -195.937868) (xy 284.021994 -195.95734) (xy 283.970032 -195.9692) (xy 283.916882 -195.973184)
			(xy 283.863732 -195.9692) (xy 283.81177 -195.95734) (xy 283.762156 -195.937868) (xy 283.715998 -195.911219)
			(xy 283.674327 -195.877988) (xy 283.638075 -195.838917) (xy 283.608051 -195.79488) (xy 283.584925 -195.746859)
			(xy 283.569215 -195.695929) (xy 283.561272 -195.643225) (xy 269.184892 -195.643225) (xy 269.176949 -195.695929)
			(xy 269.161239 -195.746859) (xy 269.138113 -195.79488) (xy 269.108089 -195.838917) (xy 269.071837 -195.877988)
			(xy 269.030166 -195.911219) (xy 268.984008 -195.937868) (xy 268.934394 -195.95734) (xy 268.882432 -195.9692)
			(xy 268.829282 -195.973184) (xy 268.776132 -195.9692) (xy 268.72417 -195.95734) (xy 268.674556 -195.937868)
			(xy 268.628398 -195.911219) (xy 268.586727 -195.877988) (xy 268.550475 -195.838917) (xy 268.520451 -195.79488)
			(xy 268.497325 -195.746859) (xy 268.481615 -195.695929) (xy 268.473672 -195.643225) (xy 254 -195.643225)
			(xy 254 -196.493363) (xy 264.373604 -196.493363) (xy 264.373604 -196.440065) (xy 264.381547 -196.387361)
			(xy 264.397257 -196.336431) (xy 264.420383 -196.28841) (xy 264.450407 -196.244373) (xy 264.486659 -196.205302)
			(xy 264.52833 -196.172071) (xy 264.574488 -196.145422) (xy 264.624102 -196.12595) (xy 264.676064 -196.11409)
			(xy 264.729214 -196.110107) (xy 264.782364 -196.11409) (xy 264.834326 -196.12595) (xy 264.88394 -196.145422)
			(xy 264.930098 -196.172071) (xy 264.971769 -196.205302) (xy 265.008021 -196.244373) (xy 265.038045 -196.28841)
			(xy 265.061171 -196.336431) (xy 265.076881 -196.387361) (xy 265.084824 -196.440065) (xy 265.085322 -196.466714)
			(xy 265.084824 -196.493363) (xy 279.461204 -196.493363) (xy 279.461204 -196.440065) (xy 279.469147 -196.387361)
			(xy 279.484857 -196.336431) (xy 279.507983 -196.28841) (xy 279.538007 -196.244373) (xy 279.574259 -196.205302)
			(xy 279.61593 -196.172071) (xy 279.662088 -196.145422) (xy 279.711702 -196.12595) (xy 279.763664 -196.11409)
			(xy 279.816814 -196.110107) (xy 279.869964 -196.11409) (xy 279.921926 -196.12595) (xy 279.97154 -196.145422)
			(xy 280.017698 -196.172071) (xy 280.059369 -196.205302) (xy 280.095621 -196.244373) (xy 280.125645 -196.28841)
			(xy 280.148771 -196.336431) (xy 280.164481 -196.387361) (xy 280.172424 -196.440065) (xy 280.172922 -196.466714)
			(xy 280.172424 -196.493363) (xy 294.548804 -196.493363) (xy 294.548804 -196.440065) (xy 294.556747 -196.387361)
			(xy 294.572457 -196.336431) (xy 294.595583 -196.28841) (xy 294.625607 -196.244373) (xy 294.661859 -196.205302)
			(xy 294.70353 -196.172071) (xy 294.749688 -196.145422) (xy 294.799302 -196.12595) (xy 294.851264 -196.11409)
			(xy 294.904414 -196.110107) (xy 294.957564 -196.11409) (xy 295.009526 -196.12595) (xy 295.05914 -196.145422)
			(xy 295.105298 -196.172071) (xy 295.146969 -196.205302) (xy 295.183221 -196.244373) (xy 295.213245 -196.28841)
			(xy 295.236371 -196.336431) (xy 295.252081 -196.387361) (xy 295.260024 -196.440065) (xy 295.260522 -196.466714)
			(xy 295.260024 -196.493363) (xy 295.252081 -196.546067) (xy 295.236371 -196.596997) (xy 295.213245 -196.645018)
			(xy 295.183221 -196.689055) (xy 295.146969 -196.728126) (xy 295.105298 -196.761357) (xy 295.05914 -196.788006)
			(xy 295.009526 -196.807478) (xy 294.957564 -196.819338) (xy 294.904414 -196.823322) (xy 294.851264 -196.819338)
			(xy 294.799302 -196.807478) (xy 294.749688 -196.788006) (xy 294.70353 -196.761357) (xy 294.661859 -196.728126)
			(xy 294.625607 -196.689055) (xy 294.595583 -196.645018) (xy 294.572457 -196.596997) (xy 294.556747 -196.546067)
			(xy 294.548804 -196.493363) (xy 280.172424 -196.493363) (xy 280.164481 -196.546067) (xy 280.148771 -196.596997)
			(xy 280.125645 -196.645018) (xy 280.095621 -196.689055) (xy 280.059369 -196.728126) (xy 280.017698 -196.761357)
			(xy 279.97154 -196.788006) (xy 279.921926 -196.807478) (xy 279.869964 -196.819338) (xy 279.816814 -196.823322)
			(xy 279.763664 -196.819338) (xy 279.711702 -196.807478) (xy 279.662088 -196.788006) (xy 279.61593 -196.761357)
			(xy 279.574259 -196.728126) (xy 279.538007 -196.689055) (xy 279.507983 -196.645018) (xy 279.484857 -196.596997)
			(xy 279.469147 -196.546067) (xy 279.461204 -196.493363) (xy 265.084824 -196.493363) (xy 265.076881 -196.546067)
			(xy 265.061171 -196.596997) (xy 265.038045 -196.645018) (xy 265.008021 -196.689055) (xy 264.971769 -196.728126)
			(xy 264.930098 -196.761357) (xy 264.88394 -196.788006) (xy 264.834326 -196.807478) (xy 264.782364 -196.819338)
			(xy 264.729214 -196.823322) (xy 264.676064 -196.819338) (xy 264.624102 -196.807478) (xy 264.574488 -196.788006)
			(xy 264.52833 -196.761357) (xy 264.486659 -196.728126) (xy 264.450407 -196.689055) (xy 264.420383 -196.645018)
			(xy 264.397257 -196.596997) (xy 264.381547 -196.546067) (xy 264.373604 -196.493363) (xy 254 -196.493363)
			(xy 254 -197.343247) (xy 268.473672 -197.343247) (xy 268.473672 -197.289949) (xy 268.481615 -197.237245)
			(xy 268.497325 -197.186315) (xy 268.520451 -197.138294) (xy 268.550475 -197.094257) (xy 268.586727 -197.055186)
			(xy 268.628398 -197.021955) (xy 268.674556 -196.995306) (xy 268.72417 -196.975834) (xy 268.776132 -196.963974)
			(xy 268.829282 -196.959991) (xy 268.882432 -196.963974) (xy 268.934394 -196.975834) (xy 268.984008 -196.995306)
			(xy 269.030166 -197.021955) (xy 269.071837 -197.055186) (xy 269.108089 -197.094257) (xy 269.138113 -197.138294)
			(xy 269.161239 -197.186315) (xy 269.176949 -197.237245) (xy 269.184892 -197.289949) (xy 269.18539 -197.316598)
			(xy 269.184892 -197.343247) (xy 283.561272 -197.343247) (xy 283.561272 -197.289949) (xy 283.569215 -197.237245)
			(xy 283.584925 -197.186315) (xy 283.608051 -197.138294) (xy 283.638075 -197.094257) (xy 283.674327 -197.055186)
			(xy 283.715998 -197.021955) (xy 283.762156 -196.995306) (xy 283.81177 -196.975834) (xy 283.863732 -196.963974)
			(xy 283.916882 -196.959991) (xy 283.970032 -196.963974) (xy 284.021994 -196.975834) (xy 284.071608 -196.995306)
			(xy 284.117766 -197.021955) (xy 284.159437 -197.055186) (xy 284.195689 -197.094257) (xy 284.225713 -197.138294)
			(xy 284.248839 -197.186315) (xy 284.264549 -197.237245) (xy 284.272492 -197.289949) (xy 284.27299 -197.316598)
			(xy 284.272492 -197.343247) (xy 298.648872 -197.343247) (xy 298.648872 -197.289949) (xy 298.656815 -197.237245)
			(xy 298.672525 -197.186315) (xy 298.695651 -197.138294) (xy 298.725675 -197.094257) (xy 298.761927 -197.055186)
			(xy 298.803598 -197.021955) (xy 298.849756 -196.995306) (xy 298.89937 -196.975834) (xy 298.951332 -196.963974)
			(xy 299.004482 -196.959991) (xy 299.057632 -196.963974) (xy 299.109594 -196.975834) (xy 299.159208 -196.995306)
			(xy 299.205366 -197.021955) (xy 299.247037 -197.055186) (xy 299.283289 -197.094257) (xy 299.313313 -197.138294)
			(xy 299.336439 -197.186315) (xy 299.352149 -197.237245) (xy 299.360092 -197.289949) (xy 299.36059 -197.316598)
			(xy 299.360092 -197.343247) (xy 299.352149 -197.395951) (xy 299.336439 -197.446881) (xy 299.313313 -197.494902)
			(xy 299.283289 -197.538939) (xy 299.247037 -197.57801) (xy 299.205366 -197.611241) (xy 299.159208 -197.63789)
			(xy 299.109594 -197.657362) (xy 299.057632 -197.669222) (xy 299.004482 -197.673206) (xy 298.951332 -197.669222)
			(xy 298.89937 -197.657362) (xy 298.849756 -197.63789) (xy 298.803598 -197.611241) (xy 298.761927 -197.57801)
			(xy 298.725675 -197.538939) (xy 298.695651 -197.494902) (xy 298.672525 -197.446881) (xy 298.656815 -197.395951)
			(xy 298.648872 -197.343247) (xy 284.272492 -197.343247) (xy 284.264549 -197.395951) (xy 284.248839 -197.446881)
			(xy 284.225713 -197.494902) (xy 284.195689 -197.538939) (xy 284.159437 -197.57801) (xy 284.117766 -197.611241)
			(xy 284.071608 -197.63789) (xy 284.021994 -197.657362) (xy 283.970032 -197.669222) (xy 283.916882 -197.673206)
			(xy 283.863732 -197.669222) (xy 283.81177 -197.657362) (xy 283.762156 -197.63789) (xy 283.715998 -197.611241)
			(xy 283.674327 -197.57801) (xy 283.638075 -197.538939) (xy 283.608051 -197.494902) (xy 283.584925 -197.446881)
			(xy 283.569215 -197.395951) (xy 283.561272 -197.343247) (xy 269.184892 -197.343247) (xy 269.176949 -197.395951)
			(xy 269.161239 -197.446881) (xy 269.138113 -197.494902) (xy 269.108089 -197.538939) (xy 269.071837 -197.57801)
			(xy 269.030166 -197.611241) (xy 268.984008 -197.63789) (xy 268.934394 -197.657362) (xy 268.882432 -197.669222)
			(xy 268.829282 -197.673206) (xy 268.776132 -197.669222) (xy 268.72417 -197.657362) (xy 268.674556 -197.63789)
			(xy 268.628398 -197.611241) (xy 268.586727 -197.57801) (xy 268.550475 -197.538939) (xy 268.520451 -197.494902)
			(xy 268.497325 -197.446881) (xy 268.481615 -197.395951) (xy 268.473672 -197.343247) (xy 254 -197.343247)
			(xy 254 -198.193385) (xy 264.373604 -198.193385) (xy 264.373604 -198.140087) (xy 264.381547 -198.087383)
			(xy 264.397257 -198.036453) (xy 264.420383 -197.988432) (xy 264.450407 -197.944395) (xy 264.486659 -197.905324)
			(xy 264.52833 -197.872093) (xy 264.574488 -197.845444) (xy 264.624102 -197.825972) (xy 264.676064 -197.814112)
			(xy 264.729214 -197.810129) (xy 264.782364 -197.814112) (xy 264.834326 -197.825972) (xy 264.88394 -197.845444)
			(xy 264.930098 -197.872093) (xy 264.971769 -197.905324) (xy 265.008021 -197.944395) (xy 265.038045 -197.988432)
			(xy 265.061171 -198.036453) (xy 265.076881 -198.087383) (xy 265.084824 -198.140087) (xy 265.085322 -198.166736)
			(xy 265.084824 -198.193385) (xy 279.461204 -198.193385) (xy 279.461204 -198.140087) (xy 279.469147 -198.087383)
			(xy 279.484857 -198.036453) (xy 279.507983 -197.988432) (xy 279.538007 -197.944395) (xy 279.574259 -197.905324)
			(xy 279.61593 -197.872093) (xy 279.662088 -197.845444) (xy 279.711702 -197.825972) (xy 279.763664 -197.814112)
			(xy 279.816814 -197.810129) (xy 279.869964 -197.814112) (xy 279.921926 -197.825972) (xy 279.97154 -197.845444)
			(xy 280.017698 -197.872093) (xy 280.059369 -197.905324) (xy 280.095621 -197.944395) (xy 280.125645 -197.988432)
			(xy 280.148771 -198.036453) (xy 280.164481 -198.087383) (xy 280.172424 -198.140087) (xy 280.172922 -198.166736)
			(xy 280.172424 -198.193385) (xy 294.548804 -198.193385) (xy 294.548804 -198.140087) (xy 294.556747 -198.087383)
			(xy 294.572457 -198.036453) (xy 294.595583 -197.988432) (xy 294.625607 -197.944395) (xy 294.661859 -197.905324)
			(xy 294.70353 -197.872093) (xy 294.749688 -197.845444) (xy 294.799302 -197.825972) (xy 294.851264 -197.814112)
			(xy 294.904414 -197.810129) (xy 294.957564 -197.814112) (xy 295.009526 -197.825972) (xy 295.05914 -197.845444)
			(xy 295.105298 -197.872093) (xy 295.146969 -197.905324) (xy 295.183221 -197.944395) (xy 295.213245 -197.988432)
			(xy 295.236371 -198.036453) (xy 295.252081 -198.087383) (xy 295.260024 -198.140087) (xy 295.260522 -198.166736)
			(xy 295.260024 -198.193385) (xy 295.252081 -198.246089) (xy 295.236371 -198.297019) (xy 295.213245 -198.34504)
			(xy 295.183221 -198.389077) (xy 295.146969 -198.428148) (xy 295.105298 -198.461379) (xy 295.05914 -198.488028)
			(xy 295.009526 -198.5075) (xy 294.957564 -198.51936) (xy 294.904414 -198.523344) (xy 294.851264 -198.51936)
			(xy 294.799302 -198.5075) (xy 294.749688 -198.488028) (xy 294.70353 -198.461379) (xy 294.661859 -198.428148)
			(xy 294.625607 -198.389077) (xy 294.595583 -198.34504) (xy 294.572457 -198.297019) (xy 294.556747 -198.246089)
			(xy 294.548804 -198.193385) (xy 280.172424 -198.193385) (xy 280.164481 -198.246089) (xy 280.148771 -198.297019)
			(xy 280.125645 -198.34504) (xy 280.095621 -198.389077) (xy 280.059369 -198.428148) (xy 280.017698 -198.461379)
			(xy 279.97154 -198.488028) (xy 279.921926 -198.5075) (xy 279.869964 -198.51936) (xy 279.816814 -198.523344)
			(xy 279.763664 -198.51936) (xy 279.711702 -198.5075) (xy 279.662088 -198.488028) (xy 279.61593 -198.461379)
			(xy 279.574259 -198.428148) (xy 279.538007 -198.389077) (xy 279.507983 -198.34504) (xy 279.484857 -198.297019)
			(xy 279.469147 -198.246089) (xy 279.461204 -198.193385) (xy 265.084824 -198.193385) (xy 265.076881 -198.246089)
			(xy 265.061171 -198.297019) (xy 265.038045 -198.34504) (xy 265.008021 -198.389077) (xy 264.971769 -198.428148)
			(xy 264.930098 -198.461379) (xy 264.88394 -198.488028) (xy 264.834326 -198.5075) (xy 264.782364 -198.51936)
			(xy 264.729214 -198.523344) (xy 264.676064 -198.51936) (xy 264.624102 -198.5075) (xy 264.574488 -198.488028)
			(xy 264.52833 -198.461379) (xy 264.486659 -198.428148) (xy 264.450407 -198.389077) (xy 264.420383 -198.34504)
			(xy 264.397257 -198.297019) (xy 264.381547 -198.246089) (xy 264.373604 -198.193385) (xy 254 -198.193385)
			(xy 254 -199.043269) (xy 268.473672 -199.043269) (xy 268.473672 -198.989971) (xy 268.481615 -198.937267)
			(xy 268.497325 -198.886337) (xy 268.520451 -198.838316) (xy 268.550475 -198.794279) (xy 268.586727 -198.755208)
			(xy 268.628398 -198.721977) (xy 268.674556 -198.695328) (xy 268.72417 -198.675856) (xy 268.776132 -198.663996)
			(xy 268.829282 -198.660013) (xy 268.882432 -198.663996) (xy 268.934394 -198.675856) (xy 268.984008 -198.695328)
			(xy 269.030166 -198.721977) (xy 269.071837 -198.755208) (xy 269.108089 -198.794279) (xy 269.138113 -198.838316)
			(xy 269.161239 -198.886337) (xy 269.176949 -198.937267) (xy 269.184892 -198.989971) (xy 269.18539 -199.01662)
			(xy 269.184892 -199.043269) (xy 283.561272 -199.043269) (xy 283.561272 -198.989971) (xy 283.569215 -198.937267)
			(xy 283.584925 -198.886337) (xy 283.608051 -198.838316) (xy 283.638075 -198.794279) (xy 283.674327 -198.755208)
			(xy 283.715998 -198.721977) (xy 283.762156 -198.695328) (xy 283.81177 -198.675856) (xy 283.863732 -198.663996)
			(xy 283.916882 -198.660013) (xy 283.970032 -198.663996) (xy 284.021994 -198.675856) (xy 284.071608 -198.695328)
			(xy 284.117766 -198.721977) (xy 284.159437 -198.755208) (xy 284.195689 -198.794279) (xy 284.225713 -198.838316)
			(xy 284.248839 -198.886337) (xy 284.264549 -198.937267) (xy 284.272492 -198.989971) (xy 284.27299 -199.01662)
			(xy 284.272492 -199.043269) (xy 298.648872 -199.043269) (xy 298.648872 -198.989971) (xy 298.656815 -198.937267)
			(xy 298.672525 -198.886337) (xy 298.695651 -198.838316) (xy 298.725675 -198.794279) (xy 298.761927 -198.755208)
			(xy 298.803598 -198.721977) (xy 298.849756 -198.695328) (xy 298.89937 -198.675856) (xy 298.951332 -198.663996)
			(xy 299.004482 -198.660013) (xy 299.057632 -198.663996) (xy 299.109594 -198.675856) (xy 299.159208 -198.695328)
			(xy 299.205366 -198.721977) (xy 299.247037 -198.755208) (xy 299.283289 -198.794279) (xy 299.313313 -198.838316)
			(xy 299.336439 -198.886337) (xy 299.352149 -198.937267) (xy 299.360092 -198.989971) (xy 299.36059 -199.01662)
			(xy 299.360092 -199.043269) (xy 299.352149 -199.095973) (xy 299.336439 -199.146903) (xy 299.313313 -199.194924)
			(xy 299.283289 -199.238961) (xy 299.247037 -199.278032) (xy 299.205366 -199.311263) (xy 299.159208 -199.337912)
			(xy 299.109594 -199.357384) (xy 299.057632 -199.369244) (xy 299.004482 -199.373228) (xy 298.951332 -199.369244)
			(xy 298.89937 -199.357384) (xy 298.849756 -199.337912) (xy 298.803598 -199.311263) (xy 298.761927 -199.278032)
			(xy 298.725675 -199.238961) (xy 298.695651 -199.194924) (xy 298.672525 -199.146903) (xy 298.656815 -199.095973)
			(xy 298.648872 -199.043269) (xy 284.272492 -199.043269) (xy 284.264549 -199.095973) (xy 284.248839 -199.146903)
			(xy 284.225713 -199.194924) (xy 284.195689 -199.238961) (xy 284.159437 -199.278032) (xy 284.117766 -199.311263)
			(xy 284.071608 -199.337912) (xy 284.021994 -199.357384) (xy 283.970032 -199.369244) (xy 283.916882 -199.373228)
			(xy 283.863732 -199.369244) (xy 283.81177 -199.357384) (xy 283.762156 -199.337912) (xy 283.715998 -199.311263)
			(xy 283.674327 -199.278032) (xy 283.638075 -199.238961) (xy 283.608051 -199.194924) (xy 283.584925 -199.146903)
			(xy 283.569215 -199.095973) (xy 283.561272 -199.043269) (xy 269.184892 -199.043269) (xy 269.176949 -199.095973)
			(xy 269.161239 -199.146903) (xy 269.138113 -199.194924) (xy 269.108089 -199.238961) (xy 269.071837 -199.278032)
			(xy 269.030166 -199.311263) (xy 268.984008 -199.337912) (xy 268.934394 -199.357384) (xy 268.882432 -199.369244)
			(xy 268.829282 -199.373228) (xy 268.776132 -199.369244) (xy 268.72417 -199.357384) (xy 268.674556 -199.337912)
			(xy 268.628398 -199.311263) (xy 268.586727 -199.278032) (xy 268.550475 -199.238961) (xy 268.520451 -199.194924)
			(xy 268.497325 -199.146903) (xy 268.481615 -199.095973) (xy 268.473672 -199.043269) (xy 254 -199.043269)
			(xy 254 -199.893407) (xy 264.373604 -199.893407) (xy 264.373604 -199.840109) (xy 264.381547 -199.787405)
			(xy 264.397257 -199.736475) (xy 264.420383 -199.688454) (xy 264.450407 -199.644417) (xy 264.486659 -199.605346)
			(xy 264.52833 -199.572115) (xy 264.574488 -199.545466) (xy 264.624102 -199.525994) (xy 264.676064 -199.514134)
			(xy 264.729214 -199.510151) (xy 264.782364 -199.514134) (xy 264.834326 -199.525994) (xy 264.88394 -199.545466)
			(xy 264.930098 -199.572115) (xy 264.971769 -199.605346) (xy 265.008021 -199.644417) (xy 265.038045 -199.688454)
			(xy 265.061171 -199.736475) (xy 265.076881 -199.787405) (xy 265.084824 -199.840109) (xy 265.085322 -199.866758)
			(xy 265.084824 -199.893407) (xy 268.473672 -199.893407) (xy 268.473672 -199.840109) (xy 268.481615 -199.787405)
			(xy 268.497325 -199.736475) (xy 268.520451 -199.688454) (xy 268.550475 -199.644417) (xy 268.586727 -199.605346)
			(xy 268.628398 -199.572115) (xy 268.674556 -199.545466) (xy 268.72417 -199.525994) (xy 268.776132 -199.514134)
			(xy 268.829282 -199.510151) (xy 268.882432 -199.514134) (xy 268.934394 -199.525994) (xy 268.984008 -199.545466)
			(xy 269.030166 -199.572115) (xy 269.071837 -199.605346) (xy 269.108089 -199.644417) (xy 269.138113 -199.688454)
			(xy 269.161239 -199.736475) (xy 269.176949 -199.787405) (xy 269.184892 -199.840109) (xy 269.18539 -199.866758)
			(xy 269.184892 -199.893407) (xy 279.461204 -199.893407) (xy 279.461204 -199.840109) (xy 279.469147 -199.787405)
			(xy 279.484857 -199.736475) (xy 279.507983 -199.688454) (xy 279.538007 -199.644417) (xy 279.574259 -199.605346)
			(xy 279.61593 -199.572115) (xy 279.662088 -199.545466) (xy 279.711702 -199.525994) (xy 279.763664 -199.514134)
			(xy 279.816814 -199.510151) (xy 279.869964 -199.514134) (xy 279.921926 -199.525994) (xy 279.97154 -199.545466)
			(xy 280.017698 -199.572115) (xy 280.059369 -199.605346) (xy 280.095621 -199.644417) (xy 280.125645 -199.688454)
			(xy 280.148771 -199.736475) (xy 280.164481 -199.787405) (xy 280.172424 -199.840109) (xy 280.172922 -199.866758)
			(xy 280.172424 -199.893407) (xy 283.561272 -199.893407) (xy 283.561272 -199.840109) (xy 283.569215 -199.787405)
			(xy 283.584925 -199.736475) (xy 283.608051 -199.688454) (xy 283.638075 -199.644417) (xy 283.674327 -199.605346)
			(xy 283.715998 -199.572115) (xy 283.762156 -199.545466) (xy 283.81177 -199.525994) (xy 283.863732 -199.514134)
			(xy 283.916882 -199.510151) (xy 283.970032 -199.514134) (xy 284.021994 -199.525994) (xy 284.071608 -199.545466)
			(xy 284.117766 -199.572115) (xy 284.159437 -199.605346) (xy 284.195689 -199.644417) (xy 284.225713 -199.688454)
			(xy 284.248839 -199.736475) (xy 284.264549 -199.787405) (xy 284.272492 -199.840109) (xy 284.27299 -199.866758)
			(xy 284.272492 -199.893407) (xy 294.548804 -199.893407) (xy 294.548804 -199.840109) (xy 294.556747 -199.787405)
			(xy 294.572457 -199.736475) (xy 294.595583 -199.688454) (xy 294.625607 -199.644417) (xy 294.661859 -199.605346)
			(xy 294.70353 -199.572115) (xy 294.749688 -199.545466) (xy 294.799302 -199.525994) (xy 294.851264 -199.514134)
			(xy 294.904414 -199.510151) (xy 294.957564 -199.514134) (xy 295.009526 -199.525994) (xy 295.05914 -199.545466)
			(xy 295.105298 -199.572115) (xy 295.146969 -199.605346) (xy 295.183221 -199.644417) (xy 295.213245 -199.688454)
			(xy 295.236371 -199.736475) (xy 295.252081 -199.787405) (xy 295.260024 -199.840109) (xy 295.260522 -199.866758)
			(xy 295.260024 -199.893407) (xy 298.648872 -199.893407) (xy 298.648872 -199.840109) (xy 298.656815 -199.787405)
			(xy 298.672525 -199.736475) (xy 298.695651 -199.688454) (xy 298.725675 -199.644417) (xy 298.761927 -199.605346)
			(xy 298.803598 -199.572115) (xy 298.849756 -199.545466) (xy 298.89937 -199.525994) (xy 298.951332 -199.514134)
			(xy 299.004482 -199.510151) (xy 299.057632 -199.514134) (xy 299.109594 -199.525994) (xy 299.159208 -199.545466)
			(xy 299.205366 -199.572115) (xy 299.247037 -199.605346) (xy 299.283289 -199.644417) (xy 299.313313 -199.688454)
			(xy 299.336439 -199.736475) (xy 299.352149 -199.787405) (xy 299.360092 -199.840109) (xy 299.36059 -199.866758)
			(xy 299.360092 -199.893407) (xy 299.352149 -199.946111) (xy 299.336439 -199.997041) (xy 299.313313 -200.045062)
			(xy 299.283289 -200.089099) (xy 299.247037 -200.12817) (xy 299.205366 -200.161401) (xy 299.159208 -200.18805)
			(xy 299.109594 -200.207522) (xy 299.057632 -200.219382) (xy 299.004482 -200.223366) (xy 298.951332 -200.219382)
			(xy 298.89937 -200.207522) (xy 298.849756 -200.18805) (xy 298.803598 -200.161401) (xy 298.761927 -200.12817)
			(xy 298.725675 -200.089099) (xy 298.695651 -200.045062) (xy 298.672525 -199.997041) (xy 298.656815 -199.946111)
			(xy 298.648872 -199.893407) (xy 295.260024 -199.893407) (xy 295.252081 -199.946111) (xy 295.236371 -199.997041)
			(xy 295.213245 -200.045062) (xy 295.183221 -200.089099) (xy 295.146969 -200.12817) (xy 295.105298 -200.161401)
			(xy 295.05914 -200.18805) (xy 295.009526 -200.207522) (xy 294.957564 -200.219382) (xy 294.904414 -200.223366)
			(xy 294.851264 -200.219382) (xy 294.799302 -200.207522) (xy 294.749688 -200.18805) (xy 294.70353 -200.161401)
			(xy 294.661859 -200.12817) (xy 294.625607 -200.089099) (xy 294.595583 -200.045062) (xy 294.572457 -199.997041)
			(xy 294.556747 -199.946111) (xy 294.548804 -199.893407) (xy 284.272492 -199.893407) (xy 284.264549 -199.946111)
			(xy 284.248839 -199.997041) (xy 284.225713 -200.045062) (xy 284.195689 -200.089099) (xy 284.159437 -200.12817)
			(xy 284.117766 -200.161401) (xy 284.071608 -200.18805) (xy 284.021994 -200.207522) (xy 283.970032 -200.219382)
			(xy 283.916882 -200.223366) (xy 283.863732 -200.219382) (xy 283.81177 -200.207522) (xy 283.762156 -200.18805)
			(xy 283.715998 -200.161401) (xy 283.674327 -200.12817) (xy 283.638075 -200.089099) (xy 283.608051 -200.045062)
			(xy 283.584925 -199.997041) (xy 283.569215 -199.946111) (xy 283.561272 -199.893407) (xy 280.172424 -199.893407)
			(xy 280.164481 -199.946111) (xy 280.148771 -199.997041) (xy 280.125645 -200.045062) (xy 280.095621 -200.089099)
			(xy 280.059369 -200.12817) (xy 280.017698 -200.161401) (xy 279.97154 -200.18805) (xy 279.921926 -200.207522)
			(xy 279.869964 -200.219382) (xy 279.816814 -200.223366) (xy 279.763664 -200.219382) (xy 279.711702 -200.207522)
			(xy 279.662088 -200.18805) (xy 279.61593 -200.161401) (xy 279.574259 -200.12817) (xy 279.538007 -200.089099)
			(xy 279.507983 -200.045062) (xy 279.484857 -199.997041) (xy 279.469147 -199.946111) (xy 279.461204 -199.893407)
			(xy 269.184892 -199.893407) (xy 269.176949 -199.946111) (xy 269.161239 -199.997041) (xy 269.138113 -200.045062)
			(xy 269.108089 -200.089099) (xy 269.071837 -200.12817) (xy 269.030166 -200.161401) (xy 268.984008 -200.18805)
			(xy 268.934394 -200.207522) (xy 268.882432 -200.219382) (xy 268.829282 -200.223366) (xy 268.776132 -200.219382)
			(xy 268.72417 -200.207522) (xy 268.674556 -200.18805) (xy 268.628398 -200.161401) (xy 268.586727 -200.12817)
			(xy 268.550475 -200.089099) (xy 268.520451 -200.045062) (xy 268.497325 -199.997041) (xy 268.481615 -199.946111)
			(xy 268.473672 -199.893407) (xy 265.084824 -199.893407) (xy 265.076881 -199.946111) (xy 265.061171 -199.997041)
			(xy 265.038045 -200.045062) (xy 265.008021 -200.089099) (xy 264.971769 -200.12817) (xy 264.930098 -200.161401)
			(xy 264.88394 -200.18805) (xy 264.834326 -200.207522) (xy 264.782364 -200.219382) (xy 264.729214 -200.223366)
			(xy 264.676064 -200.219382) (xy 264.624102 -200.207522) (xy 264.574488 -200.18805) (xy 264.52833 -200.161401)
			(xy 264.486659 -200.12817) (xy 264.450407 -200.089099) (xy 264.420383 -200.045062) (xy 264.397257 -199.997041)
			(xy 264.381547 -199.946111) (xy 264.373604 -199.893407) (xy 254 -199.893407) (xy 254 -200.743291)
			(xy 264.373604 -200.743291) (xy 264.373604 -200.689993) (xy 264.381547 -200.637289) (xy 264.397257 -200.586359)
			(xy 264.420383 -200.538338) (xy 264.450407 -200.494301) (xy 264.486659 -200.45523) (xy 264.52833 -200.421999)
			(xy 264.574488 -200.39535) (xy 264.624102 -200.375878) (xy 264.676064 -200.364018) (xy 264.729214 -200.360035)
			(xy 264.782364 -200.364018) (xy 264.834326 -200.375878) (xy 264.88394 -200.39535) (xy 264.930098 -200.421999)
			(xy 264.971769 -200.45523) (xy 265.008021 -200.494301) (xy 265.038045 -200.538338) (xy 265.061171 -200.586359)
			(xy 265.076881 -200.637289) (xy 265.084824 -200.689993) (xy 265.085322 -200.716642) (xy 265.084824 -200.743291)
			(xy 279.461204 -200.743291) (xy 279.461204 -200.689993) (xy 279.469147 -200.637289) (xy 279.484857 -200.586359)
			(xy 279.507983 -200.538338) (xy 279.538007 -200.494301) (xy 279.574259 -200.45523) (xy 279.61593 -200.421999)
			(xy 279.662088 -200.39535) (xy 279.711702 -200.375878) (xy 279.763664 -200.364018) (xy 279.816814 -200.360035)
			(xy 279.869964 -200.364018) (xy 279.921926 -200.375878) (xy 279.97154 -200.39535) (xy 280.017698 -200.421999)
			(xy 280.059369 -200.45523) (xy 280.095621 -200.494301) (xy 280.125645 -200.538338) (xy 280.148771 -200.586359)
			(xy 280.164481 -200.637289) (xy 280.172424 -200.689993) (xy 280.172922 -200.716642) (xy 280.172424 -200.743291)
			(xy 294.548804 -200.743291) (xy 294.548804 -200.689993) (xy 294.556747 -200.637289) (xy 294.572457 -200.586359)
			(xy 294.595583 -200.538338) (xy 294.625607 -200.494301) (xy 294.661859 -200.45523) (xy 294.70353 -200.421999)
			(xy 294.749688 -200.39535) (xy 294.799302 -200.375878) (xy 294.851264 -200.364018) (xy 294.904414 -200.360035)
			(xy 294.957564 -200.364018) (xy 295.009526 -200.375878) (xy 295.05914 -200.39535) (xy 295.105298 -200.421999)
			(xy 295.146969 -200.45523) (xy 295.183221 -200.494301) (xy 295.213245 -200.538338) (xy 295.236371 -200.586359)
			(xy 295.252081 -200.637289) (xy 295.260024 -200.689993) (xy 295.260522 -200.716642) (xy 295.260024 -200.743291)
			(xy 295.252081 -200.795995) (xy 295.236371 -200.846925) (xy 295.213245 -200.894946) (xy 295.183221 -200.938983)
			(xy 295.146969 -200.978054) (xy 295.105298 -201.011285) (xy 295.05914 -201.037934) (xy 295.009526 -201.057406)
			(xy 294.957564 -201.069266) (xy 294.904414 -201.07325) (xy 294.851264 -201.069266) (xy 294.799302 -201.057406)
			(xy 294.749688 -201.037934) (xy 294.70353 -201.011285) (xy 294.661859 -200.978054) (xy 294.625607 -200.938983)
			(xy 294.595583 -200.894946) (xy 294.572457 -200.846925) (xy 294.556747 -200.795995) (xy 294.548804 -200.743291)
			(xy 280.172424 -200.743291) (xy 280.164481 -200.795995) (xy 280.148771 -200.846925) (xy 280.125645 -200.894946)
			(xy 280.095621 -200.938983) (xy 280.059369 -200.978054) (xy 280.017698 -201.011285) (xy 279.97154 -201.037934)
			(xy 279.921926 -201.057406) (xy 279.869964 -201.069266) (xy 279.816814 -201.07325) (xy 279.763664 -201.069266)
			(xy 279.711702 -201.057406) (xy 279.662088 -201.037934) (xy 279.61593 -201.011285) (xy 279.574259 -200.978054)
			(xy 279.538007 -200.938983) (xy 279.507983 -200.894946) (xy 279.484857 -200.846925) (xy 279.469147 -200.795995)
			(xy 279.461204 -200.743291) (xy 265.084824 -200.743291) (xy 265.076881 -200.795995) (xy 265.061171 -200.846925)
			(xy 265.038045 -200.894946) (xy 265.008021 -200.938983) (xy 264.971769 -200.978054) (xy 264.930098 -201.011285)
			(xy 264.88394 -201.037934) (xy 264.834326 -201.057406) (xy 264.782364 -201.069266) (xy 264.729214 -201.07325)
			(xy 264.676064 -201.069266) (xy 264.624102 -201.057406) (xy 264.574488 -201.037934) (xy 264.52833 -201.011285)
			(xy 264.486659 -200.978054) (xy 264.450407 -200.938983) (xy 264.420383 -200.894946) (xy 264.397257 -200.846925)
			(xy 264.381547 -200.795995) (xy 264.373604 -200.743291) (xy 254 -200.743291) (xy 254 -201.593429)
			(xy 268.473672 -201.593429) (xy 268.473672 -201.540131) (xy 268.481615 -201.487427) (xy 268.497325 -201.436497)
			(xy 268.520451 -201.388476) (xy 268.550475 -201.344439) (xy 268.586727 -201.305368) (xy 268.628398 -201.272137)
			(xy 268.674556 -201.245488) (xy 268.72417 -201.226016) (xy 268.776132 -201.214156) (xy 268.829282 -201.210173)
			(xy 268.882432 -201.214156) (xy 268.934394 -201.226016) (xy 268.984008 -201.245488) (xy 269.030166 -201.272137)
			(xy 269.071837 -201.305368) (xy 269.108089 -201.344439) (xy 269.138113 -201.388476) (xy 269.161239 -201.436497)
			(xy 269.176949 -201.487427) (xy 269.184892 -201.540131) (xy 269.18539 -201.56678) (xy 269.184892 -201.593429)
			(xy 283.561272 -201.593429) (xy 283.561272 -201.540131) (xy 283.569215 -201.487427) (xy 283.584925 -201.436497)
			(xy 283.608051 -201.388476) (xy 283.638075 -201.344439) (xy 283.674327 -201.305368) (xy 283.715998 -201.272137)
			(xy 283.762156 -201.245488) (xy 283.81177 -201.226016) (xy 283.863732 -201.214156) (xy 283.916882 -201.210173)
			(xy 283.970032 -201.214156) (xy 284.021994 -201.226016) (xy 284.071608 -201.245488) (xy 284.117766 -201.272137)
			(xy 284.159437 -201.305368) (xy 284.195689 -201.344439) (xy 284.225713 -201.388476) (xy 284.248839 -201.436497)
			(xy 284.264549 -201.487427) (xy 284.272492 -201.540131) (xy 284.27299 -201.56678) (xy 284.272492 -201.593429)
			(xy 298.648872 -201.593429) (xy 298.648872 -201.540131) (xy 298.656815 -201.487427) (xy 298.672525 -201.436497)
			(xy 298.695651 -201.388476) (xy 298.725675 -201.344439) (xy 298.761927 -201.305368) (xy 298.803598 -201.272137)
			(xy 298.849756 -201.245488) (xy 298.89937 -201.226016) (xy 298.951332 -201.214156) (xy 299.004482 -201.210173)
			(xy 299.057632 -201.214156) (xy 299.109594 -201.226016) (xy 299.159208 -201.245488) (xy 299.205366 -201.272137)
			(xy 299.247037 -201.305368) (xy 299.283289 -201.344439) (xy 299.313313 -201.388476) (xy 299.336439 -201.436497)
			(xy 299.352149 -201.487427) (xy 299.360092 -201.540131) (xy 299.36059 -201.56678) (xy 299.360092 -201.593429)
			(xy 299.352149 -201.646133) (xy 299.336439 -201.697063) (xy 299.313313 -201.745084) (xy 299.283289 -201.789121)
			(xy 299.247037 -201.828192) (xy 299.205366 -201.861423) (xy 299.159208 -201.888072) (xy 299.109594 -201.907544)
			(xy 299.057632 -201.919404) (xy 299.004482 -201.923388) (xy 298.951332 -201.919404) (xy 298.89937 -201.907544)
			(xy 298.849756 -201.888072) (xy 298.803598 -201.861423) (xy 298.761927 -201.828192) (xy 298.725675 -201.789121)
			(xy 298.695651 -201.745084) (xy 298.672525 -201.697063) (xy 298.656815 -201.646133) (xy 298.648872 -201.593429)
			(xy 284.272492 -201.593429) (xy 284.264549 -201.646133) (xy 284.248839 -201.697063) (xy 284.225713 -201.745084)
			(xy 284.195689 -201.789121) (xy 284.159437 -201.828192) (xy 284.117766 -201.861423) (xy 284.071608 -201.888072)
			(xy 284.021994 -201.907544) (xy 283.970032 -201.919404) (xy 283.916882 -201.923388) (xy 283.863732 -201.919404)
			(xy 283.81177 -201.907544) (xy 283.762156 -201.888072) (xy 283.715998 -201.861423) (xy 283.674327 -201.828192)
			(xy 283.638075 -201.789121) (xy 283.608051 -201.745084) (xy 283.584925 -201.697063) (xy 283.569215 -201.646133)
			(xy 283.561272 -201.593429) (xy 269.184892 -201.593429) (xy 269.176949 -201.646133) (xy 269.161239 -201.697063)
			(xy 269.138113 -201.745084) (xy 269.108089 -201.789121) (xy 269.071837 -201.828192) (xy 269.030166 -201.861423)
			(xy 268.984008 -201.888072) (xy 268.934394 -201.907544) (xy 268.882432 -201.919404) (xy 268.829282 -201.923388)
			(xy 268.776132 -201.919404) (xy 268.72417 -201.907544) (xy 268.674556 -201.888072) (xy 268.628398 -201.861423)
			(xy 268.586727 -201.828192) (xy 268.550475 -201.789121) (xy 268.520451 -201.745084) (xy 268.497325 -201.697063)
			(xy 268.481615 -201.646133) (xy 268.473672 -201.593429) (xy 254 -201.593429) (xy 254 -202.443313)
			(xy 264.373604 -202.443313) (xy 264.373604 -202.390015) (xy 264.381547 -202.337311) (xy 264.397257 -202.286381)
			(xy 264.420383 -202.23836) (xy 264.450407 -202.194323) (xy 264.486659 -202.155252) (xy 264.52833 -202.122021)
			(xy 264.574488 -202.095372) (xy 264.624102 -202.0759) (xy 264.676064 -202.06404) (xy 264.729214 -202.060057)
			(xy 264.782364 -202.06404) (xy 264.834326 -202.0759) (xy 264.88394 -202.095372) (xy 264.930098 -202.122021)
			(xy 264.971769 -202.155252) (xy 265.008021 -202.194323) (xy 265.038045 -202.23836) (xy 265.061171 -202.286381)
			(xy 265.076881 -202.337311) (xy 265.084824 -202.390015) (xy 265.085322 -202.416664) (xy 265.084824 -202.443313)
			(xy 279.461204 -202.443313) (xy 279.461204 -202.390015) (xy 279.469147 -202.337311) (xy 279.484857 -202.286381)
			(xy 279.507983 -202.23836) (xy 279.538007 -202.194323) (xy 279.574259 -202.155252) (xy 279.61593 -202.122021)
			(xy 279.662088 -202.095372) (xy 279.711702 -202.0759) (xy 279.763664 -202.06404) (xy 279.816814 -202.060057)
			(xy 279.869964 -202.06404) (xy 279.921926 -202.0759) (xy 279.97154 -202.095372) (xy 280.017698 -202.122021)
			(xy 280.059369 -202.155252) (xy 280.095621 -202.194323) (xy 280.125645 -202.23836) (xy 280.148771 -202.286381)
			(xy 280.164481 -202.337311) (xy 280.172424 -202.390015) (xy 280.172922 -202.416664) (xy 280.172424 -202.443313)
			(xy 294.548804 -202.443313) (xy 294.548804 -202.390015) (xy 294.556747 -202.337311) (xy 294.572457 -202.286381)
			(xy 294.595583 -202.23836) (xy 294.625607 -202.194323) (xy 294.661859 -202.155252) (xy 294.70353 -202.122021)
			(xy 294.749688 -202.095372) (xy 294.799302 -202.0759) (xy 294.851264 -202.06404) (xy 294.904414 -202.060057)
			(xy 294.957564 -202.06404) (xy 295.009526 -202.0759) (xy 295.05914 -202.095372) (xy 295.105298 -202.122021)
			(xy 295.146969 -202.155252) (xy 295.183221 -202.194323) (xy 295.213245 -202.23836) (xy 295.236371 -202.286381)
			(xy 295.252081 -202.337311) (xy 295.260024 -202.390015) (xy 295.260522 -202.416664) (xy 295.260024 -202.443313)
			(xy 295.252081 -202.496017) (xy 295.236371 -202.546947) (xy 295.213245 -202.594968) (xy 295.183221 -202.639005)
			(xy 295.146969 -202.678076) (xy 295.105298 -202.711307) (xy 295.05914 -202.737956) (xy 295.009526 -202.757428)
			(xy 294.957564 -202.769288) (xy 294.904414 -202.773272) (xy 294.851264 -202.769288) (xy 294.799302 -202.757428)
			(xy 294.749688 -202.737956) (xy 294.70353 -202.711307) (xy 294.661859 -202.678076) (xy 294.625607 -202.639005)
			(xy 294.595583 -202.594968) (xy 294.572457 -202.546947) (xy 294.556747 -202.496017) (xy 294.548804 -202.443313)
			(xy 280.172424 -202.443313) (xy 280.164481 -202.496017) (xy 280.148771 -202.546947) (xy 280.125645 -202.594968)
			(xy 280.095621 -202.639005) (xy 280.059369 -202.678076) (xy 280.017698 -202.711307) (xy 279.97154 -202.737956)
			(xy 279.921926 -202.757428) (xy 279.869964 -202.769288) (xy 279.816814 -202.773272) (xy 279.763664 -202.769288)
			(xy 279.711702 -202.757428) (xy 279.662088 -202.737956) (xy 279.61593 -202.711307) (xy 279.574259 -202.678076)
			(xy 279.538007 -202.639005) (xy 279.507983 -202.594968) (xy 279.484857 -202.546947) (xy 279.469147 -202.496017)
			(xy 279.461204 -202.443313) (xy 265.084824 -202.443313) (xy 265.076881 -202.496017) (xy 265.061171 -202.546947)
			(xy 265.038045 -202.594968) (xy 265.008021 -202.639005) (xy 264.971769 -202.678076) (xy 264.930098 -202.711307)
			(xy 264.88394 -202.737956) (xy 264.834326 -202.757428) (xy 264.782364 -202.769288) (xy 264.729214 -202.773272)
			(xy 264.676064 -202.769288) (xy 264.624102 -202.757428) (xy 264.574488 -202.737956) (xy 264.52833 -202.711307)
			(xy 264.486659 -202.678076) (xy 264.450407 -202.639005) (xy 264.420383 -202.594968) (xy 264.397257 -202.546947)
			(xy 264.381547 -202.496017) (xy 264.373604 -202.443313) (xy 254 -202.443313) (xy 254 -203.293451)
			(xy 268.473672 -203.293451) (xy 268.473672 -203.240153) (xy 268.481615 -203.187449) (xy 268.497325 -203.136519)
			(xy 268.520451 -203.088498) (xy 268.550475 -203.044461) (xy 268.586727 -203.00539) (xy 268.628398 -202.972159)
			(xy 268.674556 -202.94551) (xy 268.72417 -202.926038) (xy 268.776132 -202.914178) (xy 268.829282 -202.910195)
			(xy 268.882432 -202.914178) (xy 268.934394 -202.926038) (xy 268.984008 -202.94551) (xy 269.030166 -202.972159)
			(xy 269.071837 -203.00539) (xy 269.108089 -203.044461) (xy 269.138113 -203.088498) (xy 269.161239 -203.136519)
			(xy 269.176949 -203.187449) (xy 269.184892 -203.240153) (xy 269.18539 -203.266802) (xy 269.184892 -203.293451)
			(xy 283.561272 -203.293451) (xy 283.561272 -203.240153) (xy 283.569215 -203.187449) (xy 283.584925 -203.136519)
			(xy 283.608051 -203.088498) (xy 283.638075 -203.044461) (xy 283.674327 -203.00539) (xy 283.715998 -202.972159)
			(xy 283.762156 -202.94551) (xy 283.81177 -202.926038) (xy 283.863732 -202.914178) (xy 283.916882 -202.910195)
			(xy 283.970032 -202.914178) (xy 284.021994 -202.926038) (xy 284.071608 -202.94551) (xy 284.117766 -202.972159)
			(xy 284.159437 -203.00539) (xy 284.195689 -203.044461) (xy 284.225713 -203.088498) (xy 284.248839 -203.136519)
			(xy 284.264549 -203.187449) (xy 284.272492 -203.240153) (xy 284.27299 -203.266802) (xy 284.272492 -203.293451)
			(xy 298.648872 -203.293451) (xy 298.648872 -203.240153) (xy 298.656815 -203.187449) (xy 298.672525 -203.136519)
			(xy 298.695651 -203.088498) (xy 298.725675 -203.044461) (xy 298.761927 -203.00539) (xy 298.803598 -202.972159)
			(xy 298.849756 -202.94551) (xy 298.89937 -202.926038) (xy 298.951332 -202.914178) (xy 299.004482 -202.910195)
			(xy 299.057632 -202.914178) (xy 299.109594 -202.926038) (xy 299.159208 -202.94551) (xy 299.205366 -202.972159)
			(xy 299.247037 -203.00539) (xy 299.283289 -203.044461) (xy 299.313313 -203.088498) (xy 299.336439 -203.136519)
			(xy 299.352149 -203.187449) (xy 299.360092 -203.240153) (xy 299.36059 -203.266802) (xy 299.360092 -203.293451)
			(xy 299.352149 -203.346155) (xy 299.336439 -203.397085) (xy 299.313313 -203.445106) (xy 299.283289 -203.489143)
			(xy 299.247037 -203.528214) (xy 299.205366 -203.561445) (xy 299.159208 -203.588094) (xy 299.109594 -203.607566)
			(xy 299.057632 -203.619426) (xy 299.004482 -203.62341) (xy 298.951332 -203.619426) (xy 298.89937 -203.607566)
			(xy 298.849756 -203.588094) (xy 298.803598 -203.561445) (xy 298.761927 -203.528214) (xy 298.725675 -203.489143)
			(xy 298.695651 -203.445106) (xy 298.672525 -203.397085) (xy 298.656815 -203.346155) (xy 298.648872 -203.293451)
			(xy 284.272492 -203.293451) (xy 284.264549 -203.346155) (xy 284.248839 -203.397085) (xy 284.225713 -203.445106)
			(xy 284.195689 -203.489143) (xy 284.159437 -203.528214) (xy 284.117766 -203.561445) (xy 284.071608 -203.588094)
			(xy 284.021994 -203.607566) (xy 283.970032 -203.619426) (xy 283.916882 -203.62341) (xy 283.863732 -203.619426)
			(xy 283.81177 -203.607566) (xy 283.762156 -203.588094) (xy 283.715998 -203.561445) (xy 283.674327 -203.528214)
			(xy 283.638075 -203.489143) (xy 283.608051 -203.445106) (xy 283.584925 -203.397085) (xy 283.569215 -203.346155)
			(xy 283.561272 -203.293451) (xy 269.184892 -203.293451) (xy 269.176949 -203.346155) (xy 269.161239 -203.397085)
			(xy 269.138113 -203.445106) (xy 269.108089 -203.489143) (xy 269.071837 -203.528214) (xy 269.030166 -203.561445)
			(xy 268.984008 -203.588094) (xy 268.934394 -203.607566) (xy 268.882432 -203.619426) (xy 268.829282 -203.62341)
			(xy 268.776132 -203.619426) (xy 268.72417 -203.607566) (xy 268.674556 -203.588094) (xy 268.628398 -203.561445)
			(xy 268.586727 -203.528214) (xy 268.550475 -203.489143) (xy 268.520451 -203.445106) (xy 268.497325 -203.397085)
			(xy 268.481615 -203.346155) (xy 268.473672 -203.293451) (xy 254 -203.293451) (xy 254 -204.143335)
			(xy 264.373604 -204.143335) (xy 264.373604 -204.090037) (xy 264.381547 -204.037333) (xy 264.397257 -203.986403)
			(xy 264.420383 -203.938382) (xy 264.450407 -203.894345) (xy 264.486659 -203.855274) (xy 264.52833 -203.822043)
			(xy 264.574488 -203.795394) (xy 264.624102 -203.775922) (xy 264.676064 -203.764062) (xy 264.729214 -203.760079)
			(xy 264.782364 -203.764062) (xy 264.834326 -203.775922) (xy 264.88394 -203.795394) (xy 264.930098 -203.822043)
			(xy 264.971769 -203.855274) (xy 265.008021 -203.894345) (xy 265.038045 -203.938382) (xy 265.061171 -203.986403)
			(xy 265.076881 -204.037333) (xy 265.084824 -204.090037) (xy 265.085322 -204.116686) (xy 265.084824 -204.143335)
			(xy 279.461204 -204.143335) (xy 279.461204 -204.090037) (xy 279.469147 -204.037333) (xy 279.484857 -203.986403)
			(xy 279.507983 -203.938382) (xy 279.538007 -203.894345) (xy 279.574259 -203.855274) (xy 279.61593 -203.822043)
			(xy 279.662088 -203.795394) (xy 279.711702 -203.775922) (xy 279.763664 -203.764062) (xy 279.816814 -203.760079)
			(xy 279.869964 -203.764062) (xy 279.921926 -203.775922) (xy 279.97154 -203.795394) (xy 280.017698 -203.822043)
			(xy 280.059369 -203.855274) (xy 280.095621 -203.894345) (xy 280.125645 -203.938382) (xy 280.148771 -203.986403)
			(xy 280.164481 -204.037333) (xy 280.172424 -204.090037) (xy 280.172922 -204.116686) (xy 280.172424 -204.143335)
			(xy 294.548804 -204.143335) (xy 294.548804 -204.090037) (xy 294.556747 -204.037333) (xy 294.572457 -203.986403)
			(xy 294.595583 -203.938382) (xy 294.625607 -203.894345) (xy 294.661859 -203.855274) (xy 294.70353 -203.822043)
			(xy 294.749688 -203.795394) (xy 294.799302 -203.775922) (xy 294.851264 -203.764062) (xy 294.904414 -203.760079)
			(xy 294.957564 -203.764062) (xy 295.009526 -203.775922) (xy 295.05914 -203.795394) (xy 295.105298 -203.822043)
			(xy 295.146969 -203.855274) (xy 295.183221 -203.894345) (xy 295.213245 -203.938382) (xy 295.236371 -203.986403)
			(xy 295.252081 -204.037333) (xy 295.260024 -204.090037) (xy 295.260522 -204.116686) (xy 295.260024 -204.143335)
			(xy 295.252081 -204.196039) (xy 295.236371 -204.246969) (xy 295.213245 -204.29499) (xy 295.183221 -204.339027)
			(xy 295.146969 -204.378098) (xy 295.105298 -204.411329) (xy 295.05914 -204.437978) (xy 295.009526 -204.45745)
			(xy 294.957564 -204.46931) (xy 294.904414 -204.473294) (xy 294.851264 -204.46931) (xy 294.799302 -204.45745)
			(xy 294.749688 -204.437978) (xy 294.70353 -204.411329) (xy 294.661859 -204.378098) (xy 294.625607 -204.339027)
			(xy 294.595583 -204.29499) (xy 294.572457 -204.246969) (xy 294.556747 -204.196039) (xy 294.548804 -204.143335)
			(xy 280.172424 -204.143335) (xy 280.164481 -204.196039) (xy 280.148771 -204.246969) (xy 280.125645 -204.29499)
			(xy 280.095621 -204.339027) (xy 280.059369 -204.378098) (xy 280.017698 -204.411329) (xy 279.97154 -204.437978)
			(xy 279.921926 -204.45745) (xy 279.869964 -204.46931) (xy 279.816814 -204.473294) (xy 279.763664 -204.46931)
			(xy 279.711702 -204.45745) (xy 279.662088 -204.437978) (xy 279.61593 -204.411329) (xy 279.574259 -204.378098)
			(xy 279.538007 -204.339027) (xy 279.507983 -204.29499) (xy 279.484857 -204.246969) (xy 279.469147 -204.196039)
			(xy 279.461204 -204.143335) (xy 265.084824 -204.143335) (xy 265.076881 -204.196039) (xy 265.061171 -204.246969)
			(xy 265.038045 -204.29499) (xy 265.008021 -204.339027) (xy 264.971769 -204.378098) (xy 264.930098 -204.411329)
			(xy 264.88394 -204.437978) (xy 264.834326 -204.45745) (xy 264.782364 -204.46931) (xy 264.729214 -204.473294)
			(xy 264.676064 -204.46931) (xy 264.624102 -204.45745) (xy 264.574488 -204.437978) (xy 264.52833 -204.411329)
			(xy 264.486659 -204.378098) (xy 264.450407 -204.339027) (xy 264.420383 -204.29499) (xy 264.397257 -204.246969)
			(xy 264.381547 -204.196039) (xy 264.373604 -204.143335) (xy 254 -204.143335) (xy 254 -204.993219)
			(xy 268.473672 -204.993219) (xy 268.473672 -204.939921) (xy 268.481615 -204.887217) (xy 268.497325 -204.836287)
			(xy 268.520451 -204.788266) (xy 268.550475 -204.744229) (xy 268.586727 -204.705158) (xy 268.628398 -204.671927)
			(xy 268.674556 -204.645278) (xy 268.72417 -204.625806) (xy 268.776132 -204.613946) (xy 268.829282 -204.609963)
			(xy 268.882432 -204.613946) (xy 268.934394 -204.625806) (xy 268.984008 -204.645278) (xy 269.030166 -204.671927)
			(xy 269.071837 -204.705158) (xy 269.108089 -204.744229) (xy 269.138113 -204.788266) (xy 269.161239 -204.836287)
			(xy 269.176949 -204.887217) (xy 269.184892 -204.939921) (xy 269.18539 -204.96657) (xy 269.184892 -204.993219)
			(xy 283.561272 -204.993219) (xy 283.561272 -204.939921) (xy 283.569215 -204.887217) (xy 283.584925 -204.836287)
			(xy 283.608051 -204.788266) (xy 283.638075 -204.744229) (xy 283.674327 -204.705158) (xy 283.715998 -204.671927)
			(xy 283.762156 -204.645278) (xy 283.81177 -204.625806) (xy 283.863732 -204.613946) (xy 283.916882 -204.609963)
			(xy 283.970032 -204.613946) (xy 284.021994 -204.625806) (xy 284.071608 -204.645278) (xy 284.117766 -204.671927)
			(xy 284.159437 -204.705158) (xy 284.195689 -204.744229) (xy 284.225713 -204.788266) (xy 284.248839 -204.836287)
			(xy 284.264549 -204.887217) (xy 284.272492 -204.939921) (xy 284.27299 -204.96657) (xy 284.272492 -204.993219)
			(xy 298.648872 -204.993219) (xy 298.648872 -204.939921) (xy 298.656815 -204.887217) (xy 298.672525 -204.836287)
			(xy 298.695651 -204.788266) (xy 298.725675 -204.744229) (xy 298.761927 -204.705158) (xy 298.803598 -204.671927)
			(xy 298.849756 -204.645278) (xy 298.89937 -204.625806) (xy 298.951332 -204.613946) (xy 299.004482 -204.609963)
			(xy 299.057632 -204.613946) (xy 299.109594 -204.625806) (xy 299.159208 -204.645278) (xy 299.205366 -204.671927)
			(xy 299.247037 -204.705158) (xy 299.283289 -204.744229) (xy 299.313313 -204.788266) (xy 299.336439 -204.836287)
			(xy 299.352149 -204.887217) (xy 299.360092 -204.939921) (xy 299.36059 -204.96657) (xy 299.360092 -204.993219)
			(xy 299.352149 -205.045923) (xy 299.336439 -205.096853) (xy 299.313313 -205.144874) (xy 299.283289 -205.188911)
			(xy 299.247037 -205.227982) (xy 299.205366 -205.261213) (xy 299.159208 -205.287862) (xy 299.109594 -205.307334)
			(xy 299.057632 -205.319194) (xy 299.004482 -205.323178) (xy 298.951332 -205.319194) (xy 298.89937 -205.307334)
			(xy 298.849756 -205.287862) (xy 298.803598 -205.261213) (xy 298.761927 -205.227982) (xy 298.725675 -205.188911)
			(xy 298.695651 -205.144874) (xy 298.672525 -205.096853) (xy 298.656815 -205.045923) (xy 298.648872 -204.993219)
			(xy 284.272492 -204.993219) (xy 284.264549 -205.045923) (xy 284.248839 -205.096853) (xy 284.225713 -205.144874)
			(xy 284.195689 -205.188911) (xy 284.159437 -205.227982) (xy 284.117766 -205.261213) (xy 284.071608 -205.287862)
			(xy 284.021994 -205.307334) (xy 283.970032 -205.319194) (xy 283.916882 -205.323178) (xy 283.863732 -205.319194)
			(xy 283.81177 -205.307334) (xy 283.762156 -205.287862) (xy 283.715998 -205.261213) (xy 283.674327 -205.227982)
			(xy 283.638075 -205.188911) (xy 283.608051 -205.144874) (xy 283.584925 -205.096853) (xy 283.569215 -205.045923)
			(xy 283.561272 -204.993219) (xy 269.184892 -204.993219) (xy 269.176949 -205.045923) (xy 269.161239 -205.096853)
			(xy 269.138113 -205.144874) (xy 269.108089 -205.188911) (xy 269.071837 -205.227982) (xy 269.030166 -205.261213)
			(xy 268.984008 -205.287862) (xy 268.934394 -205.307334) (xy 268.882432 -205.319194) (xy 268.829282 -205.323178)
			(xy 268.776132 -205.319194) (xy 268.72417 -205.307334) (xy 268.674556 -205.287862) (xy 268.628398 -205.261213)
			(xy 268.586727 -205.227982) (xy 268.550475 -205.188911) (xy 268.520451 -205.144874) (xy 268.497325 -205.096853)
			(xy 268.481615 -205.045923) (xy 268.473672 -204.993219) (xy 254 -204.993219) (xy 254 -205.843357)
			(xy 264.373604 -205.843357) (xy 264.373604 -205.790059) (xy 264.381547 -205.737355) (xy 264.397257 -205.686425)
			(xy 264.420383 -205.638404) (xy 264.450407 -205.594367) (xy 264.486659 -205.555296) (xy 264.52833 -205.522065)
			(xy 264.574488 -205.495416) (xy 264.624102 -205.475944) (xy 264.676064 -205.464084) (xy 264.729214 -205.460101)
			(xy 264.782364 -205.464084) (xy 264.834326 -205.475944) (xy 264.88394 -205.495416) (xy 264.930098 -205.522065)
			(xy 264.971769 -205.555296) (xy 265.008021 -205.594367) (xy 265.038045 -205.638404) (xy 265.061171 -205.686425)
			(xy 265.076881 -205.737355) (xy 265.084824 -205.790059) (xy 265.085322 -205.816708) (xy 265.084824 -205.843357)
			(xy 279.461204 -205.843357) (xy 279.461204 -205.790059) (xy 279.469147 -205.737355) (xy 279.484857 -205.686425)
			(xy 279.507983 -205.638404) (xy 279.538007 -205.594367) (xy 279.574259 -205.555296) (xy 279.61593 -205.522065)
			(xy 279.662088 -205.495416) (xy 279.711702 -205.475944) (xy 279.763664 -205.464084) (xy 279.816814 -205.460101)
			(xy 279.869964 -205.464084) (xy 279.921926 -205.475944) (xy 279.97154 -205.495416) (xy 280.017698 -205.522065)
			(xy 280.059369 -205.555296) (xy 280.095621 -205.594367) (xy 280.125645 -205.638404) (xy 280.148771 -205.686425)
			(xy 280.164481 -205.737355) (xy 280.172424 -205.790059) (xy 280.172922 -205.816708) (xy 280.172424 -205.843357)
			(xy 294.548804 -205.843357) (xy 294.548804 -205.790059) (xy 294.556747 -205.737355) (xy 294.572457 -205.686425)
			(xy 294.595583 -205.638404) (xy 294.625607 -205.594367) (xy 294.661859 -205.555296) (xy 294.70353 -205.522065)
			(xy 294.749688 -205.495416) (xy 294.799302 -205.475944) (xy 294.851264 -205.464084) (xy 294.904414 -205.460101)
			(xy 294.957564 -205.464084) (xy 295.009526 -205.475944) (xy 295.05914 -205.495416) (xy 295.105298 -205.522065)
			(xy 295.146969 -205.555296) (xy 295.183221 -205.594367) (xy 295.213245 -205.638404) (xy 295.236371 -205.686425)
			(xy 295.252081 -205.737355) (xy 295.260024 -205.790059) (xy 295.260522 -205.816708) (xy 295.260024 -205.843357)
			(xy 295.252081 -205.896061) (xy 295.236371 -205.946991) (xy 295.213245 -205.995012) (xy 295.183221 -206.039049)
			(xy 295.146969 -206.07812) (xy 295.105298 -206.111351) (xy 295.05914 -206.138) (xy 295.009526 -206.157472)
			(xy 294.957564 -206.169332) (xy 294.904414 -206.173316) (xy 294.851264 -206.169332) (xy 294.799302 -206.157472)
			(xy 294.749688 -206.138) (xy 294.70353 -206.111351) (xy 294.661859 -206.07812) (xy 294.625607 -206.039049)
			(xy 294.595583 -205.995012) (xy 294.572457 -205.946991) (xy 294.556747 -205.896061) (xy 294.548804 -205.843357)
			(xy 280.172424 -205.843357) (xy 280.164481 -205.896061) (xy 280.148771 -205.946991) (xy 280.125645 -205.995012)
			(xy 280.095621 -206.039049) (xy 280.059369 -206.07812) (xy 280.017698 -206.111351) (xy 279.97154 -206.138)
			(xy 279.921926 -206.157472) (xy 279.869964 -206.169332) (xy 279.816814 -206.173316) (xy 279.763664 -206.169332)
			(xy 279.711702 -206.157472) (xy 279.662088 -206.138) (xy 279.61593 -206.111351) (xy 279.574259 -206.07812)
			(xy 279.538007 -206.039049) (xy 279.507983 -205.995012) (xy 279.484857 -205.946991) (xy 279.469147 -205.896061)
			(xy 279.461204 -205.843357) (xy 265.084824 -205.843357) (xy 265.076881 -205.896061) (xy 265.061171 -205.946991)
			(xy 265.038045 -205.995012) (xy 265.008021 -206.039049) (xy 264.971769 -206.07812) (xy 264.930098 -206.111351)
			(xy 264.88394 -206.138) (xy 264.834326 -206.157472) (xy 264.782364 -206.169332) (xy 264.729214 -206.173316)
			(xy 264.676064 -206.169332) (xy 264.624102 -206.157472) (xy 264.574488 -206.138) (xy 264.52833 -206.111351)
			(xy 264.486659 -206.07812) (xy 264.450407 -206.039049) (xy 264.420383 -205.995012) (xy 264.397257 -205.946991)
			(xy 264.381547 -205.896061) (xy 264.373604 -205.843357) (xy 254 -205.843357) (xy 254 -206.693241)
			(xy 268.473672 -206.693241) (xy 268.473672 -206.639943) (xy 268.481615 -206.587239) (xy 268.497325 -206.536309)
			(xy 268.520451 -206.488288) (xy 268.550475 -206.444251) (xy 268.586727 -206.40518) (xy 268.628398 -206.371949)
			(xy 268.674556 -206.3453) (xy 268.72417 -206.325828) (xy 268.776132 -206.313968) (xy 268.829282 -206.309985)
			(xy 268.882432 -206.313968) (xy 268.934394 -206.325828) (xy 268.984008 -206.3453) (xy 269.030166 -206.371949)
			(xy 269.071837 -206.40518) (xy 269.108089 -206.444251) (xy 269.138113 -206.488288) (xy 269.161239 -206.536309)
			(xy 269.176949 -206.587239) (xy 269.184892 -206.639943) (xy 269.18539 -206.666592) (xy 269.184892 -206.693241)
			(xy 283.561272 -206.693241) (xy 283.561272 -206.639943) (xy 283.569215 -206.587239) (xy 283.584925 -206.536309)
			(xy 283.608051 -206.488288) (xy 283.638075 -206.444251) (xy 283.674327 -206.40518) (xy 283.715998 -206.371949)
			(xy 283.762156 -206.3453) (xy 283.81177 -206.325828) (xy 283.863732 -206.313968) (xy 283.916882 -206.309985)
			(xy 283.970032 -206.313968) (xy 284.021994 -206.325828) (xy 284.071608 -206.3453) (xy 284.117766 -206.371949)
			(xy 284.159437 -206.40518) (xy 284.195689 -206.444251) (xy 284.225713 -206.488288) (xy 284.248839 -206.536309)
			(xy 284.264549 -206.587239) (xy 284.272492 -206.639943) (xy 284.27299 -206.666592) (xy 284.272492 -206.693241)
			(xy 298.648872 -206.693241) (xy 298.648872 -206.639943) (xy 298.656815 -206.587239) (xy 298.672525 -206.536309)
			(xy 298.695651 -206.488288) (xy 298.725675 -206.444251) (xy 298.761927 -206.40518) (xy 298.803598 -206.371949)
			(xy 298.849756 -206.3453) (xy 298.89937 -206.325828) (xy 298.951332 -206.313968) (xy 299.004482 -206.309985)
			(xy 299.057632 -206.313968) (xy 299.109594 -206.325828) (xy 299.159208 -206.3453) (xy 299.205366 -206.371949)
			(xy 299.247037 -206.40518) (xy 299.283289 -206.444251) (xy 299.313313 -206.488288) (xy 299.336439 -206.536309)
			(xy 299.352149 -206.587239) (xy 299.360092 -206.639943) (xy 299.36059 -206.666592) (xy 299.360092 -206.693241)
			(xy 299.352149 -206.745945) (xy 299.336439 -206.796875) (xy 299.313313 -206.844896) (xy 299.283289 -206.888933)
			(xy 299.247037 -206.928004) (xy 299.205366 -206.961235) (xy 299.159208 -206.987884) (xy 299.109594 -207.007356)
			(xy 299.057632 -207.019216) (xy 299.004482 -207.0232) (xy 298.951332 -207.019216) (xy 298.89937 -207.007356)
			(xy 298.849756 -206.987884) (xy 298.803598 -206.961235) (xy 298.761927 -206.928004) (xy 298.725675 -206.888933)
			(xy 298.695651 -206.844896) (xy 298.672525 -206.796875) (xy 298.656815 -206.745945) (xy 298.648872 -206.693241)
			(xy 284.272492 -206.693241) (xy 284.264549 -206.745945) (xy 284.248839 -206.796875) (xy 284.225713 -206.844896)
			(xy 284.195689 -206.888933) (xy 284.159437 -206.928004) (xy 284.117766 -206.961235) (xy 284.071608 -206.987884)
			(xy 284.021994 -207.007356) (xy 283.970032 -207.019216) (xy 283.916882 -207.0232) (xy 283.863732 -207.019216)
			(xy 283.81177 -207.007356) (xy 283.762156 -206.987884) (xy 283.715998 -206.961235) (xy 283.674327 -206.928004)
			(xy 283.638075 -206.888933) (xy 283.608051 -206.844896) (xy 283.584925 -206.796875) (xy 283.569215 -206.745945)
			(xy 283.561272 -206.693241) (xy 269.184892 -206.693241) (xy 269.176949 -206.745945) (xy 269.161239 -206.796875)
			(xy 269.138113 -206.844896) (xy 269.108089 -206.888933) (xy 269.071837 -206.928004) (xy 269.030166 -206.961235)
			(xy 268.984008 -206.987884) (xy 268.934394 -207.007356) (xy 268.882432 -207.019216) (xy 268.829282 -207.0232)
			(xy 268.776132 -207.019216) (xy 268.72417 -207.007356) (xy 268.674556 -206.987884) (xy 268.628398 -206.961235)
			(xy 268.586727 -206.928004) (xy 268.550475 -206.888933) (xy 268.520451 -206.844896) (xy 268.497325 -206.796875)
			(xy 268.481615 -206.745945) (xy 268.473672 -206.693241) (xy 254 -206.693241) (xy 254 -207.543379)
			(xy 264.373604 -207.543379) (xy 264.373604 -207.490081) (xy 264.381547 -207.437377) (xy 264.397257 -207.386447)
			(xy 264.420383 -207.338426) (xy 264.450407 -207.294389) (xy 264.486659 -207.255318) (xy 264.52833 -207.222087)
			(xy 264.574488 -207.195438) (xy 264.624102 -207.175966) (xy 264.676064 -207.164106) (xy 264.729214 -207.160123)
			(xy 264.782364 -207.164106) (xy 264.834326 -207.175966) (xy 264.88394 -207.195438) (xy 264.930098 -207.222087)
			(xy 264.971769 -207.255318) (xy 265.008021 -207.294389) (xy 265.038045 -207.338426) (xy 265.061171 -207.386447)
			(xy 265.076881 -207.437377) (xy 265.084824 -207.490081) (xy 265.085322 -207.51673) (xy 265.084824 -207.543379)
			(xy 279.461204 -207.543379) (xy 279.461204 -207.490081) (xy 279.469147 -207.437377) (xy 279.484857 -207.386447)
			(xy 279.507983 -207.338426) (xy 279.538007 -207.294389) (xy 279.574259 -207.255318) (xy 279.61593 -207.222087)
			(xy 279.662088 -207.195438) (xy 279.711702 -207.175966) (xy 279.763664 -207.164106) (xy 279.816814 -207.160123)
			(xy 279.869964 -207.164106) (xy 279.921926 -207.175966) (xy 279.97154 -207.195438) (xy 280.017698 -207.222087)
			(xy 280.059369 -207.255318) (xy 280.095621 -207.294389) (xy 280.125645 -207.338426) (xy 280.148771 -207.386447)
			(xy 280.164481 -207.437377) (xy 280.172424 -207.490081) (xy 280.172922 -207.51673) (xy 280.172424 -207.543379)
			(xy 294.548804 -207.543379) (xy 294.548804 -207.490081) (xy 294.556747 -207.437377) (xy 294.572457 -207.386447)
			(xy 294.595583 -207.338426) (xy 294.625607 -207.294389) (xy 294.661859 -207.255318) (xy 294.70353 -207.222087)
			(xy 294.749688 -207.195438) (xy 294.799302 -207.175966) (xy 294.851264 -207.164106) (xy 294.904414 -207.160123)
			(xy 294.957564 -207.164106) (xy 295.009526 -207.175966) (xy 295.05914 -207.195438) (xy 295.105298 -207.222087)
			(xy 295.146969 -207.255318) (xy 295.183221 -207.294389) (xy 295.213245 -207.338426) (xy 295.236371 -207.386447)
			(xy 295.252081 -207.437377) (xy 295.260024 -207.490081) (xy 295.260522 -207.51673) (xy 295.260024 -207.543379)
			(xy 295.252081 -207.596083) (xy 295.236371 -207.647013) (xy 295.213245 -207.695034) (xy 295.183221 -207.739071)
			(xy 295.146969 -207.778142) (xy 295.105298 -207.811373) (xy 295.05914 -207.838022) (xy 295.009526 -207.857494)
			(xy 294.957564 -207.869354) (xy 294.904414 -207.873338) (xy 294.851264 -207.869354) (xy 294.799302 -207.857494)
			(xy 294.749688 -207.838022) (xy 294.70353 -207.811373) (xy 294.661859 -207.778142) (xy 294.625607 -207.739071)
			(xy 294.595583 -207.695034) (xy 294.572457 -207.647013) (xy 294.556747 -207.596083) (xy 294.548804 -207.543379)
			(xy 280.172424 -207.543379) (xy 280.164481 -207.596083) (xy 280.148771 -207.647013) (xy 280.125645 -207.695034)
			(xy 280.095621 -207.739071) (xy 280.059369 -207.778142) (xy 280.017698 -207.811373) (xy 279.97154 -207.838022)
			(xy 279.921926 -207.857494) (xy 279.869964 -207.869354) (xy 279.816814 -207.873338) (xy 279.763664 -207.869354)
			(xy 279.711702 -207.857494) (xy 279.662088 -207.838022) (xy 279.61593 -207.811373) (xy 279.574259 -207.778142)
			(xy 279.538007 -207.739071) (xy 279.507983 -207.695034) (xy 279.484857 -207.647013) (xy 279.469147 -207.596083)
			(xy 279.461204 -207.543379) (xy 265.084824 -207.543379) (xy 265.076881 -207.596083) (xy 265.061171 -207.647013)
			(xy 265.038045 -207.695034) (xy 265.008021 -207.739071) (xy 264.971769 -207.778142) (xy 264.930098 -207.811373)
			(xy 264.88394 -207.838022) (xy 264.834326 -207.857494) (xy 264.782364 -207.869354) (xy 264.729214 -207.873338)
			(xy 264.676064 -207.869354) (xy 264.624102 -207.857494) (xy 264.574488 -207.838022) (xy 264.52833 -207.811373)
			(xy 264.486659 -207.778142) (xy 264.450407 -207.739071) (xy 264.420383 -207.695034) (xy 264.397257 -207.647013)
			(xy 264.381547 -207.596083) (xy 264.373604 -207.543379) (xy 254 -207.543379) (xy 254 -208.393263)
			(xy 268.473672 -208.393263) (xy 268.473672 -208.339965) (xy 268.481615 -208.287261) (xy 268.497325 -208.236331)
			(xy 268.520451 -208.18831) (xy 268.550475 -208.144273) (xy 268.586727 -208.105202) (xy 268.628398 -208.071971)
			(xy 268.674556 -208.045322) (xy 268.72417 -208.02585) (xy 268.776132 -208.01399) (xy 268.829282 -208.010007)
			(xy 268.882432 -208.01399) (xy 268.934394 -208.02585) (xy 268.984008 -208.045322) (xy 269.030166 -208.071971)
			(xy 269.071837 -208.105202) (xy 269.108089 -208.144273) (xy 269.138113 -208.18831) (xy 269.161239 -208.236331)
			(xy 269.176949 -208.287261) (xy 269.184892 -208.339965) (xy 269.18539 -208.366614) (xy 269.184892 -208.393263)
			(xy 283.561272 -208.393263) (xy 283.561272 -208.339965) (xy 283.569215 -208.287261) (xy 283.584925 -208.236331)
			(xy 283.608051 -208.18831) (xy 283.638075 -208.144273) (xy 283.674327 -208.105202) (xy 283.715998 -208.071971)
			(xy 283.762156 -208.045322) (xy 283.81177 -208.02585) (xy 283.863732 -208.01399) (xy 283.916882 -208.010007)
			(xy 283.970032 -208.01399) (xy 284.021994 -208.02585) (xy 284.071608 -208.045322) (xy 284.117766 -208.071971)
			(xy 284.159437 -208.105202) (xy 284.195689 -208.144273) (xy 284.225713 -208.18831) (xy 284.248839 -208.236331)
			(xy 284.264549 -208.287261) (xy 284.272492 -208.339965) (xy 284.27299 -208.366614) (xy 284.272492 -208.393263)
			(xy 298.648872 -208.393263) (xy 298.648872 -208.339965) (xy 298.656815 -208.287261) (xy 298.672525 -208.236331)
			(xy 298.695651 -208.18831) (xy 298.725675 -208.144273) (xy 298.761927 -208.105202) (xy 298.803598 -208.071971)
			(xy 298.849756 -208.045322) (xy 298.89937 -208.02585) (xy 298.951332 -208.01399) (xy 299.004482 -208.010007)
			(xy 299.057632 -208.01399) (xy 299.109594 -208.02585) (xy 299.159208 -208.045322) (xy 299.205366 -208.071971)
			(xy 299.247037 -208.105202) (xy 299.283289 -208.144273) (xy 299.313313 -208.18831) (xy 299.336439 -208.236331)
			(xy 299.352149 -208.287261) (xy 299.360092 -208.339965) (xy 299.36059 -208.366614) (xy 299.360092 -208.393263)
			(xy 299.352149 -208.445967) (xy 299.336439 -208.496897) (xy 299.313313 -208.544918) (xy 299.283289 -208.588955)
			(xy 299.247037 -208.628026) (xy 299.205366 -208.661257) (xy 299.159208 -208.687906) (xy 299.109594 -208.707378)
			(xy 299.057632 -208.719238) (xy 299.004482 -208.723222) (xy 298.951332 -208.719238) (xy 298.89937 -208.707378)
			(xy 298.849756 -208.687906) (xy 298.803598 -208.661257) (xy 298.761927 -208.628026) (xy 298.725675 -208.588955)
			(xy 298.695651 -208.544918) (xy 298.672525 -208.496897) (xy 298.656815 -208.445967) (xy 298.648872 -208.393263)
			(xy 284.272492 -208.393263) (xy 284.264549 -208.445967) (xy 284.248839 -208.496897) (xy 284.225713 -208.544918)
			(xy 284.195689 -208.588955) (xy 284.159437 -208.628026) (xy 284.117766 -208.661257) (xy 284.071608 -208.687906)
			(xy 284.021994 -208.707378) (xy 283.970032 -208.719238) (xy 283.916882 -208.723222) (xy 283.863732 -208.719238)
			(xy 283.81177 -208.707378) (xy 283.762156 -208.687906) (xy 283.715998 -208.661257) (xy 283.674327 -208.628026)
			(xy 283.638075 -208.588955) (xy 283.608051 -208.544918) (xy 283.584925 -208.496897) (xy 283.569215 -208.445967)
			(xy 283.561272 -208.393263) (xy 269.184892 -208.393263) (xy 269.176949 -208.445967) (xy 269.161239 -208.496897)
			(xy 269.138113 -208.544918) (xy 269.108089 -208.588955) (xy 269.071837 -208.628026) (xy 269.030166 -208.661257)
			(xy 268.984008 -208.687906) (xy 268.934394 -208.707378) (xy 268.882432 -208.719238) (xy 268.829282 -208.723222)
			(xy 268.776132 -208.719238) (xy 268.72417 -208.707378) (xy 268.674556 -208.687906) (xy 268.628398 -208.661257)
			(xy 268.586727 -208.628026) (xy 268.550475 -208.588955) (xy 268.520451 -208.544918) (xy 268.497325 -208.496897)
			(xy 268.481615 -208.445967) (xy 268.473672 -208.393263) (xy 254 -208.393263) (xy 254 -209.243401)
			(xy 264.373604 -209.243401) (xy 264.373604 -209.190103) (xy 264.381547 -209.137399) (xy 264.397257 -209.086469)
			(xy 264.420383 -209.038448) (xy 264.450407 -208.994411) (xy 264.486659 -208.95534) (xy 264.52833 -208.922109)
			(xy 264.574488 -208.89546) (xy 264.624102 -208.875988) (xy 264.676064 -208.864128) (xy 264.729214 -208.860145)
			(xy 264.782364 -208.864128) (xy 264.834326 -208.875988) (xy 264.88394 -208.89546) (xy 264.930098 -208.922109)
			(xy 264.971769 -208.95534) (xy 265.008021 -208.994411) (xy 265.038045 -209.038448) (xy 265.061171 -209.086469)
			(xy 265.076881 -209.137399) (xy 265.084824 -209.190103) (xy 265.085322 -209.216752) (xy 265.084824 -209.243401)
			(xy 268.473672 -209.243401) (xy 268.473672 -209.190103) (xy 268.481615 -209.137399) (xy 268.497325 -209.086469)
			(xy 268.520451 -209.038448) (xy 268.550475 -208.994411) (xy 268.586727 -208.95534) (xy 268.628398 -208.922109)
			(xy 268.674556 -208.89546) (xy 268.72417 -208.875988) (xy 268.776132 -208.864128) (xy 268.829282 -208.860145)
			(xy 268.882432 -208.864128) (xy 268.934394 -208.875988) (xy 268.984008 -208.89546) (xy 269.030166 -208.922109)
			(xy 269.071837 -208.95534) (xy 269.108089 -208.994411) (xy 269.138113 -209.038448) (xy 269.161239 -209.086469)
			(xy 269.176949 -209.137399) (xy 269.184892 -209.190103) (xy 269.18539 -209.216752) (xy 269.184892 -209.243401)
			(xy 279.461204 -209.243401) (xy 279.461204 -209.190103) (xy 279.469147 -209.137399) (xy 279.484857 -209.086469)
			(xy 279.507983 -209.038448) (xy 279.538007 -208.994411) (xy 279.574259 -208.95534) (xy 279.61593 -208.922109)
			(xy 279.662088 -208.89546) (xy 279.711702 -208.875988) (xy 279.763664 -208.864128) (xy 279.816814 -208.860145)
			(xy 279.869964 -208.864128) (xy 279.921926 -208.875988) (xy 279.97154 -208.89546) (xy 280.017698 -208.922109)
			(xy 280.059369 -208.95534) (xy 280.095621 -208.994411) (xy 280.125645 -209.038448) (xy 280.148771 -209.086469)
			(xy 280.164481 -209.137399) (xy 280.172424 -209.190103) (xy 280.172922 -209.216752) (xy 280.172424 -209.243401)
			(xy 283.561272 -209.243401) (xy 283.561272 -209.190103) (xy 283.569215 -209.137399) (xy 283.584925 -209.086469)
			(xy 283.608051 -209.038448) (xy 283.638075 -208.994411) (xy 283.674327 -208.95534) (xy 283.715998 -208.922109)
			(xy 283.762156 -208.89546) (xy 283.81177 -208.875988) (xy 283.863732 -208.864128) (xy 283.916882 -208.860145)
			(xy 283.970032 -208.864128) (xy 284.021994 -208.875988) (xy 284.071608 -208.89546) (xy 284.117766 -208.922109)
			(xy 284.159437 -208.95534) (xy 284.195689 -208.994411) (xy 284.225713 -209.038448) (xy 284.248839 -209.086469)
			(xy 284.264549 -209.137399) (xy 284.272492 -209.190103) (xy 284.27299 -209.216752) (xy 284.272492 -209.243401)
			(xy 294.548804 -209.243401) (xy 294.548804 -209.190103) (xy 294.556747 -209.137399) (xy 294.572457 -209.086469)
			(xy 294.595583 -209.038448) (xy 294.625607 -208.994411) (xy 294.661859 -208.95534) (xy 294.70353 -208.922109)
			(xy 294.749688 -208.89546) (xy 294.799302 -208.875988) (xy 294.851264 -208.864128) (xy 294.904414 -208.860145)
			(xy 294.957564 -208.864128) (xy 295.009526 -208.875988) (xy 295.05914 -208.89546) (xy 295.105298 -208.922109)
			(xy 295.146969 -208.95534) (xy 295.183221 -208.994411) (xy 295.213245 -209.038448) (xy 295.236371 -209.086469)
			(xy 295.252081 -209.137399) (xy 295.260024 -209.190103) (xy 295.260522 -209.216752) (xy 295.260024 -209.243401)
			(xy 298.648872 -209.243401) (xy 298.648872 -209.190103) (xy 298.656815 -209.137399) (xy 298.672525 -209.086469)
			(xy 298.695651 -209.038448) (xy 298.725675 -208.994411) (xy 298.761927 -208.95534) (xy 298.803598 -208.922109)
			(xy 298.849756 -208.89546) (xy 298.89937 -208.875988) (xy 298.951332 -208.864128) (xy 299.004482 -208.860145)
			(xy 299.057632 -208.864128) (xy 299.109594 -208.875988) (xy 299.159208 -208.89546) (xy 299.205366 -208.922109)
			(xy 299.247037 -208.95534) (xy 299.283289 -208.994411) (xy 299.313313 -209.038448) (xy 299.336439 -209.086469)
			(xy 299.352149 -209.137399) (xy 299.360092 -209.190103) (xy 299.36059 -209.216752) (xy 299.360092 -209.243401)
			(xy 299.352149 -209.296105) (xy 299.336439 -209.347035) (xy 299.313313 -209.395056) (xy 299.283289 -209.439093)
			(xy 299.247037 -209.478164) (xy 299.205366 -209.511395) (xy 299.159208 -209.538044) (xy 299.109594 -209.557516)
			(xy 299.057632 -209.569376) (xy 299.004482 -209.57336) (xy 298.951332 -209.569376) (xy 298.89937 -209.557516)
			(xy 298.849756 -209.538044) (xy 298.803598 -209.511395) (xy 298.761927 -209.478164) (xy 298.725675 -209.439093)
			(xy 298.695651 -209.395056) (xy 298.672525 -209.347035) (xy 298.656815 -209.296105) (xy 298.648872 -209.243401)
			(xy 295.260024 -209.243401) (xy 295.252081 -209.296105) (xy 295.236371 -209.347035) (xy 295.213245 -209.395056)
			(xy 295.183221 -209.439093) (xy 295.146969 -209.478164) (xy 295.105298 -209.511395) (xy 295.05914 -209.538044)
			(xy 295.009526 -209.557516) (xy 294.957564 -209.569376) (xy 294.904414 -209.57336) (xy 294.851264 -209.569376)
			(xy 294.799302 -209.557516) (xy 294.749688 -209.538044) (xy 294.70353 -209.511395) (xy 294.661859 -209.478164)
			(xy 294.625607 -209.439093) (xy 294.595583 -209.395056) (xy 294.572457 -209.347035) (xy 294.556747 -209.296105)
			(xy 294.548804 -209.243401) (xy 284.272492 -209.243401) (xy 284.264549 -209.296105) (xy 284.248839 -209.347035)
			(xy 284.225713 -209.395056) (xy 284.195689 -209.439093) (xy 284.159437 -209.478164) (xy 284.117766 -209.511395)
			(xy 284.071608 -209.538044) (xy 284.021994 -209.557516) (xy 283.970032 -209.569376) (xy 283.916882 -209.57336)
			(xy 283.863732 -209.569376) (xy 283.81177 -209.557516) (xy 283.762156 -209.538044) (xy 283.715998 -209.511395)
			(xy 283.674327 -209.478164) (xy 283.638075 -209.439093) (xy 283.608051 -209.395056) (xy 283.584925 -209.347035)
			(xy 283.569215 -209.296105) (xy 283.561272 -209.243401) (xy 280.172424 -209.243401) (xy 280.164481 -209.296105)
			(xy 280.148771 -209.347035) (xy 280.125645 -209.395056) (xy 280.095621 -209.439093) (xy 280.059369 -209.478164)
			(xy 280.017698 -209.511395) (xy 279.97154 -209.538044) (xy 279.921926 -209.557516) (xy 279.869964 -209.569376)
			(xy 279.816814 -209.57336) (xy 279.763664 -209.569376) (xy 279.711702 -209.557516) (xy 279.662088 -209.538044)
			(xy 279.61593 -209.511395) (xy 279.574259 -209.478164) (xy 279.538007 -209.439093) (xy 279.507983 -209.395056)
			(xy 279.484857 -209.347035) (xy 279.469147 -209.296105) (xy 279.461204 -209.243401) (xy 269.184892 -209.243401)
			(xy 269.176949 -209.296105) (xy 269.161239 -209.347035) (xy 269.138113 -209.395056) (xy 269.108089 -209.439093)
			(xy 269.071837 -209.478164) (xy 269.030166 -209.511395) (xy 268.984008 -209.538044) (xy 268.934394 -209.557516)
			(xy 268.882432 -209.569376) (xy 268.829282 -209.57336) (xy 268.776132 -209.569376) (xy 268.72417 -209.557516)
			(xy 268.674556 -209.538044) (xy 268.628398 -209.511395) (xy 268.586727 -209.478164) (xy 268.550475 -209.439093)
			(xy 268.520451 -209.395056) (xy 268.497325 -209.347035) (xy 268.481615 -209.296105) (xy 268.473672 -209.243401)
			(xy 265.084824 -209.243401) (xy 265.076881 -209.296105) (xy 265.061171 -209.347035) (xy 265.038045 -209.395056)
			(xy 265.008021 -209.439093) (xy 264.971769 -209.478164) (xy 264.930098 -209.511395) (xy 264.88394 -209.538044)
			(xy 264.834326 -209.557516) (xy 264.782364 -209.569376) (xy 264.729214 -209.57336) (xy 264.676064 -209.569376)
			(xy 264.624102 -209.557516) (xy 264.574488 -209.538044) (xy 264.52833 -209.511395) (xy 264.486659 -209.478164)
			(xy 264.450407 -209.439093) (xy 264.420383 -209.395056) (xy 264.397257 -209.347035) (xy 264.381547 -209.296105)
			(xy 264.373604 -209.243401) (xy 254 -209.243401) (xy 254 -210.093285) (xy 264.373604 -210.093285)
			(xy 264.373604 -210.039987) (xy 264.381547 -209.987283) (xy 264.397257 -209.936353) (xy 264.420383 -209.888332)
			(xy 264.450407 -209.844295) (xy 264.486659 -209.805224) (xy 264.52833 -209.771993) (xy 264.574488 -209.745344)
			(xy 264.624102 -209.725872) (xy 264.676064 -209.714012) (xy 264.729214 -209.710029) (xy 264.782364 -209.714012)
			(xy 264.834326 -209.725872) (xy 264.88394 -209.745344) (xy 264.930098 -209.771993) (xy 264.971769 -209.805224)
			(xy 265.008021 -209.844295) (xy 265.038045 -209.888332) (xy 265.061171 -209.936353) (xy 265.076881 -209.987283)
			(xy 265.084824 -210.039987) (xy 265.085322 -210.066636) (xy 265.084824 -210.093285) (xy 279.461204 -210.093285)
			(xy 279.461204 -210.039987) (xy 279.469147 -209.987283) (xy 279.484857 -209.936353) (xy 279.507983 -209.888332)
			(xy 279.538007 -209.844295) (xy 279.574259 -209.805224) (xy 279.61593 -209.771993) (xy 279.662088 -209.745344)
			(xy 279.711702 -209.725872) (xy 279.763664 -209.714012) (xy 279.816814 -209.710029) (xy 279.869964 -209.714012)
			(xy 279.921926 -209.725872) (xy 279.97154 -209.745344) (xy 280.017698 -209.771993) (xy 280.059369 -209.805224)
			(xy 280.095621 -209.844295) (xy 280.125645 -209.888332) (xy 280.148771 -209.936353) (xy 280.164481 -209.987283)
			(xy 280.172424 -210.039987) (xy 280.172922 -210.066636) (xy 280.172424 -210.093285) (xy 294.548804 -210.093285)
			(xy 294.548804 -210.039987) (xy 294.556747 -209.987283) (xy 294.572457 -209.936353) (xy 294.595583 -209.888332)
			(xy 294.625607 -209.844295) (xy 294.661859 -209.805224) (xy 294.70353 -209.771993) (xy 294.749688 -209.745344)
			(xy 294.799302 -209.725872) (xy 294.851264 -209.714012) (xy 294.904414 -209.710029) (xy 294.957564 -209.714012)
			(xy 295.009526 -209.725872) (xy 295.05914 -209.745344) (xy 295.105298 -209.771993) (xy 295.146969 -209.805224)
			(xy 295.183221 -209.844295) (xy 295.213245 -209.888332) (xy 295.236371 -209.936353) (xy 295.252081 -209.987283)
			(xy 295.260024 -210.039987) (xy 295.260522 -210.066636) (xy 295.260024 -210.093285) (xy 295.252081 -210.145989)
			(xy 295.236371 -210.196919) (xy 295.213245 -210.24494) (xy 295.183221 -210.288977) (xy 295.146969 -210.328048)
			(xy 295.105298 -210.361279) (xy 295.05914 -210.387928) (xy 295.009526 -210.4074) (xy 294.957564 -210.41926)
			(xy 294.904414 -210.423244) (xy 294.851264 -210.41926) (xy 294.799302 -210.4074) (xy 294.749688 -210.387928)
			(xy 294.70353 -210.361279) (xy 294.661859 -210.328048) (xy 294.625607 -210.288977) (xy 294.595583 -210.24494)
			(xy 294.572457 -210.196919) (xy 294.556747 -210.145989) (xy 294.548804 -210.093285) (xy 280.172424 -210.093285)
			(xy 280.164481 -210.145989) (xy 280.148771 -210.196919) (xy 280.125645 -210.24494) (xy 280.095621 -210.288977)
			(xy 280.059369 -210.328048) (xy 280.017698 -210.361279) (xy 279.97154 -210.387928) (xy 279.921926 -210.4074)
			(xy 279.869964 -210.41926) (xy 279.816814 -210.423244) (xy 279.763664 -210.41926) (xy 279.711702 -210.4074)
			(xy 279.662088 -210.387928) (xy 279.61593 -210.361279) (xy 279.574259 -210.328048) (xy 279.538007 -210.288977)
			(xy 279.507983 -210.24494) (xy 279.484857 -210.196919) (xy 279.469147 -210.145989) (xy 279.461204 -210.093285)
			(xy 265.084824 -210.093285) (xy 265.076881 -210.145989) (xy 265.061171 -210.196919) (xy 265.038045 -210.24494)
			(xy 265.008021 -210.288977) (xy 264.971769 -210.328048) (xy 264.930098 -210.361279) (xy 264.88394 -210.387928)
			(xy 264.834326 -210.4074) (xy 264.782364 -210.41926) (xy 264.729214 -210.423244) (xy 264.676064 -210.41926)
			(xy 264.624102 -210.4074) (xy 264.574488 -210.387928) (xy 264.52833 -210.361279) (xy 264.486659 -210.328048)
			(xy 264.450407 -210.288977) (xy 264.420383 -210.24494) (xy 264.397257 -210.196919) (xy 264.381547 -210.145989)
			(xy 264.373604 -210.093285) (xy 254 -210.093285) (xy 254 -210.943423) (xy 268.473672 -210.943423)
			(xy 268.473672 -210.890125) (xy 268.481615 -210.837421) (xy 268.497325 -210.786491) (xy 268.520451 -210.73847)
			(xy 268.550475 -210.694433) (xy 268.586727 -210.655362) (xy 268.628398 -210.622131) (xy 268.674556 -210.595482)
			(xy 268.72417 -210.57601) (xy 268.776132 -210.56415) (xy 268.829282 -210.560167) (xy 268.882432 -210.56415)
			(xy 268.934394 -210.57601) (xy 268.984008 -210.595482) (xy 269.030166 -210.622131) (xy 269.071837 -210.655362)
			(xy 269.108089 -210.694433) (xy 269.138113 -210.73847) (xy 269.161239 -210.786491) (xy 269.176949 -210.837421)
			(xy 269.184892 -210.890125) (xy 269.18539 -210.916774) (xy 269.184892 -210.943423) (xy 283.561272 -210.943423)
			(xy 283.561272 -210.890125) (xy 283.569215 -210.837421) (xy 283.584925 -210.786491) (xy 283.608051 -210.73847)
			(xy 283.638075 -210.694433) (xy 283.674327 -210.655362) (xy 283.715998 -210.622131) (xy 283.762156 -210.595482)
			(xy 283.81177 -210.57601) (xy 283.863732 -210.56415) (xy 283.916882 -210.560167) (xy 283.970032 -210.56415)
			(xy 284.021994 -210.57601) (xy 284.071608 -210.595482) (xy 284.117766 -210.622131) (xy 284.159437 -210.655362)
			(xy 284.195689 -210.694433) (xy 284.225713 -210.73847) (xy 284.248839 -210.786491) (xy 284.264549 -210.837421)
			(xy 284.272492 -210.890125) (xy 284.27299 -210.916774) (xy 284.272492 -210.943423) (xy 298.648872 -210.943423)
			(xy 298.648872 -210.890125) (xy 298.656815 -210.837421) (xy 298.672525 -210.786491) (xy 298.695651 -210.73847)
			(xy 298.725675 -210.694433) (xy 298.761927 -210.655362) (xy 298.803598 -210.622131) (xy 298.849756 -210.595482)
			(xy 298.89937 -210.57601) (xy 298.951332 -210.56415) (xy 299.004482 -210.560167) (xy 299.057632 -210.56415)
			(xy 299.109594 -210.57601) (xy 299.159208 -210.595482) (xy 299.205366 -210.622131) (xy 299.247037 -210.655362)
			(xy 299.283289 -210.694433) (xy 299.313313 -210.73847) (xy 299.336439 -210.786491) (xy 299.352149 -210.837421)
			(xy 299.360092 -210.890125) (xy 299.36059 -210.916774) (xy 299.360092 -210.943423) (xy 299.352149 -210.996127)
			(xy 299.336439 -211.047057) (xy 299.313313 -211.095078) (xy 299.283289 -211.139115) (xy 299.247037 -211.178186)
			(xy 299.205366 -211.211417) (xy 299.159208 -211.238066) (xy 299.109594 -211.257538) (xy 299.057632 -211.269398)
			(xy 299.004482 -211.273382) (xy 298.951332 -211.269398) (xy 298.89937 -211.257538) (xy 298.849756 -211.238066)
			(xy 298.803598 -211.211417) (xy 298.761927 -211.178186) (xy 298.725675 -211.139115) (xy 298.695651 -211.095078)
			(xy 298.672525 -211.047057) (xy 298.656815 -210.996127) (xy 298.648872 -210.943423) (xy 284.272492 -210.943423)
			(xy 284.264549 -210.996127) (xy 284.248839 -211.047057) (xy 284.225713 -211.095078) (xy 284.195689 -211.139115)
			(xy 284.159437 -211.178186) (xy 284.117766 -211.211417) (xy 284.071608 -211.238066) (xy 284.021994 -211.257538)
			(xy 283.970032 -211.269398) (xy 283.916882 -211.273382) (xy 283.863732 -211.269398) (xy 283.81177 -211.257538)
			(xy 283.762156 -211.238066) (xy 283.715998 -211.211417) (xy 283.674327 -211.178186) (xy 283.638075 -211.139115)
			(xy 283.608051 -211.095078) (xy 283.584925 -211.047057) (xy 283.569215 -210.996127) (xy 283.561272 -210.943423)
			(xy 269.184892 -210.943423) (xy 269.176949 -210.996127) (xy 269.161239 -211.047057) (xy 269.138113 -211.095078)
			(xy 269.108089 -211.139115) (xy 269.071837 -211.178186) (xy 269.030166 -211.211417) (xy 268.984008 -211.238066)
			(xy 268.934394 -211.257538) (xy 268.882432 -211.269398) (xy 268.829282 -211.273382) (xy 268.776132 -211.269398)
			(xy 268.72417 -211.257538) (xy 268.674556 -211.238066) (xy 268.628398 -211.211417) (xy 268.586727 -211.178186)
			(xy 268.550475 -211.139115) (xy 268.520451 -211.095078) (xy 268.497325 -211.047057) (xy 268.481615 -210.996127)
			(xy 268.473672 -210.943423) (xy 254 -210.943423) (xy 254 -211.793307) (xy 264.373604 -211.793307)
			(xy 264.373604 -211.740009) (xy 264.381547 -211.687305) (xy 264.397257 -211.636375) (xy 264.420383 -211.588354)
			(xy 264.450407 -211.544317) (xy 264.486659 -211.505246) (xy 264.52833 -211.472015) (xy 264.574488 -211.445366)
			(xy 264.624102 -211.425894) (xy 264.676064 -211.414034) (xy 264.729214 -211.410051) (xy 264.782364 -211.414034)
			(xy 264.834326 -211.425894) (xy 264.88394 -211.445366) (xy 264.930098 -211.472015) (xy 264.971769 -211.505246)
			(xy 265.008021 -211.544317) (xy 265.038045 -211.588354) (xy 265.061171 -211.636375) (xy 265.076881 -211.687305)
			(xy 265.084824 -211.740009) (xy 265.085322 -211.766658) (xy 265.084824 -211.793307) (xy 279.461204 -211.793307)
			(xy 279.461204 -211.740009) (xy 279.469147 -211.687305) (xy 279.484857 -211.636375) (xy 279.507983 -211.588354)
			(xy 279.538007 -211.544317) (xy 279.574259 -211.505246) (xy 279.61593 -211.472015) (xy 279.662088 -211.445366)
			(xy 279.711702 -211.425894) (xy 279.763664 -211.414034) (xy 279.816814 -211.410051) (xy 279.869964 -211.414034)
			(xy 279.921926 -211.425894) (xy 279.97154 -211.445366) (xy 280.017698 -211.472015) (xy 280.059369 -211.505246)
			(xy 280.095621 -211.544317) (xy 280.125645 -211.588354) (xy 280.148771 -211.636375) (xy 280.164481 -211.687305)
			(xy 280.172424 -211.740009) (xy 280.172922 -211.766658) (xy 280.172424 -211.793307) (xy 294.548804 -211.793307)
			(xy 294.548804 -211.740009) (xy 294.556747 -211.687305) (xy 294.572457 -211.636375) (xy 294.595583 -211.588354)
			(xy 294.625607 -211.544317) (xy 294.661859 -211.505246) (xy 294.70353 -211.472015) (xy 294.749688 -211.445366)
			(xy 294.799302 -211.425894) (xy 294.851264 -211.414034) (xy 294.904414 -211.410051) (xy 294.957564 -211.414034)
			(xy 295.009526 -211.425894) (xy 295.05914 -211.445366) (xy 295.105298 -211.472015) (xy 295.146969 -211.505246)
			(xy 295.183221 -211.544317) (xy 295.213245 -211.588354) (xy 295.236371 -211.636375) (xy 295.252081 -211.687305)
			(xy 295.260024 -211.740009) (xy 295.260522 -211.766658) (xy 295.260024 -211.793307) (xy 295.252081 -211.846011)
			(xy 295.236371 -211.896941) (xy 295.213245 -211.944962) (xy 295.183221 -211.988999) (xy 295.146969 -212.02807)
			(xy 295.105298 -212.061301) (xy 295.05914 -212.08795) (xy 295.009526 -212.107422) (xy 294.957564 -212.119282)
			(xy 294.904414 -212.123266) (xy 294.851264 -212.119282) (xy 294.799302 -212.107422) (xy 294.749688 -212.08795)
			(xy 294.70353 -212.061301) (xy 294.661859 -212.02807) (xy 294.625607 -211.988999) (xy 294.595583 -211.944962)
			(xy 294.572457 -211.896941) (xy 294.556747 -211.846011) (xy 294.548804 -211.793307) (xy 280.172424 -211.793307)
			(xy 280.164481 -211.846011) (xy 280.148771 -211.896941) (xy 280.125645 -211.944962) (xy 280.095621 -211.988999)
			(xy 280.059369 -212.02807) (xy 280.017698 -212.061301) (xy 279.97154 -212.08795) (xy 279.921926 -212.107422)
			(xy 279.869964 -212.119282) (xy 279.816814 -212.123266) (xy 279.763664 -212.119282) (xy 279.711702 -212.107422)
			(xy 279.662088 -212.08795) (xy 279.61593 -212.061301) (xy 279.574259 -212.02807) (xy 279.538007 -211.988999)
			(xy 279.507983 -211.944962) (xy 279.484857 -211.896941) (xy 279.469147 -211.846011) (xy 279.461204 -211.793307)
			(xy 265.084824 -211.793307) (xy 265.076881 -211.846011) (xy 265.061171 -211.896941) (xy 265.038045 -211.944962)
			(xy 265.008021 -211.988999) (xy 264.971769 -212.02807) (xy 264.930098 -212.061301) (xy 264.88394 -212.08795)
			(xy 264.834326 -212.107422) (xy 264.782364 -212.119282) (xy 264.729214 -212.123266) (xy 264.676064 -212.119282)
			(xy 264.624102 -212.107422) (xy 264.574488 -212.08795) (xy 264.52833 -212.061301) (xy 264.486659 -212.02807)
			(xy 264.450407 -211.988999) (xy 264.420383 -211.944962) (xy 264.397257 -211.896941) (xy 264.381547 -211.846011)
			(xy 264.373604 -211.793307) (xy 254 -211.793307) (xy 254 -212.643445) (xy 268.473672 -212.643445)
			(xy 268.473672 -212.590147) (xy 268.481615 -212.537443) (xy 268.497325 -212.486513) (xy 268.520451 -212.438492)
			(xy 268.550475 -212.394455) (xy 268.586727 -212.355384) (xy 268.628398 -212.322153) (xy 268.674556 -212.295504)
			(xy 268.72417 -212.276032) (xy 268.776132 -212.264172) (xy 268.829282 -212.260189) (xy 268.882432 -212.264172)
			(xy 268.934394 -212.276032) (xy 268.984008 -212.295504) (xy 269.030166 -212.322153) (xy 269.071837 -212.355384)
			(xy 269.108089 -212.394455) (xy 269.138113 -212.438492) (xy 269.161239 -212.486513) (xy 269.176949 -212.537443)
			(xy 269.184892 -212.590147) (xy 269.18539 -212.616796) (xy 269.184892 -212.643445) (xy 283.561272 -212.643445)
			(xy 283.561272 -212.590147) (xy 283.569215 -212.537443) (xy 283.584925 -212.486513) (xy 283.608051 -212.438492)
			(xy 283.638075 -212.394455) (xy 283.674327 -212.355384) (xy 283.715998 -212.322153) (xy 283.762156 -212.295504)
			(xy 283.81177 -212.276032) (xy 283.863732 -212.264172) (xy 283.916882 -212.260189) (xy 283.970032 -212.264172)
			(xy 284.021994 -212.276032) (xy 284.071608 -212.295504) (xy 284.117766 -212.322153) (xy 284.159437 -212.355384)
			(xy 284.195689 -212.394455) (xy 284.225713 -212.438492) (xy 284.248839 -212.486513) (xy 284.264549 -212.537443)
			(xy 284.272492 -212.590147) (xy 284.27299 -212.616796) (xy 284.272492 -212.643445) (xy 298.648872 -212.643445)
			(xy 298.648872 -212.590147) (xy 298.656815 -212.537443) (xy 298.672525 -212.486513) (xy 298.695651 -212.438492)
			(xy 298.725675 -212.394455) (xy 298.761927 -212.355384) (xy 298.803598 -212.322153) (xy 298.849756 -212.295504)
			(xy 298.89937 -212.276032) (xy 298.951332 -212.264172) (xy 299.004482 -212.260189) (xy 299.057632 -212.264172)
			(xy 299.109594 -212.276032) (xy 299.159208 -212.295504) (xy 299.205366 -212.322153) (xy 299.247037 -212.355384)
			(xy 299.283289 -212.394455) (xy 299.313313 -212.438492) (xy 299.336439 -212.486513) (xy 299.352149 -212.537443)
			(xy 299.360092 -212.590147) (xy 299.36059 -212.616796) (xy 299.360092 -212.643445) (xy 299.352149 -212.696149)
			(xy 299.336439 -212.747079) (xy 299.313313 -212.7951) (xy 299.283289 -212.839137) (xy 299.247037 -212.878208)
			(xy 299.205366 -212.911439) (xy 299.159208 -212.938088) (xy 299.109594 -212.95756) (xy 299.057632 -212.96942)
			(xy 299.004482 -212.973404) (xy 298.951332 -212.96942) (xy 298.89937 -212.95756) (xy 298.849756 -212.938088)
			(xy 298.803598 -212.911439) (xy 298.761927 -212.878208) (xy 298.725675 -212.839137) (xy 298.695651 -212.7951)
			(xy 298.672525 -212.747079) (xy 298.656815 -212.696149) (xy 298.648872 -212.643445) (xy 284.272492 -212.643445)
			(xy 284.264549 -212.696149) (xy 284.248839 -212.747079) (xy 284.225713 -212.7951) (xy 284.195689 -212.839137)
			(xy 284.159437 -212.878208) (xy 284.117766 -212.911439) (xy 284.071608 -212.938088) (xy 284.021994 -212.95756)
			(xy 283.970032 -212.96942) (xy 283.916882 -212.973404) (xy 283.863732 -212.96942) (xy 283.81177 -212.95756)
			(xy 283.762156 -212.938088) (xy 283.715998 -212.911439) (xy 283.674327 -212.878208) (xy 283.638075 -212.839137)
			(xy 283.608051 -212.7951) (xy 283.584925 -212.747079) (xy 283.569215 -212.696149) (xy 283.561272 -212.643445)
			(xy 269.184892 -212.643445) (xy 269.176949 -212.696149) (xy 269.161239 -212.747079) (xy 269.138113 -212.7951)
			(xy 269.108089 -212.839137) (xy 269.071837 -212.878208) (xy 269.030166 -212.911439) (xy 268.984008 -212.938088)
			(xy 268.934394 -212.95756) (xy 268.882432 -212.96942) (xy 268.829282 -212.973404) (xy 268.776132 -212.96942)
			(xy 268.72417 -212.95756) (xy 268.674556 -212.938088) (xy 268.628398 -212.911439) (xy 268.586727 -212.878208)
			(xy 268.550475 -212.839137) (xy 268.520451 -212.7951) (xy 268.497325 -212.747079) (xy 268.481615 -212.696149)
			(xy 268.473672 -212.643445) (xy 254 -212.643445) (xy 254 -213.493329) (xy 264.373604 -213.493329)
			(xy 264.373604 -213.440031) (xy 264.381547 -213.387327) (xy 264.397257 -213.336397) (xy 264.420383 -213.288376)
			(xy 264.450407 -213.244339) (xy 264.486659 -213.205268) (xy 264.52833 -213.172037) (xy 264.574488 -213.145388)
			(xy 264.624102 -213.125916) (xy 264.676064 -213.114056) (xy 264.729214 -213.110073) (xy 264.782364 -213.114056)
			(xy 264.834326 -213.125916) (xy 264.88394 -213.145388) (xy 264.930098 -213.172037) (xy 264.971769 -213.205268)
			(xy 265.008021 -213.244339) (xy 265.038045 -213.288376) (xy 265.061171 -213.336397) (xy 265.076881 -213.387327)
			(xy 265.084824 -213.440031) (xy 265.085322 -213.46668) (xy 265.084824 -213.493329) (xy 279.461204 -213.493329)
			(xy 279.461204 -213.440031) (xy 279.469147 -213.387327) (xy 279.484857 -213.336397) (xy 279.507983 -213.288376)
			(xy 279.538007 -213.244339) (xy 279.574259 -213.205268) (xy 279.61593 -213.172037) (xy 279.662088 -213.145388)
			(xy 279.711702 -213.125916) (xy 279.763664 -213.114056) (xy 279.816814 -213.110073) (xy 279.869964 -213.114056)
			(xy 279.921926 -213.125916) (xy 279.97154 -213.145388) (xy 280.017698 -213.172037) (xy 280.059369 -213.205268)
			(xy 280.095621 -213.244339) (xy 280.125645 -213.288376) (xy 280.148771 -213.336397) (xy 280.164481 -213.387327)
			(xy 280.172424 -213.440031) (xy 280.172922 -213.46668) (xy 280.172424 -213.493329) (xy 294.548804 -213.493329)
			(xy 294.548804 -213.440031) (xy 294.556747 -213.387327) (xy 294.572457 -213.336397) (xy 294.595583 -213.288376)
			(xy 294.625607 -213.244339) (xy 294.661859 -213.205268) (xy 294.70353 -213.172037) (xy 294.749688 -213.145388)
			(xy 294.799302 -213.125916) (xy 294.851264 -213.114056) (xy 294.904414 -213.110073) (xy 294.957564 -213.114056)
			(xy 295.009526 -213.125916) (xy 295.05914 -213.145388) (xy 295.105298 -213.172037) (xy 295.146969 -213.205268)
			(xy 295.183221 -213.244339) (xy 295.213245 -213.288376) (xy 295.236371 -213.336397) (xy 295.252081 -213.387327)
			(xy 295.260024 -213.440031) (xy 295.260522 -213.46668) (xy 295.260024 -213.493329) (xy 295.252081 -213.546033)
			(xy 295.236371 -213.596963) (xy 295.213245 -213.644984) (xy 295.183221 -213.689021) (xy 295.146969 -213.728092)
			(xy 295.105298 -213.761323) (xy 295.05914 -213.787972) (xy 295.009526 -213.807444) (xy 294.957564 -213.819304)
			(xy 294.904414 -213.823288) (xy 294.851264 -213.819304) (xy 294.799302 -213.807444) (xy 294.749688 -213.787972)
			(xy 294.70353 -213.761323) (xy 294.661859 -213.728092) (xy 294.625607 -213.689021) (xy 294.595583 -213.644984)
			(xy 294.572457 -213.596963) (xy 294.556747 -213.546033) (xy 294.548804 -213.493329) (xy 280.172424 -213.493329)
			(xy 280.164481 -213.546033) (xy 280.148771 -213.596963) (xy 280.125645 -213.644984) (xy 280.095621 -213.689021)
			(xy 280.059369 -213.728092) (xy 280.017698 -213.761323) (xy 279.97154 -213.787972) (xy 279.921926 -213.807444)
			(xy 279.869964 -213.819304) (xy 279.816814 -213.823288) (xy 279.763664 -213.819304) (xy 279.711702 -213.807444)
			(xy 279.662088 -213.787972) (xy 279.61593 -213.761323) (xy 279.574259 -213.728092) (xy 279.538007 -213.689021)
			(xy 279.507983 -213.644984) (xy 279.484857 -213.596963) (xy 279.469147 -213.546033) (xy 279.461204 -213.493329)
			(xy 265.084824 -213.493329) (xy 265.076881 -213.546033) (xy 265.061171 -213.596963) (xy 265.038045 -213.644984)
			(xy 265.008021 -213.689021) (xy 264.971769 -213.728092) (xy 264.930098 -213.761323) (xy 264.88394 -213.787972)
			(xy 264.834326 -213.807444) (xy 264.782364 -213.819304) (xy 264.729214 -213.823288) (xy 264.676064 -213.819304)
			(xy 264.624102 -213.807444) (xy 264.574488 -213.787972) (xy 264.52833 -213.761323) (xy 264.486659 -213.728092)
			(xy 264.450407 -213.689021) (xy 264.420383 -213.644984) (xy 264.397257 -213.596963) (xy 264.381547 -213.546033)
			(xy 264.373604 -213.493329) (xy 254 -213.493329) (xy 254 -214.343213) (xy 268.473672 -214.343213)
			(xy 268.473672 -214.289915) (xy 268.481615 -214.237211) (xy 268.497325 -214.186281) (xy 268.520451 -214.13826)
			(xy 268.550475 -214.094223) (xy 268.586727 -214.055152) (xy 268.628398 -214.021921) (xy 268.674556 -213.995272)
			(xy 268.72417 -213.9758) (xy 268.776132 -213.96394) (xy 268.829282 -213.959957) (xy 268.882432 -213.96394)
			(xy 268.934394 -213.9758) (xy 268.984008 -213.995272) (xy 269.030166 -214.021921) (xy 269.071837 -214.055152)
			(xy 269.108089 -214.094223) (xy 269.138113 -214.13826) (xy 269.161239 -214.186281) (xy 269.176949 -214.237211)
			(xy 269.184892 -214.289915) (xy 269.18539 -214.316564) (xy 269.184892 -214.343213) (xy 283.561272 -214.343213)
			(xy 283.561272 -214.289915) (xy 283.569215 -214.237211) (xy 283.584925 -214.186281) (xy 283.608051 -214.13826)
			(xy 283.638075 -214.094223) (xy 283.674327 -214.055152) (xy 283.715998 -214.021921) (xy 283.762156 -213.995272)
			(xy 283.81177 -213.9758) (xy 283.863732 -213.96394) (xy 283.916882 -213.959957) (xy 283.970032 -213.96394)
			(xy 284.021994 -213.9758) (xy 284.071608 -213.995272) (xy 284.117766 -214.021921) (xy 284.159437 -214.055152)
			(xy 284.195689 -214.094223) (xy 284.225713 -214.13826) (xy 284.248839 -214.186281) (xy 284.264549 -214.237211)
			(xy 284.272492 -214.289915) (xy 284.27299 -214.316564) (xy 284.272492 -214.343213) (xy 298.648872 -214.343213)
			(xy 298.648872 -214.289915) (xy 298.656815 -214.237211) (xy 298.672525 -214.186281) (xy 298.695651 -214.13826)
			(xy 298.725675 -214.094223) (xy 298.761927 -214.055152) (xy 298.803598 -214.021921) (xy 298.849756 -213.995272)
			(xy 298.89937 -213.9758) (xy 298.951332 -213.96394) (xy 299.004482 -213.959957) (xy 299.057632 -213.96394)
			(xy 299.109594 -213.9758) (xy 299.159208 -213.995272) (xy 299.205366 -214.021921) (xy 299.247037 -214.055152)
			(xy 299.283289 -214.094223) (xy 299.313313 -214.13826) (xy 299.336439 -214.186281) (xy 299.352149 -214.237211)
			(xy 299.360092 -214.289915) (xy 299.36059 -214.316564) (xy 299.360092 -214.343213) (xy 299.352149 -214.395917)
			(xy 299.336439 -214.446847) (xy 299.313313 -214.494868) (xy 299.283289 -214.538905) (xy 299.247037 -214.577976)
			(xy 299.205366 -214.611207) (xy 299.159208 -214.637856) (xy 299.109594 -214.657328) (xy 299.057632 -214.669188)
			(xy 299.004482 -214.673172) (xy 298.951332 -214.669188) (xy 298.89937 -214.657328) (xy 298.849756 -214.637856)
			(xy 298.803598 -214.611207) (xy 298.761927 -214.577976) (xy 298.725675 -214.538905) (xy 298.695651 -214.494868)
			(xy 298.672525 -214.446847) (xy 298.656815 -214.395917) (xy 298.648872 -214.343213) (xy 284.272492 -214.343213)
			(xy 284.264549 -214.395917) (xy 284.248839 -214.446847) (xy 284.225713 -214.494868) (xy 284.195689 -214.538905)
			(xy 284.159437 -214.577976) (xy 284.117766 -214.611207) (xy 284.071608 -214.637856) (xy 284.021994 -214.657328)
			(xy 283.970032 -214.669188) (xy 283.916882 -214.673172) (xy 283.863732 -214.669188) (xy 283.81177 -214.657328)
			(xy 283.762156 -214.637856) (xy 283.715998 -214.611207) (xy 283.674327 -214.577976) (xy 283.638075 -214.538905)
			(xy 283.608051 -214.494868) (xy 283.584925 -214.446847) (xy 283.569215 -214.395917) (xy 283.561272 -214.343213)
			(xy 269.184892 -214.343213) (xy 269.176949 -214.395917) (xy 269.161239 -214.446847) (xy 269.138113 -214.494868)
			(xy 269.108089 -214.538905) (xy 269.071837 -214.577976) (xy 269.030166 -214.611207) (xy 268.984008 -214.637856)
			(xy 268.934394 -214.657328) (xy 268.882432 -214.669188) (xy 268.829282 -214.673172) (xy 268.776132 -214.669188)
			(xy 268.72417 -214.657328) (xy 268.674556 -214.637856) (xy 268.628398 -214.611207) (xy 268.586727 -214.577976)
			(xy 268.550475 -214.538905) (xy 268.520451 -214.494868) (xy 268.497325 -214.446847) (xy 268.481615 -214.395917)
			(xy 268.473672 -214.343213) (xy 254 -214.343213) (xy 254 -215.193351) (xy 264.373604 -215.193351)
			(xy 264.373604 -215.140053) (xy 264.381547 -215.087349) (xy 264.397257 -215.036419) (xy 264.420383 -214.988398)
			(xy 264.450407 -214.944361) (xy 264.486659 -214.90529) (xy 264.52833 -214.872059) (xy 264.574488 -214.84541)
			(xy 264.624102 -214.825938) (xy 264.676064 -214.814078) (xy 264.729214 -214.810095) (xy 264.782364 -214.814078)
			(xy 264.834326 -214.825938) (xy 264.88394 -214.84541) (xy 264.930098 -214.872059) (xy 264.971769 -214.90529)
			(xy 265.008021 -214.944361) (xy 265.038045 -214.988398) (xy 265.061171 -215.036419) (xy 265.076881 -215.087349)
			(xy 265.084824 -215.140053) (xy 265.085322 -215.166702) (xy 265.084824 -215.193351) (xy 279.461204 -215.193351)
			(xy 279.461204 -215.140053) (xy 279.469147 -215.087349) (xy 279.484857 -215.036419) (xy 279.507983 -214.988398)
			(xy 279.538007 -214.944361) (xy 279.574259 -214.90529) (xy 279.61593 -214.872059) (xy 279.662088 -214.84541)
			(xy 279.711702 -214.825938) (xy 279.763664 -214.814078) (xy 279.816814 -214.810095) (xy 279.869964 -214.814078)
			(xy 279.921926 -214.825938) (xy 279.97154 -214.84541) (xy 280.017698 -214.872059) (xy 280.059369 -214.90529)
			(xy 280.095621 -214.944361) (xy 280.125645 -214.988398) (xy 280.148771 -215.036419) (xy 280.164481 -215.087349)
			(xy 280.172424 -215.140053) (xy 280.172922 -215.166702) (xy 280.172424 -215.193351) (xy 294.548804 -215.193351)
			(xy 294.548804 -215.140053) (xy 294.556747 -215.087349) (xy 294.572457 -215.036419) (xy 294.595583 -214.988398)
			(xy 294.625607 -214.944361) (xy 294.661859 -214.90529) (xy 294.70353 -214.872059) (xy 294.749688 -214.84541)
			(xy 294.799302 -214.825938) (xy 294.851264 -214.814078) (xy 294.904414 -214.810095) (xy 294.957564 -214.814078)
			(xy 295.009526 -214.825938) (xy 295.05914 -214.84541) (xy 295.105298 -214.872059) (xy 295.146969 -214.90529)
			(xy 295.183221 -214.944361) (xy 295.213245 -214.988398) (xy 295.236371 -215.036419) (xy 295.252081 -215.087349)
			(xy 295.260024 -215.140053) (xy 295.260522 -215.166702) (xy 295.260024 -215.193351) (xy 295.252081 -215.246055)
			(xy 295.236371 -215.296985) (xy 295.213245 -215.345006) (xy 295.183221 -215.389043) (xy 295.146969 -215.428114)
			(xy 295.105298 -215.461345) (xy 295.05914 -215.487994) (xy 295.009526 -215.507466) (xy 294.957564 -215.519326)
			(xy 294.904414 -215.52331) (xy 294.851264 -215.519326) (xy 294.799302 -215.507466) (xy 294.749688 -215.487994)
			(xy 294.70353 -215.461345) (xy 294.661859 -215.428114) (xy 294.625607 -215.389043) (xy 294.595583 -215.345006)
			(xy 294.572457 -215.296985) (xy 294.556747 -215.246055) (xy 294.548804 -215.193351) (xy 280.172424 -215.193351)
			(xy 280.164481 -215.246055) (xy 280.148771 -215.296985) (xy 280.125645 -215.345006) (xy 280.095621 -215.389043)
			(xy 280.059369 -215.428114) (xy 280.017698 -215.461345) (xy 279.97154 -215.487994) (xy 279.921926 -215.507466)
			(xy 279.869964 -215.519326) (xy 279.816814 -215.52331) (xy 279.763664 -215.519326) (xy 279.711702 -215.507466)
			(xy 279.662088 -215.487994) (xy 279.61593 -215.461345) (xy 279.574259 -215.428114) (xy 279.538007 -215.389043)
			(xy 279.507983 -215.345006) (xy 279.484857 -215.296985) (xy 279.469147 -215.246055) (xy 279.461204 -215.193351)
			(xy 265.084824 -215.193351) (xy 265.076881 -215.246055) (xy 265.061171 -215.296985) (xy 265.038045 -215.345006)
			(xy 265.008021 -215.389043) (xy 264.971769 -215.428114) (xy 264.930098 -215.461345) (xy 264.88394 -215.487994)
			(xy 264.834326 -215.507466) (xy 264.782364 -215.519326) (xy 264.729214 -215.52331) (xy 264.676064 -215.519326)
			(xy 264.624102 -215.507466) (xy 264.574488 -215.487994) (xy 264.52833 -215.461345) (xy 264.486659 -215.428114)
			(xy 264.450407 -215.389043) (xy 264.420383 -215.345006) (xy 264.397257 -215.296985) (xy 264.381547 -215.246055)
			(xy 264.373604 -215.193351) (xy 254 -215.193351) (xy 254 -216.043235) (xy 268.473672 -216.043235)
			(xy 268.473672 -215.989937) (xy 268.481615 -215.937233) (xy 268.497325 -215.886303) (xy 268.520451 -215.838282)
			(xy 268.550475 -215.794245) (xy 268.586727 -215.755174) (xy 268.628398 -215.721943) (xy 268.674556 -215.695294)
			(xy 268.72417 -215.675822) (xy 268.776132 -215.663962) (xy 268.829282 -215.659979) (xy 268.882432 -215.663962)
			(xy 268.934394 -215.675822) (xy 268.984008 -215.695294) (xy 269.030166 -215.721943) (xy 269.071837 -215.755174)
			(xy 269.108089 -215.794245) (xy 269.138113 -215.838282) (xy 269.161239 -215.886303) (xy 269.176949 -215.937233)
			(xy 269.184892 -215.989937) (xy 269.18539 -216.016586) (xy 269.184892 -216.043235) (xy 283.561272 -216.043235)
			(xy 283.561272 -215.989937) (xy 283.569215 -215.937233) (xy 283.584925 -215.886303) (xy 283.608051 -215.838282)
			(xy 283.638075 -215.794245) (xy 283.674327 -215.755174) (xy 283.715998 -215.721943) (xy 283.762156 -215.695294)
			(xy 283.81177 -215.675822) (xy 283.863732 -215.663962) (xy 283.916882 -215.659979) (xy 283.970032 -215.663962)
			(xy 284.021994 -215.675822) (xy 284.071608 -215.695294) (xy 284.117766 -215.721943) (xy 284.159437 -215.755174)
			(xy 284.195689 -215.794245) (xy 284.225713 -215.838282) (xy 284.248839 -215.886303) (xy 284.264549 -215.937233)
			(xy 284.272492 -215.989937) (xy 284.27299 -216.016586) (xy 284.272492 -216.043235) (xy 298.648872 -216.043235)
			(xy 298.648872 -215.989937) (xy 298.656815 -215.937233) (xy 298.672525 -215.886303) (xy 298.695651 -215.838282)
			(xy 298.725675 -215.794245) (xy 298.761927 -215.755174) (xy 298.803598 -215.721943) (xy 298.849756 -215.695294)
			(xy 298.89937 -215.675822) (xy 298.951332 -215.663962) (xy 299.004482 -215.659979) (xy 299.057632 -215.663962)
			(xy 299.109594 -215.675822) (xy 299.159208 -215.695294) (xy 299.205366 -215.721943) (xy 299.247037 -215.755174)
			(xy 299.283289 -215.794245) (xy 299.313313 -215.838282) (xy 299.336439 -215.886303) (xy 299.352149 -215.937233)
			(xy 299.360092 -215.989937) (xy 299.36059 -216.016586) (xy 299.360092 -216.043235) (xy 299.352149 -216.095939)
			(xy 299.336439 -216.146869) (xy 299.313313 -216.19489) (xy 299.283289 -216.238927) (xy 299.247037 -216.277998)
			(xy 299.205366 -216.311229) (xy 299.159208 -216.337878) (xy 299.109594 -216.35735) (xy 299.057632 -216.36921)
			(xy 299.004482 -216.373194) (xy 298.951332 -216.36921) (xy 298.89937 -216.35735) (xy 298.849756 -216.337878)
			(xy 298.803598 -216.311229) (xy 298.761927 -216.277998) (xy 298.725675 -216.238927) (xy 298.695651 -216.19489)
			(xy 298.672525 -216.146869) (xy 298.656815 -216.095939) (xy 298.648872 -216.043235) (xy 284.272492 -216.043235)
			(xy 284.264549 -216.095939) (xy 284.248839 -216.146869) (xy 284.225713 -216.19489) (xy 284.195689 -216.238927)
			(xy 284.159437 -216.277998) (xy 284.117766 -216.311229) (xy 284.071608 -216.337878) (xy 284.021994 -216.35735)
			(xy 283.970032 -216.36921) (xy 283.916882 -216.373194) (xy 283.863732 -216.36921) (xy 283.81177 -216.35735)
			(xy 283.762156 -216.337878) (xy 283.715998 -216.311229) (xy 283.674327 -216.277998) (xy 283.638075 -216.238927)
			(xy 283.608051 -216.19489) (xy 283.584925 -216.146869) (xy 283.569215 -216.095939) (xy 283.561272 -216.043235)
			(xy 269.184892 -216.043235) (xy 269.176949 -216.095939) (xy 269.161239 -216.146869) (xy 269.138113 -216.19489)
			(xy 269.108089 -216.238927) (xy 269.071837 -216.277998) (xy 269.030166 -216.311229) (xy 268.984008 -216.337878)
			(xy 268.934394 -216.35735) (xy 268.882432 -216.36921) (xy 268.829282 -216.373194) (xy 268.776132 -216.36921)
			(xy 268.72417 -216.35735) (xy 268.674556 -216.337878) (xy 268.628398 -216.311229) (xy 268.586727 -216.277998)
			(xy 268.550475 -216.238927) (xy 268.520451 -216.19489) (xy 268.497325 -216.146869) (xy 268.481615 -216.095939)
			(xy 268.473672 -216.043235) (xy 254 -216.043235) (xy 254 -216.893373) (xy 264.373604 -216.893373)
			(xy 264.373604 -216.840075) (xy 264.381547 -216.787371) (xy 264.397257 -216.736441) (xy 264.420383 -216.68842)
			(xy 264.450407 -216.644383) (xy 264.486659 -216.605312) (xy 264.52833 -216.572081) (xy 264.574488 -216.545432)
			(xy 264.624102 -216.52596) (xy 264.676064 -216.5141) (xy 264.729214 -216.510117) (xy 264.782364 -216.5141)
			(xy 264.834326 -216.52596) (xy 264.88394 -216.545432) (xy 264.930098 -216.572081) (xy 264.971769 -216.605312)
			(xy 265.008021 -216.644383) (xy 265.038045 -216.68842) (xy 265.061171 -216.736441) (xy 265.076881 -216.787371)
			(xy 265.084824 -216.840075) (xy 265.085322 -216.866724) (xy 265.084824 -216.893373) (xy 279.461204 -216.893373)
			(xy 279.461204 -216.840075) (xy 279.469147 -216.787371) (xy 279.484857 -216.736441) (xy 279.507983 -216.68842)
			(xy 279.538007 -216.644383) (xy 279.574259 -216.605312) (xy 279.61593 -216.572081) (xy 279.662088 -216.545432)
			(xy 279.711702 -216.52596) (xy 279.763664 -216.5141) (xy 279.816814 -216.510117) (xy 279.869964 -216.5141)
			(xy 279.921926 -216.52596) (xy 279.97154 -216.545432) (xy 280.017698 -216.572081) (xy 280.059369 -216.605312)
			(xy 280.095621 -216.644383) (xy 280.125645 -216.68842) (xy 280.148771 -216.736441) (xy 280.164481 -216.787371)
			(xy 280.172424 -216.840075) (xy 280.172922 -216.866724) (xy 280.172424 -216.893373) (xy 294.548804 -216.893373)
			(xy 294.548804 -216.840075) (xy 294.556747 -216.787371) (xy 294.572457 -216.736441) (xy 294.595583 -216.68842)
			(xy 294.625607 -216.644383) (xy 294.661859 -216.605312) (xy 294.70353 -216.572081) (xy 294.749688 -216.545432)
			(xy 294.799302 -216.52596) (xy 294.851264 -216.5141) (xy 294.904414 -216.510117) (xy 294.957564 -216.5141)
			(xy 295.009526 -216.52596) (xy 295.05914 -216.545432) (xy 295.105298 -216.572081) (xy 295.146969 -216.605312)
			(xy 295.183221 -216.644383) (xy 295.213245 -216.68842) (xy 295.236371 -216.736441) (xy 295.252081 -216.787371)
			(xy 295.260024 -216.840075) (xy 295.260522 -216.866724) (xy 295.260024 -216.893373) (xy 295.252081 -216.946077)
			(xy 295.236371 -216.997007) (xy 295.213245 -217.045028) (xy 295.183221 -217.089065) (xy 295.146969 -217.128136)
			(xy 295.105298 -217.161367) (xy 295.05914 -217.188016) (xy 295.009526 -217.207488) (xy 294.957564 -217.219348)
			(xy 294.904414 -217.223332) (xy 294.851264 -217.219348) (xy 294.799302 -217.207488) (xy 294.749688 -217.188016)
			(xy 294.70353 -217.161367) (xy 294.661859 -217.128136) (xy 294.625607 -217.089065) (xy 294.595583 -217.045028)
			(xy 294.572457 -216.997007) (xy 294.556747 -216.946077) (xy 294.548804 -216.893373) (xy 280.172424 -216.893373)
			(xy 280.164481 -216.946077) (xy 280.148771 -216.997007) (xy 280.125645 -217.045028) (xy 280.095621 -217.089065)
			(xy 280.059369 -217.128136) (xy 280.017698 -217.161367) (xy 279.97154 -217.188016) (xy 279.921926 -217.207488)
			(xy 279.869964 -217.219348) (xy 279.816814 -217.223332) (xy 279.763664 -217.219348) (xy 279.711702 -217.207488)
			(xy 279.662088 -217.188016) (xy 279.61593 -217.161367) (xy 279.574259 -217.128136) (xy 279.538007 -217.089065)
			(xy 279.507983 -217.045028) (xy 279.484857 -216.997007) (xy 279.469147 -216.946077) (xy 279.461204 -216.893373)
			(xy 265.084824 -216.893373) (xy 265.076881 -216.946077) (xy 265.061171 -216.997007) (xy 265.038045 -217.045028)
			(xy 265.008021 -217.089065) (xy 264.971769 -217.128136) (xy 264.930098 -217.161367) (xy 264.88394 -217.188016)
			(xy 264.834326 -217.207488) (xy 264.782364 -217.219348) (xy 264.729214 -217.223332) (xy 264.676064 -217.219348)
			(xy 264.624102 -217.207488) (xy 264.574488 -217.188016) (xy 264.52833 -217.161367) (xy 264.486659 -217.128136)
			(xy 264.450407 -217.089065) (xy 264.420383 -217.045028) (xy 264.397257 -216.997007) (xy 264.381547 -216.946077)
			(xy 264.373604 -216.893373) (xy 254 -216.893373) (xy 254 -217.743257) (xy 268.473672 -217.743257)
			(xy 268.473672 -217.689959) (xy 268.481615 -217.637255) (xy 268.497325 -217.586325) (xy 268.520451 -217.538304)
			(xy 268.550475 -217.494267) (xy 268.586727 -217.455196) (xy 268.628398 -217.421965) (xy 268.674556 -217.395316)
			(xy 268.72417 -217.375844) (xy 268.776132 -217.363984) (xy 268.829282 -217.360001) (xy 268.882432 -217.363984)
			(xy 268.934394 -217.375844) (xy 268.984008 -217.395316) (xy 269.030166 -217.421965) (xy 269.071837 -217.455196)
			(xy 269.108089 -217.494267) (xy 269.138113 -217.538304) (xy 269.161239 -217.586325) (xy 269.176949 -217.637255)
			(xy 269.184892 -217.689959) (xy 269.18539 -217.716608) (xy 269.184892 -217.743257) (xy 283.561272 -217.743257)
			(xy 283.561272 -217.689959) (xy 283.569215 -217.637255) (xy 283.584925 -217.586325) (xy 283.608051 -217.538304)
			(xy 283.638075 -217.494267) (xy 283.674327 -217.455196) (xy 283.715998 -217.421965) (xy 283.762156 -217.395316)
			(xy 283.81177 -217.375844) (xy 283.863732 -217.363984) (xy 283.916882 -217.360001) (xy 283.970032 -217.363984)
			(xy 284.021994 -217.375844) (xy 284.071608 -217.395316) (xy 284.117766 -217.421965) (xy 284.159437 -217.455196)
			(xy 284.195689 -217.494267) (xy 284.225713 -217.538304) (xy 284.248839 -217.586325) (xy 284.264549 -217.637255)
			(xy 284.272492 -217.689959) (xy 284.27299 -217.716608) (xy 284.272492 -217.743257) (xy 298.648872 -217.743257)
			(xy 298.648872 -217.689959) (xy 298.656815 -217.637255) (xy 298.672525 -217.586325) (xy 298.695651 -217.538304)
			(xy 298.725675 -217.494267) (xy 298.761927 -217.455196) (xy 298.803598 -217.421965) (xy 298.849756 -217.395316)
			(xy 298.89937 -217.375844) (xy 298.951332 -217.363984) (xy 299.004482 -217.360001) (xy 299.057632 -217.363984)
			(xy 299.109594 -217.375844) (xy 299.159208 -217.395316) (xy 299.205366 -217.421965) (xy 299.247037 -217.455196)
			(xy 299.283289 -217.494267) (xy 299.313313 -217.538304) (xy 299.336439 -217.586325) (xy 299.352149 -217.637255)
			(xy 299.360092 -217.689959) (xy 299.36059 -217.716608) (xy 299.360092 -217.743257) (xy 299.352149 -217.795961)
			(xy 299.336439 -217.846891) (xy 299.313313 -217.894912) (xy 299.283289 -217.938949) (xy 299.247037 -217.97802)
			(xy 299.205366 -218.011251) (xy 299.159208 -218.0379) (xy 299.109594 -218.057372) (xy 299.057632 -218.069232)
			(xy 299.004482 -218.073216) (xy 298.951332 -218.069232) (xy 298.89937 -218.057372) (xy 298.849756 -218.0379)
			(xy 298.803598 -218.011251) (xy 298.761927 -217.97802) (xy 298.725675 -217.938949) (xy 298.695651 -217.894912)
			(xy 298.672525 -217.846891) (xy 298.656815 -217.795961) (xy 298.648872 -217.743257) (xy 284.272492 -217.743257)
			(xy 284.264549 -217.795961) (xy 284.248839 -217.846891) (xy 284.225713 -217.894912) (xy 284.195689 -217.938949)
			(xy 284.159437 -217.97802) (xy 284.117766 -218.011251) (xy 284.071608 -218.0379) (xy 284.021994 -218.057372)
			(xy 283.970032 -218.069232) (xy 283.916882 -218.073216) (xy 283.863732 -218.069232) (xy 283.81177 -218.057372)
			(xy 283.762156 -218.0379) (xy 283.715998 -218.011251) (xy 283.674327 -217.97802) (xy 283.638075 -217.938949)
			(xy 283.608051 -217.894912) (xy 283.584925 -217.846891) (xy 283.569215 -217.795961) (xy 283.561272 -217.743257)
			(xy 269.184892 -217.743257) (xy 269.176949 -217.795961) (xy 269.161239 -217.846891) (xy 269.138113 -217.894912)
			(xy 269.108089 -217.938949) (xy 269.071837 -217.97802) (xy 269.030166 -218.011251) (xy 268.984008 -218.0379)
			(xy 268.934394 -218.057372) (xy 268.882432 -218.069232) (xy 268.829282 -218.073216) (xy 268.776132 -218.069232)
			(xy 268.72417 -218.057372) (xy 268.674556 -218.0379) (xy 268.628398 -218.011251) (xy 268.586727 -217.97802)
			(xy 268.550475 -217.938949) (xy 268.520451 -217.894912) (xy 268.497325 -217.846891) (xy 268.481615 -217.795961)
			(xy 268.473672 -217.743257) (xy 254 -217.743257) (xy 254 -218.593395) (xy 264.373604 -218.593395)
			(xy 264.373604 -218.540097) (xy 264.381547 -218.487393) (xy 264.397257 -218.436463) (xy 264.420383 -218.388442)
			(xy 264.450407 -218.344405) (xy 264.486659 -218.305334) (xy 264.52833 -218.272103) (xy 264.574488 -218.245454)
			(xy 264.624102 -218.225982) (xy 264.676064 -218.214122) (xy 264.729214 -218.210139) (xy 264.782364 -218.214122)
			(xy 264.834326 -218.225982) (xy 264.88394 -218.245454) (xy 264.930098 -218.272103) (xy 264.971769 -218.305334)
			(xy 265.008021 -218.344405) (xy 265.038045 -218.388442) (xy 265.061171 -218.436463) (xy 265.076881 -218.487393)
			(xy 265.084824 -218.540097) (xy 265.085322 -218.566746) (xy 265.084824 -218.593395) (xy 268.473672 -218.593395)
			(xy 268.473672 -218.540097) (xy 268.481615 -218.487393) (xy 268.497325 -218.436463) (xy 268.520451 -218.388442)
			(xy 268.550475 -218.344405) (xy 268.586727 -218.305334) (xy 268.628398 -218.272103) (xy 268.674556 -218.245454)
			(xy 268.72417 -218.225982) (xy 268.776132 -218.214122) (xy 268.829282 -218.210139) (xy 268.882432 -218.214122)
			(xy 268.934394 -218.225982) (xy 268.984008 -218.245454) (xy 269.030166 -218.272103) (xy 269.071837 -218.305334)
			(xy 269.108089 -218.344405) (xy 269.138113 -218.388442) (xy 269.161239 -218.436463) (xy 269.176949 -218.487393)
			(xy 269.184892 -218.540097) (xy 269.18539 -218.566746) (xy 269.184892 -218.593395) (xy 279.461204 -218.593395)
			(xy 279.461204 -218.540097) (xy 279.469147 -218.487393) (xy 279.484857 -218.436463) (xy 279.507983 -218.388442)
			(xy 279.538007 -218.344405) (xy 279.574259 -218.305334) (xy 279.61593 -218.272103) (xy 279.662088 -218.245454)
			(xy 279.711702 -218.225982) (xy 279.763664 -218.214122) (xy 279.816814 -218.210139) (xy 279.869964 -218.214122)
			(xy 279.921926 -218.225982) (xy 279.97154 -218.245454) (xy 280.017698 -218.272103) (xy 280.059369 -218.305334)
			(xy 280.095621 -218.344405) (xy 280.125645 -218.388442) (xy 280.148771 -218.436463) (xy 280.164481 -218.487393)
			(xy 280.172424 -218.540097) (xy 280.172922 -218.566746) (xy 280.172424 -218.593395) (xy 283.561272 -218.593395)
			(xy 283.561272 -218.540097) (xy 283.569215 -218.487393) (xy 283.584925 -218.436463) (xy 283.608051 -218.388442)
			(xy 283.638075 -218.344405) (xy 283.674327 -218.305334) (xy 283.715998 -218.272103) (xy 283.762156 -218.245454)
			(xy 283.81177 -218.225982) (xy 283.863732 -218.214122) (xy 283.916882 -218.210139) (xy 283.970032 -218.214122)
			(xy 284.021994 -218.225982) (xy 284.071608 -218.245454) (xy 284.117766 -218.272103) (xy 284.159437 -218.305334)
			(xy 284.195689 -218.344405) (xy 284.225713 -218.388442) (xy 284.248839 -218.436463) (xy 284.264549 -218.487393)
			(xy 284.272492 -218.540097) (xy 284.27299 -218.566746) (xy 284.272492 -218.593395) (xy 294.548804 -218.593395)
			(xy 294.548804 -218.540097) (xy 294.556747 -218.487393) (xy 294.572457 -218.436463) (xy 294.595583 -218.388442)
			(xy 294.625607 -218.344405) (xy 294.661859 -218.305334) (xy 294.70353 -218.272103) (xy 294.749688 -218.245454)
			(xy 294.799302 -218.225982) (xy 294.851264 -218.214122) (xy 294.904414 -218.210139) (xy 294.957564 -218.214122)
			(xy 295.009526 -218.225982) (xy 295.05914 -218.245454) (xy 295.105298 -218.272103) (xy 295.146969 -218.305334)
			(xy 295.183221 -218.344405) (xy 295.213245 -218.388442) (xy 295.236371 -218.436463) (xy 295.252081 -218.487393)
			(xy 295.260024 -218.540097) (xy 295.260522 -218.566746) (xy 295.260024 -218.593395) (xy 298.648872 -218.593395)
			(xy 298.648872 -218.540097) (xy 298.656815 -218.487393) (xy 298.672525 -218.436463) (xy 298.695651 -218.388442)
			(xy 298.725675 -218.344405) (xy 298.761927 -218.305334) (xy 298.803598 -218.272103) (xy 298.849756 -218.245454)
			(xy 298.89937 -218.225982) (xy 298.951332 -218.214122) (xy 299.004482 -218.210139) (xy 299.057632 -218.214122)
			(xy 299.109594 -218.225982) (xy 299.159208 -218.245454) (xy 299.205366 -218.272103) (xy 299.247037 -218.305334)
			(xy 299.283289 -218.344405) (xy 299.313313 -218.388442) (xy 299.336439 -218.436463) (xy 299.352149 -218.487393)
			(xy 299.360092 -218.540097) (xy 299.36059 -218.566746) (xy 299.360092 -218.593395) (xy 299.352149 -218.646099)
			(xy 299.336439 -218.697029) (xy 299.313313 -218.74505) (xy 299.283289 -218.789087) (xy 299.247037 -218.828158)
			(xy 299.205366 -218.861389) (xy 299.159208 -218.888038) (xy 299.109594 -218.90751) (xy 299.057632 -218.91937)
			(xy 299.004482 -218.923354) (xy 298.951332 -218.91937) (xy 298.89937 -218.90751) (xy 298.849756 -218.888038)
			(xy 298.803598 -218.861389) (xy 298.761927 -218.828158) (xy 298.725675 -218.789087) (xy 298.695651 -218.74505)
			(xy 298.672525 -218.697029) (xy 298.656815 -218.646099) (xy 298.648872 -218.593395) (xy 295.260024 -218.593395)
			(xy 295.252081 -218.646099) (xy 295.236371 -218.697029) (xy 295.213245 -218.74505) (xy 295.183221 -218.789087)
			(xy 295.146969 -218.828158) (xy 295.105298 -218.861389) (xy 295.05914 -218.888038) (xy 295.009526 -218.90751)
			(xy 294.957564 -218.91937) (xy 294.904414 -218.923354) (xy 294.851264 -218.91937) (xy 294.799302 -218.90751)
			(xy 294.749688 -218.888038) (xy 294.70353 -218.861389) (xy 294.661859 -218.828158) (xy 294.625607 -218.789087)
			(xy 294.595583 -218.74505) (xy 294.572457 -218.697029) (xy 294.556747 -218.646099) (xy 294.548804 -218.593395)
			(xy 284.272492 -218.593395) (xy 284.264549 -218.646099) (xy 284.248839 -218.697029) (xy 284.225713 -218.74505)
			(xy 284.195689 -218.789087) (xy 284.159437 -218.828158) (xy 284.117766 -218.861389) (xy 284.071608 -218.888038)
			(xy 284.021994 -218.90751) (xy 283.970032 -218.91937) (xy 283.916882 -218.923354) (xy 283.863732 -218.91937)
			(xy 283.81177 -218.90751) (xy 283.762156 -218.888038) (xy 283.715998 -218.861389) (xy 283.674327 -218.828158)
			(xy 283.638075 -218.789087) (xy 283.608051 -218.74505) (xy 283.584925 -218.697029) (xy 283.569215 -218.646099)
			(xy 283.561272 -218.593395) (xy 280.172424 -218.593395) (xy 280.164481 -218.646099) (xy 280.148771 -218.697029)
			(xy 280.125645 -218.74505) (xy 280.095621 -218.789087) (xy 280.059369 -218.828158) (xy 280.017698 -218.861389)
			(xy 279.97154 -218.888038) (xy 279.921926 -218.90751) (xy 279.869964 -218.91937) (xy 279.816814 -218.923354)
			(xy 279.763664 -218.91937) (xy 279.711702 -218.90751) (xy 279.662088 -218.888038) (xy 279.61593 -218.861389)
			(xy 279.574259 -218.828158) (xy 279.538007 -218.789087) (xy 279.507983 -218.74505) (xy 279.484857 -218.697029)
			(xy 279.469147 -218.646099) (xy 279.461204 -218.593395) (xy 269.184892 -218.593395) (xy 269.176949 -218.646099)
			(xy 269.161239 -218.697029) (xy 269.138113 -218.74505) (xy 269.108089 -218.789087) (xy 269.071837 -218.828158)
			(xy 269.030166 -218.861389) (xy 268.984008 -218.888038) (xy 268.934394 -218.90751) (xy 268.882432 -218.91937)
			(xy 268.829282 -218.923354) (xy 268.776132 -218.91937) (xy 268.72417 -218.90751) (xy 268.674556 -218.888038)
			(xy 268.628398 -218.861389) (xy 268.586727 -218.828158) (xy 268.550475 -218.789087) (xy 268.520451 -218.74505)
			(xy 268.497325 -218.697029) (xy 268.481615 -218.646099) (xy 268.473672 -218.593395) (xy 265.084824 -218.593395)
			(xy 265.076881 -218.646099) (xy 265.061171 -218.697029) (xy 265.038045 -218.74505) (xy 265.008021 -218.789087)
			(xy 264.971769 -218.828158) (xy 264.930098 -218.861389) (xy 264.88394 -218.888038) (xy 264.834326 -218.90751)
			(xy 264.782364 -218.91937) (xy 264.729214 -218.923354) (xy 264.676064 -218.91937) (xy 264.624102 -218.90751)
			(xy 264.574488 -218.888038) (xy 264.52833 -218.861389) (xy 264.486659 -218.828158) (xy 264.450407 -218.789087)
			(xy 264.420383 -218.74505) (xy 264.397257 -218.697029) (xy 264.381547 -218.646099) (xy 264.373604 -218.593395)
			(xy 254 -218.593395) (xy 254 -219.443279) (xy 264.373604 -219.443279) (xy 264.373604 -219.389981)
			(xy 264.381547 -219.337277) (xy 264.397257 -219.286347) (xy 264.420383 -219.238326) (xy 264.450407 -219.194289)
			(xy 264.486659 -219.155218) (xy 264.52833 -219.121987) (xy 264.574488 -219.095338) (xy 264.624102 -219.075866)
			(xy 264.676064 -219.064006) (xy 264.729214 -219.060023) (xy 264.782364 -219.064006) (xy 264.834326 -219.075866)
			(xy 264.88394 -219.095338) (xy 264.930098 -219.121987) (xy 264.971769 -219.155218) (xy 265.008021 -219.194289)
			(xy 265.038045 -219.238326) (xy 265.061171 -219.286347) (xy 265.076881 -219.337277) (xy 265.084824 -219.389981)
			(xy 265.085322 -219.41663) (xy 265.084824 -219.443279) (xy 279.461204 -219.443279) (xy 279.461204 -219.389981)
			(xy 279.469147 -219.337277) (xy 279.484857 -219.286347) (xy 279.507983 -219.238326) (xy 279.538007 -219.194289)
			(xy 279.574259 -219.155218) (xy 279.61593 -219.121987) (xy 279.662088 -219.095338) (xy 279.711702 -219.075866)
			(xy 279.763664 -219.064006) (xy 279.816814 -219.060023) (xy 279.869964 -219.064006) (xy 279.921926 -219.075866)
			(xy 279.97154 -219.095338) (xy 280.017698 -219.121987) (xy 280.059369 -219.155218) (xy 280.095621 -219.194289)
			(xy 280.125645 -219.238326) (xy 280.148771 -219.286347) (xy 280.164481 -219.337277) (xy 280.172424 -219.389981)
			(xy 280.172922 -219.41663) (xy 280.172424 -219.443279) (xy 294.548804 -219.443279) (xy 294.548804 -219.389981)
			(xy 294.556747 -219.337277) (xy 294.572457 -219.286347) (xy 294.595583 -219.238326) (xy 294.625607 -219.194289)
			(xy 294.661859 -219.155218) (xy 294.70353 -219.121987) (xy 294.749688 -219.095338) (xy 294.799302 -219.075866)
			(xy 294.851264 -219.064006) (xy 294.904414 -219.060023) (xy 294.957564 -219.064006) (xy 295.009526 -219.075866)
			(xy 295.05914 -219.095338) (xy 295.105298 -219.121987) (xy 295.146969 -219.155218) (xy 295.183221 -219.194289)
			(xy 295.213245 -219.238326) (xy 295.236371 -219.286347) (xy 295.252081 -219.337277) (xy 295.260024 -219.389981)
			(xy 295.260522 -219.41663) (xy 295.260024 -219.443279) (xy 295.252081 -219.495983) (xy 295.236371 -219.546913)
			(xy 295.213245 -219.594934) (xy 295.183221 -219.638971) (xy 295.146969 -219.678042) (xy 295.105298 -219.711273)
			(xy 295.05914 -219.737922) (xy 295.009526 -219.757394) (xy 294.957564 -219.769254) (xy 294.904414 -219.773238)
			(xy 294.851264 -219.769254) (xy 294.799302 -219.757394) (xy 294.749688 -219.737922) (xy 294.70353 -219.711273)
			(xy 294.661859 -219.678042) (xy 294.625607 -219.638971) (xy 294.595583 -219.594934) (xy 294.572457 -219.546913)
			(xy 294.556747 -219.495983) (xy 294.548804 -219.443279) (xy 280.172424 -219.443279) (xy 280.164481 -219.495983)
			(xy 280.148771 -219.546913) (xy 280.125645 -219.594934) (xy 280.095621 -219.638971) (xy 280.059369 -219.678042)
			(xy 280.017698 -219.711273) (xy 279.97154 -219.737922) (xy 279.921926 -219.757394) (xy 279.869964 -219.769254)
			(xy 279.816814 -219.773238) (xy 279.763664 -219.769254) (xy 279.711702 -219.757394) (xy 279.662088 -219.737922)
			(xy 279.61593 -219.711273) (xy 279.574259 -219.678042) (xy 279.538007 -219.638971) (xy 279.507983 -219.594934)
			(xy 279.484857 -219.546913) (xy 279.469147 -219.495983) (xy 279.461204 -219.443279) (xy 265.084824 -219.443279)
			(xy 265.076881 -219.495983) (xy 265.061171 -219.546913) (xy 265.038045 -219.594934) (xy 265.008021 -219.638971)
			(xy 264.971769 -219.678042) (xy 264.930098 -219.711273) (xy 264.88394 -219.737922) (xy 264.834326 -219.757394)
			(xy 264.782364 -219.769254) (xy 264.729214 -219.773238) (xy 264.676064 -219.769254) (xy 264.624102 -219.757394)
			(xy 264.574488 -219.737922) (xy 264.52833 -219.711273) (xy 264.486659 -219.678042) (xy 264.450407 -219.638971)
			(xy 264.420383 -219.594934) (xy 264.397257 -219.546913) (xy 264.381547 -219.495983) (xy 264.373604 -219.443279)
			(xy 254 -219.443279) (xy 254 -220.293417) (xy 268.473672 -220.293417) (xy 268.473672 -220.240119)
			(xy 268.481615 -220.187415) (xy 268.497325 -220.136485) (xy 268.520451 -220.088464) (xy 268.550475 -220.044427)
			(xy 268.586727 -220.005356) (xy 268.628398 -219.972125) (xy 268.674556 -219.945476) (xy 268.72417 -219.926004)
			(xy 268.776132 -219.914144) (xy 268.829282 -219.910161) (xy 268.882432 -219.914144) (xy 268.934394 -219.926004)
			(xy 268.984008 -219.945476) (xy 269.030166 -219.972125) (xy 269.071837 -220.005356) (xy 269.108089 -220.044427)
			(xy 269.138113 -220.088464) (xy 269.161239 -220.136485) (xy 269.176949 -220.187415) (xy 269.184892 -220.240119)
			(xy 269.18539 -220.266768) (xy 269.184892 -220.293417) (xy 283.561272 -220.293417) (xy 283.561272 -220.240119)
			(xy 283.569215 -220.187415) (xy 283.584925 -220.136485) (xy 283.608051 -220.088464) (xy 283.638075 -220.044427)
			(xy 283.674327 -220.005356) (xy 283.715998 -219.972125) (xy 283.762156 -219.945476) (xy 283.81177 -219.926004)
			(xy 283.863732 -219.914144) (xy 283.916882 -219.910161) (xy 283.970032 -219.914144) (xy 284.021994 -219.926004)
			(xy 284.071608 -219.945476) (xy 284.117766 -219.972125) (xy 284.159437 -220.005356) (xy 284.195689 -220.044427)
			(xy 284.225713 -220.088464) (xy 284.248839 -220.136485) (xy 284.264549 -220.187415) (xy 284.272492 -220.240119)
			(xy 284.27299 -220.266768) (xy 284.272492 -220.293417) (xy 298.648872 -220.293417) (xy 298.648872 -220.240119)
			(xy 298.656815 -220.187415) (xy 298.672525 -220.136485) (xy 298.695651 -220.088464) (xy 298.725675 -220.044427)
			(xy 298.761927 -220.005356) (xy 298.803598 -219.972125) (xy 298.849756 -219.945476) (xy 298.89937 -219.926004)
			(xy 298.951332 -219.914144) (xy 299.004482 -219.910161) (xy 299.057632 -219.914144) (xy 299.109594 -219.926004)
			(xy 299.159208 -219.945476) (xy 299.205366 -219.972125) (xy 299.247037 -220.005356) (xy 299.283289 -220.044427)
			(xy 299.313313 -220.088464) (xy 299.336439 -220.136485) (xy 299.352149 -220.187415) (xy 299.360092 -220.240119)
			(xy 299.36059 -220.266768) (xy 299.360092 -220.293417) (xy 299.352149 -220.346121) (xy 299.336439 -220.397051)
			(xy 299.313313 -220.445072) (xy 299.283289 -220.489109) (xy 299.247037 -220.52818) (xy 299.205366 -220.561411)
			(xy 299.159208 -220.58806) (xy 299.109594 -220.607532) (xy 299.057632 -220.619392) (xy 299.004482 -220.623376)
			(xy 298.951332 -220.619392) (xy 298.89937 -220.607532) (xy 298.849756 -220.58806) (xy 298.803598 -220.561411)
			(xy 298.761927 -220.52818) (xy 298.725675 -220.489109) (xy 298.695651 -220.445072) (xy 298.672525 -220.397051)
			(xy 298.656815 -220.346121) (xy 298.648872 -220.293417) (xy 284.272492 -220.293417) (xy 284.264549 -220.346121)
			(xy 284.248839 -220.397051) (xy 284.225713 -220.445072) (xy 284.195689 -220.489109) (xy 284.159437 -220.52818)
			(xy 284.117766 -220.561411) (xy 284.071608 -220.58806) (xy 284.021994 -220.607532) (xy 283.970032 -220.619392)
			(xy 283.916882 -220.623376) (xy 283.863732 -220.619392) (xy 283.81177 -220.607532) (xy 283.762156 -220.58806)
			(xy 283.715998 -220.561411) (xy 283.674327 -220.52818) (xy 283.638075 -220.489109) (xy 283.608051 -220.445072)
			(xy 283.584925 -220.397051) (xy 283.569215 -220.346121) (xy 283.561272 -220.293417) (xy 269.184892 -220.293417)
			(xy 269.176949 -220.346121) (xy 269.161239 -220.397051) (xy 269.138113 -220.445072) (xy 269.108089 -220.489109)
			(xy 269.071837 -220.52818) (xy 269.030166 -220.561411) (xy 268.984008 -220.58806) (xy 268.934394 -220.607532)
			(xy 268.882432 -220.619392) (xy 268.829282 -220.623376) (xy 268.776132 -220.619392) (xy 268.72417 -220.607532)
			(xy 268.674556 -220.58806) (xy 268.628398 -220.561411) (xy 268.586727 -220.52818) (xy 268.550475 -220.489109)
			(xy 268.520451 -220.445072) (xy 268.497325 -220.397051) (xy 268.481615 -220.346121) (xy 268.473672 -220.293417)
			(xy 254 -220.293417) (xy 254 -221.143301) (xy 264.373604 -221.143301) (xy 264.373604 -221.090003)
			(xy 264.381547 -221.037299) (xy 264.397257 -220.986369) (xy 264.420383 -220.938348) (xy 264.450407 -220.894311)
			(xy 264.486659 -220.85524) (xy 264.52833 -220.822009) (xy 264.574488 -220.79536) (xy 264.624102 -220.775888)
			(xy 264.676064 -220.764028) (xy 264.729214 -220.760045) (xy 264.782364 -220.764028) (xy 264.834326 -220.775888)
			(xy 264.88394 -220.79536) (xy 264.930098 -220.822009) (xy 264.971769 -220.85524) (xy 265.008021 -220.894311)
			(xy 265.038045 -220.938348) (xy 265.061171 -220.986369) (xy 265.076881 -221.037299) (xy 265.084824 -221.090003)
			(xy 265.085322 -221.116652) (xy 265.084824 -221.143301) (xy 279.461204 -221.143301) (xy 279.461204 -221.090003)
			(xy 279.469147 -221.037299) (xy 279.484857 -220.986369) (xy 279.507983 -220.938348) (xy 279.538007 -220.894311)
			(xy 279.574259 -220.85524) (xy 279.61593 -220.822009) (xy 279.662088 -220.79536) (xy 279.711702 -220.775888)
			(xy 279.763664 -220.764028) (xy 279.816814 -220.760045) (xy 279.869964 -220.764028) (xy 279.921926 -220.775888)
			(xy 279.97154 -220.79536) (xy 280.017698 -220.822009) (xy 280.059369 -220.85524) (xy 280.095621 -220.894311)
			(xy 280.125645 -220.938348) (xy 280.148771 -220.986369) (xy 280.164481 -221.037299) (xy 280.172424 -221.090003)
			(xy 280.172922 -221.116652) (xy 280.172424 -221.143301) (xy 294.548804 -221.143301) (xy 294.548804 -221.090003)
			(xy 294.556747 -221.037299) (xy 294.572457 -220.986369) (xy 294.595583 -220.938348) (xy 294.625607 -220.894311)
			(xy 294.661859 -220.85524) (xy 294.70353 -220.822009) (xy 294.749688 -220.79536) (xy 294.799302 -220.775888)
			(xy 294.851264 -220.764028) (xy 294.904414 -220.760045) (xy 294.957564 -220.764028) (xy 295.009526 -220.775888)
			(xy 295.05914 -220.79536) (xy 295.105298 -220.822009) (xy 295.146969 -220.85524) (xy 295.183221 -220.894311)
			(xy 295.213245 -220.938348) (xy 295.236371 -220.986369) (xy 295.252081 -221.037299) (xy 295.260024 -221.090003)
			(xy 295.260522 -221.116652) (xy 295.260024 -221.143301) (xy 295.252081 -221.196005) (xy 295.236371 -221.246935)
			(xy 295.213245 -221.294956) (xy 295.183221 -221.338993) (xy 295.146969 -221.378064) (xy 295.105298 -221.411295)
			(xy 295.05914 -221.437944) (xy 295.009526 -221.457416) (xy 294.957564 -221.469276) (xy 294.904414 -221.47326)
			(xy 294.851264 -221.469276) (xy 294.799302 -221.457416) (xy 294.749688 -221.437944) (xy 294.70353 -221.411295)
			(xy 294.661859 -221.378064) (xy 294.625607 -221.338993) (xy 294.595583 -221.294956) (xy 294.572457 -221.246935)
			(xy 294.556747 -221.196005) (xy 294.548804 -221.143301) (xy 280.172424 -221.143301) (xy 280.164481 -221.196005)
			(xy 280.148771 -221.246935) (xy 280.125645 -221.294956) (xy 280.095621 -221.338993) (xy 280.059369 -221.378064)
			(xy 280.017698 -221.411295) (xy 279.97154 -221.437944) (xy 279.921926 -221.457416) (xy 279.869964 -221.469276)
			(xy 279.816814 -221.47326) (xy 279.763664 -221.469276) (xy 279.711702 -221.457416) (xy 279.662088 -221.437944)
			(xy 279.61593 -221.411295) (xy 279.574259 -221.378064) (xy 279.538007 -221.338993) (xy 279.507983 -221.294956)
			(xy 279.484857 -221.246935) (xy 279.469147 -221.196005) (xy 279.461204 -221.143301) (xy 265.084824 -221.143301)
			(xy 265.076881 -221.196005) (xy 265.061171 -221.246935) (xy 265.038045 -221.294956) (xy 265.008021 -221.338993)
			(xy 264.971769 -221.378064) (xy 264.930098 -221.411295) (xy 264.88394 -221.437944) (xy 264.834326 -221.457416)
			(xy 264.782364 -221.469276) (xy 264.729214 -221.47326) (xy 264.676064 -221.469276) (xy 264.624102 -221.457416)
			(xy 264.574488 -221.437944) (xy 264.52833 -221.411295) (xy 264.486659 -221.378064) (xy 264.450407 -221.338993)
			(xy 264.420383 -221.294956) (xy 264.397257 -221.246935) (xy 264.381547 -221.196005) (xy 264.373604 -221.143301)
			(xy 254 -221.143301) (xy 254 -221.993439) (xy 268.473672 -221.993439) (xy 268.473672 -221.940141)
			(xy 268.481615 -221.887437) (xy 268.497325 -221.836507) (xy 268.520451 -221.788486) (xy 268.550475 -221.744449)
			(xy 268.586727 -221.705378) (xy 268.628398 -221.672147) (xy 268.674556 -221.645498) (xy 268.72417 -221.626026)
			(xy 268.776132 -221.614166) (xy 268.829282 -221.610183) (xy 268.882432 -221.614166) (xy 268.934394 -221.626026)
			(xy 268.984008 -221.645498) (xy 269.030166 -221.672147) (xy 269.071837 -221.705378) (xy 269.108089 -221.744449)
			(xy 269.138113 -221.788486) (xy 269.161239 -221.836507) (xy 269.176949 -221.887437) (xy 269.184892 -221.940141)
			(xy 269.18539 -221.96679) (xy 269.184892 -221.993439) (xy 283.561272 -221.993439) (xy 283.561272 -221.940141)
			(xy 283.569215 -221.887437) (xy 283.584925 -221.836507) (xy 283.608051 -221.788486) (xy 283.638075 -221.744449)
			(xy 283.674327 -221.705378) (xy 283.715998 -221.672147) (xy 283.762156 -221.645498) (xy 283.81177 -221.626026)
			(xy 283.863732 -221.614166) (xy 283.916882 -221.610183) (xy 283.970032 -221.614166) (xy 284.021994 -221.626026)
			(xy 284.071608 -221.645498) (xy 284.117766 -221.672147) (xy 284.159437 -221.705378) (xy 284.195689 -221.744449)
			(xy 284.225713 -221.788486) (xy 284.248839 -221.836507) (xy 284.264549 -221.887437) (xy 284.272492 -221.940141)
			(xy 284.27299 -221.96679) (xy 284.272492 -221.993439) (xy 298.648872 -221.993439) (xy 298.648872 -221.940141)
			(xy 298.656815 -221.887437) (xy 298.672525 -221.836507) (xy 298.695651 -221.788486) (xy 298.725675 -221.744449)
			(xy 298.761927 -221.705378) (xy 298.803598 -221.672147) (xy 298.849756 -221.645498) (xy 298.89937 -221.626026)
			(xy 298.951332 -221.614166) (xy 299.004482 -221.610183) (xy 299.057632 -221.614166) (xy 299.109594 -221.626026)
			(xy 299.159208 -221.645498) (xy 299.205366 -221.672147) (xy 299.247037 -221.705378) (xy 299.283289 -221.744449)
			(xy 299.313313 -221.788486) (xy 299.336439 -221.836507) (xy 299.352149 -221.887437) (xy 299.360092 -221.940141)
			(xy 299.36059 -221.96679) (xy 299.360092 -221.993439) (xy 299.352149 -222.046143) (xy 299.336439 -222.097073)
			(xy 299.313313 -222.145094) (xy 299.283289 -222.189131) (xy 299.247037 -222.228202) (xy 299.205366 -222.261433)
			(xy 299.159208 -222.288082) (xy 299.109594 -222.307554) (xy 299.057632 -222.319414) (xy 299.004482 -222.323398)
			(xy 298.951332 -222.319414) (xy 298.89937 -222.307554) (xy 298.849756 -222.288082) (xy 298.803598 -222.261433)
			(xy 298.761927 -222.228202) (xy 298.725675 -222.189131) (xy 298.695651 -222.145094) (xy 298.672525 -222.097073)
			(xy 298.656815 -222.046143) (xy 298.648872 -221.993439) (xy 284.272492 -221.993439) (xy 284.264549 -222.046143)
			(xy 284.248839 -222.097073) (xy 284.225713 -222.145094) (xy 284.195689 -222.189131) (xy 284.159437 -222.228202)
			(xy 284.117766 -222.261433) (xy 284.071608 -222.288082) (xy 284.021994 -222.307554) (xy 283.970032 -222.319414)
			(xy 283.916882 -222.323398) (xy 283.863732 -222.319414) (xy 283.81177 -222.307554) (xy 283.762156 -222.288082)
			(xy 283.715998 -222.261433) (xy 283.674327 -222.228202) (xy 283.638075 -222.189131) (xy 283.608051 -222.145094)
			(xy 283.584925 -222.097073) (xy 283.569215 -222.046143) (xy 283.561272 -221.993439) (xy 269.184892 -221.993439)
			(xy 269.176949 -222.046143) (xy 269.161239 -222.097073) (xy 269.138113 -222.145094) (xy 269.108089 -222.189131)
			(xy 269.071837 -222.228202) (xy 269.030166 -222.261433) (xy 268.984008 -222.288082) (xy 268.934394 -222.307554)
			(xy 268.882432 -222.319414) (xy 268.829282 -222.323398) (xy 268.776132 -222.319414) (xy 268.72417 -222.307554)
			(xy 268.674556 -222.288082) (xy 268.628398 -222.261433) (xy 268.586727 -222.228202) (xy 268.550475 -222.189131)
			(xy 268.520451 -222.145094) (xy 268.497325 -222.097073) (xy 268.481615 -222.046143) (xy 268.473672 -221.993439)
			(xy 254 -221.993439) (xy 254 -222.843323) (xy 264.373604 -222.843323) (xy 264.373604 -222.790025)
			(xy 264.381547 -222.737321) (xy 264.397257 -222.686391) (xy 264.420383 -222.63837) (xy 264.450407 -222.594333)
			(xy 264.486659 -222.555262) (xy 264.52833 -222.522031) (xy 264.574488 -222.495382) (xy 264.624102 -222.47591)
			(xy 264.676064 -222.46405) (xy 264.729214 -222.460067) (xy 264.782364 -222.46405) (xy 264.834326 -222.47591)
			(xy 264.88394 -222.495382) (xy 264.930098 -222.522031) (xy 264.971769 -222.555262) (xy 265.008021 -222.594333)
			(xy 265.038045 -222.63837) (xy 265.061171 -222.686391) (xy 265.076881 -222.737321) (xy 265.084824 -222.790025)
			(xy 265.085322 -222.816674) (xy 265.084824 -222.843323) (xy 279.461204 -222.843323) (xy 279.461204 -222.790025)
			(xy 279.469147 -222.737321) (xy 279.484857 -222.686391) (xy 279.507983 -222.63837) (xy 279.538007 -222.594333)
			(xy 279.574259 -222.555262) (xy 279.61593 -222.522031) (xy 279.662088 -222.495382) (xy 279.711702 -222.47591)
			(xy 279.763664 -222.46405) (xy 279.816814 -222.460067) (xy 279.869964 -222.46405) (xy 279.921926 -222.47591)
			(xy 279.97154 -222.495382) (xy 280.017698 -222.522031) (xy 280.059369 -222.555262) (xy 280.095621 -222.594333)
			(xy 280.125645 -222.63837) (xy 280.148771 -222.686391) (xy 280.164481 -222.737321) (xy 280.172424 -222.790025)
			(xy 280.172922 -222.816674) (xy 280.172424 -222.843323) (xy 294.548804 -222.843323) (xy 294.548804 -222.790025)
			(xy 294.556747 -222.737321) (xy 294.572457 -222.686391) (xy 294.595583 -222.63837) (xy 294.625607 -222.594333)
			(xy 294.661859 -222.555262) (xy 294.70353 -222.522031) (xy 294.749688 -222.495382) (xy 294.799302 -222.47591)
			(xy 294.851264 -222.46405) (xy 294.904414 -222.460067) (xy 294.957564 -222.46405) (xy 295.009526 -222.47591)
			(xy 295.05914 -222.495382) (xy 295.105298 -222.522031) (xy 295.146969 -222.555262) (xy 295.183221 -222.594333)
			(xy 295.213245 -222.63837) (xy 295.236371 -222.686391) (xy 295.252081 -222.737321) (xy 295.260024 -222.790025)
			(xy 295.260522 -222.816674) (xy 295.260024 -222.843323) (xy 295.252081 -222.896027) (xy 295.236371 -222.946957)
			(xy 295.213245 -222.994978) (xy 295.183221 -223.039015) (xy 295.146969 -223.078086) (xy 295.105298 -223.111317)
			(xy 295.05914 -223.137966) (xy 295.009526 -223.157438) (xy 294.957564 -223.169298) (xy 294.904414 -223.173282)
			(xy 294.851264 -223.169298) (xy 294.799302 -223.157438) (xy 294.749688 -223.137966) (xy 294.70353 -223.111317)
			(xy 294.661859 -223.078086) (xy 294.625607 -223.039015) (xy 294.595583 -222.994978) (xy 294.572457 -222.946957)
			(xy 294.556747 -222.896027) (xy 294.548804 -222.843323) (xy 280.172424 -222.843323) (xy 280.164481 -222.896027)
			(xy 280.148771 -222.946957) (xy 280.125645 -222.994978) (xy 280.095621 -223.039015) (xy 280.059369 -223.078086)
			(xy 280.017698 -223.111317) (xy 279.97154 -223.137966) (xy 279.921926 -223.157438) (xy 279.869964 -223.169298)
			(xy 279.816814 -223.173282) (xy 279.763664 -223.169298) (xy 279.711702 -223.157438) (xy 279.662088 -223.137966)
			(xy 279.61593 -223.111317) (xy 279.574259 -223.078086) (xy 279.538007 -223.039015) (xy 279.507983 -222.994978)
			(xy 279.484857 -222.946957) (xy 279.469147 -222.896027) (xy 279.461204 -222.843323) (xy 265.084824 -222.843323)
			(xy 265.076881 -222.896027) (xy 265.061171 -222.946957) (xy 265.038045 -222.994978) (xy 265.008021 -223.039015)
			(xy 264.971769 -223.078086) (xy 264.930098 -223.111317) (xy 264.88394 -223.137966) (xy 264.834326 -223.157438)
			(xy 264.782364 -223.169298) (xy 264.729214 -223.173282) (xy 264.676064 -223.169298) (xy 264.624102 -223.157438)
			(xy 264.574488 -223.137966) (xy 264.52833 -223.111317) (xy 264.486659 -223.078086) (xy 264.450407 -223.039015)
			(xy 264.420383 -222.994978) (xy 264.397257 -222.946957) (xy 264.381547 -222.896027) (xy 264.373604 -222.843323)
			(xy 254 -222.843323) (xy 254 -223.693207) (xy 268.473672 -223.693207) (xy 268.473672 -223.639909)
			(xy 268.481615 -223.587205) (xy 268.497325 -223.536275) (xy 268.520451 -223.488254) (xy 268.550475 -223.444217)
			(xy 268.586727 -223.405146) (xy 268.628398 -223.371915) (xy 268.674556 -223.345266) (xy 268.72417 -223.325794)
			(xy 268.776132 -223.313934) (xy 268.829282 -223.309951) (xy 268.882432 -223.313934) (xy 268.934394 -223.325794)
			(xy 268.984008 -223.345266) (xy 269.030166 -223.371915) (xy 269.071837 -223.405146) (xy 269.108089 -223.444217)
			(xy 269.138113 -223.488254) (xy 269.161239 -223.536275) (xy 269.176949 -223.587205) (xy 269.184892 -223.639909)
			(xy 269.18539 -223.666558) (xy 269.184892 -223.693207) (xy 283.561272 -223.693207) (xy 283.561272 -223.639909)
			(xy 283.569215 -223.587205) (xy 283.584925 -223.536275) (xy 283.608051 -223.488254) (xy 283.638075 -223.444217)
			(xy 283.674327 -223.405146) (xy 283.715998 -223.371915) (xy 283.762156 -223.345266) (xy 283.81177 -223.325794)
			(xy 283.863732 -223.313934) (xy 283.916882 -223.309951) (xy 283.970032 -223.313934) (xy 284.021994 -223.325794)
			(xy 284.071608 -223.345266) (xy 284.117766 -223.371915) (xy 284.159437 -223.405146) (xy 284.195689 -223.444217)
			(xy 284.225713 -223.488254) (xy 284.248839 -223.536275) (xy 284.264549 -223.587205) (xy 284.272492 -223.639909)
			(xy 284.27299 -223.666558) (xy 284.272492 -223.693207) (xy 298.648872 -223.693207) (xy 298.648872 -223.639909)
			(xy 298.656815 -223.587205) (xy 298.672525 -223.536275) (xy 298.695651 -223.488254) (xy 298.725675 -223.444217)
			(xy 298.761927 -223.405146) (xy 298.803598 -223.371915) (xy 298.849756 -223.345266) (xy 298.89937 -223.325794)
			(xy 298.951332 -223.313934) (xy 299.004482 -223.309951) (xy 299.057632 -223.313934) (xy 299.109594 -223.325794)
			(xy 299.159208 -223.345266) (xy 299.205366 -223.371915) (xy 299.247037 -223.405146) (xy 299.283289 -223.444217)
			(xy 299.313313 -223.488254) (xy 299.336439 -223.536275) (xy 299.352149 -223.587205) (xy 299.360092 -223.639909)
			(xy 299.36059 -223.666558) (xy 299.360092 -223.693207) (xy 299.352149 -223.745911) (xy 299.336439 -223.796841)
			(xy 299.313313 -223.844862) (xy 299.283289 -223.888899) (xy 299.247037 -223.92797) (xy 299.205366 -223.961201)
			(xy 299.159208 -223.98785) (xy 299.109594 -224.007322) (xy 299.057632 -224.019182) (xy 299.004482 -224.023166)
			(xy 298.951332 -224.019182) (xy 298.89937 -224.007322) (xy 298.849756 -223.98785) (xy 298.803598 -223.961201)
			(xy 298.761927 -223.92797) (xy 298.725675 -223.888899) (xy 298.695651 -223.844862) (xy 298.672525 -223.796841)
			(xy 298.656815 -223.745911) (xy 298.648872 -223.693207) (xy 284.272492 -223.693207) (xy 284.264549 -223.745911)
			(xy 284.248839 -223.796841) (xy 284.225713 -223.844862) (xy 284.195689 -223.888899) (xy 284.159437 -223.92797)
			(xy 284.117766 -223.961201) (xy 284.071608 -223.98785) (xy 284.021994 -224.007322) (xy 283.970032 -224.019182)
			(xy 283.916882 -224.023166) (xy 283.863732 -224.019182) (xy 283.81177 -224.007322) (xy 283.762156 -223.98785)
			(xy 283.715998 -223.961201) (xy 283.674327 -223.92797) (xy 283.638075 -223.888899) (xy 283.608051 -223.844862)
			(xy 283.584925 -223.796841) (xy 283.569215 -223.745911) (xy 283.561272 -223.693207) (xy 269.184892 -223.693207)
			(xy 269.176949 -223.745911) (xy 269.161239 -223.796841) (xy 269.138113 -223.844862) (xy 269.108089 -223.888899)
			(xy 269.071837 -223.92797) (xy 269.030166 -223.961201) (xy 268.984008 -223.98785) (xy 268.934394 -224.007322)
			(xy 268.882432 -224.019182) (xy 268.829282 -224.023166) (xy 268.776132 -224.019182) (xy 268.72417 -224.007322)
			(xy 268.674556 -223.98785) (xy 268.628398 -223.961201) (xy 268.586727 -223.92797) (xy 268.550475 -223.888899)
			(xy 268.520451 -223.844862) (xy 268.497325 -223.796841) (xy 268.481615 -223.745911) (xy 268.473672 -223.693207)
			(xy 254 -223.693207) (xy 254 -224.543345) (xy 264.373604 -224.543345) (xy 264.373604 -224.490047)
			(xy 264.381547 -224.437343) (xy 264.397257 -224.386413) (xy 264.420383 -224.338392) (xy 264.450407 -224.294355)
			(xy 264.486659 -224.255284) (xy 264.52833 -224.222053) (xy 264.574488 -224.195404) (xy 264.624102 -224.175932)
			(xy 264.676064 -224.164072) (xy 264.729214 -224.160089) (xy 264.782364 -224.164072) (xy 264.834326 -224.175932)
			(xy 264.88394 -224.195404) (xy 264.930098 -224.222053) (xy 264.971769 -224.255284) (xy 265.008021 -224.294355)
			(xy 265.038045 -224.338392) (xy 265.061171 -224.386413) (xy 265.076881 -224.437343) (xy 265.084824 -224.490047)
			(xy 265.085322 -224.516696) (xy 265.084824 -224.543345) (xy 279.461204 -224.543345) (xy 279.461204 -224.490047)
			(xy 279.469147 -224.437343) (xy 279.484857 -224.386413) (xy 279.507983 -224.338392) (xy 279.538007 -224.294355)
			(xy 279.574259 -224.255284) (xy 279.61593 -224.222053) (xy 279.662088 -224.195404) (xy 279.711702 -224.175932)
			(xy 279.763664 -224.164072) (xy 279.816814 -224.160089) (xy 279.869964 -224.164072) (xy 279.921926 -224.175932)
			(xy 279.97154 -224.195404) (xy 280.017698 -224.222053) (xy 280.059369 -224.255284) (xy 280.095621 -224.294355)
			(xy 280.125645 -224.338392) (xy 280.148771 -224.386413) (xy 280.164481 -224.437343) (xy 280.172424 -224.490047)
			(xy 280.172922 -224.516696) (xy 280.172424 -224.543345) (xy 294.548804 -224.543345) (xy 294.548804 -224.490047)
			(xy 294.556747 -224.437343) (xy 294.572457 -224.386413) (xy 294.595583 -224.338392) (xy 294.625607 -224.294355)
			(xy 294.661859 -224.255284) (xy 294.70353 -224.222053) (xy 294.749688 -224.195404) (xy 294.799302 -224.175932)
			(xy 294.851264 -224.164072) (xy 294.904414 -224.160089) (xy 294.957564 -224.164072) (xy 295.009526 -224.175932)
			(xy 295.05914 -224.195404) (xy 295.105298 -224.222053) (xy 295.146969 -224.255284) (xy 295.183221 -224.294355)
			(xy 295.213245 -224.338392) (xy 295.236371 -224.386413) (xy 295.252081 -224.437343) (xy 295.260024 -224.490047)
			(xy 295.260522 -224.516696) (xy 295.260024 -224.543345) (xy 309.636404 -224.543345) (xy 309.636404 -224.490047)
			(xy 309.644347 -224.437343) (xy 309.660057 -224.386413) (xy 309.683183 -224.338392) (xy 309.713207 -224.294355)
			(xy 309.749459 -224.255284) (xy 309.79113 -224.222053) (xy 309.837288 -224.195404) (xy 309.886902 -224.175932)
			(xy 309.938864 -224.164072) (xy 309.992014 -224.160089) (xy 310.045164 -224.164072) (xy 310.097126 -224.175932)
			(xy 310.14674 -224.195404) (xy 310.192898 -224.222053) (xy 310.234569 -224.255284) (xy 310.270821 -224.294355)
			(xy 310.300845 -224.338392) (xy 310.323971 -224.386413) (xy 310.339681 -224.437343) (xy 310.347624 -224.490047)
			(xy 310.348122 -224.516696) (xy 310.347624 -224.543345) (xy 310.339681 -224.596049) (xy 310.323971 -224.646979)
			(xy 310.300845 -224.695) (xy 310.270821 -224.739037) (xy 310.234569 -224.778108) (xy 310.192898 -224.811339)
			(xy 310.14674 -224.837988) (xy 310.097126 -224.85746) (xy 310.045164 -224.86932) (xy 309.992014 -224.873304)
			(xy 309.938864 -224.86932) (xy 309.886902 -224.85746) (xy 309.837288 -224.837988) (xy 309.79113 -224.811339)
			(xy 309.749459 -224.778108) (xy 309.713207 -224.739037) (xy 309.683183 -224.695) (xy 309.660057 -224.646979)
			(xy 309.644347 -224.596049) (xy 309.636404 -224.543345) (xy 295.260024 -224.543345) (xy 295.252081 -224.596049)
			(xy 295.236371 -224.646979) (xy 295.213245 -224.695) (xy 295.183221 -224.739037) (xy 295.146969 -224.778108)
			(xy 295.105298 -224.811339) (xy 295.05914 -224.837988) (xy 295.009526 -224.85746) (xy 294.957564 -224.86932)
			(xy 294.904414 -224.873304) (xy 294.851264 -224.86932) (xy 294.799302 -224.85746) (xy 294.749688 -224.837988)
			(xy 294.70353 -224.811339) (xy 294.661859 -224.778108) (xy 294.625607 -224.739037) (xy 294.595583 -224.695)
			(xy 294.572457 -224.646979) (xy 294.556747 -224.596049) (xy 294.548804 -224.543345) (xy 280.172424 -224.543345)
			(xy 280.164481 -224.596049) (xy 280.148771 -224.646979) (xy 280.125645 -224.695) (xy 280.095621 -224.739037)
			(xy 280.059369 -224.778108) (xy 280.017698 -224.811339) (xy 279.97154 -224.837988) (xy 279.921926 -224.85746)
			(xy 279.869964 -224.86932) (xy 279.816814 -224.873304) (xy 279.763664 -224.86932) (xy 279.711702 -224.85746)
			(xy 279.662088 -224.837988) (xy 279.61593 -224.811339) (xy 279.574259 -224.778108) (xy 279.538007 -224.739037)
			(xy 279.507983 -224.695) (xy 279.484857 -224.646979) (xy 279.469147 -224.596049) (xy 279.461204 -224.543345)
			(xy 265.084824 -224.543345) (xy 265.076881 -224.596049) (xy 265.061171 -224.646979) (xy 265.038045 -224.695)
			(xy 265.008021 -224.739037) (xy 264.971769 -224.778108) (xy 264.930098 -224.811339) (xy 264.88394 -224.837988)
			(xy 264.834326 -224.85746) (xy 264.782364 -224.86932) (xy 264.729214 -224.873304) (xy 264.676064 -224.86932)
			(xy 264.624102 -224.85746) (xy 264.574488 -224.837988) (xy 264.52833 -224.811339) (xy 264.486659 -224.778108)
			(xy 264.450407 -224.739037) (xy 264.420383 -224.695) (xy 264.397257 -224.646979) (xy 264.381547 -224.596049)
			(xy 264.373604 -224.543345) (xy 254 -224.543345) (xy 254 -225.393229) (xy 268.473672 -225.393229)
			(xy 268.473672 -225.339931) (xy 268.481615 -225.287227) (xy 268.497325 -225.236297) (xy 268.520451 -225.188276)
			(xy 268.550475 -225.144239) (xy 268.586727 -225.105168) (xy 268.628398 -225.071937) (xy 268.674556 -225.045288)
			(xy 268.72417 -225.025816) (xy 268.776132 -225.013956) (xy 268.829282 -225.009973) (xy 268.882432 -225.013956)
			(xy 268.934394 -225.025816) (xy 268.984008 -225.045288) (xy 269.030166 -225.071937) (xy 269.071837 -225.105168)
			(xy 269.108089 -225.144239) (xy 269.138113 -225.188276) (xy 269.161239 -225.236297) (xy 269.176949 -225.287227)
			(xy 269.184892 -225.339931) (xy 269.18539 -225.36658) (xy 269.184892 -225.393229) (xy 283.561272 -225.393229)
			(xy 283.561272 -225.339931) (xy 283.569215 -225.287227) (xy 283.584925 -225.236297) (xy 283.608051 -225.188276)
			(xy 283.638075 -225.144239) (xy 283.674327 -225.105168) (xy 283.715998 -225.071937) (xy 283.762156 -225.045288)
			(xy 283.81177 -225.025816) (xy 283.863732 -225.013956) (xy 283.916882 -225.009973) (xy 283.970032 -225.013956)
			(xy 284.021994 -225.025816) (xy 284.071608 -225.045288) (xy 284.117766 -225.071937) (xy 284.159437 -225.105168)
			(xy 284.195689 -225.144239) (xy 284.225713 -225.188276) (xy 284.248839 -225.236297) (xy 284.264549 -225.287227)
			(xy 284.272492 -225.339931) (xy 284.27299 -225.36658) (xy 284.272492 -225.393229) (xy 298.648872 -225.393229)
			(xy 298.648872 -225.339931) (xy 298.656815 -225.287227) (xy 298.672525 -225.236297) (xy 298.695651 -225.188276)
			(xy 298.725675 -225.144239) (xy 298.761927 -225.105168) (xy 298.803598 -225.071937) (xy 298.849756 -225.045288)
			(xy 298.89937 -225.025816) (xy 298.951332 -225.013956) (xy 299.004482 -225.009973) (xy 299.057632 -225.013956)
			(xy 299.109594 -225.025816) (xy 299.159208 -225.045288) (xy 299.205366 -225.071937) (xy 299.247037 -225.105168)
			(xy 299.283289 -225.144239) (xy 299.313313 -225.188276) (xy 299.336439 -225.236297) (xy 299.352149 -225.287227)
			(xy 299.360092 -225.339931) (xy 299.36059 -225.36658) (xy 299.360092 -225.393229) (xy 299.352149 -225.445933)
			(xy 299.336439 -225.496863) (xy 299.313313 -225.544884) (xy 299.283289 -225.588921) (xy 299.247037 -225.627992)
			(xy 299.205366 -225.661223) (xy 299.159208 -225.687872) (xy 299.109594 -225.707344) (xy 299.057632 -225.719204)
			(xy 299.004482 -225.723188) (xy 298.951332 -225.719204) (xy 298.89937 -225.707344) (xy 298.849756 -225.687872)
			(xy 298.803598 -225.661223) (xy 298.761927 -225.627992) (xy 298.725675 -225.588921) (xy 298.695651 -225.544884)
			(xy 298.672525 -225.496863) (xy 298.656815 -225.445933) (xy 298.648872 -225.393229) (xy 284.272492 -225.393229)
			(xy 284.264549 -225.445933) (xy 284.248839 -225.496863) (xy 284.225713 -225.544884) (xy 284.195689 -225.588921)
			(xy 284.159437 -225.627992) (xy 284.117766 -225.661223) (xy 284.071608 -225.687872) (xy 284.021994 -225.707344)
			(xy 283.970032 -225.719204) (xy 283.916882 -225.723188) (xy 283.863732 -225.719204) (xy 283.81177 -225.707344)
			(xy 283.762156 -225.687872) (xy 283.715998 -225.661223) (xy 283.674327 -225.627992) (xy 283.638075 -225.588921)
			(xy 283.608051 -225.544884) (xy 283.584925 -225.496863) (xy 283.569215 -225.445933) (xy 283.561272 -225.393229)
			(xy 269.184892 -225.393229) (xy 269.176949 -225.445933) (xy 269.161239 -225.496863) (xy 269.138113 -225.544884)
			(xy 269.108089 -225.588921) (xy 269.071837 -225.627992) (xy 269.030166 -225.661223) (xy 268.984008 -225.687872)
			(xy 268.934394 -225.707344) (xy 268.882432 -225.719204) (xy 268.829282 -225.723188) (xy 268.776132 -225.719204)
			(xy 268.72417 -225.707344) (xy 268.674556 -225.687872) (xy 268.628398 -225.661223) (xy 268.586727 -225.627992)
			(xy 268.550475 -225.588921) (xy 268.520451 -225.544884) (xy 268.497325 -225.496863) (xy 268.481615 -225.445933)
			(xy 268.473672 -225.393229) (xy 254 -225.393229) (xy 254 -226.243367) (xy 264.373604 -226.243367)
			(xy 264.373604 -226.190069) (xy 264.381547 -226.137365) (xy 264.397257 -226.086435) (xy 264.420383 -226.038414)
			(xy 264.450407 -225.994377) (xy 264.486659 -225.955306) (xy 264.52833 -225.922075) (xy 264.574488 -225.895426)
			(xy 264.624102 -225.875954) (xy 264.676064 -225.864094) (xy 264.729214 -225.860111) (xy 264.782364 -225.864094)
			(xy 264.834326 -225.875954) (xy 264.88394 -225.895426) (xy 264.930098 -225.922075) (xy 264.971769 -225.955306)
			(xy 265.008021 -225.994377) (xy 265.038045 -226.038414) (xy 265.061171 -226.086435) (xy 265.076881 -226.137365)
			(xy 265.084824 -226.190069) (xy 265.085322 -226.216718) (xy 265.084824 -226.243367) (xy 279.461204 -226.243367)
			(xy 279.461204 -226.190069) (xy 279.469147 -226.137365) (xy 279.484857 -226.086435) (xy 279.507983 -226.038414)
			(xy 279.538007 -225.994377) (xy 279.574259 -225.955306) (xy 279.61593 -225.922075) (xy 279.662088 -225.895426)
			(xy 279.711702 -225.875954) (xy 279.763664 -225.864094) (xy 279.816814 -225.860111) (xy 279.869964 -225.864094)
			(xy 279.921926 -225.875954) (xy 279.97154 -225.895426) (xy 280.017698 -225.922075) (xy 280.059369 -225.955306)
			(xy 280.095621 -225.994377) (xy 280.125645 -226.038414) (xy 280.148771 -226.086435) (xy 280.164481 -226.137365)
			(xy 280.172424 -226.190069) (xy 280.172922 -226.216718) (xy 280.172424 -226.243367) (xy 294.548804 -226.243367)
			(xy 294.548804 -226.190069) (xy 294.556747 -226.137365) (xy 294.572457 -226.086435) (xy 294.595583 -226.038414)
			(xy 294.625607 -225.994377) (xy 294.661859 -225.955306) (xy 294.70353 -225.922075) (xy 294.749688 -225.895426)
			(xy 294.799302 -225.875954) (xy 294.851264 -225.864094) (xy 294.904414 -225.860111) (xy 294.957564 -225.864094)
			(xy 295.009526 -225.875954) (xy 295.05914 -225.895426) (xy 295.105298 -225.922075) (xy 295.146969 -225.955306)
			(xy 295.183221 -225.994377) (xy 295.213245 -226.038414) (xy 295.236371 -226.086435) (xy 295.252081 -226.137365)
			(xy 295.260024 -226.190069) (xy 295.260522 -226.216718) (xy 295.260024 -226.243367) (xy 309.636404 -226.243367)
			(xy 309.636404 -226.190069) (xy 309.644347 -226.137365) (xy 309.660057 -226.086435) (xy 309.683183 -226.038414)
			(xy 309.713207 -225.994377) (xy 309.749459 -225.955306) (xy 309.79113 -225.922075) (xy 309.837288 -225.895426)
			(xy 309.886902 -225.875954) (xy 309.938864 -225.864094) (xy 309.992014 -225.860111) (xy 310.045164 -225.864094)
			(xy 310.097126 -225.875954) (xy 310.14674 -225.895426) (xy 310.192898 -225.922075) (xy 310.234569 -225.955306)
			(xy 310.270821 -225.994377) (xy 310.300845 -226.038414) (xy 310.323971 -226.086435) (xy 310.339681 -226.137365)
			(xy 310.347624 -226.190069) (xy 310.348122 -226.216718) (xy 310.347624 -226.243367) (xy 310.339681 -226.296071)
			(xy 310.323971 -226.347001) (xy 310.300845 -226.395022) (xy 310.270821 -226.439059) (xy 310.234569 -226.47813)
			(xy 310.192898 -226.511361) (xy 310.14674 -226.53801) (xy 310.097126 -226.557482) (xy 310.045164 -226.569342)
			(xy 309.992014 -226.573326) (xy 309.938864 -226.569342) (xy 309.886902 -226.557482) (xy 309.837288 -226.53801)
			(xy 309.79113 -226.511361) (xy 309.749459 -226.47813) (xy 309.713207 -226.439059) (xy 309.683183 -226.395022)
			(xy 309.660057 -226.347001) (xy 309.644347 -226.296071) (xy 309.636404 -226.243367) (xy 295.260024 -226.243367)
			(xy 295.252081 -226.296071) (xy 295.236371 -226.347001) (xy 295.213245 -226.395022) (xy 295.183221 -226.439059)
			(xy 295.146969 -226.47813) (xy 295.105298 -226.511361) (xy 295.05914 -226.53801) (xy 295.009526 -226.557482)
			(xy 294.957564 -226.569342) (xy 294.904414 -226.573326) (xy 294.851264 -226.569342) (xy 294.799302 -226.557482)
			(xy 294.749688 -226.53801) (xy 294.70353 -226.511361) (xy 294.661859 -226.47813) (xy 294.625607 -226.439059)
			(xy 294.595583 -226.395022) (xy 294.572457 -226.347001) (xy 294.556747 -226.296071) (xy 294.548804 -226.243367)
			(xy 280.172424 -226.243367) (xy 280.164481 -226.296071) (xy 280.148771 -226.347001) (xy 280.125645 -226.395022)
			(xy 280.095621 -226.439059) (xy 280.059369 -226.47813) (xy 280.017698 -226.511361) (xy 279.97154 -226.53801)
			(xy 279.921926 -226.557482) (xy 279.869964 -226.569342) (xy 279.816814 -226.573326) (xy 279.763664 -226.569342)
			(xy 279.711702 -226.557482) (xy 279.662088 -226.53801) (xy 279.61593 -226.511361) (xy 279.574259 -226.47813)
			(xy 279.538007 -226.439059) (xy 279.507983 -226.395022) (xy 279.484857 -226.347001) (xy 279.469147 -226.296071)
			(xy 279.461204 -226.243367) (xy 265.084824 -226.243367) (xy 265.076881 -226.296071) (xy 265.061171 -226.347001)
			(xy 265.038045 -226.395022) (xy 265.008021 -226.439059) (xy 264.971769 -226.47813) (xy 264.930098 -226.511361)
			(xy 264.88394 -226.53801) (xy 264.834326 -226.557482) (xy 264.782364 -226.569342) (xy 264.729214 -226.573326)
			(xy 264.676064 -226.569342) (xy 264.624102 -226.557482) (xy 264.574488 -226.53801) (xy 264.52833 -226.511361)
			(xy 264.486659 -226.47813) (xy 264.450407 -226.439059) (xy 264.420383 -226.395022) (xy 264.397257 -226.347001)
			(xy 264.381547 -226.296071) (xy 264.373604 -226.243367) (xy 254 -226.243367) (xy 254 -227.093251)
			(xy 268.473672 -227.093251) (xy 268.473672 -227.039953) (xy 268.481615 -226.987249) (xy 268.497325 -226.936319)
			(xy 268.520451 -226.888298) (xy 268.550475 -226.844261) (xy 268.586727 -226.80519) (xy 268.628398 -226.771959)
			(xy 268.674556 -226.74531) (xy 268.72417 -226.725838) (xy 268.776132 -226.713978) (xy 268.829282 -226.709995)
			(xy 268.882432 -226.713978) (xy 268.934394 -226.725838) (xy 268.984008 -226.74531) (xy 269.030166 -226.771959)
			(xy 269.071837 -226.80519) (xy 269.108089 -226.844261) (xy 269.138113 -226.888298) (xy 269.161239 -226.936319)
			(xy 269.176949 -226.987249) (xy 269.184892 -227.039953) (xy 269.18539 -227.066602) (xy 269.184892 -227.093251)
			(xy 283.561272 -227.093251) (xy 283.561272 -227.039953) (xy 283.569215 -226.987249) (xy 283.584925 -226.936319)
			(xy 283.608051 -226.888298) (xy 283.638075 -226.844261) (xy 283.674327 -226.80519) (xy 283.715998 -226.771959)
			(xy 283.762156 -226.74531) (xy 283.81177 -226.725838) (xy 283.863732 -226.713978) (xy 283.916882 -226.709995)
			(xy 283.970032 -226.713978) (xy 284.021994 -226.725838) (xy 284.071608 -226.74531) (xy 284.117766 -226.771959)
			(xy 284.159437 -226.80519) (xy 284.195689 -226.844261) (xy 284.225713 -226.888298) (xy 284.248839 -226.936319)
			(xy 284.264549 -226.987249) (xy 284.272492 -227.039953) (xy 284.27299 -227.066602) (xy 284.272492 -227.093251)
			(xy 298.648872 -227.093251) (xy 298.648872 -227.039953) (xy 298.656815 -226.987249) (xy 298.672525 -226.936319)
			(xy 298.695651 -226.888298) (xy 298.725675 -226.844261) (xy 298.761927 -226.80519) (xy 298.803598 -226.771959)
			(xy 298.849756 -226.74531) (xy 298.89937 -226.725838) (xy 298.951332 -226.713978) (xy 299.004482 -226.709995)
			(xy 299.057632 -226.713978) (xy 299.109594 -226.725838) (xy 299.159208 -226.74531) (xy 299.205366 -226.771959)
			(xy 299.247037 -226.80519) (xy 299.283289 -226.844261) (xy 299.313313 -226.888298) (xy 299.336439 -226.936319)
			(xy 299.352149 -226.987249) (xy 299.360092 -227.039953) (xy 299.36059 -227.066602) (xy 299.360092 -227.093251)
			(xy 299.352149 -227.145955) (xy 299.336439 -227.196885) (xy 299.313313 -227.244906) (xy 299.283289 -227.288943)
			(xy 299.247037 -227.328014) (xy 299.205366 -227.361245) (xy 299.159208 -227.387894) (xy 299.109594 -227.407366)
			(xy 299.057632 -227.419226) (xy 299.004482 -227.42321) (xy 298.951332 -227.419226) (xy 298.89937 -227.407366)
			(xy 298.849756 -227.387894) (xy 298.803598 -227.361245) (xy 298.761927 -227.328014) (xy 298.725675 -227.288943)
			(xy 298.695651 -227.244906) (xy 298.672525 -227.196885) (xy 298.656815 -227.145955) (xy 298.648872 -227.093251)
			(xy 284.272492 -227.093251) (xy 284.264549 -227.145955) (xy 284.248839 -227.196885) (xy 284.225713 -227.244906)
			(xy 284.195689 -227.288943) (xy 284.159437 -227.328014) (xy 284.117766 -227.361245) (xy 284.071608 -227.387894)
			(xy 284.021994 -227.407366) (xy 283.970032 -227.419226) (xy 283.916882 -227.42321) (xy 283.863732 -227.419226)
			(xy 283.81177 -227.407366) (xy 283.762156 -227.387894) (xy 283.715998 -227.361245) (xy 283.674327 -227.328014)
			(xy 283.638075 -227.288943) (xy 283.608051 -227.244906) (xy 283.584925 -227.196885) (xy 283.569215 -227.145955)
			(xy 283.561272 -227.093251) (xy 269.184892 -227.093251) (xy 269.176949 -227.145955) (xy 269.161239 -227.196885)
			(xy 269.138113 -227.244906) (xy 269.108089 -227.288943) (xy 269.071837 -227.328014) (xy 269.030166 -227.361245)
			(xy 268.984008 -227.387894) (xy 268.934394 -227.407366) (xy 268.882432 -227.419226) (xy 268.829282 -227.42321)
			(xy 268.776132 -227.419226) (xy 268.72417 -227.407366) (xy 268.674556 -227.387894) (xy 268.628398 -227.361245)
			(xy 268.586727 -227.328014) (xy 268.550475 -227.288943) (xy 268.520451 -227.244906) (xy 268.497325 -227.196885)
			(xy 268.481615 -227.145955) (xy 268.473672 -227.093251) (xy 254 -227.093251) (xy 254 -227.943389)
			(xy 264.373604 -227.943389) (xy 264.373604 -227.890091) (xy 264.381547 -227.837387) (xy 264.397257 -227.786457)
			(xy 264.420383 -227.738436) (xy 264.450407 -227.694399) (xy 264.486659 -227.655328) (xy 264.52833 -227.622097)
			(xy 264.574488 -227.595448) (xy 264.624102 -227.575976) (xy 264.676064 -227.564116) (xy 264.729214 -227.560133)
			(xy 264.782364 -227.564116) (xy 264.834326 -227.575976) (xy 264.88394 -227.595448) (xy 264.930098 -227.622097)
			(xy 264.971769 -227.655328) (xy 265.008021 -227.694399) (xy 265.038045 -227.738436) (xy 265.061171 -227.786457)
			(xy 265.076881 -227.837387) (xy 265.084824 -227.890091) (xy 265.085322 -227.91674) (xy 265.084824 -227.943389)
			(xy 268.473672 -227.943389) (xy 268.473672 -227.890091) (xy 268.481615 -227.837387) (xy 268.497325 -227.786457)
			(xy 268.520451 -227.738436) (xy 268.550475 -227.694399) (xy 268.586727 -227.655328) (xy 268.628398 -227.622097)
			(xy 268.674556 -227.595448) (xy 268.72417 -227.575976) (xy 268.776132 -227.564116) (xy 268.829282 -227.560133)
			(xy 268.882432 -227.564116) (xy 268.934394 -227.575976) (xy 268.984008 -227.595448) (xy 269.030166 -227.622097)
			(xy 269.071837 -227.655328) (xy 269.108089 -227.694399) (xy 269.138113 -227.738436) (xy 269.161239 -227.786457)
			(xy 269.176949 -227.837387) (xy 269.184892 -227.890091) (xy 269.18539 -227.91674) (xy 269.184892 -227.943389)
			(xy 279.461204 -227.943389) (xy 279.461204 -227.890091) (xy 279.469147 -227.837387) (xy 279.484857 -227.786457)
			(xy 279.507983 -227.738436) (xy 279.538007 -227.694399) (xy 279.574259 -227.655328) (xy 279.61593 -227.622097)
			(xy 279.662088 -227.595448) (xy 279.711702 -227.575976) (xy 279.763664 -227.564116) (xy 279.816814 -227.560133)
			(xy 279.869964 -227.564116) (xy 279.921926 -227.575976) (xy 279.97154 -227.595448) (xy 280.017698 -227.622097)
			(xy 280.059369 -227.655328) (xy 280.095621 -227.694399) (xy 280.125645 -227.738436) (xy 280.148771 -227.786457)
			(xy 280.164481 -227.837387) (xy 280.172424 -227.890091) (xy 280.172922 -227.91674) (xy 280.172424 -227.943389)
			(xy 283.561272 -227.943389) (xy 283.561272 -227.890091) (xy 283.569215 -227.837387) (xy 283.584925 -227.786457)
			(xy 283.608051 -227.738436) (xy 283.638075 -227.694399) (xy 283.674327 -227.655328) (xy 283.715998 -227.622097)
			(xy 283.762156 -227.595448) (xy 283.81177 -227.575976) (xy 283.863732 -227.564116) (xy 283.916882 -227.560133)
			(xy 283.970032 -227.564116) (xy 284.021994 -227.575976) (xy 284.071608 -227.595448) (xy 284.117766 -227.622097)
			(xy 284.159437 -227.655328) (xy 284.195689 -227.694399) (xy 284.225713 -227.738436) (xy 284.248839 -227.786457)
			(xy 284.264549 -227.837387) (xy 284.272492 -227.890091) (xy 284.27299 -227.91674) (xy 284.272492 -227.943389)
			(xy 294.548804 -227.943389) (xy 294.548804 -227.890091) (xy 294.556747 -227.837387) (xy 294.572457 -227.786457)
			(xy 294.595583 -227.738436) (xy 294.625607 -227.694399) (xy 294.661859 -227.655328) (xy 294.70353 -227.622097)
			(xy 294.749688 -227.595448) (xy 294.799302 -227.575976) (xy 294.851264 -227.564116) (xy 294.904414 -227.560133)
			(xy 294.957564 -227.564116) (xy 295.009526 -227.575976) (xy 295.05914 -227.595448) (xy 295.105298 -227.622097)
			(xy 295.146969 -227.655328) (xy 295.183221 -227.694399) (xy 295.213245 -227.738436) (xy 295.236371 -227.786457)
			(xy 295.252081 -227.837387) (xy 295.260024 -227.890091) (xy 295.260522 -227.91674) (xy 295.260024 -227.943389)
			(xy 298.648872 -227.943389) (xy 298.648872 -227.890091) (xy 298.656815 -227.837387) (xy 298.672525 -227.786457)
			(xy 298.695651 -227.738436) (xy 298.725675 -227.694399) (xy 298.761927 -227.655328) (xy 298.803598 -227.622097)
			(xy 298.849756 -227.595448) (xy 298.89937 -227.575976) (xy 298.951332 -227.564116) (xy 299.004482 -227.560133)
			(xy 299.057632 -227.564116) (xy 299.109594 -227.575976) (xy 299.159208 -227.595448) (xy 299.205366 -227.622097)
			(xy 299.247037 -227.655328) (xy 299.283289 -227.694399) (xy 299.313313 -227.738436) (xy 299.336439 -227.786457)
			(xy 299.352149 -227.837387) (xy 299.360092 -227.890091) (xy 299.36059 -227.91674) (xy 299.360092 -227.943389)
			(xy 309.636404 -227.943389) (xy 309.636404 -227.890091) (xy 309.644347 -227.837387) (xy 309.660057 -227.786457)
			(xy 309.683183 -227.738436) (xy 309.713207 -227.694399) (xy 309.749459 -227.655328) (xy 309.79113 -227.622097)
			(xy 309.837288 -227.595448) (xy 309.886902 -227.575976) (xy 309.938864 -227.564116) (xy 309.992014 -227.560133)
			(xy 310.045164 -227.564116) (xy 310.097126 -227.575976) (xy 310.14674 -227.595448) (xy 310.192898 -227.622097)
			(xy 310.234569 -227.655328) (xy 310.270821 -227.694399) (xy 310.300845 -227.738436) (xy 310.323971 -227.786457)
			(xy 310.339681 -227.837387) (xy 310.347624 -227.890091) (xy 310.348122 -227.91674) (xy 310.347624 -227.943389)
			(xy 310.339681 -227.996093) (xy 310.323971 -228.047023) (xy 310.300845 -228.095044) (xy 310.270821 -228.139081)
			(xy 310.234569 -228.178152) (xy 310.192898 -228.211383) (xy 310.14674 -228.238032) (xy 310.097126 -228.257504)
			(xy 310.045164 -228.269364) (xy 309.992014 -228.273348) (xy 309.938864 -228.269364) (xy 309.886902 -228.257504)
			(xy 309.837288 -228.238032) (xy 309.79113 -228.211383) (xy 309.749459 -228.178152) (xy 309.713207 -228.139081)
			(xy 309.683183 -228.095044) (xy 309.660057 -228.047023) (xy 309.644347 -227.996093) (xy 309.636404 -227.943389)
			(xy 299.360092 -227.943389) (xy 299.352149 -227.996093) (xy 299.336439 -228.047023) (xy 299.313313 -228.095044)
			(xy 299.283289 -228.139081) (xy 299.247037 -228.178152) (xy 299.205366 -228.211383) (xy 299.159208 -228.238032)
			(xy 299.109594 -228.257504) (xy 299.057632 -228.269364) (xy 299.004482 -228.273348) (xy 298.951332 -228.269364)
			(xy 298.89937 -228.257504) (xy 298.849756 -228.238032) (xy 298.803598 -228.211383) (xy 298.761927 -228.178152)
			(xy 298.725675 -228.139081) (xy 298.695651 -228.095044) (xy 298.672525 -228.047023) (xy 298.656815 -227.996093)
			(xy 298.648872 -227.943389) (xy 295.260024 -227.943389) (xy 295.252081 -227.996093) (xy 295.236371 -228.047023)
			(xy 295.213245 -228.095044) (xy 295.183221 -228.139081) (xy 295.146969 -228.178152) (xy 295.105298 -228.211383)
			(xy 295.05914 -228.238032) (xy 295.009526 -228.257504) (xy 294.957564 -228.269364) (xy 294.904414 -228.273348)
			(xy 294.851264 -228.269364) (xy 294.799302 -228.257504) (xy 294.749688 -228.238032) (xy 294.70353 -228.211383)
			(xy 294.661859 -228.178152) (xy 294.625607 -228.139081) (xy 294.595583 -228.095044) (xy 294.572457 -228.047023)
			(xy 294.556747 -227.996093) (xy 294.548804 -227.943389) (xy 284.272492 -227.943389) (xy 284.264549 -227.996093)
			(xy 284.248839 -228.047023) (xy 284.225713 -228.095044) (xy 284.195689 -228.139081) (xy 284.159437 -228.178152)
			(xy 284.117766 -228.211383) (xy 284.071608 -228.238032) (xy 284.021994 -228.257504) (xy 283.970032 -228.269364)
			(xy 283.916882 -228.273348) (xy 283.863732 -228.269364) (xy 283.81177 -228.257504) (xy 283.762156 -228.238032)
			(xy 283.715998 -228.211383) (xy 283.674327 -228.178152) (xy 283.638075 -228.139081) (xy 283.608051 -228.095044)
			(xy 283.584925 -228.047023) (xy 283.569215 -227.996093) (xy 283.561272 -227.943389) (xy 280.172424 -227.943389)
			(xy 280.164481 -227.996093) (xy 280.148771 -228.047023) (xy 280.125645 -228.095044) (xy 280.095621 -228.139081)
			(xy 280.059369 -228.178152) (xy 280.017698 -228.211383) (xy 279.97154 -228.238032) (xy 279.921926 -228.257504)
			(xy 279.869964 -228.269364) (xy 279.816814 -228.273348) (xy 279.763664 -228.269364) (xy 279.711702 -228.257504)
			(xy 279.662088 -228.238032) (xy 279.61593 -228.211383) (xy 279.574259 -228.178152) (xy 279.538007 -228.139081)
			(xy 279.507983 -228.095044) (xy 279.484857 -228.047023) (xy 279.469147 -227.996093) (xy 279.461204 -227.943389)
			(xy 269.184892 -227.943389) (xy 269.176949 -227.996093) (xy 269.161239 -228.047023) (xy 269.138113 -228.095044)
			(xy 269.108089 -228.139081) (xy 269.071837 -228.178152) (xy 269.030166 -228.211383) (xy 268.984008 -228.238032)
			(xy 268.934394 -228.257504) (xy 268.882432 -228.269364) (xy 268.829282 -228.273348) (xy 268.776132 -228.269364)
			(xy 268.72417 -228.257504) (xy 268.674556 -228.238032) (xy 268.628398 -228.211383) (xy 268.586727 -228.178152)
			(xy 268.550475 -228.139081) (xy 268.520451 -228.095044) (xy 268.497325 -228.047023) (xy 268.481615 -227.996093)
			(xy 268.473672 -227.943389) (xy 265.084824 -227.943389) (xy 265.076881 -227.996093) (xy 265.061171 -228.047023)
			(xy 265.038045 -228.095044) (xy 265.008021 -228.139081) (xy 264.971769 -228.178152) (xy 264.930098 -228.211383)
			(xy 264.88394 -228.238032) (xy 264.834326 -228.257504) (xy 264.782364 -228.269364) (xy 264.729214 -228.273348)
			(xy 264.676064 -228.269364) (xy 264.624102 -228.257504) (xy 264.574488 -228.238032) (xy 264.52833 -228.211383)
			(xy 264.486659 -228.178152) (xy 264.450407 -228.139081) (xy 264.420383 -228.095044) (xy 264.397257 -228.047023)
			(xy 264.381547 -227.996093) (xy 264.373604 -227.943389) (xy 254 -227.943389) (xy 254 -228.793273)
			(xy 264.373604 -228.793273) (xy 264.373604 -228.739975) (xy 264.381547 -228.687271) (xy 264.397257 -228.636341)
			(xy 264.420383 -228.58832) (xy 264.450407 -228.544283) (xy 264.486659 -228.505212) (xy 264.52833 -228.471981)
			(xy 264.574488 -228.445332) (xy 264.624102 -228.42586) (xy 264.676064 -228.414) (xy 264.729214 -228.410017)
			(xy 264.782364 -228.414) (xy 264.834326 -228.42586) (xy 264.88394 -228.445332) (xy 264.930098 -228.471981)
			(xy 264.971769 -228.505212) (xy 265.008021 -228.544283) (xy 265.038045 -228.58832) (xy 265.061171 -228.636341)
			(xy 265.076881 -228.687271) (xy 265.084824 -228.739975) (xy 265.085322 -228.766624) (xy 265.084824 -228.793273)
			(xy 279.461204 -228.793273) (xy 279.461204 -228.739975) (xy 279.469147 -228.687271) (xy 279.484857 -228.636341)
			(xy 279.507983 -228.58832) (xy 279.538007 -228.544283) (xy 279.574259 -228.505212) (xy 279.61593 -228.471981)
			(xy 279.662088 -228.445332) (xy 279.711702 -228.42586) (xy 279.763664 -228.414) (xy 279.816814 -228.410017)
			(xy 279.869964 -228.414) (xy 279.921926 -228.42586) (xy 279.97154 -228.445332) (xy 280.017698 -228.471981)
			(xy 280.059369 -228.505212) (xy 280.095621 -228.544283) (xy 280.125645 -228.58832) (xy 280.148771 -228.636341)
			(xy 280.164481 -228.687271) (xy 280.172424 -228.739975) (xy 280.172922 -228.766624) (xy 280.172424 -228.793273)
			(xy 294.548804 -228.793273) (xy 294.548804 -228.739975) (xy 294.556747 -228.687271) (xy 294.572457 -228.636341)
			(xy 294.595583 -228.58832) (xy 294.625607 -228.544283) (xy 294.661859 -228.505212) (xy 294.70353 -228.471981)
			(xy 294.749688 -228.445332) (xy 294.799302 -228.42586) (xy 294.851264 -228.414) (xy 294.904414 -228.410017)
			(xy 294.957564 -228.414) (xy 295.009526 -228.42586) (xy 295.05914 -228.445332) (xy 295.105298 -228.471981)
			(xy 295.146969 -228.505212) (xy 295.183221 -228.544283) (xy 295.213245 -228.58832) (xy 295.236371 -228.636341)
			(xy 295.252081 -228.687271) (xy 295.260024 -228.739975) (xy 295.260522 -228.766624) (xy 295.260024 -228.793273)
			(xy 309.636404 -228.793273) (xy 309.636404 -228.739975) (xy 309.644347 -228.687271) (xy 309.660057 -228.636341)
			(xy 309.683183 -228.58832) (xy 309.713207 -228.544283) (xy 309.749459 -228.505212) (xy 309.79113 -228.471981)
			(xy 309.837288 -228.445332) (xy 309.886902 -228.42586) (xy 309.938864 -228.414) (xy 309.992014 -228.410017)
			(xy 310.045164 -228.414) (xy 310.097126 -228.42586) (xy 310.14674 -228.445332) (xy 310.192898 -228.471981)
			(xy 310.234569 -228.505212) (xy 310.270821 -228.544283) (xy 310.300845 -228.58832) (xy 310.323971 -228.636341)
			(xy 310.339681 -228.687271) (xy 310.347624 -228.739975) (xy 310.348122 -228.766624) (xy 310.347624 -228.793273)
			(xy 310.339681 -228.845977) (xy 310.323971 -228.896907) (xy 310.300845 -228.944928) (xy 310.270821 -228.988965)
			(xy 310.234569 -229.028036) (xy 310.192898 -229.061267) (xy 310.14674 -229.087916) (xy 310.097126 -229.107388)
			(xy 310.045164 -229.119248) (xy 309.992014 -229.123232) (xy 309.938864 -229.119248) (xy 309.886902 -229.107388)
			(xy 309.837288 -229.087916) (xy 309.79113 -229.061267) (xy 309.749459 -229.028036) (xy 309.713207 -228.988965)
			(xy 309.683183 -228.944928) (xy 309.660057 -228.896907) (xy 309.644347 -228.845977) (xy 309.636404 -228.793273)
			(xy 295.260024 -228.793273) (xy 295.252081 -228.845977) (xy 295.236371 -228.896907) (xy 295.213245 -228.944928)
			(xy 295.183221 -228.988965) (xy 295.146969 -229.028036) (xy 295.105298 -229.061267) (xy 295.05914 -229.087916)
			(xy 295.009526 -229.107388) (xy 294.957564 -229.119248) (xy 294.904414 -229.123232) (xy 294.851264 -229.119248)
			(xy 294.799302 -229.107388) (xy 294.749688 -229.087916) (xy 294.70353 -229.061267) (xy 294.661859 -229.028036)
			(xy 294.625607 -228.988965) (xy 294.595583 -228.944928) (xy 294.572457 -228.896907) (xy 294.556747 -228.845977)
			(xy 294.548804 -228.793273) (xy 280.172424 -228.793273) (xy 280.164481 -228.845977) (xy 280.148771 -228.896907)
			(xy 280.125645 -228.944928) (xy 280.095621 -228.988965) (xy 280.059369 -229.028036) (xy 280.017698 -229.061267)
			(xy 279.97154 -229.087916) (xy 279.921926 -229.107388) (xy 279.869964 -229.119248) (xy 279.816814 -229.123232)
			(xy 279.763664 -229.119248) (xy 279.711702 -229.107388) (xy 279.662088 -229.087916) (xy 279.61593 -229.061267)
			(xy 279.574259 -229.028036) (xy 279.538007 -228.988965) (xy 279.507983 -228.944928) (xy 279.484857 -228.896907)
			(xy 279.469147 -228.845977) (xy 279.461204 -228.793273) (xy 265.084824 -228.793273) (xy 265.076881 -228.845977)
			(xy 265.061171 -228.896907) (xy 265.038045 -228.944928) (xy 265.008021 -228.988965) (xy 264.971769 -229.028036)
			(xy 264.930098 -229.061267) (xy 264.88394 -229.087916) (xy 264.834326 -229.107388) (xy 264.782364 -229.119248)
			(xy 264.729214 -229.123232) (xy 264.676064 -229.119248) (xy 264.624102 -229.107388) (xy 264.574488 -229.087916)
			(xy 264.52833 -229.061267) (xy 264.486659 -229.028036) (xy 264.450407 -228.988965) (xy 264.420383 -228.944928)
			(xy 264.397257 -228.896907) (xy 264.381547 -228.845977) (xy 264.373604 -228.793273) (xy 254 -228.793273)
			(xy 254 -229.643411) (xy 268.473672 -229.643411) (xy 268.473672 -229.590113) (xy 268.481615 -229.537409)
			(xy 268.497325 -229.486479) (xy 268.520451 -229.438458) (xy 268.550475 -229.394421) (xy 268.586727 -229.35535)
			(xy 268.628398 -229.322119) (xy 268.674556 -229.29547) (xy 268.72417 -229.275998) (xy 268.776132 -229.264138)
			(xy 268.829282 -229.260155) (xy 268.882432 -229.264138) (xy 268.934394 -229.275998) (xy 268.984008 -229.29547)
			(xy 269.030166 -229.322119) (xy 269.071837 -229.35535) (xy 269.108089 -229.394421) (xy 269.138113 -229.438458)
			(xy 269.161239 -229.486479) (xy 269.176949 -229.537409) (xy 269.184892 -229.590113) (xy 269.18539 -229.616762)
			(xy 269.184892 -229.643411) (xy 283.561272 -229.643411) (xy 283.561272 -229.590113) (xy 283.569215 -229.537409)
			(xy 283.584925 -229.486479) (xy 283.608051 -229.438458) (xy 283.638075 -229.394421) (xy 283.674327 -229.35535)
			(xy 283.715998 -229.322119) (xy 283.762156 -229.29547) (xy 283.81177 -229.275998) (xy 283.863732 -229.264138)
			(xy 283.916882 -229.260155) (xy 283.970032 -229.264138) (xy 284.021994 -229.275998) (xy 284.071608 -229.29547)
			(xy 284.117766 -229.322119) (xy 284.159437 -229.35535) (xy 284.195689 -229.394421) (xy 284.225713 -229.438458)
			(xy 284.248839 -229.486479) (xy 284.264549 -229.537409) (xy 284.272492 -229.590113) (xy 284.27299 -229.616762)
			(xy 284.272492 -229.643411) (xy 298.648872 -229.643411) (xy 298.648872 -229.590113) (xy 298.656815 -229.537409)
			(xy 298.672525 -229.486479) (xy 298.695651 -229.438458) (xy 298.725675 -229.394421) (xy 298.761927 -229.35535)
			(xy 298.803598 -229.322119) (xy 298.849756 -229.29547) (xy 298.89937 -229.275998) (xy 298.951332 -229.264138)
			(xy 299.004482 -229.260155) (xy 299.057632 -229.264138) (xy 299.109594 -229.275998) (xy 299.159208 -229.29547)
			(xy 299.205366 -229.322119) (xy 299.247037 -229.35535) (xy 299.283289 -229.394421) (xy 299.313313 -229.438458)
			(xy 299.336439 -229.486479) (xy 299.352149 -229.537409) (xy 299.360092 -229.590113) (xy 299.36059 -229.616762)
			(xy 299.360092 -229.643411) (xy 299.352149 -229.696115) (xy 299.336439 -229.747045) (xy 299.313313 -229.795066)
			(xy 299.283289 -229.839103) (xy 299.247037 -229.878174) (xy 299.205366 -229.911405) (xy 299.159208 -229.938054)
			(xy 299.109594 -229.957526) (xy 299.057632 -229.969386) (xy 299.004482 -229.97337) (xy 298.951332 -229.969386)
			(xy 298.89937 -229.957526) (xy 298.849756 -229.938054) (xy 298.803598 -229.911405) (xy 298.761927 -229.878174)
			(xy 298.725675 -229.839103) (xy 298.695651 -229.795066) (xy 298.672525 -229.747045) (xy 298.656815 -229.696115)
			(xy 298.648872 -229.643411) (xy 284.272492 -229.643411) (xy 284.264549 -229.696115) (xy 284.248839 -229.747045)
			(xy 284.225713 -229.795066) (xy 284.195689 -229.839103) (xy 284.159437 -229.878174) (xy 284.117766 -229.911405)
			(xy 284.071608 -229.938054) (xy 284.021994 -229.957526) (xy 283.970032 -229.969386) (xy 283.916882 -229.97337)
			(xy 283.863732 -229.969386) (xy 283.81177 -229.957526) (xy 283.762156 -229.938054) (xy 283.715998 -229.911405)
			(xy 283.674327 -229.878174) (xy 283.638075 -229.839103) (xy 283.608051 -229.795066) (xy 283.584925 -229.747045)
			(xy 283.569215 -229.696115) (xy 283.561272 -229.643411) (xy 269.184892 -229.643411) (xy 269.176949 -229.696115)
			(xy 269.161239 -229.747045) (xy 269.138113 -229.795066) (xy 269.108089 -229.839103) (xy 269.071837 -229.878174)
			(xy 269.030166 -229.911405) (xy 268.984008 -229.938054) (xy 268.934394 -229.957526) (xy 268.882432 -229.969386)
			(xy 268.829282 -229.97337) (xy 268.776132 -229.969386) (xy 268.72417 -229.957526) (xy 268.674556 -229.938054)
			(xy 268.628398 -229.911405) (xy 268.586727 -229.878174) (xy 268.550475 -229.839103) (xy 268.520451 -229.795066)
			(xy 268.497325 -229.747045) (xy 268.481615 -229.696115) (xy 268.473672 -229.643411) (xy 254 -229.643411)
			(xy 254 -230.493295) (xy 264.373604 -230.493295) (xy 264.373604 -230.439997) (xy 264.381547 -230.387293)
			(xy 264.397257 -230.336363) (xy 264.420383 -230.288342) (xy 264.450407 -230.244305) (xy 264.486659 -230.205234)
			(xy 264.52833 -230.172003) (xy 264.574488 -230.145354) (xy 264.624102 -230.125882) (xy 264.676064 -230.114022)
			(xy 264.729214 -230.110039) (xy 264.782364 -230.114022) (xy 264.834326 -230.125882) (xy 264.88394 -230.145354)
			(xy 264.930098 -230.172003) (xy 264.971769 -230.205234) (xy 265.008021 -230.244305) (xy 265.038045 -230.288342)
			(xy 265.061171 -230.336363) (xy 265.076881 -230.387293) (xy 265.084824 -230.439997) (xy 265.085322 -230.466646)
			(xy 265.084824 -230.493295) (xy 279.461204 -230.493295) (xy 279.461204 -230.439997) (xy 279.469147 -230.387293)
			(xy 279.484857 -230.336363) (xy 279.507983 -230.288342) (xy 279.538007 -230.244305) (xy 279.574259 -230.205234)
			(xy 279.61593 -230.172003) (xy 279.662088 -230.145354) (xy 279.711702 -230.125882) (xy 279.763664 -230.114022)
			(xy 279.816814 -230.110039) (xy 279.869964 -230.114022) (xy 279.921926 -230.125882) (xy 279.97154 -230.145354)
			(xy 280.017698 -230.172003) (xy 280.059369 -230.205234) (xy 280.095621 -230.244305) (xy 280.125645 -230.288342)
			(xy 280.148771 -230.336363) (xy 280.164481 -230.387293) (xy 280.172424 -230.439997) (xy 280.172922 -230.466646)
			(xy 280.172424 -230.493295) (xy 294.548804 -230.493295) (xy 294.548804 -230.439997) (xy 294.556747 -230.387293)
			(xy 294.572457 -230.336363) (xy 294.595583 -230.288342) (xy 294.625607 -230.244305) (xy 294.661859 -230.205234)
			(xy 294.70353 -230.172003) (xy 294.749688 -230.145354) (xy 294.799302 -230.125882) (xy 294.851264 -230.114022)
			(xy 294.904414 -230.110039) (xy 294.957564 -230.114022) (xy 295.009526 -230.125882) (xy 295.05914 -230.145354)
			(xy 295.105298 -230.172003) (xy 295.146969 -230.205234) (xy 295.183221 -230.244305) (xy 295.213245 -230.288342)
			(xy 295.236371 -230.336363) (xy 295.252081 -230.387293) (xy 295.260024 -230.439997) (xy 295.260522 -230.466646)
			(xy 295.260024 -230.493295) (xy 309.636404 -230.493295) (xy 309.636404 -230.439997) (xy 309.644347 -230.387293)
			(xy 309.660057 -230.336363) (xy 309.683183 -230.288342) (xy 309.713207 -230.244305) (xy 309.749459 -230.205234)
			(xy 309.79113 -230.172003) (xy 309.837288 -230.145354) (xy 309.886902 -230.125882) (xy 309.938864 -230.114022)
			(xy 309.992014 -230.110039) (xy 310.045164 -230.114022) (xy 310.097126 -230.125882) (xy 310.14674 -230.145354)
			(xy 310.192898 -230.172003) (xy 310.234569 -230.205234) (xy 310.270821 -230.244305) (xy 310.300845 -230.288342)
			(xy 310.323971 -230.336363) (xy 310.339681 -230.387293) (xy 310.347624 -230.439997) (xy 310.348122 -230.466646)
			(xy 310.347624 -230.493295) (xy 310.339681 -230.545999) (xy 310.323971 -230.596929) (xy 310.300845 -230.64495)
			(xy 310.270821 -230.688987) (xy 310.234569 -230.728058) (xy 310.192898 -230.761289) (xy 310.14674 -230.787938)
			(xy 310.097126 -230.80741) (xy 310.045164 -230.81927) (xy 309.992014 -230.823254) (xy 309.938864 -230.81927)
			(xy 309.886902 -230.80741) (xy 309.837288 -230.787938) (xy 309.79113 -230.761289) (xy 309.749459 -230.728058)
			(xy 309.713207 -230.688987) (xy 309.683183 -230.64495) (xy 309.660057 -230.596929) (xy 309.644347 -230.545999)
			(xy 309.636404 -230.493295) (xy 295.260024 -230.493295) (xy 295.252081 -230.545999) (xy 295.236371 -230.596929)
			(xy 295.213245 -230.64495) (xy 295.183221 -230.688987) (xy 295.146969 -230.728058) (xy 295.105298 -230.761289)
			(xy 295.05914 -230.787938) (xy 295.009526 -230.80741) (xy 294.957564 -230.81927) (xy 294.904414 -230.823254)
			(xy 294.851264 -230.81927) (xy 294.799302 -230.80741) (xy 294.749688 -230.787938) (xy 294.70353 -230.761289)
			(xy 294.661859 -230.728058) (xy 294.625607 -230.688987) (xy 294.595583 -230.64495) (xy 294.572457 -230.596929)
			(xy 294.556747 -230.545999) (xy 294.548804 -230.493295) (xy 280.172424 -230.493295) (xy 280.164481 -230.545999)
			(xy 280.148771 -230.596929) (xy 280.125645 -230.64495) (xy 280.095621 -230.688987) (xy 280.059369 -230.728058)
			(xy 280.017698 -230.761289) (xy 279.97154 -230.787938) (xy 279.921926 -230.80741) (xy 279.869964 -230.81927)
			(xy 279.816814 -230.823254) (xy 279.763664 -230.81927) (xy 279.711702 -230.80741) (xy 279.662088 -230.787938)
			(xy 279.61593 -230.761289) (xy 279.574259 -230.728058) (xy 279.538007 -230.688987) (xy 279.507983 -230.64495)
			(xy 279.484857 -230.596929) (xy 279.469147 -230.545999) (xy 279.461204 -230.493295) (xy 265.084824 -230.493295)
			(xy 265.076881 -230.545999) (xy 265.061171 -230.596929) (xy 265.038045 -230.64495) (xy 265.008021 -230.688987)
			(xy 264.971769 -230.728058) (xy 264.930098 -230.761289) (xy 264.88394 -230.787938) (xy 264.834326 -230.80741)
			(xy 264.782364 -230.81927) (xy 264.729214 -230.823254) (xy 264.676064 -230.81927) (xy 264.624102 -230.80741)
			(xy 264.574488 -230.787938) (xy 264.52833 -230.761289) (xy 264.486659 -230.728058) (xy 264.450407 -230.688987)
			(xy 264.420383 -230.64495) (xy 264.397257 -230.596929) (xy 264.381547 -230.545999) (xy 264.373604 -230.493295)
			(xy 254 -230.493295) (xy 254 -231.343433) (xy 268.473672 -231.343433) (xy 268.473672 -231.290135)
			(xy 268.481615 -231.237431) (xy 268.497325 -231.186501) (xy 268.520451 -231.13848) (xy 268.550475 -231.094443)
			(xy 268.586727 -231.055372) (xy 268.628398 -231.022141) (xy 268.674556 -230.995492) (xy 268.72417 -230.97602)
			(xy 268.776132 -230.96416) (xy 268.829282 -230.960177) (xy 268.882432 -230.96416) (xy 268.934394 -230.97602)
			(xy 268.984008 -230.995492) (xy 269.030166 -231.022141) (xy 269.071837 -231.055372) (xy 269.108089 -231.094443)
			(xy 269.138113 -231.13848) (xy 269.161239 -231.186501) (xy 269.176949 -231.237431) (xy 269.184892 -231.290135)
			(xy 269.18539 -231.316784) (xy 269.184892 -231.343433) (xy 283.561272 -231.343433) (xy 283.561272 -231.290135)
			(xy 283.569215 -231.237431) (xy 283.584925 -231.186501) (xy 283.608051 -231.13848) (xy 283.638075 -231.094443)
			(xy 283.674327 -231.055372) (xy 283.715998 -231.022141) (xy 283.762156 -230.995492) (xy 283.81177 -230.97602)
			(xy 283.863732 -230.96416) (xy 283.916882 -230.960177) (xy 283.970032 -230.96416) (xy 284.021994 -230.97602)
			(xy 284.071608 -230.995492) (xy 284.117766 -231.022141) (xy 284.159437 -231.055372) (xy 284.195689 -231.094443)
			(xy 284.225713 -231.13848) (xy 284.248839 -231.186501) (xy 284.264549 -231.237431) (xy 284.272492 -231.290135)
			(xy 284.27299 -231.316784) (xy 284.272492 -231.343433) (xy 298.648872 -231.343433) (xy 298.648872 -231.290135)
			(xy 298.656815 -231.237431) (xy 298.672525 -231.186501) (xy 298.695651 -231.13848) (xy 298.725675 -231.094443)
			(xy 298.761927 -231.055372) (xy 298.803598 -231.022141) (xy 298.849756 -230.995492) (xy 298.89937 -230.97602)
			(xy 298.951332 -230.96416) (xy 299.004482 -230.960177) (xy 299.057632 -230.96416) (xy 299.109594 -230.97602)
			(xy 299.159208 -230.995492) (xy 299.205366 -231.022141) (xy 299.247037 -231.055372) (xy 299.283289 -231.094443)
			(xy 299.313313 -231.13848) (xy 299.336439 -231.186501) (xy 299.352149 -231.237431) (xy 299.360092 -231.290135)
			(xy 299.36059 -231.316784) (xy 299.360092 -231.343433) (xy 299.352149 -231.396137) (xy 299.336439 -231.447067)
			(xy 299.313313 -231.495088) (xy 299.283289 -231.539125) (xy 299.247037 -231.578196) (xy 299.205366 -231.611427)
			(xy 299.159208 -231.638076) (xy 299.109594 -231.657548) (xy 299.057632 -231.669408) (xy 299.004482 -231.673392)
			(xy 298.951332 -231.669408) (xy 298.89937 -231.657548) (xy 298.849756 -231.638076) (xy 298.803598 -231.611427)
			(xy 298.761927 -231.578196) (xy 298.725675 -231.539125) (xy 298.695651 -231.495088) (xy 298.672525 -231.447067)
			(xy 298.656815 -231.396137) (xy 298.648872 -231.343433) (xy 284.272492 -231.343433) (xy 284.264549 -231.396137)
			(xy 284.248839 -231.447067) (xy 284.225713 -231.495088) (xy 284.195689 -231.539125) (xy 284.159437 -231.578196)
			(xy 284.117766 -231.611427) (xy 284.071608 -231.638076) (xy 284.021994 -231.657548) (xy 283.970032 -231.669408)
			(xy 283.916882 -231.673392) (xy 283.863732 -231.669408) (xy 283.81177 -231.657548) (xy 283.762156 -231.638076)
			(xy 283.715998 -231.611427) (xy 283.674327 -231.578196) (xy 283.638075 -231.539125) (xy 283.608051 -231.495088)
			(xy 283.584925 -231.447067) (xy 283.569215 -231.396137) (xy 283.561272 -231.343433) (xy 269.184892 -231.343433)
			(xy 269.176949 -231.396137) (xy 269.161239 -231.447067) (xy 269.138113 -231.495088) (xy 269.108089 -231.539125)
			(xy 269.071837 -231.578196) (xy 269.030166 -231.611427) (xy 268.984008 -231.638076) (xy 268.934394 -231.657548)
			(xy 268.882432 -231.669408) (xy 268.829282 -231.673392) (xy 268.776132 -231.669408) (xy 268.72417 -231.657548)
			(xy 268.674556 -231.638076) (xy 268.628398 -231.611427) (xy 268.586727 -231.578196) (xy 268.550475 -231.539125)
			(xy 268.520451 -231.495088) (xy 268.497325 -231.447067) (xy 268.481615 -231.396137) (xy 268.473672 -231.343433)
			(xy 254 -231.343433) (xy 254 -232.193317) (xy 264.373604 -232.193317) (xy 264.373604 -232.140019)
			(xy 264.381547 -232.087315) (xy 264.397257 -232.036385) (xy 264.420383 -231.988364) (xy 264.450407 -231.944327)
			(xy 264.486659 -231.905256) (xy 264.52833 -231.872025) (xy 264.574488 -231.845376) (xy 264.624102 -231.825904)
			(xy 264.676064 -231.814044) (xy 264.729214 -231.810061) (xy 264.782364 -231.814044) (xy 264.834326 -231.825904)
			(xy 264.88394 -231.845376) (xy 264.930098 -231.872025) (xy 264.971769 -231.905256) (xy 265.008021 -231.944327)
			(xy 265.038045 -231.988364) (xy 265.061171 -232.036385) (xy 265.076881 -232.087315) (xy 265.084824 -232.140019)
			(xy 265.085322 -232.166668) (xy 265.084824 -232.193317) (xy 279.461204 -232.193317) (xy 279.461204 -232.140019)
			(xy 279.469147 -232.087315) (xy 279.484857 -232.036385) (xy 279.507983 -231.988364) (xy 279.538007 -231.944327)
			(xy 279.574259 -231.905256) (xy 279.61593 -231.872025) (xy 279.662088 -231.845376) (xy 279.711702 -231.825904)
			(xy 279.763664 -231.814044) (xy 279.816814 -231.810061) (xy 279.869964 -231.814044) (xy 279.921926 -231.825904)
			(xy 279.97154 -231.845376) (xy 280.017698 -231.872025) (xy 280.059369 -231.905256) (xy 280.095621 -231.944327)
			(xy 280.125645 -231.988364) (xy 280.148771 -232.036385) (xy 280.164481 -232.087315) (xy 280.172424 -232.140019)
			(xy 280.172922 -232.166668) (xy 280.172424 -232.193317) (xy 294.548804 -232.193317) (xy 294.548804 -232.140019)
			(xy 294.556747 -232.087315) (xy 294.572457 -232.036385) (xy 294.595583 -231.988364) (xy 294.625607 -231.944327)
			(xy 294.661859 -231.905256) (xy 294.70353 -231.872025) (xy 294.749688 -231.845376) (xy 294.799302 -231.825904)
			(xy 294.851264 -231.814044) (xy 294.904414 -231.810061) (xy 294.957564 -231.814044) (xy 295.009526 -231.825904)
			(xy 295.05914 -231.845376) (xy 295.105298 -231.872025) (xy 295.146969 -231.905256) (xy 295.183221 -231.944327)
			(xy 295.213245 -231.988364) (xy 295.236371 -232.036385) (xy 295.252081 -232.087315) (xy 295.260024 -232.140019)
			(xy 295.260522 -232.166668) (xy 295.260024 -232.193317) (xy 309.636404 -232.193317) (xy 309.636404 -232.140019)
			(xy 309.644347 -232.087315) (xy 309.660057 -232.036385) (xy 309.683183 -231.988364) (xy 309.713207 -231.944327)
			(xy 309.749459 -231.905256) (xy 309.79113 -231.872025) (xy 309.837288 -231.845376) (xy 309.886902 -231.825904)
			(xy 309.938864 -231.814044) (xy 309.992014 -231.810061) (xy 310.045164 -231.814044) (xy 310.097126 -231.825904)
			(xy 310.14674 -231.845376) (xy 310.192898 -231.872025) (xy 310.234569 -231.905256) (xy 310.270821 -231.944327)
			(xy 310.300845 -231.988364) (xy 310.323971 -232.036385) (xy 310.339681 -232.087315) (xy 310.347624 -232.140019)
			(xy 310.348122 -232.166668) (xy 310.347624 -232.193317) (xy 310.339681 -232.246021) (xy 310.323971 -232.296951)
			(xy 310.300845 -232.344972) (xy 310.270821 -232.389009) (xy 310.234569 -232.42808) (xy 310.192898 -232.461311)
			(xy 310.14674 -232.48796) (xy 310.097126 -232.507432) (xy 310.045164 -232.519292) (xy 309.992014 -232.523276)
			(xy 309.938864 -232.519292) (xy 309.886902 -232.507432) (xy 309.837288 -232.48796) (xy 309.79113 -232.461311)
			(xy 309.749459 -232.42808) (xy 309.713207 -232.389009) (xy 309.683183 -232.344972) (xy 309.660057 -232.296951)
			(xy 309.644347 -232.246021) (xy 309.636404 -232.193317) (xy 295.260024 -232.193317) (xy 295.252081 -232.246021)
			(xy 295.236371 -232.296951) (xy 295.213245 -232.344972) (xy 295.183221 -232.389009) (xy 295.146969 -232.42808)
			(xy 295.105298 -232.461311) (xy 295.05914 -232.48796) (xy 295.009526 -232.507432) (xy 294.957564 -232.519292)
			(xy 294.904414 -232.523276) (xy 294.851264 -232.519292) (xy 294.799302 -232.507432) (xy 294.749688 -232.48796)
			(xy 294.70353 -232.461311) (xy 294.661859 -232.42808) (xy 294.625607 -232.389009) (xy 294.595583 -232.344972)
			(xy 294.572457 -232.296951) (xy 294.556747 -232.246021) (xy 294.548804 -232.193317) (xy 280.172424 -232.193317)
			(xy 280.164481 -232.246021) (xy 280.148771 -232.296951) (xy 280.125645 -232.344972) (xy 280.095621 -232.389009)
			(xy 280.059369 -232.42808) (xy 280.017698 -232.461311) (xy 279.97154 -232.48796) (xy 279.921926 -232.507432)
			(xy 279.869964 -232.519292) (xy 279.816814 -232.523276) (xy 279.763664 -232.519292) (xy 279.711702 -232.507432)
			(xy 279.662088 -232.48796) (xy 279.61593 -232.461311) (xy 279.574259 -232.42808) (xy 279.538007 -232.389009)
			(xy 279.507983 -232.344972) (xy 279.484857 -232.296951) (xy 279.469147 -232.246021) (xy 279.461204 -232.193317)
			(xy 265.084824 -232.193317) (xy 265.076881 -232.246021) (xy 265.061171 -232.296951) (xy 265.038045 -232.344972)
			(xy 265.008021 -232.389009) (xy 264.971769 -232.42808) (xy 264.930098 -232.461311) (xy 264.88394 -232.48796)
			(xy 264.834326 -232.507432) (xy 264.782364 -232.519292) (xy 264.729214 -232.523276) (xy 264.676064 -232.519292)
			(xy 264.624102 -232.507432) (xy 264.574488 -232.48796) (xy 264.52833 -232.461311) (xy 264.486659 -232.42808)
			(xy 264.450407 -232.389009) (xy 264.420383 -232.344972) (xy 264.397257 -232.296951) (xy 264.381547 -232.246021)
			(xy 264.373604 -232.193317) (xy 254 -232.193317) (xy 254 -233.043455) (xy 268.473672 -233.043455)
			(xy 268.473672 -232.990157) (xy 268.481615 -232.937453) (xy 268.497325 -232.886523) (xy 268.520451 -232.838502)
			(xy 268.550475 -232.794465) (xy 268.586727 -232.755394) (xy 268.628398 -232.722163) (xy 268.674556 -232.695514)
			(xy 268.72417 -232.676042) (xy 268.776132 -232.664182) (xy 268.829282 -232.660199) (xy 268.882432 -232.664182)
			(xy 268.934394 -232.676042) (xy 268.984008 -232.695514) (xy 269.030166 -232.722163) (xy 269.071837 -232.755394)
			(xy 269.108089 -232.794465) (xy 269.138113 -232.838502) (xy 269.161239 -232.886523) (xy 269.176949 -232.937453)
			(xy 269.184892 -232.990157) (xy 269.18539 -233.016806) (xy 269.184892 -233.043455) (xy 283.561272 -233.043455)
			(xy 283.561272 -232.990157) (xy 283.569215 -232.937453) (xy 283.584925 -232.886523) (xy 283.608051 -232.838502)
			(xy 283.638075 -232.794465) (xy 283.674327 -232.755394) (xy 283.715998 -232.722163) (xy 283.762156 -232.695514)
			(xy 283.81177 -232.676042) (xy 283.863732 -232.664182) (xy 283.916882 -232.660199) (xy 283.970032 -232.664182)
			(xy 284.021994 -232.676042) (xy 284.071608 -232.695514) (xy 284.117766 -232.722163) (xy 284.159437 -232.755394)
			(xy 284.195689 -232.794465) (xy 284.225713 -232.838502) (xy 284.248839 -232.886523) (xy 284.264549 -232.937453)
			(xy 284.272492 -232.990157) (xy 284.27299 -233.016806) (xy 284.272492 -233.043455) (xy 298.648872 -233.043455)
			(xy 298.648872 -232.990157) (xy 298.656815 -232.937453) (xy 298.672525 -232.886523) (xy 298.695651 -232.838502)
			(xy 298.725675 -232.794465) (xy 298.761927 -232.755394) (xy 298.803598 -232.722163) (xy 298.849756 -232.695514)
			(xy 298.89937 -232.676042) (xy 298.951332 -232.664182) (xy 299.004482 -232.660199) (xy 299.057632 -232.664182)
			(xy 299.109594 -232.676042) (xy 299.159208 -232.695514) (xy 299.205366 -232.722163) (xy 299.247037 -232.755394)
			(xy 299.283289 -232.794465) (xy 299.313313 -232.838502) (xy 299.336439 -232.886523) (xy 299.352149 -232.937453)
			(xy 299.360092 -232.990157) (xy 299.36059 -233.016806) (xy 299.360092 -233.043455) (xy 299.352149 -233.096159)
			(xy 299.336439 -233.147089) (xy 299.313313 -233.19511) (xy 299.283289 -233.239147) (xy 299.247037 -233.278218)
			(xy 299.205366 -233.311449) (xy 299.159208 -233.338098) (xy 299.109594 -233.35757) (xy 299.057632 -233.36943)
			(xy 299.004482 -233.373414) (xy 298.951332 -233.36943) (xy 298.89937 -233.35757) (xy 298.849756 -233.338098)
			(xy 298.803598 -233.311449) (xy 298.761927 -233.278218) (xy 298.725675 -233.239147) (xy 298.695651 -233.19511)
			(xy 298.672525 -233.147089) (xy 298.656815 -233.096159) (xy 298.648872 -233.043455) (xy 284.272492 -233.043455)
			(xy 284.264549 -233.096159) (xy 284.248839 -233.147089) (xy 284.225713 -233.19511) (xy 284.195689 -233.239147)
			(xy 284.159437 -233.278218) (xy 284.117766 -233.311449) (xy 284.071608 -233.338098) (xy 284.021994 -233.35757)
			(xy 283.970032 -233.36943) (xy 283.916882 -233.373414) (xy 283.863732 -233.36943) (xy 283.81177 -233.35757)
			(xy 283.762156 -233.338098) (xy 283.715998 -233.311449) (xy 283.674327 -233.278218) (xy 283.638075 -233.239147)
			(xy 283.608051 -233.19511) (xy 283.584925 -233.147089) (xy 283.569215 -233.096159) (xy 283.561272 -233.043455)
			(xy 269.184892 -233.043455) (xy 269.176949 -233.096159) (xy 269.161239 -233.147089) (xy 269.138113 -233.19511)
			(xy 269.108089 -233.239147) (xy 269.071837 -233.278218) (xy 269.030166 -233.311449) (xy 268.984008 -233.338098)
			(xy 268.934394 -233.35757) (xy 268.882432 -233.36943) (xy 268.829282 -233.373414) (xy 268.776132 -233.36943)
			(xy 268.72417 -233.35757) (xy 268.674556 -233.338098) (xy 268.628398 -233.311449) (xy 268.586727 -233.278218)
			(xy 268.550475 -233.239147) (xy 268.520451 -233.19511) (xy 268.497325 -233.147089) (xy 268.481615 -233.096159)
			(xy 268.473672 -233.043455) (xy 254 -233.043455) (xy 254 -233.893339) (xy 264.373604 -233.893339)
			(xy 264.373604 -233.840041) (xy 264.381547 -233.787337) (xy 264.397257 -233.736407) (xy 264.420383 -233.688386)
			(xy 264.450407 -233.644349) (xy 264.486659 -233.605278) (xy 264.52833 -233.572047) (xy 264.574488 -233.545398)
			(xy 264.624102 -233.525926) (xy 264.676064 -233.514066) (xy 264.729214 -233.510083) (xy 264.782364 -233.514066)
			(xy 264.834326 -233.525926) (xy 264.88394 -233.545398) (xy 264.930098 -233.572047) (xy 264.971769 -233.605278)
			(xy 265.008021 -233.644349) (xy 265.038045 -233.688386) (xy 265.061171 -233.736407) (xy 265.076881 -233.787337)
			(xy 265.084824 -233.840041) (xy 265.085322 -233.86669) (xy 265.084824 -233.893339) (xy 279.461204 -233.893339)
			(xy 279.461204 -233.840041) (xy 279.469147 -233.787337) (xy 279.484857 -233.736407) (xy 279.507983 -233.688386)
			(xy 279.538007 -233.644349) (xy 279.574259 -233.605278) (xy 279.61593 -233.572047) (xy 279.662088 -233.545398)
			(xy 279.711702 -233.525926) (xy 279.763664 -233.514066) (xy 279.816814 -233.510083) (xy 279.869964 -233.514066)
			(xy 279.921926 -233.525926) (xy 279.97154 -233.545398) (xy 280.017698 -233.572047) (xy 280.059369 -233.605278)
			(xy 280.095621 -233.644349) (xy 280.125645 -233.688386) (xy 280.148771 -233.736407) (xy 280.164481 -233.787337)
			(xy 280.172424 -233.840041) (xy 280.172922 -233.86669) (xy 280.172424 -233.893339) (xy 294.548804 -233.893339)
			(xy 294.548804 -233.840041) (xy 294.556747 -233.787337) (xy 294.572457 -233.736407) (xy 294.595583 -233.688386)
			(xy 294.625607 -233.644349) (xy 294.661859 -233.605278) (xy 294.70353 -233.572047) (xy 294.749688 -233.545398)
			(xy 294.799302 -233.525926) (xy 294.851264 -233.514066) (xy 294.904414 -233.510083) (xy 294.957564 -233.514066)
			(xy 295.009526 -233.525926) (xy 295.05914 -233.545398) (xy 295.105298 -233.572047) (xy 295.146969 -233.605278)
			(xy 295.183221 -233.644349) (xy 295.213245 -233.688386) (xy 295.236371 -233.736407) (xy 295.252081 -233.787337)
			(xy 295.260024 -233.840041) (xy 295.260522 -233.86669) (xy 295.260024 -233.893339) (xy 295.252081 -233.946043)
			(xy 295.236371 -233.996973) (xy 295.213245 -234.044994) (xy 295.183221 -234.089031) (xy 295.146969 -234.128102)
			(xy 295.105298 -234.161333) (xy 295.05914 -234.187982) (xy 295.009526 -234.207454) (xy 294.957564 -234.219314)
			(xy 294.904414 -234.223298) (xy 294.851264 -234.219314) (xy 294.799302 -234.207454) (xy 294.749688 -234.187982)
			(xy 294.70353 -234.161333) (xy 294.661859 -234.128102) (xy 294.625607 -234.089031) (xy 294.595583 -234.044994)
			(xy 294.572457 -233.996973) (xy 294.556747 -233.946043) (xy 294.548804 -233.893339) (xy 280.172424 -233.893339)
			(xy 280.164481 -233.946043) (xy 280.148771 -233.996973) (xy 280.125645 -234.044994) (xy 280.095621 -234.089031)
			(xy 280.059369 -234.128102) (xy 280.017698 -234.161333) (xy 279.97154 -234.187982) (xy 279.921926 -234.207454)
			(xy 279.869964 -234.219314) (xy 279.816814 -234.223298) (xy 279.763664 -234.219314) (xy 279.711702 -234.207454)
			(xy 279.662088 -234.187982) (xy 279.61593 -234.161333) (xy 279.574259 -234.128102) (xy 279.538007 -234.089031)
			(xy 279.507983 -234.044994) (xy 279.484857 -233.996973) (xy 279.469147 -233.946043) (xy 279.461204 -233.893339)
			(xy 265.084824 -233.893339) (xy 265.076881 -233.946043) (xy 265.061171 -233.996973) (xy 265.038045 -234.044994)
			(xy 265.008021 -234.089031) (xy 264.971769 -234.128102) (xy 264.930098 -234.161333) (xy 264.88394 -234.187982)
			(xy 264.834326 -234.207454) (xy 264.782364 -234.219314) (xy 264.729214 -234.223298) (xy 264.676064 -234.219314)
			(xy 264.624102 -234.207454) (xy 264.574488 -234.187982) (xy 264.52833 -234.161333) (xy 264.486659 -234.128102)
			(xy 264.450407 -234.089031) (xy 264.420383 -234.044994) (xy 264.397257 -233.996973) (xy 264.381547 -233.946043)
			(xy 264.373604 -233.893339) (xy 254 -233.893339) (xy 254 -234.743223) (xy 268.473672 -234.743223)
			(xy 268.473672 -234.689925) (xy 268.481615 -234.637221) (xy 268.497325 -234.586291) (xy 268.520451 -234.53827)
			(xy 268.550475 -234.494233) (xy 268.586727 -234.455162) (xy 268.628398 -234.421931) (xy 268.674556 -234.395282)
			(xy 268.72417 -234.37581) (xy 268.776132 -234.36395) (xy 268.829282 -234.359967) (xy 268.882432 -234.36395)
			(xy 268.934394 -234.37581) (xy 268.984008 -234.395282) (xy 269.030166 -234.421931) (xy 269.071837 -234.455162)
			(xy 269.108089 -234.494233) (xy 269.138113 -234.53827) (xy 269.161239 -234.586291) (xy 269.176949 -234.637221)
			(xy 269.184892 -234.689925) (xy 269.18539 -234.716574) (xy 269.184892 -234.743223) (xy 283.561272 -234.743223)
			(xy 283.561272 -234.689925) (xy 283.569215 -234.637221) (xy 283.584925 -234.586291) (xy 283.608051 -234.53827)
			(xy 283.638075 -234.494233) (xy 283.674327 -234.455162) (xy 283.715998 -234.421931) (xy 283.762156 -234.395282)
			(xy 283.81177 -234.37581) (xy 283.863732 -234.36395) (xy 283.916882 -234.359967) (xy 283.970032 -234.36395)
			(xy 284.021994 -234.37581) (xy 284.071608 -234.395282) (xy 284.117766 -234.421931) (xy 284.159437 -234.455162)
			(xy 284.195689 -234.494233) (xy 284.225713 -234.53827) (xy 284.248839 -234.586291) (xy 284.264549 -234.637221)
			(xy 284.272492 -234.689925) (xy 284.27299 -234.716574) (xy 284.272492 -234.743223) (xy 298.648872 -234.743223)
			(xy 298.648872 -234.689925) (xy 298.656815 -234.637221) (xy 298.672525 -234.586291) (xy 298.695651 -234.53827)
			(xy 298.725675 -234.494233) (xy 298.761927 -234.455162) (xy 298.803598 -234.421931) (xy 298.849756 -234.395282)
			(xy 298.89937 -234.37581) (xy 298.951332 -234.36395) (xy 299.004482 -234.359967) (xy 299.057632 -234.36395)
			(xy 299.109594 -234.37581) (xy 299.159208 -234.395282) (xy 299.205366 -234.421931) (xy 299.247037 -234.455162)
			(xy 299.283289 -234.494233) (xy 299.313313 -234.53827) (xy 299.336439 -234.586291) (xy 299.352149 -234.637221)
			(xy 299.360092 -234.689925) (xy 299.36059 -234.716574) (xy 299.360092 -234.743223) (xy 299.352149 -234.795927)
			(xy 299.336439 -234.846857) (xy 299.313313 -234.894878) (xy 299.283289 -234.938915) (xy 299.247037 -234.977986)
			(xy 299.205366 -235.011217) (xy 299.159208 -235.037866) (xy 299.109594 -235.057338) (xy 299.057632 -235.069198)
			(xy 299.004482 -235.073182) (xy 298.951332 -235.069198) (xy 298.89937 -235.057338) (xy 298.849756 -235.037866)
			(xy 298.803598 -235.011217) (xy 298.761927 -234.977986) (xy 298.725675 -234.938915) (xy 298.695651 -234.894878)
			(xy 298.672525 -234.846857) (xy 298.656815 -234.795927) (xy 298.648872 -234.743223) (xy 284.272492 -234.743223)
			(xy 284.264549 -234.795927) (xy 284.248839 -234.846857) (xy 284.225713 -234.894878) (xy 284.195689 -234.938915)
			(xy 284.159437 -234.977986) (xy 284.117766 -235.011217) (xy 284.071608 -235.037866) (xy 284.021994 -235.057338)
			(xy 283.970032 -235.069198) (xy 283.916882 -235.073182) (xy 283.863732 -235.069198) (xy 283.81177 -235.057338)
			(xy 283.762156 -235.037866) (xy 283.715998 -235.011217) (xy 283.674327 -234.977986) (xy 283.638075 -234.938915)
			(xy 283.608051 -234.894878) (xy 283.584925 -234.846857) (xy 283.569215 -234.795927) (xy 283.561272 -234.743223)
			(xy 269.184892 -234.743223) (xy 269.176949 -234.795927) (xy 269.161239 -234.846857) (xy 269.138113 -234.894878)
			(xy 269.108089 -234.938915) (xy 269.071837 -234.977986) (xy 269.030166 -235.011217) (xy 268.984008 -235.037866)
			(xy 268.934394 -235.057338) (xy 268.882432 -235.069198) (xy 268.829282 -235.073182) (xy 268.776132 -235.069198)
			(xy 268.72417 -235.057338) (xy 268.674556 -235.037866) (xy 268.628398 -235.011217) (xy 268.586727 -234.977986)
			(xy 268.550475 -234.938915) (xy 268.520451 -234.894878) (xy 268.497325 -234.846857) (xy 268.481615 -234.795927)
			(xy 268.473672 -234.743223) (xy 254 -234.743223) (xy 254 -235.593361) (xy 264.373604 -235.593361)
			(xy 264.373604 -235.540063) (xy 264.381547 -235.487359) (xy 264.397257 -235.436429) (xy 264.420383 -235.388408)
			(xy 264.450407 -235.344371) (xy 264.486659 -235.3053) (xy 264.52833 -235.272069) (xy 264.574488 -235.24542)
			(xy 264.624102 -235.225948) (xy 264.676064 -235.214088) (xy 264.729214 -235.210105) (xy 264.782364 -235.214088)
			(xy 264.834326 -235.225948) (xy 264.88394 -235.24542) (xy 264.930098 -235.272069) (xy 264.971769 -235.3053)
			(xy 265.008021 -235.344371) (xy 265.038045 -235.388408) (xy 265.061171 -235.436429) (xy 265.076881 -235.487359)
			(xy 265.084824 -235.540063) (xy 265.085322 -235.566712) (xy 265.084824 -235.593361) (xy 279.461204 -235.593361)
			(xy 279.461204 -235.540063) (xy 279.469147 -235.487359) (xy 279.484857 -235.436429) (xy 279.507983 -235.388408)
			(xy 279.538007 -235.344371) (xy 279.574259 -235.3053) (xy 279.61593 -235.272069) (xy 279.662088 -235.24542)
			(xy 279.711702 -235.225948) (xy 279.763664 -235.214088) (xy 279.816814 -235.210105) (xy 279.869964 -235.214088)
			(xy 279.921926 -235.225948) (xy 279.97154 -235.24542) (xy 280.017698 -235.272069) (xy 280.059369 -235.3053)
			(xy 280.095621 -235.344371) (xy 280.125645 -235.388408) (xy 280.148771 -235.436429) (xy 280.164481 -235.487359)
			(xy 280.172424 -235.540063) (xy 280.172922 -235.566712) (xy 280.172424 -235.593361) (xy 294.548804 -235.593361)
			(xy 294.548804 -235.540063) (xy 294.556747 -235.487359) (xy 294.572457 -235.436429) (xy 294.595583 -235.388408)
			(xy 294.625607 -235.344371) (xy 294.661859 -235.3053) (xy 294.70353 -235.272069) (xy 294.749688 -235.24542)
			(xy 294.799302 -235.225948) (xy 294.851264 -235.214088) (xy 294.904414 -235.210105) (xy 294.957564 -235.214088)
			(xy 295.009526 -235.225948) (xy 295.05914 -235.24542) (xy 295.105298 -235.272069) (xy 295.146969 -235.3053)
			(xy 295.183221 -235.344371) (xy 295.213245 -235.388408) (xy 295.236371 -235.436429) (xy 295.252081 -235.487359)
			(xy 295.260024 -235.540063) (xy 295.260522 -235.566712) (xy 295.260024 -235.593361) (xy 295.252081 -235.646065)
			(xy 295.236371 -235.696995) (xy 295.213245 -235.745016) (xy 295.183221 -235.789053) (xy 295.146969 -235.828124)
			(xy 295.105298 -235.861355) (xy 295.05914 -235.888004) (xy 295.009526 -235.907476) (xy 294.957564 -235.919336)
			(xy 294.904414 -235.92332) (xy 294.851264 -235.919336) (xy 294.799302 -235.907476) (xy 294.749688 -235.888004)
			(xy 294.70353 -235.861355) (xy 294.661859 -235.828124) (xy 294.625607 -235.789053) (xy 294.595583 -235.745016)
			(xy 294.572457 -235.696995) (xy 294.556747 -235.646065) (xy 294.548804 -235.593361) (xy 280.172424 -235.593361)
			(xy 280.164481 -235.646065) (xy 280.148771 -235.696995) (xy 280.125645 -235.745016) (xy 280.095621 -235.789053)
			(xy 280.059369 -235.828124) (xy 280.017698 -235.861355) (xy 279.97154 -235.888004) (xy 279.921926 -235.907476)
			(xy 279.869964 -235.919336) (xy 279.816814 -235.92332) (xy 279.763664 -235.919336) (xy 279.711702 -235.907476)
			(xy 279.662088 -235.888004) (xy 279.61593 -235.861355) (xy 279.574259 -235.828124) (xy 279.538007 -235.789053)
			(xy 279.507983 -235.745016) (xy 279.484857 -235.696995) (xy 279.469147 -235.646065) (xy 279.461204 -235.593361)
			(xy 265.084824 -235.593361) (xy 265.076881 -235.646065) (xy 265.061171 -235.696995) (xy 265.038045 -235.745016)
			(xy 265.008021 -235.789053) (xy 264.971769 -235.828124) (xy 264.930098 -235.861355) (xy 264.88394 -235.888004)
			(xy 264.834326 -235.907476) (xy 264.782364 -235.919336) (xy 264.729214 -235.92332) (xy 264.676064 -235.919336)
			(xy 264.624102 -235.907476) (xy 264.574488 -235.888004) (xy 264.52833 -235.861355) (xy 264.486659 -235.828124)
			(xy 264.450407 -235.789053) (xy 264.420383 -235.745016) (xy 264.397257 -235.696995) (xy 264.381547 -235.646065)
			(xy 264.373604 -235.593361) (xy 254 -235.593361) (xy 254 -236.443245) (xy 268.473672 -236.443245)
			(xy 268.473672 -236.389947) (xy 268.481615 -236.337243) (xy 268.497325 -236.286313) (xy 268.520451 -236.238292)
			(xy 268.550475 -236.194255) (xy 268.586727 -236.155184) (xy 268.628398 -236.121953) (xy 268.674556 -236.095304)
			(xy 268.72417 -236.075832) (xy 268.776132 -236.063972) (xy 268.829282 -236.059989) (xy 268.882432 -236.063972)
			(xy 268.934394 -236.075832) (xy 268.984008 -236.095304) (xy 269.030166 -236.121953) (xy 269.071837 -236.155184)
			(xy 269.108089 -236.194255) (xy 269.138113 -236.238292) (xy 269.161239 -236.286313) (xy 269.176949 -236.337243)
			(xy 269.184892 -236.389947) (xy 269.18539 -236.416596) (xy 269.184892 -236.443245) (xy 283.561272 -236.443245)
			(xy 283.561272 -236.389947) (xy 283.569215 -236.337243) (xy 283.584925 -236.286313) (xy 283.608051 -236.238292)
			(xy 283.638075 -236.194255) (xy 283.674327 -236.155184) (xy 283.715998 -236.121953) (xy 283.762156 -236.095304)
			(xy 283.81177 -236.075832) (xy 283.863732 -236.063972) (xy 283.916882 -236.059989) (xy 283.970032 -236.063972)
			(xy 284.021994 -236.075832) (xy 284.071608 -236.095304) (xy 284.117766 -236.121953) (xy 284.159437 -236.155184)
			(xy 284.195689 -236.194255) (xy 284.225713 -236.238292) (xy 284.248839 -236.286313) (xy 284.264549 -236.337243)
			(xy 284.272492 -236.389947) (xy 284.27299 -236.416596) (xy 284.272492 -236.443245) (xy 298.648872 -236.443245)
			(xy 298.648872 -236.389947) (xy 298.656815 -236.337243) (xy 298.672525 -236.286313) (xy 298.695651 -236.238292)
			(xy 298.725675 -236.194255) (xy 298.761927 -236.155184) (xy 298.803598 -236.121953) (xy 298.849756 -236.095304)
			(xy 298.89937 -236.075832) (xy 298.951332 -236.063972) (xy 299.004482 -236.059989) (xy 299.057632 -236.063972)
			(xy 299.109594 -236.075832) (xy 299.159208 -236.095304) (xy 299.205366 -236.121953) (xy 299.247037 -236.155184)
			(xy 299.283289 -236.194255) (xy 299.313313 -236.238292) (xy 299.336439 -236.286313) (xy 299.352149 -236.337243)
			(xy 299.360092 -236.389947) (xy 299.36059 -236.416596) (xy 299.360092 -236.443245) (xy 299.352149 -236.495949)
			(xy 299.336439 -236.546879) (xy 299.313313 -236.5949) (xy 299.283289 -236.638937) (xy 299.247037 -236.678008)
			(xy 299.205366 -236.711239) (xy 299.159208 -236.737888) (xy 299.109594 -236.75736) (xy 299.057632 -236.76922)
			(xy 299.004482 -236.773204) (xy 298.951332 -236.76922) (xy 298.89937 -236.75736) (xy 298.849756 -236.737888)
			(xy 298.803598 -236.711239) (xy 298.761927 -236.678008) (xy 298.725675 -236.638937) (xy 298.695651 -236.5949)
			(xy 298.672525 -236.546879) (xy 298.656815 -236.495949) (xy 298.648872 -236.443245) (xy 284.272492 -236.443245)
			(xy 284.264549 -236.495949) (xy 284.248839 -236.546879) (xy 284.225713 -236.5949) (xy 284.195689 -236.638937)
			(xy 284.159437 -236.678008) (xy 284.117766 -236.711239) (xy 284.071608 -236.737888) (xy 284.021994 -236.75736)
			(xy 283.970032 -236.76922) (xy 283.916882 -236.773204) (xy 283.863732 -236.76922) (xy 283.81177 -236.75736)
			(xy 283.762156 -236.737888) (xy 283.715998 -236.711239) (xy 283.674327 -236.678008) (xy 283.638075 -236.638937)
			(xy 283.608051 -236.5949) (xy 283.584925 -236.546879) (xy 283.569215 -236.495949) (xy 283.561272 -236.443245)
			(xy 269.184892 -236.443245) (xy 269.176949 -236.495949) (xy 269.161239 -236.546879) (xy 269.138113 -236.5949)
			(xy 269.108089 -236.638937) (xy 269.071837 -236.678008) (xy 269.030166 -236.711239) (xy 268.984008 -236.737888)
			(xy 268.934394 -236.75736) (xy 268.882432 -236.76922) (xy 268.829282 -236.773204) (xy 268.776132 -236.76922)
			(xy 268.72417 -236.75736) (xy 268.674556 -236.737888) (xy 268.628398 -236.711239) (xy 268.586727 -236.678008)
			(xy 268.550475 -236.638937) (xy 268.520451 -236.5949) (xy 268.497325 -236.546879) (xy 268.481615 -236.495949)
			(xy 268.473672 -236.443245) (xy 254 -236.443245) (xy 254 -237.293383) (xy 264.373604 -237.293383)
			(xy 264.373604 -237.240085) (xy 264.381547 -237.187381) (xy 264.397257 -237.136451) (xy 264.420383 -237.08843)
			(xy 264.450407 -237.044393) (xy 264.486659 -237.005322) (xy 264.52833 -236.972091) (xy 264.574488 -236.945442)
			(xy 264.624102 -236.92597) (xy 264.676064 -236.91411) (xy 264.729214 -236.910127) (xy 264.782364 -236.91411)
			(xy 264.834326 -236.92597) (xy 264.88394 -236.945442) (xy 264.930098 -236.972091) (xy 264.971769 -237.005322)
			(xy 265.008021 -237.044393) (xy 265.038045 -237.08843) (xy 265.061171 -237.136451) (xy 265.076881 -237.187381)
			(xy 265.084824 -237.240085) (xy 265.085322 -237.266734) (xy 265.084824 -237.293383) (xy 268.473672 -237.293383)
			(xy 268.473672 -237.240085) (xy 268.481615 -237.187381) (xy 268.497325 -237.136451) (xy 268.520451 -237.08843)
			(xy 268.550475 -237.044393) (xy 268.586727 -237.005322) (xy 268.628398 -236.972091) (xy 268.674556 -236.945442)
			(xy 268.72417 -236.92597) (xy 268.776132 -236.91411) (xy 268.829282 -236.910127) (xy 268.882432 -236.91411)
			(xy 268.934394 -236.92597) (xy 268.984008 -236.945442) (xy 269.030166 -236.972091) (xy 269.071837 -237.005322)
			(xy 269.108089 -237.044393) (xy 269.138113 -237.08843) (xy 269.161239 -237.136451) (xy 269.176949 -237.187381)
			(xy 269.184892 -237.240085) (xy 269.18539 -237.266734) (xy 269.184892 -237.293383) (xy 279.461204 -237.293383)
			(xy 279.461204 -237.240085) (xy 279.469147 -237.187381) (xy 279.484857 -237.136451) (xy 279.507983 -237.08843)
			(xy 279.538007 -237.044393) (xy 279.574259 -237.005322) (xy 279.61593 -236.972091) (xy 279.662088 -236.945442)
			(xy 279.711702 -236.92597) (xy 279.763664 -236.91411) (xy 279.816814 -236.910127) (xy 279.869964 -236.91411)
			(xy 279.921926 -236.92597) (xy 279.97154 -236.945442) (xy 280.017698 -236.972091) (xy 280.059369 -237.005322)
			(xy 280.095621 -237.044393) (xy 280.125645 -237.08843) (xy 280.148771 -237.136451) (xy 280.164481 -237.187381)
			(xy 280.172424 -237.240085) (xy 280.172922 -237.266734) (xy 280.172424 -237.293383) (xy 283.561272 -237.293383)
			(xy 283.561272 -237.240085) (xy 283.569215 -237.187381) (xy 283.584925 -237.136451) (xy 283.608051 -237.08843)
			(xy 283.638075 -237.044393) (xy 283.674327 -237.005322) (xy 283.715998 -236.972091) (xy 283.762156 -236.945442)
			(xy 283.81177 -236.92597) (xy 283.863732 -236.91411) (xy 283.916882 -236.910127) (xy 283.970032 -236.91411)
			(xy 284.021994 -236.92597) (xy 284.071608 -236.945442) (xy 284.117766 -236.972091) (xy 284.159437 -237.005322)
			(xy 284.195689 -237.044393) (xy 284.225713 -237.08843) (xy 284.248839 -237.136451) (xy 284.264549 -237.187381)
			(xy 284.272492 -237.240085) (xy 284.27299 -237.266734) (xy 284.272492 -237.293383) (xy 294.548804 -237.293383)
			(xy 294.548804 -237.240085) (xy 294.556747 -237.187381) (xy 294.572457 -237.136451) (xy 294.595583 -237.08843)
			(xy 294.625607 -237.044393) (xy 294.661859 -237.005322) (xy 294.70353 -236.972091) (xy 294.749688 -236.945442)
			(xy 294.799302 -236.92597) (xy 294.851264 -236.91411) (xy 294.904414 -236.910127) (xy 294.957564 -236.91411)
			(xy 295.009526 -236.92597) (xy 295.05914 -236.945442) (xy 295.105298 -236.972091) (xy 295.146969 -237.005322)
			(xy 295.183221 -237.044393) (xy 295.213245 -237.08843) (xy 295.236371 -237.136451) (xy 295.252081 -237.187381)
			(xy 295.260024 -237.240085) (xy 295.260522 -237.266734) (xy 295.260024 -237.293383) (xy 298.648872 -237.293383)
			(xy 298.648872 -237.240085) (xy 298.656815 -237.187381) (xy 298.672525 -237.136451) (xy 298.695651 -237.08843)
			(xy 298.725675 -237.044393) (xy 298.761927 -237.005322) (xy 298.803598 -236.972091) (xy 298.849756 -236.945442)
			(xy 298.89937 -236.92597) (xy 298.951332 -236.91411) (xy 299.004482 -236.910127) (xy 299.057632 -236.91411)
			(xy 299.109594 -236.92597) (xy 299.159208 -236.945442) (xy 299.205366 -236.972091) (xy 299.247037 -237.005322)
			(xy 299.283289 -237.044393) (xy 299.313313 -237.08843) (xy 299.336439 -237.136451) (xy 299.352149 -237.187381)
			(xy 299.360092 -237.240085) (xy 299.36059 -237.266734) (xy 299.360092 -237.293383) (xy 299.352149 -237.346087)
			(xy 299.336439 -237.397017) (xy 299.313313 -237.445038) (xy 299.283289 -237.489075) (xy 299.247037 -237.528146)
			(xy 299.205366 -237.561377) (xy 299.159208 -237.588026) (xy 299.109594 -237.607498) (xy 299.057632 -237.619358)
			(xy 299.004482 -237.623342) (xy 298.951332 -237.619358) (xy 298.89937 -237.607498) (xy 298.849756 -237.588026)
			(xy 298.803598 -237.561377) (xy 298.761927 -237.528146) (xy 298.725675 -237.489075) (xy 298.695651 -237.445038)
			(xy 298.672525 -237.397017) (xy 298.656815 -237.346087) (xy 298.648872 -237.293383) (xy 295.260024 -237.293383)
			(xy 295.252081 -237.346087) (xy 295.236371 -237.397017) (xy 295.213245 -237.445038) (xy 295.183221 -237.489075)
			(xy 295.146969 -237.528146) (xy 295.105298 -237.561377) (xy 295.05914 -237.588026) (xy 295.009526 -237.607498)
			(xy 294.957564 -237.619358) (xy 294.904414 -237.623342) (xy 294.851264 -237.619358) (xy 294.799302 -237.607498)
			(xy 294.749688 -237.588026) (xy 294.70353 -237.561377) (xy 294.661859 -237.528146) (xy 294.625607 -237.489075)
			(xy 294.595583 -237.445038) (xy 294.572457 -237.397017) (xy 294.556747 -237.346087) (xy 294.548804 -237.293383)
			(xy 284.272492 -237.293383) (xy 284.264549 -237.346087) (xy 284.248839 -237.397017) (xy 284.225713 -237.445038)
			(xy 284.195689 -237.489075) (xy 284.159437 -237.528146) (xy 284.117766 -237.561377) (xy 284.071608 -237.588026)
			(xy 284.021994 -237.607498) (xy 283.970032 -237.619358) (xy 283.916882 -237.623342) (xy 283.863732 -237.619358)
			(xy 283.81177 -237.607498) (xy 283.762156 -237.588026) (xy 283.715998 -237.561377) (xy 283.674327 -237.528146)
			(xy 283.638075 -237.489075) (xy 283.608051 -237.445038) (xy 283.584925 -237.397017) (xy 283.569215 -237.346087)
			(xy 283.561272 -237.293383) (xy 280.172424 -237.293383) (xy 280.164481 -237.346087) (xy 280.148771 -237.397017)
			(xy 280.125645 -237.445038) (xy 280.095621 -237.489075) (xy 280.059369 -237.528146) (xy 280.017698 -237.561377)
			(xy 279.97154 -237.588026) (xy 279.921926 -237.607498) (xy 279.869964 -237.619358) (xy 279.816814 -237.623342)
			(xy 279.763664 -237.619358) (xy 279.711702 -237.607498) (xy 279.662088 -237.588026) (xy 279.61593 -237.561377)
			(xy 279.574259 -237.528146) (xy 279.538007 -237.489075) (xy 279.507983 -237.445038) (xy 279.484857 -237.397017)
			(xy 279.469147 -237.346087) (xy 279.461204 -237.293383) (xy 269.184892 -237.293383) (xy 269.176949 -237.346087)
			(xy 269.161239 -237.397017) (xy 269.138113 -237.445038) (xy 269.108089 -237.489075) (xy 269.071837 -237.528146)
			(xy 269.030166 -237.561377) (xy 268.984008 -237.588026) (xy 268.934394 -237.607498) (xy 268.882432 -237.619358)
			(xy 268.829282 -237.623342) (xy 268.776132 -237.619358) (xy 268.72417 -237.607498) (xy 268.674556 -237.588026)
			(xy 268.628398 -237.561377) (xy 268.586727 -237.528146) (xy 268.550475 -237.489075) (xy 268.520451 -237.445038)
			(xy 268.497325 -237.397017) (xy 268.481615 -237.346087) (xy 268.473672 -237.293383) (xy 265.084824 -237.293383)
			(xy 265.076881 -237.346087) (xy 265.061171 -237.397017) (xy 265.038045 -237.445038) (xy 265.008021 -237.489075)
			(xy 264.971769 -237.528146) (xy 264.930098 -237.561377) (xy 264.88394 -237.588026) (xy 264.834326 -237.607498)
			(xy 264.782364 -237.619358) (xy 264.729214 -237.623342) (xy 264.676064 -237.619358) (xy 264.624102 -237.607498)
			(xy 264.574488 -237.588026) (xy 264.52833 -237.561377) (xy 264.486659 -237.528146) (xy 264.450407 -237.489075)
			(xy 264.420383 -237.445038) (xy 264.397257 -237.397017) (xy 264.381547 -237.346087) (xy 264.373604 -237.293383)
			(xy 254 -237.293383) (xy 254 -238.143267) (xy 264.373604 -238.143267) (xy 264.373604 -238.089969)
			(xy 264.381547 -238.037265) (xy 264.397257 -237.986335) (xy 264.420383 -237.938314) (xy 264.450407 -237.894277)
			(xy 264.486659 -237.855206) (xy 264.52833 -237.821975) (xy 264.574488 -237.795326) (xy 264.624102 -237.775854)
			(xy 264.676064 -237.763994) (xy 264.729214 -237.760011) (xy 264.782364 -237.763994) (xy 264.834326 -237.775854)
			(xy 264.88394 -237.795326) (xy 264.930098 -237.821975) (xy 264.971769 -237.855206) (xy 265.008021 -237.894277)
			(xy 265.038045 -237.938314) (xy 265.061171 -237.986335) (xy 265.076881 -238.037265) (xy 265.084824 -238.089969)
			(xy 265.085322 -238.116618) (xy 265.084824 -238.143267) (xy 279.461204 -238.143267) (xy 279.461204 -238.089969)
			(xy 279.469147 -238.037265) (xy 279.484857 -237.986335) (xy 279.507983 -237.938314) (xy 279.538007 -237.894277)
			(xy 279.574259 -237.855206) (xy 279.61593 -237.821975) (xy 279.662088 -237.795326) (xy 279.711702 -237.775854)
			(xy 279.763664 -237.763994) (xy 279.816814 -237.760011) (xy 279.869964 -237.763994) (xy 279.921926 -237.775854)
			(xy 279.97154 -237.795326) (xy 280.017698 -237.821975) (xy 280.059369 -237.855206) (xy 280.095621 -237.894277)
			(xy 280.125645 -237.938314) (xy 280.148771 -237.986335) (xy 280.164481 -238.037265) (xy 280.172424 -238.089969)
			(xy 280.172922 -238.116618) (xy 280.172424 -238.143267) (xy 294.548804 -238.143267) (xy 294.548804 -238.089969)
			(xy 294.556747 -238.037265) (xy 294.572457 -237.986335) (xy 294.595583 -237.938314) (xy 294.625607 -237.894277)
			(xy 294.661859 -237.855206) (xy 294.70353 -237.821975) (xy 294.749688 -237.795326) (xy 294.799302 -237.775854)
			(xy 294.851264 -237.763994) (xy 294.904414 -237.760011) (xy 294.957564 -237.763994) (xy 295.009526 -237.775854)
			(xy 295.05914 -237.795326) (xy 295.105298 -237.821975) (xy 295.146969 -237.855206) (xy 295.183221 -237.894277)
			(xy 295.213245 -237.938314) (xy 295.236371 -237.986335) (xy 295.252081 -238.037265) (xy 295.260024 -238.089969)
			(xy 295.260522 -238.116618) (xy 295.260024 -238.143267) (xy 295.252081 -238.195971) (xy 295.236371 -238.246901)
			(xy 295.213245 -238.294922) (xy 295.183221 -238.338959) (xy 295.146969 -238.37803) (xy 295.105298 -238.411261)
			(xy 295.05914 -238.43791) (xy 295.009526 -238.457382) (xy 294.957564 -238.469242) (xy 294.904414 -238.473226)
			(xy 294.851264 -238.469242) (xy 294.799302 -238.457382) (xy 294.749688 -238.43791) (xy 294.70353 -238.411261)
			(xy 294.661859 -238.37803) (xy 294.625607 -238.338959) (xy 294.595583 -238.294922) (xy 294.572457 -238.246901)
			(xy 294.556747 -238.195971) (xy 294.548804 -238.143267) (xy 280.172424 -238.143267) (xy 280.164481 -238.195971)
			(xy 280.148771 -238.246901) (xy 280.125645 -238.294922) (xy 280.095621 -238.338959) (xy 280.059369 -238.37803)
			(xy 280.017698 -238.411261) (xy 279.97154 -238.43791) (xy 279.921926 -238.457382) (xy 279.869964 -238.469242)
			(xy 279.816814 -238.473226) (xy 279.763664 -238.469242) (xy 279.711702 -238.457382) (xy 279.662088 -238.43791)
			(xy 279.61593 -238.411261) (xy 279.574259 -238.37803) (xy 279.538007 -238.338959) (xy 279.507983 -238.294922)
			(xy 279.484857 -238.246901) (xy 279.469147 -238.195971) (xy 279.461204 -238.143267) (xy 265.084824 -238.143267)
			(xy 265.076881 -238.195971) (xy 265.061171 -238.246901) (xy 265.038045 -238.294922) (xy 265.008021 -238.338959)
			(xy 264.971769 -238.37803) (xy 264.930098 -238.411261) (xy 264.88394 -238.43791) (xy 264.834326 -238.457382)
			(xy 264.782364 -238.469242) (xy 264.729214 -238.473226) (xy 264.676064 -238.469242) (xy 264.624102 -238.457382)
			(xy 264.574488 -238.43791) (xy 264.52833 -238.411261) (xy 264.486659 -238.37803) (xy 264.450407 -238.338959)
			(xy 264.420383 -238.294922) (xy 264.397257 -238.246901) (xy 264.381547 -238.195971) (xy 264.373604 -238.143267)
			(xy 254 -238.143267) (xy 254 -238.993405) (xy 268.473672 -238.993405) (xy 268.473672 -238.940107)
			(xy 268.481615 -238.887403) (xy 268.497325 -238.836473) (xy 268.520451 -238.788452) (xy 268.550475 -238.744415)
			(xy 268.586727 -238.705344) (xy 268.628398 -238.672113) (xy 268.674556 -238.645464) (xy 268.72417 -238.625992)
			(xy 268.776132 -238.614132) (xy 268.829282 -238.610149) (xy 268.882432 -238.614132) (xy 268.934394 -238.625992)
			(xy 268.984008 -238.645464) (xy 269.030166 -238.672113) (xy 269.071837 -238.705344) (xy 269.108089 -238.744415)
			(xy 269.138113 -238.788452) (xy 269.161239 -238.836473) (xy 269.176949 -238.887403) (xy 269.184892 -238.940107)
			(xy 269.18539 -238.966756) (xy 269.184892 -238.993405) (xy 283.561272 -238.993405) (xy 283.561272 -238.940107)
			(xy 283.569215 -238.887403) (xy 283.584925 -238.836473) (xy 283.608051 -238.788452) (xy 283.638075 -238.744415)
			(xy 283.674327 -238.705344) (xy 283.715998 -238.672113) (xy 283.762156 -238.645464) (xy 283.81177 -238.625992)
			(xy 283.863732 -238.614132) (xy 283.916882 -238.610149) (xy 283.970032 -238.614132) (xy 284.021994 -238.625992)
			(xy 284.071608 -238.645464) (xy 284.117766 -238.672113) (xy 284.159437 -238.705344) (xy 284.195689 -238.744415)
			(xy 284.225713 -238.788452) (xy 284.248839 -238.836473) (xy 284.264549 -238.887403) (xy 284.272492 -238.940107)
			(xy 284.27299 -238.966756) (xy 284.272492 -238.993405) (xy 298.648872 -238.993405) (xy 298.648872 -238.940107)
			(xy 298.656815 -238.887403) (xy 298.672525 -238.836473) (xy 298.695651 -238.788452) (xy 298.725675 -238.744415)
			(xy 298.761927 -238.705344) (xy 298.803598 -238.672113) (xy 298.849756 -238.645464) (xy 298.89937 -238.625992)
			(xy 298.951332 -238.614132) (xy 299.004482 -238.610149) (xy 299.057632 -238.614132) (xy 299.109594 -238.625992)
			(xy 299.159208 -238.645464) (xy 299.205366 -238.672113) (xy 299.247037 -238.705344) (xy 299.283289 -238.744415)
			(xy 299.313313 -238.788452) (xy 299.336439 -238.836473) (xy 299.352149 -238.887403) (xy 299.360092 -238.940107)
			(xy 299.36059 -238.966756) (xy 299.360092 -238.993405) (xy 299.352149 -239.046109) (xy 299.336439 -239.097039)
			(xy 299.313313 -239.14506) (xy 299.283289 -239.189097) (xy 299.247037 -239.228168) (xy 299.205366 -239.261399)
			(xy 299.159208 -239.288048) (xy 299.109594 -239.30752) (xy 299.057632 -239.31938) (xy 299.004482 -239.323364)
			(xy 298.951332 -239.31938) (xy 298.89937 -239.30752) (xy 298.849756 -239.288048) (xy 298.803598 -239.261399)
			(xy 298.761927 -239.228168) (xy 298.725675 -239.189097) (xy 298.695651 -239.14506) (xy 298.672525 -239.097039)
			(xy 298.656815 -239.046109) (xy 298.648872 -238.993405) (xy 284.272492 -238.993405) (xy 284.264549 -239.046109)
			(xy 284.248839 -239.097039) (xy 284.225713 -239.14506) (xy 284.195689 -239.189097) (xy 284.159437 -239.228168)
			(xy 284.117766 -239.261399) (xy 284.071608 -239.288048) (xy 284.021994 -239.30752) (xy 283.970032 -239.31938)
			(xy 283.916882 -239.323364) (xy 283.863732 -239.31938) (xy 283.81177 -239.30752) (xy 283.762156 -239.288048)
			(xy 283.715998 -239.261399) (xy 283.674327 -239.228168) (xy 283.638075 -239.189097) (xy 283.608051 -239.14506)
			(xy 283.584925 -239.097039) (xy 283.569215 -239.046109) (xy 283.561272 -238.993405) (xy 269.184892 -238.993405)
			(xy 269.176949 -239.046109) (xy 269.161239 -239.097039) (xy 269.138113 -239.14506) (xy 269.108089 -239.189097)
			(xy 269.071837 -239.228168) (xy 269.030166 -239.261399) (xy 268.984008 -239.288048) (xy 268.934394 -239.30752)
			(xy 268.882432 -239.31938) (xy 268.829282 -239.323364) (xy 268.776132 -239.31938) (xy 268.72417 -239.30752)
			(xy 268.674556 -239.288048) (xy 268.628398 -239.261399) (xy 268.586727 -239.228168) (xy 268.550475 -239.189097)
			(xy 268.520451 -239.14506) (xy 268.497325 -239.097039) (xy 268.481615 -239.046109) (xy 268.473672 -238.993405)
			(xy 254 -238.993405) (xy 254 -239.843289) (xy 264.373604 -239.843289) (xy 264.373604 -239.789991)
			(xy 264.381547 -239.737287) (xy 264.397257 -239.686357) (xy 264.420383 -239.638336) (xy 264.450407 -239.594299)
			(xy 264.486659 -239.555228) (xy 264.52833 -239.521997) (xy 264.574488 -239.495348) (xy 264.624102 -239.475876)
			(xy 264.676064 -239.464016) (xy 264.729214 -239.460033) (xy 264.782364 -239.464016) (xy 264.834326 -239.475876)
			(xy 264.88394 -239.495348) (xy 264.930098 -239.521997) (xy 264.971769 -239.555228) (xy 265.008021 -239.594299)
			(xy 265.038045 -239.638336) (xy 265.061171 -239.686357) (xy 265.076881 -239.737287) (xy 265.084824 -239.789991)
			(xy 265.085322 -239.81664) (xy 265.084824 -239.843289) (xy 279.461204 -239.843289) (xy 279.461204 -239.789991)
			(xy 279.469147 -239.737287) (xy 279.484857 -239.686357) (xy 279.507983 -239.638336) (xy 279.538007 -239.594299)
			(xy 279.574259 -239.555228) (xy 279.61593 -239.521997) (xy 279.662088 -239.495348) (xy 279.711702 -239.475876)
			(xy 279.763664 -239.464016) (xy 279.816814 -239.460033) (xy 279.869964 -239.464016) (xy 279.921926 -239.475876)
			(xy 279.97154 -239.495348) (xy 280.017698 -239.521997) (xy 280.059369 -239.555228) (xy 280.095621 -239.594299)
			(xy 280.125645 -239.638336) (xy 280.148771 -239.686357) (xy 280.164481 -239.737287) (xy 280.172424 -239.789991)
			(xy 280.172922 -239.81664) (xy 280.172424 -239.843289) (xy 294.548804 -239.843289) (xy 294.548804 -239.789991)
			(xy 294.556747 -239.737287) (xy 294.572457 -239.686357) (xy 294.595583 -239.638336) (xy 294.625607 -239.594299)
			(xy 294.661859 -239.555228) (xy 294.70353 -239.521997) (xy 294.749688 -239.495348) (xy 294.799302 -239.475876)
			(xy 294.851264 -239.464016) (xy 294.904414 -239.460033) (xy 294.957564 -239.464016) (xy 295.009526 -239.475876)
			(xy 295.05914 -239.495348) (xy 295.105298 -239.521997) (xy 295.146969 -239.555228) (xy 295.183221 -239.594299)
			(xy 295.213245 -239.638336) (xy 295.236371 -239.686357) (xy 295.252081 -239.737287) (xy 295.260024 -239.789991)
			(xy 295.260522 -239.81664) (xy 295.260024 -239.843289) (xy 295.252081 -239.895993) (xy 295.236371 -239.946923)
			(xy 295.213245 -239.994944) (xy 295.183221 -240.038981) (xy 295.146969 -240.078052) (xy 295.105298 -240.111283)
			(xy 295.05914 -240.137932) (xy 295.009526 -240.157404) (xy 294.957564 -240.169264) (xy 294.904414 -240.173248)
			(xy 294.851264 -240.169264) (xy 294.799302 -240.157404) (xy 294.749688 -240.137932) (xy 294.70353 -240.111283)
			(xy 294.661859 -240.078052) (xy 294.625607 -240.038981) (xy 294.595583 -239.994944) (xy 294.572457 -239.946923)
			(xy 294.556747 -239.895993) (xy 294.548804 -239.843289) (xy 280.172424 -239.843289) (xy 280.164481 -239.895993)
			(xy 280.148771 -239.946923) (xy 280.125645 -239.994944) (xy 280.095621 -240.038981) (xy 280.059369 -240.078052)
			(xy 280.017698 -240.111283) (xy 279.97154 -240.137932) (xy 279.921926 -240.157404) (xy 279.869964 -240.169264)
			(xy 279.816814 -240.173248) (xy 279.763664 -240.169264) (xy 279.711702 -240.157404) (xy 279.662088 -240.137932)
			(xy 279.61593 -240.111283) (xy 279.574259 -240.078052) (xy 279.538007 -240.038981) (xy 279.507983 -239.994944)
			(xy 279.484857 -239.946923) (xy 279.469147 -239.895993) (xy 279.461204 -239.843289) (xy 265.084824 -239.843289)
			(xy 265.076881 -239.895993) (xy 265.061171 -239.946923) (xy 265.038045 -239.994944) (xy 265.008021 -240.038981)
			(xy 264.971769 -240.078052) (xy 264.930098 -240.111283) (xy 264.88394 -240.137932) (xy 264.834326 -240.157404)
			(xy 264.782364 -240.169264) (xy 264.729214 -240.173248) (xy 264.676064 -240.169264) (xy 264.624102 -240.157404)
			(xy 264.574488 -240.137932) (xy 264.52833 -240.111283) (xy 264.486659 -240.078052) (xy 264.450407 -240.038981)
			(xy 264.420383 -239.994944) (xy 264.397257 -239.946923) (xy 264.381547 -239.895993) (xy 264.373604 -239.843289)
			(xy 254 -239.843289) (xy 254 -240.693427) (xy 268.473672 -240.693427) (xy 268.473672 -240.640129)
			(xy 268.481615 -240.587425) (xy 268.497325 -240.536495) (xy 268.520451 -240.488474) (xy 268.550475 -240.444437)
			(xy 268.586727 -240.405366) (xy 268.628398 -240.372135) (xy 268.674556 -240.345486) (xy 268.72417 -240.326014)
			(xy 268.776132 -240.314154) (xy 268.829282 -240.310171) (xy 268.882432 -240.314154) (xy 268.934394 -240.326014)
			(xy 268.984008 -240.345486) (xy 269.030166 -240.372135) (xy 269.071837 -240.405366) (xy 269.108089 -240.444437)
			(xy 269.138113 -240.488474) (xy 269.161239 -240.536495) (xy 269.176949 -240.587425) (xy 269.184892 -240.640129)
			(xy 269.18539 -240.666778) (xy 269.184892 -240.693427) (xy 283.561272 -240.693427) (xy 283.561272 -240.640129)
			(xy 283.569215 -240.587425) (xy 283.584925 -240.536495) (xy 283.608051 -240.488474) (xy 283.638075 -240.444437)
			(xy 283.674327 -240.405366) (xy 283.715998 -240.372135) (xy 283.762156 -240.345486) (xy 283.81177 -240.326014)
			(xy 283.863732 -240.314154) (xy 283.916882 -240.310171) (xy 283.970032 -240.314154) (xy 284.021994 -240.326014)
			(xy 284.071608 -240.345486) (xy 284.117766 -240.372135) (xy 284.159437 -240.405366) (xy 284.195689 -240.444437)
			(xy 284.225713 -240.488474) (xy 284.248839 -240.536495) (xy 284.264549 -240.587425) (xy 284.272492 -240.640129)
			(xy 284.27299 -240.666778) (xy 284.272492 -240.693427) (xy 298.648872 -240.693427) (xy 298.648872 -240.640129)
			(xy 298.656815 -240.587425) (xy 298.672525 -240.536495) (xy 298.695651 -240.488474) (xy 298.725675 -240.444437)
			(xy 298.761927 -240.405366) (xy 298.803598 -240.372135) (xy 298.849756 -240.345486) (xy 298.89937 -240.326014)
			(xy 298.951332 -240.314154) (xy 299.004482 -240.310171) (xy 299.057632 -240.314154) (xy 299.109594 -240.326014)
			(xy 299.159208 -240.345486) (xy 299.205366 -240.372135) (xy 299.247037 -240.405366) (xy 299.283289 -240.444437)
			(xy 299.313313 -240.488474) (xy 299.336439 -240.536495) (xy 299.352149 -240.587425) (xy 299.360092 -240.640129)
			(xy 299.36059 -240.666778) (xy 299.360092 -240.693427) (xy 299.352149 -240.746131) (xy 299.336439 -240.797061)
			(xy 299.313313 -240.845082) (xy 299.283289 -240.889119) (xy 299.247037 -240.92819) (xy 299.205366 -240.961421)
			(xy 299.159208 -240.98807) (xy 299.109594 -241.007542) (xy 299.057632 -241.019402) (xy 299.004482 -241.023386)
			(xy 298.951332 -241.019402) (xy 298.89937 -241.007542) (xy 298.849756 -240.98807) (xy 298.803598 -240.961421)
			(xy 298.761927 -240.92819) (xy 298.725675 -240.889119) (xy 298.695651 -240.845082) (xy 298.672525 -240.797061)
			(xy 298.656815 -240.746131) (xy 298.648872 -240.693427) (xy 284.272492 -240.693427) (xy 284.264549 -240.746131)
			(xy 284.248839 -240.797061) (xy 284.225713 -240.845082) (xy 284.195689 -240.889119) (xy 284.159437 -240.92819)
			(xy 284.117766 -240.961421) (xy 284.071608 -240.98807) (xy 284.021994 -241.007542) (xy 283.970032 -241.019402)
			(xy 283.916882 -241.023386) (xy 283.863732 -241.019402) (xy 283.81177 -241.007542) (xy 283.762156 -240.98807)
			(xy 283.715998 -240.961421) (xy 283.674327 -240.92819) (xy 283.638075 -240.889119) (xy 283.608051 -240.845082)
			(xy 283.584925 -240.797061) (xy 283.569215 -240.746131) (xy 283.561272 -240.693427) (xy 269.184892 -240.693427)
			(xy 269.176949 -240.746131) (xy 269.161239 -240.797061) (xy 269.138113 -240.845082) (xy 269.108089 -240.889119)
			(xy 269.071837 -240.92819) (xy 269.030166 -240.961421) (xy 268.984008 -240.98807) (xy 268.934394 -241.007542)
			(xy 268.882432 -241.019402) (xy 268.829282 -241.023386) (xy 268.776132 -241.019402) (xy 268.72417 -241.007542)
			(xy 268.674556 -240.98807) (xy 268.628398 -240.961421) (xy 268.586727 -240.92819) (xy 268.550475 -240.889119)
			(xy 268.520451 -240.845082) (xy 268.497325 -240.797061) (xy 268.481615 -240.746131) (xy 268.473672 -240.693427)
			(xy 254 -240.693427) (xy 254 -241.543311) (xy 264.373604 -241.543311) (xy 264.373604 -241.490013)
			(xy 264.381547 -241.437309) (xy 264.397257 -241.386379) (xy 264.420383 -241.338358) (xy 264.450407 -241.294321)
			(xy 264.486659 -241.25525) (xy 264.52833 -241.222019) (xy 264.574488 -241.19537) (xy 264.624102 -241.175898)
			(xy 264.676064 -241.164038) (xy 264.729214 -241.160055) (xy 264.782364 -241.164038) (xy 264.834326 -241.175898)
			(xy 264.88394 -241.19537) (xy 264.930098 -241.222019) (xy 264.971769 -241.25525) (xy 265.008021 -241.294321)
			(xy 265.038045 -241.338358) (xy 265.061171 -241.386379) (xy 265.076881 -241.437309) (xy 265.084824 -241.490013)
			(xy 265.085322 -241.516662) (xy 265.084824 -241.543311) (xy 279.461204 -241.543311) (xy 279.461204 -241.490013)
			(xy 279.469147 -241.437309) (xy 279.484857 -241.386379) (xy 279.507983 -241.338358) (xy 279.538007 -241.294321)
			(xy 279.574259 -241.25525) (xy 279.61593 -241.222019) (xy 279.662088 -241.19537) (xy 279.711702 -241.175898)
			(xy 279.763664 -241.164038) (xy 279.816814 -241.160055) (xy 279.869964 -241.164038) (xy 279.921926 -241.175898)
			(xy 279.97154 -241.19537) (xy 280.017698 -241.222019) (xy 280.059369 -241.25525) (xy 280.095621 -241.294321)
			(xy 280.125645 -241.338358) (xy 280.148771 -241.386379) (xy 280.164481 -241.437309) (xy 280.172424 -241.490013)
			(xy 280.172922 -241.516662) (xy 280.172424 -241.543311) (xy 294.548804 -241.543311) (xy 294.548804 -241.490013)
			(xy 294.556747 -241.437309) (xy 294.572457 -241.386379) (xy 294.595583 -241.338358) (xy 294.625607 -241.294321)
			(xy 294.661859 -241.25525) (xy 294.70353 -241.222019) (xy 294.749688 -241.19537) (xy 294.799302 -241.175898)
			(xy 294.851264 -241.164038) (xy 294.904414 -241.160055) (xy 294.957564 -241.164038) (xy 295.009526 -241.175898)
			(xy 295.05914 -241.19537) (xy 295.105298 -241.222019) (xy 295.146969 -241.25525) (xy 295.183221 -241.294321)
			(xy 295.213245 -241.338358) (xy 295.236371 -241.386379) (xy 295.252081 -241.437309) (xy 295.260024 -241.490013)
			(xy 295.260522 -241.516662) (xy 295.260024 -241.543311) (xy 295.252081 -241.596015) (xy 295.236371 -241.646945)
			(xy 295.213245 -241.694966) (xy 295.183221 -241.739003) (xy 295.146969 -241.778074) (xy 295.105298 -241.811305)
			(xy 295.05914 -241.837954) (xy 295.009526 -241.857426) (xy 294.957564 -241.869286) (xy 294.904414 -241.87327)
			(xy 294.851264 -241.869286) (xy 294.799302 -241.857426) (xy 294.749688 -241.837954) (xy 294.70353 -241.811305)
			(xy 294.661859 -241.778074) (xy 294.625607 -241.739003) (xy 294.595583 -241.694966) (xy 294.572457 -241.646945)
			(xy 294.556747 -241.596015) (xy 294.548804 -241.543311) (xy 280.172424 -241.543311) (xy 280.164481 -241.596015)
			(xy 280.148771 -241.646945) (xy 280.125645 -241.694966) (xy 280.095621 -241.739003) (xy 280.059369 -241.778074)
			(xy 280.017698 -241.811305) (xy 279.97154 -241.837954) (xy 279.921926 -241.857426) (xy 279.869964 -241.869286)
			(xy 279.816814 -241.87327) (xy 279.763664 -241.869286) (xy 279.711702 -241.857426) (xy 279.662088 -241.837954)
			(xy 279.61593 -241.811305) (xy 279.574259 -241.778074) (xy 279.538007 -241.739003) (xy 279.507983 -241.694966)
			(xy 279.484857 -241.646945) (xy 279.469147 -241.596015) (xy 279.461204 -241.543311) (xy 265.084824 -241.543311)
			(xy 265.076881 -241.596015) (xy 265.061171 -241.646945) (xy 265.038045 -241.694966) (xy 265.008021 -241.739003)
			(xy 264.971769 -241.778074) (xy 264.930098 -241.811305) (xy 264.88394 -241.837954) (xy 264.834326 -241.857426)
			(xy 264.782364 -241.869286) (xy 264.729214 -241.87327) (xy 264.676064 -241.869286) (xy 264.624102 -241.857426)
			(xy 264.574488 -241.837954) (xy 264.52833 -241.811305) (xy 264.486659 -241.778074) (xy 264.450407 -241.739003)
			(xy 264.420383 -241.694966) (xy 264.397257 -241.646945) (xy 264.381547 -241.596015) (xy 264.373604 -241.543311)
			(xy 254 -241.543311) (xy 254 -242.393449) (xy 260.929872 -242.393449) (xy 260.929872 -242.340151)
			(xy 260.937815 -242.287447) (xy 260.953525 -242.236517) (xy 260.976651 -242.188496) (xy 261.006675 -242.144459)
			(xy 261.042927 -242.105388) (xy 261.084598 -242.072157) (xy 261.130756 -242.045508) (xy 261.18037 -242.026036)
			(xy 261.232332 -242.014176) (xy 261.285482 -242.010193) (xy 261.338632 -242.014176) (xy 261.390594 -242.026036)
			(xy 261.440208 -242.045508) (xy 261.486366 -242.072157) (xy 261.528037 -242.105388) (xy 261.564289 -242.144459)
			(xy 261.594313 -242.188496) (xy 261.617439 -242.236517) (xy 261.633149 -242.287447) (xy 261.641092 -242.340151)
			(xy 261.64159 -242.3668) (xy 261.641092 -242.393449) (xy 268.473672 -242.393449) (xy 268.473672 -242.340151)
			(xy 268.481615 -242.287447) (xy 268.497325 -242.236517) (xy 268.520451 -242.188496) (xy 268.550475 -242.144459)
			(xy 268.586727 -242.105388) (xy 268.628398 -242.072157) (xy 268.674556 -242.045508) (xy 268.72417 -242.026036)
			(xy 268.776132 -242.014176) (xy 268.829282 -242.010193) (xy 268.882432 -242.014176) (xy 268.934394 -242.026036)
			(xy 268.984008 -242.045508) (xy 269.030166 -242.072157) (xy 269.071837 -242.105388) (xy 269.108089 -242.144459)
			(xy 269.138113 -242.188496) (xy 269.161239 -242.236517) (xy 269.176949 -242.287447) (xy 269.184892 -242.340151)
			(xy 269.18539 -242.3668) (xy 269.184892 -242.393449) (xy 276.017472 -242.393449) (xy 276.017472 -242.340151)
			(xy 276.025415 -242.287447) (xy 276.041125 -242.236517) (xy 276.064251 -242.188496) (xy 276.094275 -242.144459)
			(xy 276.130527 -242.105388) (xy 276.172198 -242.072157) (xy 276.218356 -242.045508) (xy 276.26797 -242.026036)
			(xy 276.319932 -242.014176) (xy 276.373082 -242.010193) (xy 276.426232 -242.014176) (xy 276.478194 -242.026036)
			(xy 276.527808 -242.045508) (xy 276.573966 -242.072157) (xy 276.615637 -242.105388) (xy 276.651889 -242.144459)
			(xy 276.681913 -242.188496) (xy 276.705039 -242.236517) (xy 276.720749 -242.287447) (xy 276.728692 -242.340151)
			(xy 276.72919 -242.3668) (xy 276.728692 -242.393449) (xy 283.561272 -242.393449) (xy 283.561272 -242.340151)
			(xy 283.569215 -242.287447) (xy 283.584925 -242.236517) (xy 283.608051 -242.188496) (xy 283.638075 -242.144459)
			(xy 283.674327 -242.105388) (xy 283.715998 -242.072157) (xy 283.762156 -242.045508) (xy 283.81177 -242.026036)
			(xy 283.863732 -242.014176) (xy 283.916882 -242.010193) (xy 283.970032 -242.014176) (xy 284.021994 -242.026036)
			(xy 284.071608 -242.045508) (xy 284.117766 -242.072157) (xy 284.159437 -242.105388) (xy 284.195689 -242.144459)
			(xy 284.225713 -242.188496) (xy 284.248839 -242.236517) (xy 284.264549 -242.287447) (xy 284.272492 -242.340151)
			(xy 284.27299 -242.3668) (xy 284.272492 -242.393449) (xy 291.105072 -242.393449) (xy 291.105072 -242.340151)
			(xy 291.113015 -242.287447) (xy 291.128725 -242.236517) (xy 291.151851 -242.188496) (xy 291.181875 -242.144459)
			(xy 291.218127 -242.105388) (xy 291.259798 -242.072157) (xy 291.305956 -242.045508) (xy 291.35557 -242.026036)
			(xy 291.407532 -242.014176) (xy 291.460682 -242.010193) (xy 291.513832 -242.014176) (xy 291.565794 -242.026036)
			(xy 291.615408 -242.045508) (xy 291.661566 -242.072157) (xy 291.703237 -242.105388) (xy 291.739489 -242.144459)
			(xy 291.769513 -242.188496) (xy 291.792639 -242.236517) (xy 291.808349 -242.287447) (xy 291.816292 -242.340151)
			(xy 291.81679 -242.3668) (xy 291.816292 -242.393449) (xy 298.648872 -242.393449) (xy 298.648872 -242.340151)
			(xy 298.656815 -242.287447) (xy 298.672525 -242.236517) (xy 298.695651 -242.188496) (xy 298.725675 -242.144459)
			(xy 298.761927 -242.105388) (xy 298.803598 -242.072157) (xy 298.849756 -242.045508) (xy 298.89937 -242.026036)
			(xy 298.951332 -242.014176) (xy 299.004482 -242.010193) (xy 299.057632 -242.014176) (xy 299.109594 -242.026036)
			(xy 299.159208 -242.045508) (xy 299.205366 -242.072157) (xy 299.247037 -242.105388) (xy 299.283289 -242.144459)
			(xy 299.313313 -242.188496) (xy 299.336439 -242.236517) (xy 299.352149 -242.287447) (xy 299.360092 -242.340151)
			(xy 299.36059 -242.3668) (xy 299.360092 -242.393449) (xy 303.982872 -242.393449) (xy 303.982872 -242.340151)
			(xy 303.990815 -242.287447) (xy 304.006525 -242.236517) (xy 304.029651 -242.188496) (xy 304.059675 -242.144459)
			(xy 304.095927 -242.105388) (xy 304.137598 -242.072157) (xy 304.183756 -242.045508) (xy 304.23337 -242.026036)
			(xy 304.285332 -242.014176) (xy 304.338482 -242.010193) (xy 304.391632 -242.014176) (xy 304.443594 -242.026036)
			(xy 304.493208 -242.045508) (xy 304.539366 -242.072157) (xy 304.581037 -242.105388) (xy 304.617289 -242.144459)
			(xy 304.647313 -242.188496) (xy 304.670439 -242.236517) (xy 304.686149 -242.287447) (xy 304.694092 -242.340151)
			(xy 304.69459 -242.3668) (xy 304.694092 -242.393449) (xy 311.526672 -242.393449) (xy 311.526672 -242.340151)
			(xy 311.534615 -242.287447) (xy 311.550325 -242.236517) (xy 311.573451 -242.188496) (xy 311.603475 -242.144459)
			(xy 311.639727 -242.105388) (xy 311.681398 -242.072157) (xy 311.727556 -242.045508) (xy 311.77717 -242.026036)
			(xy 311.829132 -242.014176) (xy 311.882282 -242.010193) (xy 311.935432 -242.014176) (xy 311.987394 -242.026036)
			(xy 312.037008 -242.045508) (xy 312.083166 -242.072157) (xy 312.124837 -242.105388) (xy 312.161089 -242.144459)
			(xy 312.191113 -242.188496) (xy 312.214239 -242.236517) (xy 312.229949 -242.287447) (xy 312.237892 -242.340151)
			(xy 312.23839 -242.3668) (xy 312.237892 -242.393449) (xy 312.229949 -242.446153) (xy 312.214239 -242.497083)
			(xy 312.191113 -242.545104) (xy 312.161089 -242.589141) (xy 312.124837 -242.628212) (xy 312.083166 -242.661443)
			(xy 312.037008 -242.688092) (xy 311.987394 -242.707564) (xy 311.935432 -242.719424) (xy 311.882282 -242.723408)
			(xy 311.829132 -242.719424) (xy 311.77717 -242.707564) (xy 311.727556 -242.688092) (xy 311.681398 -242.661443)
			(xy 311.639727 -242.628212) (xy 311.603475 -242.589141) (xy 311.573451 -242.545104) (xy 311.550325 -242.497083)
			(xy 311.534615 -242.446153) (xy 311.526672 -242.393449) (xy 304.694092 -242.393449) (xy 304.686149 -242.446153)
			(xy 304.670439 -242.497083) (xy 304.647313 -242.545104) (xy 304.617289 -242.589141) (xy 304.581037 -242.628212)
			(xy 304.539366 -242.661443) (xy 304.493208 -242.688092) (xy 304.443594 -242.707564) (xy 304.391632 -242.719424)
			(xy 304.338482 -242.723408) (xy 304.285332 -242.719424) (xy 304.23337 -242.707564) (xy 304.183756 -242.688092)
			(xy 304.137598 -242.661443) (xy 304.095927 -242.628212) (xy 304.059675 -242.589141) (xy 304.029651 -242.545104)
			(xy 304.006525 -242.497083) (xy 303.990815 -242.446153) (xy 303.982872 -242.393449) (xy 299.360092 -242.393449)
			(xy 299.352149 -242.446153) (xy 299.336439 -242.497083) (xy 299.313313 -242.545104) (xy 299.283289 -242.589141)
			(xy 299.247037 -242.628212) (xy 299.205366 -242.661443) (xy 299.159208 -242.688092) (xy 299.109594 -242.707564)
			(xy 299.057632 -242.719424) (xy 299.004482 -242.723408) (xy 298.951332 -242.719424) (xy 298.89937 -242.707564)
			(xy 298.849756 -242.688092) (xy 298.803598 -242.661443) (xy 298.761927 -242.628212) (xy 298.725675 -242.589141)
			(xy 298.695651 -242.545104) (xy 298.672525 -242.497083) (xy 298.656815 -242.446153) (xy 298.648872 -242.393449)
			(xy 291.816292 -242.393449) (xy 291.808349 -242.446153) (xy 291.792639 -242.497083) (xy 291.769513 -242.545104)
			(xy 291.739489 -242.589141) (xy 291.703237 -242.628212) (xy 291.661566 -242.661443) (xy 291.615408 -242.688092)
			(xy 291.565794 -242.707564) (xy 291.513832 -242.719424) (xy 291.460682 -242.723408) (xy 291.407532 -242.719424)
			(xy 291.35557 -242.707564) (xy 291.305956 -242.688092) (xy 291.259798 -242.661443) (xy 291.218127 -242.628212)
			(xy 291.181875 -242.589141) (xy 291.151851 -242.545104) (xy 291.128725 -242.497083) (xy 291.113015 -242.446153)
			(xy 291.105072 -242.393449) (xy 284.272492 -242.393449) (xy 284.264549 -242.446153) (xy 284.248839 -242.497083)
			(xy 284.225713 -242.545104) (xy 284.195689 -242.589141) (xy 284.159437 -242.628212) (xy 284.117766 -242.661443)
			(xy 284.071608 -242.688092) (xy 284.021994 -242.707564) (xy 283.970032 -242.719424) (xy 283.916882 -242.723408)
			(xy 283.863732 -242.719424) (xy 283.81177 -242.707564) (xy 283.762156 -242.688092) (xy 283.715998 -242.661443)
			(xy 283.674327 -242.628212) (xy 283.638075 -242.589141) (xy 283.608051 -242.545104) (xy 283.584925 -242.497083)
			(xy 283.569215 -242.446153) (xy 283.561272 -242.393449) (xy 276.728692 -242.393449) (xy 276.720749 -242.446153)
			(xy 276.705039 -242.497083) (xy 276.681913 -242.545104) (xy 276.651889 -242.589141) (xy 276.615637 -242.628212)
			(xy 276.573966 -242.661443) (xy 276.527808 -242.688092) (xy 276.478194 -242.707564) (xy 276.426232 -242.719424)
			(xy 276.373082 -242.723408) (xy 276.319932 -242.719424) (xy 276.26797 -242.707564) (xy 276.218356 -242.688092)
			(xy 276.172198 -242.661443) (xy 276.130527 -242.628212) (xy 276.094275 -242.589141) (xy 276.064251 -242.545104)
			(xy 276.041125 -242.497083) (xy 276.025415 -242.446153) (xy 276.017472 -242.393449) (xy 269.184892 -242.393449)
			(xy 269.176949 -242.446153) (xy 269.161239 -242.497083) (xy 269.138113 -242.545104) (xy 269.108089 -242.589141)
			(xy 269.071837 -242.628212) (xy 269.030166 -242.661443) (xy 268.984008 -242.688092) (xy 268.934394 -242.707564)
			(xy 268.882432 -242.719424) (xy 268.829282 -242.723408) (xy 268.776132 -242.719424) (xy 268.72417 -242.707564)
			(xy 268.674556 -242.688092) (xy 268.628398 -242.661443) (xy 268.586727 -242.628212) (xy 268.550475 -242.589141)
			(xy 268.520451 -242.545104) (xy 268.497325 -242.497083) (xy 268.481615 -242.446153) (xy 268.473672 -242.393449)
			(xy 261.641092 -242.393449) (xy 261.633149 -242.446153) (xy 261.617439 -242.497083) (xy 261.594313 -242.545104)
			(xy 261.564289 -242.589141) (xy 261.528037 -242.628212) (xy 261.486366 -242.661443) (xy 261.440208 -242.688092)
			(xy 261.390594 -242.707564) (xy 261.338632 -242.719424) (xy 261.285482 -242.723408) (xy 261.232332 -242.719424)
			(xy 261.18037 -242.707564) (xy 261.130756 -242.688092) (xy 261.084598 -242.661443) (xy 261.042927 -242.628212)
			(xy 261.006675 -242.589141) (xy 260.976651 -242.545104) (xy 260.953525 -242.497083) (xy 260.937815 -242.446153)
			(xy 260.929872 -242.393449) (xy 254 -242.393449) (xy 254 -243.243333) (xy 256.829804 -243.243333)
			(xy 256.829804 -243.190035) (xy 256.837747 -243.137331) (xy 256.853457 -243.086401) (xy 256.876583 -243.03838)
			(xy 256.906607 -242.994343) (xy 256.942859 -242.955272) (xy 256.98453 -242.922041) (xy 257.030688 -242.895392)
			(xy 257.080302 -242.87592) (xy 257.132264 -242.86406) (xy 257.185414 -242.860077) (xy 257.238564 -242.86406)
			(xy 257.290526 -242.87592) (xy 257.34014 -242.895392) (xy 257.386298 -242.922041) (xy 257.427969 -242.955272)
			(xy 257.464221 -242.994343) (xy 257.494245 -243.03838) (xy 257.517371 -243.086401) (xy 257.533081 -243.137331)
			(xy 257.541024 -243.190035) (xy 257.541522 -243.216684) (xy 257.541024 -243.243333) (xy 260.929872 -243.243333)
			(xy 260.929872 -243.190035) (xy 260.937815 -243.137331) (xy 260.953525 -243.086401) (xy 260.976651 -243.03838)
			(xy 261.006675 -242.994343) (xy 261.042927 -242.955272) (xy 261.084598 -242.922041) (xy 261.130756 -242.895392)
			(xy 261.18037 -242.87592) (xy 261.232332 -242.86406) (xy 261.285482 -242.860077) (xy 261.338632 -242.86406)
			(xy 261.390594 -242.87592) (xy 261.440208 -242.895392) (xy 261.486366 -242.922041) (xy 261.528037 -242.955272)
			(xy 261.564289 -242.994343) (xy 261.594313 -243.03838) (xy 261.617439 -243.086401) (xy 261.633149 -243.137331)
			(xy 261.641092 -243.190035) (xy 261.64159 -243.216684) (xy 261.641092 -243.243333) (xy 264.373604 -243.243333)
			(xy 264.373604 -243.190035) (xy 264.381547 -243.137331) (xy 264.397257 -243.086401) (xy 264.420383 -243.03838)
			(xy 264.450407 -242.994343) (xy 264.486659 -242.955272) (xy 264.52833 -242.922041) (xy 264.574488 -242.895392)
			(xy 264.624102 -242.87592) (xy 264.676064 -242.86406) (xy 264.729214 -242.860077) (xy 264.782364 -242.86406)
			(xy 264.834326 -242.87592) (xy 264.88394 -242.895392) (xy 264.930098 -242.922041) (xy 264.971769 -242.955272)
			(xy 265.008021 -242.994343) (xy 265.038045 -243.03838) (xy 265.061171 -243.086401) (xy 265.076881 -243.137331)
			(xy 265.084824 -243.190035) (xy 265.085322 -243.216684) (xy 265.084824 -243.243333) (xy 268.473672 -243.243333)
			(xy 268.473672 -243.190035) (xy 268.481615 -243.137331) (xy 268.497325 -243.086401) (xy 268.520451 -243.03838)
			(xy 268.550475 -242.994343) (xy 268.586727 -242.955272) (xy 268.628398 -242.922041) (xy 268.674556 -242.895392)
			(xy 268.72417 -242.87592) (xy 268.776132 -242.86406) (xy 268.829282 -242.860077) (xy 268.882432 -242.86406)
			(xy 268.934394 -242.87592) (xy 268.984008 -242.895392) (xy 269.030166 -242.922041) (xy 269.071837 -242.955272)
			(xy 269.108089 -242.994343) (xy 269.138113 -243.03838) (xy 269.161239 -243.086401) (xy 269.176949 -243.137331)
			(xy 269.184892 -243.190035) (xy 269.18539 -243.216684) (xy 269.184892 -243.243333) (xy 271.917404 -243.243333)
			(xy 271.917404 -243.190035) (xy 271.925347 -243.137331) (xy 271.941057 -243.086401) (xy 271.964183 -243.03838)
			(xy 271.994207 -242.994343) (xy 272.030459 -242.955272) (xy 272.07213 -242.922041) (xy 272.118288 -242.895392)
			(xy 272.167902 -242.87592) (xy 272.219864 -242.86406) (xy 272.273014 -242.860077) (xy 272.326164 -242.86406)
			(xy 272.378126 -242.87592) (xy 272.42774 -242.895392) (xy 272.473898 -242.922041) (xy 272.515569 -242.955272)
			(xy 272.551821 -242.994343) (xy 272.581845 -243.03838) (xy 272.604971 -243.086401) (xy 272.620681 -243.137331)
			(xy 272.628624 -243.190035) (xy 272.629122 -243.216684) (xy 272.628624 -243.243333) (xy 276.017472 -243.243333)
			(xy 276.017472 -243.190035) (xy 276.025415 -243.137331) (xy 276.041125 -243.086401) (xy 276.064251 -243.03838)
			(xy 276.094275 -242.994343) (xy 276.130527 -242.955272) (xy 276.172198 -242.922041) (xy 276.218356 -242.895392)
			(xy 276.26797 -242.87592) (xy 276.319932 -242.86406) (xy 276.373082 -242.860077) (xy 276.426232 -242.86406)
			(xy 276.478194 -242.87592) (xy 276.527808 -242.895392) (xy 276.573966 -242.922041) (xy 276.615637 -242.955272)
			(xy 276.651889 -242.994343) (xy 276.681913 -243.03838) (xy 276.705039 -243.086401) (xy 276.720749 -243.137331)
			(xy 276.728692 -243.190035) (xy 276.72919 -243.216684) (xy 276.728692 -243.243333) (xy 279.461204 -243.243333)
			(xy 279.461204 -243.190035) (xy 279.469147 -243.137331) (xy 279.484857 -243.086401) (xy 279.507983 -243.03838)
			(xy 279.538007 -242.994343) (xy 279.574259 -242.955272) (xy 279.61593 -242.922041) (xy 279.662088 -242.895392)
			(xy 279.711702 -242.87592) (xy 279.763664 -242.86406) (xy 279.816814 -242.860077) (xy 279.869964 -242.86406)
			(xy 279.921926 -242.87592) (xy 279.97154 -242.895392) (xy 280.017698 -242.922041) (xy 280.059369 -242.955272)
			(xy 280.095621 -242.994343) (xy 280.125645 -243.03838) (xy 280.148771 -243.086401) (xy 280.164481 -243.137331)
			(xy 280.172424 -243.190035) (xy 280.172922 -243.216684) (xy 280.172424 -243.243333) (xy 283.561272 -243.243333)
			(xy 283.561272 -243.190035) (xy 283.569215 -243.137331) (xy 283.584925 -243.086401) (xy 283.608051 -243.03838)
			(xy 283.638075 -242.994343) (xy 283.674327 -242.955272) (xy 283.715998 -242.922041) (xy 283.762156 -242.895392)
			(xy 283.81177 -242.87592) (xy 283.863732 -242.86406) (xy 283.916882 -242.860077) (xy 283.970032 -242.86406)
			(xy 284.021994 -242.87592) (xy 284.071608 -242.895392) (xy 284.117766 -242.922041) (xy 284.159437 -242.955272)
			(xy 284.195689 -242.994343) (xy 284.225713 -243.03838) (xy 284.248839 -243.086401) (xy 284.264549 -243.137331)
			(xy 284.272492 -243.190035) (xy 284.27299 -243.216684) (xy 284.272492 -243.243333) (xy 287.005004 -243.243333)
			(xy 287.005004 -243.190035) (xy 287.012947 -243.137331) (xy 287.028657 -243.086401) (xy 287.051783 -243.03838)
			(xy 287.081807 -242.994343) (xy 287.118059 -242.955272) (xy 287.15973 -242.922041) (xy 287.205888 -242.895392)
			(xy 287.255502 -242.87592) (xy 287.307464 -242.86406) (xy 287.360614 -242.860077) (xy 287.413764 -242.86406)
			(xy 287.465726 -242.87592) (xy 287.51534 -242.895392) (xy 287.561498 -242.922041) (xy 287.603169 -242.955272)
			(xy 287.639421 -242.994343) (xy 287.669445 -243.03838) (xy 287.692571 -243.086401) (xy 287.708281 -243.137331)
			(xy 287.716224 -243.190035) (xy 287.716722 -243.216684) (xy 287.716224 -243.243333) (xy 291.105072 -243.243333)
			(xy 291.105072 -243.190035) (xy 291.113015 -243.137331) (xy 291.128725 -243.086401) (xy 291.151851 -243.03838)
			(xy 291.181875 -242.994343) (xy 291.218127 -242.955272) (xy 291.259798 -242.922041) (xy 291.305956 -242.895392)
			(xy 291.35557 -242.87592) (xy 291.407532 -242.86406) (xy 291.460682 -242.860077) (xy 291.513832 -242.86406)
			(xy 291.565794 -242.87592) (xy 291.615408 -242.895392) (xy 291.661566 -242.922041) (xy 291.703237 -242.955272)
			(xy 291.739489 -242.994343) (xy 291.769513 -243.03838) (xy 291.792639 -243.086401) (xy 291.808349 -243.137331)
			(xy 291.816292 -243.190035) (xy 291.81679 -243.216684) (xy 291.816292 -243.243333) (xy 294.548804 -243.243333)
			(xy 294.548804 -243.190035) (xy 294.556747 -243.137331) (xy 294.572457 -243.086401) (xy 294.595583 -243.03838)
			(xy 294.625607 -242.994343) (xy 294.661859 -242.955272) (xy 294.70353 -242.922041) (xy 294.749688 -242.895392)
			(xy 294.799302 -242.87592) (xy 294.851264 -242.86406) (xy 294.904414 -242.860077) (xy 294.957564 -242.86406)
			(xy 295.009526 -242.87592) (xy 295.05914 -242.895392) (xy 295.105298 -242.922041) (xy 295.146969 -242.955272)
			(xy 295.183221 -242.994343) (xy 295.213245 -243.03838) (xy 295.236371 -243.086401) (xy 295.252081 -243.137331)
			(xy 295.260024 -243.190035) (xy 295.260522 -243.216684) (xy 295.260024 -243.243333) (xy 298.648872 -243.243333)
			(xy 298.648872 -243.190035) (xy 298.656815 -243.137331) (xy 298.672525 -243.086401) (xy 298.695651 -243.03838)
			(xy 298.725675 -242.994343) (xy 298.761927 -242.955272) (xy 298.803598 -242.922041) (xy 298.849756 -242.895392)
			(xy 298.89937 -242.87592) (xy 298.951332 -242.86406) (xy 299.004482 -242.860077) (xy 299.057632 -242.86406)
			(xy 299.109594 -242.87592) (xy 299.159208 -242.895392) (xy 299.205366 -242.922041) (xy 299.247037 -242.955272)
			(xy 299.283289 -242.994343) (xy 299.313313 -243.03838) (xy 299.336439 -243.086401) (xy 299.352149 -243.137331)
			(xy 299.360092 -243.190035) (xy 299.36059 -243.216684) (xy 299.360092 -243.243333) (xy 302.092604 -243.243333)
			(xy 302.092604 -243.190035) (xy 302.100547 -243.137331) (xy 302.116257 -243.086401) (xy 302.139383 -243.03838)
			(xy 302.169407 -242.994343) (xy 302.205659 -242.955272) (xy 302.24733 -242.922041) (xy 302.293488 -242.895392)
			(xy 302.343102 -242.87592) (xy 302.395064 -242.86406) (xy 302.448214 -242.860077) (xy 302.501364 -242.86406)
			(xy 302.553326 -242.87592) (xy 302.60294 -242.895392) (xy 302.649098 -242.922041) (xy 302.690769 -242.955272)
			(xy 302.727021 -242.994343) (xy 302.757045 -243.03838) (xy 302.780171 -243.086401) (xy 302.795881 -243.137331)
			(xy 302.803824 -243.190035) (xy 302.804322 -243.216684) (xy 302.803824 -243.243333) (xy 303.982872 -243.243333)
			(xy 303.982872 -243.190035) (xy 303.990815 -243.137331) (xy 304.006525 -243.086401) (xy 304.029651 -243.03838)
			(xy 304.059675 -242.994343) (xy 304.095927 -242.955272) (xy 304.137598 -242.922041) (xy 304.183756 -242.895392)
			(xy 304.23337 -242.87592) (xy 304.285332 -242.86406) (xy 304.338482 -242.860077) (xy 304.391632 -242.86406)
			(xy 304.443594 -242.87592) (xy 304.493208 -242.895392) (xy 304.539366 -242.922041) (xy 304.581037 -242.955272)
			(xy 304.617289 -242.994343) (xy 304.647313 -243.03838) (xy 304.670439 -243.086401) (xy 304.686149 -243.137331)
			(xy 304.694092 -243.190035) (xy 304.69459 -243.216684) (xy 304.694092 -243.243333) (xy 309.636404 -243.243333)
			(xy 309.636404 -243.190035) (xy 309.644347 -243.137331) (xy 309.660057 -243.086401) (xy 309.683183 -243.03838)
			(xy 309.713207 -242.994343) (xy 309.749459 -242.955272) (xy 309.79113 -242.922041) (xy 309.837288 -242.895392)
			(xy 309.886902 -242.87592) (xy 309.938864 -242.86406) (xy 309.992014 -242.860077) (xy 310.045164 -242.86406)
			(xy 310.097126 -242.87592) (xy 310.14674 -242.895392) (xy 310.192898 -242.922041) (xy 310.234569 -242.955272)
			(xy 310.270821 -242.994343) (xy 310.300845 -243.03838) (xy 310.323971 -243.086401) (xy 310.339681 -243.137331)
			(xy 310.347624 -243.190035) (xy 310.348122 -243.216684) (xy 310.347624 -243.243333) (xy 311.526672 -243.243333)
			(xy 311.526672 -243.190035) (xy 311.534615 -243.137331) (xy 311.550325 -243.086401) (xy 311.573451 -243.03838)
			(xy 311.603475 -242.994343) (xy 311.639727 -242.955272) (xy 311.681398 -242.922041) (xy 311.727556 -242.895392)
			(xy 311.77717 -242.87592) (xy 311.829132 -242.86406) (xy 311.882282 -242.860077) (xy 311.935432 -242.86406)
			(xy 311.987394 -242.87592) (xy 312.037008 -242.895392) (xy 312.083166 -242.922041) (xy 312.124837 -242.955272)
			(xy 312.161089 -242.994343) (xy 312.191113 -243.03838) (xy 312.214239 -243.086401) (xy 312.229949 -243.137331)
			(xy 312.237892 -243.190035) (xy 312.23839 -243.216684) (xy 312.237892 -243.243333) (xy 312.229949 -243.296037)
			(xy 312.214239 -243.346967) (xy 312.191113 -243.394988) (xy 312.161089 -243.439025) (xy 312.124837 -243.478096)
			(xy 312.083166 -243.511327) (xy 312.037008 -243.537976) (xy 311.987394 -243.557448) (xy 311.935432 -243.569308)
			(xy 311.882282 -243.573292) (xy 311.829132 -243.569308) (xy 311.77717 -243.557448) (xy 311.727556 -243.537976)
			(xy 311.681398 -243.511327) (xy 311.639727 -243.478096) (xy 311.603475 -243.439025) (xy 311.573451 -243.394988)
			(xy 311.550325 -243.346967) (xy 311.534615 -243.296037) (xy 311.526672 -243.243333) (xy 310.347624 -243.243333)
			(xy 310.339681 -243.296037) (xy 310.323971 -243.346967) (xy 310.300845 -243.394988) (xy 310.270821 -243.439025)
			(xy 310.234569 -243.478096) (xy 310.192898 -243.511327) (xy 310.14674 -243.537976) (xy 310.097126 -243.557448)
			(xy 310.045164 -243.569308) (xy 309.992014 -243.573292) (xy 309.938864 -243.569308) (xy 309.886902 -243.557448)
			(xy 309.837288 -243.537976) (xy 309.79113 -243.511327) (xy 309.749459 -243.478096) (xy 309.713207 -243.439025)
			(xy 309.683183 -243.394988) (xy 309.660057 -243.346967) (xy 309.644347 -243.296037) (xy 309.636404 -243.243333)
			(xy 304.694092 -243.243333) (xy 304.686149 -243.296037) (xy 304.670439 -243.346967) (xy 304.647313 -243.394988)
			(xy 304.617289 -243.439025) (xy 304.581037 -243.478096) (xy 304.539366 -243.511327) (xy 304.493208 -243.537976)
			(xy 304.443594 -243.557448) (xy 304.391632 -243.569308) (xy 304.338482 -243.573292) (xy 304.285332 -243.569308)
			(xy 304.23337 -243.557448) (xy 304.183756 -243.537976) (xy 304.137598 -243.511327) (xy 304.095927 -243.478096)
			(xy 304.059675 -243.439025) (xy 304.029651 -243.394988) (xy 304.006525 -243.346967) (xy 303.990815 -243.296037)
			(xy 303.982872 -243.243333) (xy 302.803824 -243.243333) (xy 302.795881 -243.296037) (xy 302.780171 -243.346967)
			(xy 302.757045 -243.394988) (xy 302.727021 -243.439025) (xy 302.690769 -243.478096) (xy 302.649098 -243.511327)
			(xy 302.60294 -243.537976) (xy 302.553326 -243.557448) (xy 302.501364 -243.569308) (xy 302.448214 -243.573292)
			(xy 302.395064 -243.569308) (xy 302.343102 -243.557448) (xy 302.293488 -243.537976) (xy 302.24733 -243.511327)
			(xy 302.205659 -243.478096) (xy 302.169407 -243.439025) (xy 302.139383 -243.394988) (xy 302.116257 -243.346967)
			(xy 302.100547 -243.296037) (xy 302.092604 -243.243333) (xy 299.360092 -243.243333) (xy 299.352149 -243.296037)
			(xy 299.336439 -243.346967) (xy 299.313313 -243.394988) (xy 299.283289 -243.439025) (xy 299.247037 -243.478096)
			(xy 299.205366 -243.511327) (xy 299.159208 -243.537976) (xy 299.109594 -243.557448) (xy 299.057632 -243.569308)
			(xy 299.004482 -243.573292) (xy 298.951332 -243.569308) (xy 298.89937 -243.557448) (xy 298.849756 -243.537976)
			(xy 298.803598 -243.511327) (xy 298.761927 -243.478096) (xy 298.725675 -243.439025) (xy 298.695651 -243.394988)
			(xy 298.672525 -243.346967) (xy 298.656815 -243.296037) (xy 298.648872 -243.243333) (xy 295.260024 -243.243333)
			(xy 295.252081 -243.296037) (xy 295.236371 -243.346967) (xy 295.213245 -243.394988) (xy 295.183221 -243.439025)
			(xy 295.146969 -243.478096) (xy 295.105298 -243.511327) (xy 295.05914 -243.537976) (xy 295.009526 -243.557448)
			(xy 294.957564 -243.569308) (xy 294.904414 -243.573292) (xy 294.851264 -243.569308) (xy 294.799302 -243.557448)
			(xy 294.749688 -243.537976) (xy 294.70353 -243.511327) (xy 294.661859 -243.478096) (xy 294.625607 -243.439025)
			(xy 294.595583 -243.394988) (xy 294.572457 -243.346967) (xy 294.556747 -243.296037) (xy 294.548804 -243.243333)
			(xy 291.816292 -243.243333) (xy 291.808349 -243.296037) (xy 291.792639 -243.346967) (xy 291.769513 -243.394988)
			(xy 291.739489 -243.439025) (xy 291.703237 -243.478096) (xy 291.661566 -243.511327) (xy 291.615408 -243.537976)
			(xy 291.565794 -243.557448) (xy 291.513832 -243.569308) (xy 291.460682 -243.573292) (xy 291.407532 -243.569308)
			(xy 291.35557 -243.557448) (xy 291.305956 -243.537976) (xy 291.259798 -243.511327) (xy 291.218127 -243.478096)
			(xy 291.181875 -243.439025) (xy 291.151851 -243.394988) (xy 291.128725 -243.346967) (xy 291.113015 -243.296037)
			(xy 291.105072 -243.243333) (xy 287.716224 -243.243333) (xy 287.708281 -243.296037) (xy 287.692571 -243.346967)
			(xy 287.669445 -243.394988) (xy 287.639421 -243.439025) (xy 287.603169 -243.478096) (xy 287.561498 -243.511327)
			(xy 287.51534 -243.537976) (xy 287.465726 -243.557448) (xy 287.413764 -243.569308) (xy 287.360614 -243.573292)
			(xy 287.307464 -243.569308) (xy 287.255502 -243.557448) (xy 287.205888 -243.537976) (xy 287.15973 -243.511327)
			(xy 287.118059 -243.478096) (xy 287.081807 -243.439025) (xy 287.051783 -243.394988) (xy 287.028657 -243.346967)
			(xy 287.012947 -243.296037) (xy 287.005004 -243.243333) (xy 284.272492 -243.243333) (xy 284.264549 -243.296037)
			(xy 284.248839 -243.346967) (xy 284.225713 -243.394988) (xy 284.195689 -243.439025) (xy 284.159437 -243.478096)
			(xy 284.117766 -243.511327) (xy 284.071608 -243.537976) (xy 284.021994 -243.557448) (xy 283.970032 -243.569308)
			(xy 283.916882 -243.573292) (xy 283.863732 -243.569308) (xy 283.81177 -243.557448) (xy 283.762156 -243.537976)
			(xy 283.715998 -243.511327) (xy 283.674327 -243.478096) (xy 283.638075 -243.439025) (xy 283.608051 -243.394988)
			(xy 283.584925 -243.346967) (xy 283.569215 -243.296037) (xy 283.561272 -243.243333) (xy 280.172424 -243.243333)
			(xy 280.164481 -243.296037) (xy 280.148771 -243.346967) (xy 280.125645 -243.394988) (xy 280.095621 -243.439025)
			(xy 280.059369 -243.478096) (xy 280.017698 -243.511327) (xy 279.97154 -243.537976) (xy 279.921926 -243.557448)
			(xy 279.869964 -243.569308) (xy 279.816814 -243.573292) (xy 279.763664 -243.569308) (xy 279.711702 -243.557448)
			(xy 279.662088 -243.537976) (xy 279.61593 -243.511327) (xy 279.574259 -243.478096) (xy 279.538007 -243.439025)
			(xy 279.507983 -243.394988) (xy 279.484857 -243.346967) (xy 279.469147 -243.296037) (xy 279.461204 -243.243333)
			(xy 276.728692 -243.243333) (xy 276.720749 -243.296037) (xy 276.705039 -243.346967) (xy 276.681913 -243.394988)
			(xy 276.651889 -243.439025) (xy 276.615637 -243.478096) (xy 276.573966 -243.511327) (xy 276.527808 -243.537976)
			(xy 276.478194 -243.557448) (xy 276.426232 -243.569308) (xy 276.373082 -243.573292) (xy 276.319932 -243.569308)
			(xy 276.26797 -243.557448) (xy 276.218356 -243.537976) (xy 276.172198 -243.511327) (xy 276.130527 -243.478096)
			(xy 276.094275 -243.439025) (xy 276.064251 -243.394988) (xy 276.041125 -243.346967) (xy 276.025415 -243.296037)
			(xy 276.017472 -243.243333) (xy 272.628624 -243.243333) (xy 272.620681 -243.296037) (xy 272.604971 -243.346967)
			(xy 272.581845 -243.394988) (xy 272.551821 -243.439025) (xy 272.515569 -243.478096) (xy 272.473898 -243.511327)
			(xy 272.42774 -243.537976) (xy 272.378126 -243.557448) (xy 272.326164 -243.569308) (xy 272.273014 -243.573292)
			(xy 272.219864 -243.569308) (xy 272.167902 -243.557448) (xy 272.118288 -243.537976) (xy 272.07213 -243.511327)
			(xy 272.030459 -243.478096) (xy 271.994207 -243.439025) (xy 271.964183 -243.394988) (xy 271.941057 -243.346967)
			(xy 271.925347 -243.296037) (xy 271.917404 -243.243333) (xy 269.184892 -243.243333) (xy 269.176949 -243.296037)
			(xy 269.161239 -243.346967) (xy 269.138113 -243.394988) (xy 269.108089 -243.439025) (xy 269.071837 -243.478096)
			(xy 269.030166 -243.511327) (xy 268.984008 -243.537976) (xy 268.934394 -243.557448) (xy 268.882432 -243.569308)
			(xy 268.829282 -243.573292) (xy 268.776132 -243.569308) (xy 268.72417 -243.557448) (xy 268.674556 -243.537976)
			(xy 268.628398 -243.511327) (xy 268.586727 -243.478096) (xy 268.550475 -243.439025) (xy 268.520451 -243.394988)
			(xy 268.497325 -243.346967) (xy 268.481615 -243.296037) (xy 268.473672 -243.243333) (xy 265.084824 -243.243333)
			(xy 265.076881 -243.296037) (xy 265.061171 -243.346967) (xy 265.038045 -243.394988) (xy 265.008021 -243.439025)
			(xy 264.971769 -243.478096) (xy 264.930098 -243.511327) (xy 264.88394 -243.537976) (xy 264.834326 -243.557448)
			(xy 264.782364 -243.569308) (xy 264.729214 -243.573292) (xy 264.676064 -243.569308) (xy 264.624102 -243.557448)
			(xy 264.574488 -243.537976) (xy 264.52833 -243.511327) (xy 264.486659 -243.478096) (xy 264.450407 -243.439025)
			(xy 264.420383 -243.394988) (xy 264.397257 -243.346967) (xy 264.381547 -243.296037) (xy 264.373604 -243.243333)
			(xy 261.641092 -243.243333) (xy 261.633149 -243.296037) (xy 261.617439 -243.346967) (xy 261.594313 -243.394988)
			(xy 261.564289 -243.439025) (xy 261.528037 -243.478096) (xy 261.486366 -243.511327) (xy 261.440208 -243.537976)
			(xy 261.390594 -243.557448) (xy 261.338632 -243.569308) (xy 261.285482 -243.573292) (xy 261.232332 -243.569308)
			(xy 261.18037 -243.557448) (xy 261.130756 -243.537976) (xy 261.084598 -243.511327) (xy 261.042927 -243.478096)
			(xy 261.006675 -243.439025) (xy 260.976651 -243.394988) (xy 260.953525 -243.346967) (xy 260.937815 -243.296037)
			(xy 260.929872 -243.243333) (xy 257.541024 -243.243333) (xy 257.533081 -243.296037) (xy 257.517371 -243.346967)
			(xy 257.494245 -243.394988) (xy 257.464221 -243.439025) (xy 257.427969 -243.478096) (xy 257.386298 -243.511327)
			(xy 257.34014 -243.537976) (xy 257.290526 -243.557448) (xy 257.238564 -243.569308) (xy 257.185414 -243.573292)
			(xy 257.132264 -243.569308) (xy 257.080302 -243.557448) (xy 257.030688 -243.537976) (xy 256.98453 -243.511327)
			(xy 256.942859 -243.478096) (xy 256.906607 -243.439025) (xy 256.876583 -243.394988) (xy 256.853457 -243.346967)
			(xy 256.837747 -243.296037) (xy 256.829804 -243.243333) (xy 254 -243.243333) (xy 254 -244.093217)
			(xy 256.829804 -244.093217) (xy 256.829804 -244.039919) (xy 256.837747 -243.987215) (xy 256.853457 -243.936285)
			(xy 256.876583 -243.888264) (xy 256.906607 -243.844227) (xy 256.942859 -243.805156) (xy 256.98453 -243.771925)
			(xy 257.030688 -243.745276) (xy 257.080302 -243.725804) (xy 257.132264 -243.713944) (xy 257.185414 -243.709961)
			(xy 257.238564 -243.713944) (xy 257.290526 -243.725804) (xy 257.34014 -243.745276) (xy 257.386298 -243.771925)
			(xy 257.427969 -243.805156) (xy 257.464221 -243.844227) (xy 257.494245 -243.888264) (xy 257.517371 -243.936285)
			(xy 257.533081 -243.987215) (xy 257.541024 -244.039919) (xy 257.541522 -244.066568) (xy 257.541024 -244.093217)
			(xy 264.373604 -244.093217) (xy 264.373604 -244.039919) (xy 264.381547 -243.987215) (xy 264.397257 -243.936285)
			(xy 264.420383 -243.888264) (xy 264.450407 -243.844227) (xy 264.486659 -243.805156) (xy 264.52833 -243.771925)
			(xy 264.574488 -243.745276) (xy 264.624102 -243.725804) (xy 264.676064 -243.713944) (xy 264.729214 -243.709961)
			(xy 264.782364 -243.713944) (xy 264.834326 -243.725804) (xy 264.88394 -243.745276) (xy 264.930098 -243.771925)
			(xy 264.971769 -243.805156) (xy 265.008021 -243.844227) (xy 265.038045 -243.888264) (xy 265.061171 -243.936285)
			(xy 265.076881 -243.987215) (xy 265.084824 -244.039919) (xy 265.085322 -244.066568) (xy 265.084824 -244.093217)
			(xy 271.917404 -244.093217) (xy 271.917404 -244.039919) (xy 271.925347 -243.987215) (xy 271.941057 -243.936285)
			(xy 271.964183 -243.888264) (xy 271.994207 -243.844227) (xy 272.030459 -243.805156) (xy 272.07213 -243.771925)
			(xy 272.118288 -243.745276) (xy 272.167902 -243.725804) (xy 272.219864 -243.713944) (xy 272.273014 -243.709961)
			(xy 272.326164 -243.713944) (xy 272.378126 -243.725804) (xy 272.42774 -243.745276) (xy 272.473898 -243.771925)
			(xy 272.515569 -243.805156) (xy 272.551821 -243.844227) (xy 272.581845 -243.888264) (xy 272.604971 -243.936285)
			(xy 272.620681 -243.987215) (xy 272.628624 -244.039919) (xy 272.629122 -244.066568) (xy 272.628624 -244.093217)
			(xy 279.461204 -244.093217) (xy 279.461204 -244.039919) (xy 279.469147 -243.987215) (xy 279.484857 -243.936285)
			(xy 279.507983 -243.888264) (xy 279.538007 -243.844227) (xy 279.574259 -243.805156) (xy 279.61593 -243.771925)
			(xy 279.662088 -243.745276) (xy 279.711702 -243.725804) (xy 279.763664 -243.713944) (xy 279.816814 -243.709961)
			(xy 279.869964 -243.713944) (xy 279.921926 -243.725804) (xy 279.97154 -243.745276) (xy 280.017698 -243.771925)
			(xy 280.059369 -243.805156) (xy 280.095621 -243.844227) (xy 280.125645 -243.888264) (xy 280.148771 -243.936285)
			(xy 280.164481 -243.987215) (xy 280.172424 -244.039919) (xy 280.172922 -244.066568) (xy 280.172424 -244.093217)
			(xy 287.005004 -244.093217) (xy 287.005004 -244.039919) (xy 287.012947 -243.987215) (xy 287.028657 -243.936285)
			(xy 287.051783 -243.888264) (xy 287.081807 -243.844227) (xy 287.118059 -243.805156) (xy 287.15973 -243.771925)
			(xy 287.205888 -243.745276) (xy 287.255502 -243.725804) (xy 287.307464 -243.713944) (xy 287.360614 -243.709961)
			(xy 287.413764 -243.713944) (xy 287.465726 -243.725804) (xy 287.51534 -243.745276) (xy 287.561498 -243.771925)
			(xy 287.603169 -243.805156) (xy 287.639421 -243.844227) (xy 287.669445 -243.888264) (xy 287.692571 -243.936285)
			(xy 287.708281 -243.987215) (xy 287.716224 -244.039919) (xy 287.716722 -244.066568) (xy 287.716224 -244.093217)
			(xy 294.548804 -244.093217) (xy 294.548804 -244.039919) (xy 294.556747 -243.987215) (xy 294.572457 -243.936285)
			(xy 294.595583 -243.888264) (xy 294.625607 -243.844227) (xy 294.661859 -243.805156) (xy 294.70353 -243.771925)
			(xy 294.749688 -243.745276) (xy 294.799302 -243.725804) (xy 294.851264 -243.713944) (xy 294.904414 -243.709961)
			(xy 294.957564 -243.713944) (xy 295.009526 -243.725804) (xy 295.05914 -243.745276) (xy 295.105298 -243.771925)
			(xy 295.146969 -243.805156) (xy 295.183221 -243.844227) (xy 295.213245 -243.888264) (xy 295.236371 -243.936285)
			(xy 295.252081 -243.987215) (xy 295.260024 -244.039919) (xy 295.260522 -244.066568) (xy 295.260024 -244.093217)
			(xy 302.092604 -244.093217) (xy 302.092604 -244.039919) (xy 302.100547 -243.987215) (xy 302.116257 -243.936285)
			(xy 302.139383 -243.888264) (xy 302.169407 -243.844227) (xy 302.205659 -243.805156) (xy 302.24733 -243.771925)
			(xy 302.293488 -243.745276) (xy 302.343102 -243.725804) (xy 302.395064 -243.713944) (xy 302.448214 -243.709961)
			(xy 302.501364 -243.713944) (xy 302.553326 -243.725804) (xy 302.60294 -243.745276) (xy 302.649098 -243.771925)
			(xy 302.690769 -243.805156) (xy 302.727021 -243.844227) (xy 302.757045 -243.888264) (xy 302.780171 -243.936285)
			(xy 302.795881 -243.987215) (xy 302.803824 -244.039919) (xy 302.804322 -244.066568) (xy 302.803824 -244.093217)
			(xy 309.636404 -244.093217) (xy 309.636404 -244.039919) (xy 309.644347 -243.987215) (xy 309.660057 -243.936285)
			(xy 309.683183 -243.888264) (xy 309.713207 -243.844227) (xy 309.749459 -243.805156) (xy 309.79113 -243.771925)
			(xy 309.837288 -243.745276) (xy 309.886902 -243.725804) (xy 309.938864 -243.713944) (xy 309.992014 -243.709961)
			(xy 310.045164 -243.713944) (xy 310.097126 -243.725804) (xy 310.14674 -243.745276) (xy 310.192898 -243.771925)
			(xy 310.234569 -243.805156) (xy 310.270821 -243.844227) (xy 310.300845 -243.888264) (xy 310.323971 -243.936285)
			(xy 310.339681 -243.987215) (xy 310.347624 -244.039919) (xy 310.348122 -244.066568) (xy 310.347624 -244.093217)
			(xy 310.339681 -244.145921) (xy 310.323971 -244.196851) (xy 310.300845 -244.244872) (xy 310.270821 -244.288909)
			(xy 310.234569 -244.32798) (xy 310.192898 -244.361211) (xy 310.14674 -244.38786) (xy 310.097126 -244.407332)
			(xy 310.045164 -244.419192) (xy 309.992014 -244.423176) (xy 309.938864 -244.419192) (xy 309.886902 -244.407332)
			(xy 309.837288 -244.38786) (xy 309.79113 -244.361211) (xy 309.749459 -244.32798) (xy 309.713207 -244.288909)
			(xy 309.683183 -244.244872) (xy 309.660057 -244.196851) (xy 309.644347 -244.145921) (xy 309.636404 -244.093217)
			(xy 302.803824 -244.093217) (xy 302.795881 -244.145921) (xy 302.780171 -244.196851) (xy 302.757045 -244.244872)
			(xy 302.727021 -244.288909) (xy 302.690769 -244.32798) (xy 302.649098 -244.361211) (xy 302.60294 -244.38786)
			(xy 302.553326 -244.407332) (xy 302.501364 -244.419192) (xy 302.448214 -244.423176) (xy 302.395064 -244.419192)
			(xy 302.343102 -244.407332) (xy 302.293488 -244.38786) (xy 302.24733 -244.361211) (xy 302.205659 -244.32798)
			(xy 302.169407 -244.288909) (xy 302.139383 -244.244872) (xy 302.116257 -244.196851) (xy 302.100547 -244.145921)
			(xy 302.092604 -244.093217) (xy 295.260024 -244.093217) (xy 295.252081 -244.145921) (xy 295.236371 -244.196851)
			(xy 295.213245 -244.244872) (xy 295.183221 -244.288909) (xy 295.146969 -244.32798) (xy 295.105298 -244.361211)
			(xy 295.05914 -244.38786) (xy 295.009526 -244.407332) (xy 294.957564 -244.419192) (xy 294.904414 -244.423176)
			(xy 294.851264 -244.419192) (xy 294.799302 -244.407332) (xy 294.749688 -244.38786) (xy 294.70353 -244.361211)
			(xy 294.661859 -244.32798) (xy 294.625607 -244.288909) (xy 294.595583 -244.244872) (xy 294.572457 -244.196851)
			(xy 294.556747 -244.145921) (xy 294.548804 -244.093217) (xy 287.716224 -244.093217) (xy 287.708281 -244.145921)
			(xy 287.692571 -244.196851) (xy 287.669445 -244.244872) (xy 287.639421 -244.288909) (xy 287.603169 -244.32798)
			(xy 287.561498 -244.361211) (xy 287.51534 -244.38786) (xy 287.465726 -244.407332) (xy 287.413764 -244.419192)
			(xy 287.360614 -244.423176) (xy 287.307464 -244.419192) (xy 287.255502 -244.407332) (xy 287.205888 -244.38786)
			(xy 287.15973 -244.361211) (xy 287.118059 -244.32798) (xy 287.081807 -244.288909) (xy 287.051783 -244.244872)
			(xy 287.028657 -244.196851) (xy 287.012947 -244.145921) (xy 287.005004 -244.093217) (xy 280.172424 -244.093217)
			(xy 280.164481 -244.145921) (xy 280.148771 -244.196851) (xy 280.125645 -244.244872) (xy 280.095621 -244.288909)
			(xy 280.059369 -244.32798) (xy 280.017698 -244.361211) (xy 279.97154 -244.38786) (xy 279.921926 -244.407332)
			(xy 279.869964 -244.419192) (xy 279.816814 -244.423176) (xy 279.763664 -244.419192) (xy 279.711702 -244.407332)
			(xy 279.662088 -244.38786) (xy 279.61593 -244.361211) (xy 279.574259 -244.32798) (xy 279.538007 -244.288909)
			(xy 279.507983 -244.244872) (xy 279.484857 -244.196851) (xy 279.469147 -244.145921) (xy 279.461204 -244.093217)
			(xy 272.628624 -244.093217) (xy 272.620681 -244.145921) (xy 272.604971 -244.196851) (xy 272.581845 -244.244872)
			(xy 272.551821 -244.288909) (xy 272.515569 -244.32798) (xy 272.473898 -244.361211) (xy 272.42774 -244.38786)
			(xy 272.378126 -244.407332) (xy 272.326164 -244.419192) (xy 272.273014 -244.423176) (xy 272.219864 -244.419192)
			(xy 272.167902 -244.407332) (xy 272.118288 -244.38786) (xy 272.07213 -244.361211) (xy 272.030459 -244.32798)
			(xy 271.994207 -244.288909) (xy 271.964183 -244.244872) (xy 271.941057 -244.196851) (xy 271.925347 -244.145921)
			(xy 271.917404 -244.093217) (xy 265.084824 -244.093217) (xy 265.076881 -244.145921) (xy 265.061171 -244.196851)
			(xy 265.038045 -244.244872) (xy 265.008021 -244.288909) (xy 264.971769 -244.32798) (xy 264.930098 -244.361211)
			(xy 264.88394 -244.38786) (xy 264.834326 -244.407332) (xy 264.782364 -244.419192) (xy 264.729214 -244.423176)
			(xy 264.676064 -244.419192) (xy 264.624102 -244.407332) (xy 264.574488 -244.38786) (xy 264.52833 -244.361211)
			(xy 264.486659 -244.32798) (xy 264.450407 -244.288909) (xy 264.420383 -244.244872) (xy 264.397257 -244.196851)
			(xy 264.381547 -244.145921) (xy 264.373604 -244.093217) (xy 257.541024 -244.093217) (xy 257.533081 -244.145921)
			(xy 257.517371 -244.196851) (xy 257.494245 -244.244872) (xy 257.464221 -244.288909) (xy 257.427969 -244.32798)
			(xy 257.386298 -244.361211) (xy 257.34014 -244.38786) (xy 257.290526 -244.407332) (xy 257.238564 -244.419192)
			(xy 257.185414 -244.423176) (xy 257.132264 -244.419192) (xy 257.080302 -244.407332) (xy 257.030688 -244.38786)
			(xy 256.98453 -244.361211) (xy 256.942859 -244.32798) (xy 256.906607 -244.288909) (xy 256.876583 -244.244872)
			(xy 256.853457 -244.196851) (xy 256.837747 -244.145921) (xy 256.829804 -244.093217) (xy 254 -244.093217)
			(xy 254 -244.943355) (xy 260.929872 -244.943355) (xy 260.929872 -244.890057) (xy 260.937815 -244.837353)
			(xy 260.953525 -244.786423) (xy 260.976651 -244.738402) (xy 261.006675 -244.694365) (xy 261.042927 -244.655294)
			(xy 261.084598 -244.622063) (xy 261.130756 -244.595414) (xy 261.18037 -244.575942) (xy 261.232332 -244.564082)
			(xy 261.285482 -244.560099) (xy 261.338632 -244.564082) (xy 261.390594 -244.575942) (xy 261.440208 -244.595414)
			(xy 261.486366 -244.622063) (xy 261.528037 -244.655294) (xy 261.564289 -244.694365) (xy 261.594313 -244.738402)
			(xy 261.617439 -244.786423) (xy 261.633149 -244.837353) (xy 261.641092 -244.890057) (xy 261.64159 -244.916706)
			(xy 261.641092 -244.943355) (xy 268.473672 -244.943355) (xy 268.473672 -244.890057) (xy 268.481615 -244.837353)
			(xy 268.497325 -244.786423) (xy 268.520451 -244.738402) (xy 268.550475 -244.694365) (xy 268.586727 -244.655294)
			(xy 268.628398 -244.622063) (xy 268.674556 -244.595414) (xy 268.72417 -244.575942) (xy 268.776132 -244.564082)
			(xy 268.829282 -244.560099) (xy 268.882432 -244.564082) (xy 268.934394 -244.575942) (xy 268.984008 -244.595414)
			(xy 269.030166 -244.622063) (xy 269.071837 -244.655294) (xy 269.108089 -244.694365) (xy 269.138113 -244.738402)
			(xy 269.161239 -244.786423) (xy 269.176949 -244.837353) (xy 269.184892 -244.890057) (xy 269.18539 -244.916706)
			(xy 269.184892 -244.943355) (xy 276.017472 -244.943355) (xy 276.017472 -244.890057) (xy 276.025415 -244.837353)
			(xy 276.041125 -244.786423) (xy 276.064251 -244.738402) (xy 276.094275 -244.694365) (xy 276.130527 -244.655294)
			(xy 276.172198 -244.622063) (xy 276.218356 -244.595414) (xy 276.26797 -244.575942) (xy 276.319932 -244.564082)
			(xy 276.373082 -244.560099) (xy 276.426232 -244.564082) (xy 276.478194 -244.575942) (xy 276.527808 -244.595414)
			(xy 276.573966 -244.622063) (xy 276.615637 -244.655294) (xy 276.651889 -244.694365) (xy 276.681913 -244.738402)
			(xy 276.705039 -244.786423) (xy 276.720749 -244.837353) (xy 276.728692 -244.890057) (xy 276.72919 -244.916706)
			(xy 276.728692 -244.943355) (xy 283.561272 -244.943355) (xy 283.561272 -244.890057) (xy 283.569215 -244.837353)
			(xy 283.584925 -244.786423) (xy 283.608051 -244.738402) (xy 283.638075 -244.694365) (xy 283.674327 -244.655294)
			(xy 283.715998 -244.622063) (xy 283.762156 -244.595414) (xy 283.81177 -244.575942) (xy 283.863732 -244.564082)
			(xy 283.916882 -244.560099) (xy 283.970032 -244.564082) (xy 284.021994 -244.575942) (xy 284.071608 -244.595414)
			(xy 284.117766 -244.622063) (xy 284.159437 -244.655294) (xy 284.195689 -244.694365) (xy 284.225713 -244.738402)
			(xy 284.248839 -244.786423) (xy 284.264549 -244.837353) (xy 284.272492 -244.890057) (xy 284.27299 -244.916706)
			(xy 284.272492 -244.943355) (xy 291.105072 -244.943355) (xy 291.105072 -244.890057) (xy 291.113015 -244.837353)
			(xy 291.128725 -244.786423) (xy 291.151851 -244.738402) (xy 291.181875 -244.694365) (xy 291.218127 -244.655294)
			(xy 291.259798 -244.622063) (xy 291.305956 -244.595414) (xy 291.35557 -244.575942) (xy 291.407532 -244.564082)
			(xy 291.460682 -244.560099) (xy 291.513832 -244.564082) (xy 291.565794 -244.575942) (xy 291.615408 -244.595414)
			(xy 291.661566 -244.622063) (xy 291.703237 -244.655294) (xy 291.739489 -244.694365) (xy 291.769513 -244.738402)
			(xy 291.792639 -244.786423) (xy 291.808349 -244.837353) (xy 291.816292 -244.890057) (xy 291.81679 -244.916706)
			(xy 291.816292 -244.943355) (xy 298.648872 -244.943355) (xy 298.648872 -244.890057) (xy 298.656815 -244.837353)
			(xy 298.672525 -244.786423) (xy 298.695651 -244.738402) (xy 298.725675 -244.694365) (xy 298.761927 -244.655294)
			(xy 298.803598 -244.622063) (xy 298.849756 -244.595414) (xy 298.89937 -244.575942) (xy 298.951332 -244.564082)
			(xy 299.004482 -244.560099) (xy 299.057632 -244.564082) (xy 299.109594 -244.575942) (xy 299.159208 -244.595414)
			(xy 299.205366 -244.622063) (xy 299.247037 -244.655294) (xy 299.283289 -244.694365) (xy 299.313313 -244.738402)
			(xy 299.336439 -244.786423) (xy 299.352149 -244.837353) (xy 299.360092 -244.890057) (xy 299.36059 -244.916706)
			(xy 299.360092 -244.943355) (xy 299.352149 -244.996059) (xy 299.336439 -245.046989) (xy 299.313313 -245.09501)
			(xy 299.283289 -245.139047) (xy 299.247037 -245.178118) (xy 299.205366 -245.211349) (xy 299.159208 -245.237998)
			(xy 299.109594 -245.25747) (xy 299.057632 -245.26933) (xy 299.004482 -245.273314) (xy 298.951332 -245.26933)
			(xy 298.89937 -245.25747) (xy 298.849756 -245.237998) (xy 298.803598 -245.211349) (xy 298.761927 -245.178118)
			(xy 298.725675 -245.139047) (xy 298.695651 -245.09501) (xy 298.672525 -245.046989) (xy 298.656815 -244.996059)
			(xy 298.648872 -244.943355) (xy 291.816292 -244.943355) (xy 291.808349 -244.996059) (xy 291.792639 -245.046989)
			(xy 291.769513 -245.09501) (xy 291.739489 -245.139047) (xy 291.703237 -245.178118) (xy 291.661566 -245.211349)
			(xy 291.615408 -245.237998) (xy 291.565794 -245.25747) (xy 291.513832 -245.26933) (xy 291.460682 -245.273314)
			(xy 291.407532 -245.26933) (xy 291.35557 -245.25747) (xy 291.305956 -245.237998) (xy 291.259798 -245.211349)
			(xy 291.218127 -245.178118) (xy 291.181875 -245.139047) (xy 291.151851 -245.09501) (xy 291.128725 -245.046989)
			(xy 291.113015 -244.996059) (xy 291.105072 -244.943355) (xy 284.272492 -244.943355) (xy 284.264549 -244.996059)
			(xy 284.248839 -245.046989) (xy 284.225713 -245.09501) (xy 284.195689 -245.139047) (xy 284.159437 -245.178118)
			(xy 284.117766 -245.211349) (xy 284.071608 -245.237998) (xy 284.021994 -245.25747) (xy 283.970032 -245.26933)
			(xy 283.916882 -245.273314) (xy 283.863732 -245.26933) (xy 283.81177 -245.25747) (xy 283.762156 -245.237998)
			(xy 283.715998 -245.211349) (xy 283.674327 -245.178118) (xy 283.638075 -245.139047) (xy 283.608051 -245.09501)
			(xy 283.584925 -245.046989) (xy 283.569215 -244.996059) (xy 283.561272 -244.943355) (xy 276.728692 -244.943355)
			(xy 276.720749 -244.996059) (xy 276.705039 -245.046989) (xy 276.681913 -245.09501) (xy 276.651889 -245.139047)
			(xy 276.615637 -245.178118) (xy 276.573966 -245.211349) (xy 276.527808 -245.237998) (xy 276.478194 -245.25747)
			(xy 276.426232 -245.26933) (xy 276.373082 -245.273314) (xy 276.319932 -245.26933) (xy 276.26797 -245.25747)
			(xy 276.218356 -245.237998) (xy 276.172198 -245.211349) (xy 276.130527 -245.178118) (xy 276.094275 -245.139047)
			(xy 276.064251 -245.09501) (xy 276.041125 -245.046989) (xy 276.025415 -244.996059) (xy 276.017472 -244.943355)
			(xy 269.184892 -244.943355) (xy 269.176949 -244.996059) (xy 269.161239 -245.046989) (xy 269.138113 -245.09501)
			(xy 269.108089 -245.139047) (xy 269.071837 -245.178118) (xy 269.030166 -245.211349) (xy 268.984008 -245.237998)
			(xy 268.934394 -245.25747) (xy 268.882432 -245.26933) (xy 268.829282 -245.273314) (xy 268.776132 -245.26933)
			(xy 268.72417 -245.25747) (xy 268.674556 -245.237998) (xy 268.628398 -245.211349) (xy 268.586727 -245.178118)
			(xy 268.550475 -245.139047) (xy 268.520451 -245.09501) (xy 268.497325 -245.046989) (xy 268.481615 -244.996059)
			(xy 268.473672 -244.943355) (xy 261.641092 -244.943355) (xy 261.633149 -244.996059) (xy 261.617439 -245.046989)
			(xy 261.594313 -245.09501) (xy 261.564289 -245.139047) (xy 261.528037 -245.178118) (xy 261.486366 -245.211349)
			(xy 261.440208 -245.237998) (xy 261.390594 -245.25747) (xy 261.338632 -245.26933) (xy 261.285482 -245.273314)
			(xy 261.232332 -245.26933) (xy 261.18037 -245.25747) (xy 261.130756 -245.237998) (xy 261.084598 -245.211349)
			(xy 261.042927 -245.178118) (xy 261.006675 -245.139047) (xy 260.976651 -245.09501) (xy 260.953525 -245.046989)
			(xy 260.937815 -244.996059) (xy 260.929872 -244.943355) (xy 254 -244.943355) (xy 254 -245.793239)
			(xy 256.829804 -245.793239) (xy 256.829804 -245.739941) (xy 256.837747 -245.687237) (xy 256.853457 -245.636307)
			(xy 256.876583 -245.588286) (xy 256.906607 -245.544249) (xy 256.942859 -245.505178) (xy 256.98453 -245.471947)
			(xy 257.030688 -245.445298) (xy 257.080302 -245.425826) (xy 257.132264 -245.413966) (xy 257.185414 -245.409983)
			(xy 257.238564 -245.413966) (xy 257.290526 -245.425826) (xy 257.34014 -245.445298) (xy 257.386298 -245.471947)
			(xy 257.427969 -245.505178) (xy 257.464221 -245.544249) (xy 257.494245 -245.588286) (xy 257.517371 -245.636307)
			(xy 257.533081 -245.687237) (xy 257.541024 -245.739941) (xy 257.541522 -245.76659) (xy 257.541024 -245.793239)
			(xy 264.373604 -245.793239) (xy 264.373604 -245.739941) (xy 264.381547 -245.687237) (xy 264.397257 -245.636307)
			(xy 264.420383 -245.588286) (xy 264.450407 -245.544249) (xy 264.486659 -245.505178) (xy 264.52833 -245.471947)
			(xy 264.574488 -245.445298) (xy 264.624102 -245.425826) (xy 264.676064 -245.413966) (xy 264.729214 -245.409983)
			(xy 264.782364 -245.413966) (xy 264.834326 -245.425826) (xy 264.88394 -245.445298) (xy 264.930098 -245.471947)
			(xy 264.971769 -245.505178) (xy 265.008021 -245.544249) (xy 265.038045 -245.588286) (xy 265.061171 -245.636307)
			(xy 265.076881 -245.687237) (xy 265.084824 -245.739941) (xy 265.085322 -245.76659) (xy 265.084824 -245.793239)
			(xy 271.917404 -245.793239) (xy 271.917404 -245.739941) (xy 271.925347 -245.687237) (xy 271.941057 -245.636307)
			(xy 271.964183 -245.588286) (xy 271.994207 -245.544249) (xy 272.030459 -245.505178) (xy 272.07213 -245.471947)
			(xy 272.118288 -245.445298) (xy 272.167902 -245.425826) (xy 272.219864 -245.413966) (xy 272.273014 -245.409983)
			(xy 272.326164 -245.413966) (xy 272.378126 -245.425826) (xy 272.42774 -245.445298) (xy 272.473898 -245.471947)
			(xy 272.515569 -245.505178) (xy 272.551821 -245.544249) (xy 272.581845 -245.588286) (xy 272.604971 -245.636307)
			(xy 272.620681 -245.687237) (xy 272.628624 -245.739941) (xy 272.629122 -245.76659) (xy 272.628624 -245.793239)
			(xy 279.461204 -245.793239) (xy 279.461204 -245.739941) (xy 279.469147 -245.687237) (xy 279.484857 -245.636307)
			(xy 279.507983 -245.588286) (xy 279.538007 -245.544249) (xy 279.574259 -245.505178) (xy 279.61593 -245.471947)
			(xy 279.662088 -245.445298) (xy 279.711702 -245.425826) (xy 279.763664 -245.413966) (xy 279.816814 -245.409983)
			(xy 279.869964 -245.413966) (xy 279.921926 -245.425826) (xy 279.97154 -245.445298) (xy 280.017698 -245.471947)
			(xy 280.059369 -245.505178) (xy 280.095621 -245.544249) (xy 280.125645 -245.588286) (xy 280.148771 -245.636307)
			(xy 280.164481 -245.687237) (xy 280.172424 -245.739941) (xy 280.172922 -245.76659) (xy 280.172424 -245.793239)
			(xy 287.005004 -245.793239) (xy 287.005004 -245.739941) (xy 287.012947 -245.687237) (xy 287.028657 -245.636307)
			(xy 287.051783 -245.588286) (xy 287.081807 -245.544249) (xy 287.118059 -245.505178) (xy 287.15973 -245.471947)
			(xy 287.205888 -245.445298) (xy 287.255502 -245.425826) (xy 287.307464 -245.413966) (xy 287.360614 -245.409983)
			(xy 287.413764 -245.413966) (xy 287.465726 -245.425826) (xy 287.51534 -245.445298) (xy 287.561498 -245.471947)
			(xy 287.603169 -245.505178) (xy 287.639421 -245.544249) (xy 287.669445 -245.588286) (xy 287.692571 -245.636307)
			(xy 287.708281 -245.687237) (xy 287.716224 -245.739941) (xy 287.716722 -245.76659) (xy 287.716224 -245.793239)
			(xy 294.548804 -245.793239) (xy 294.548804 -245.739941) (xy 294.556747 -245.687237) (xy 294.572457 -245.636307)
			(xy 294.595583 -245.588286) (xy 294.625607 -245.544249) (xy 294.661859 -245.505178) (xy 294.70353 -245.471947)
			(xy 294.749688 -245.445298) (xy 294.799302 -245.425826) (xy 294.851264 -245.413966) (xy 294.904414 -245.409983)
			(xy 294.957564 -245.413966) (xy 295.009526 -245.425826) (xy 295.05914 -245.445298) (xy 295.105298 -245.471947)
			(xy 295.146969 -245.505178) (xy 295.183221 -245.544249) (xy 295.213245 -245.588286) (xy 295.236371 -245.636307)
			(xy 295.252081 -245.687237) (xy 295.260024 -245.739941) (xy 295.260522 -245.76659) (xy 295.260024 -245.793239)
			(xy 295.252081 -245.845943) (xy 295.236371 -245.896873) (xy 295.213245 -245.944894) (xy 295.183221 -245.988931)
			(xy 295.146969 -246.028002) (xy 295.105298 -246.061233) (xy 295.05914 -246.087882) (xy 295.009526 -246.107354)
			(xy 294.957564 -246.119214) (xy 294.904414 -246.123198) (xy 294.851264 -246.119214) (xy 294.799302 -246.107354)
			(xy 294.749688 -246.087882) (xy 294.70353 -246.061233) (xy 294.661859 -246.028002) (xy 294.625607 -245.988931)
			(xy 294.595583 -245.944894) (xy 294.572457 -245.896873) (xy 294.556747 -245.845943) (xy 294.548804 -245.793239)
			(xy 287.716224 -245.793239) (xy 287.708281 -245.845943) (xy 287.692571 -245.896873) (xy 287.669445 -245.944894)
			(xy 287.639421 -245.988931) (xy 287.603169 -246.028002) (xy 287.561498 -246.061233) (xy 287.51534 -246.087882)
			(xy 287.465726 -246.107354) (xy 287.413764 -246.119214) (xy 287.360614 -246.123198) (xy 287.307464 -246.119214)
			(xy 287.255502 -246.107354) (xy 287.205888 -246.087882) (xy 287.15973 -246.061233) (xy 287.118059 -246.028002)
			(xy 287.081807 -245.988931) (xy 287.051783 -245.944894) (xy 287.028657 -245.896873) (xy 287.012947 -245.845943)
			(xy 287.005004 -245.793239) (xy 280.172424 -245.793239) (xy 280.164481 -245.845943) (xy 280.148771 -245.896873)
			(xy 280.125645 -245.944894) (xy 280.095621 -245.988931) (xy 280.059369 -246.028002) (xy 280.017698 -246.061233)
			(xy 279.97154 -246.087882) (xy 279.921926 -246.107354) (xy 279.869964 -246.119214) (xy 279.816814 -246.123198)
			(xy 279.763664 -246.119214) (xy 279.711702 -246.107354) (xy 279.662088 -246.087882) (xy 279.61593 -246.061233)
			(xy 279.574259 -246.028002) (xy 279.538007 -245.988931) (xy 279.507983 -245.944894) (xy 279.484857 -245.896873)
			(xy 279.469147 -245.845943) (xy 279.461204 -245.793239) (xy 272.628624 -245.793239) (xy 272.620681 -245.845943)
			(xy 272.604971 -245.896873) (xy 272.581845 -245.944894) (xy 272.551821 -245.988931) (xy 272.515569 -246.028002)
			(xy 272.473898 -246.061233) (xy 272.42774 -246.087882) (xy 272.378126 -246.107354) (xy 272.326164 -246.119214)
			(xy 272.273014 -246.123198) (xy 272.219864 -246.119214) (xy 272.167902 -246.107354) (xy 272.118288 -246.087882)
			(xy 272.07213 -246.061233) (xy 272.030459 -246.028002) (xy 271.994207 -245.988931) (xy 271.964183 -245.944894)
			(xy 271.941057 -245.896873) (xy 271.925347 -245.845943) (xy 271.917404 -245.793239) (xy 265.084824 -245.793239)
			(xy 265.076881 -245.845943) (xy 265.061171 -245.896873) (xy 265.038045 -245.944894) (xy 265.008021 -245.988931)
			(xy 264.971769 -246.028002) (xy 264.930098 -246.061233) (xy 264.88394 -246.087882) (xy 264.834326 -246.107354)
			(xy 264.782364 -246.119214) (xy 264.729214 -246.123198) (xy 264.676064 -246.119214) (xy 264.624102 -246.107354)
			(xy 264.574488 -246.087882) (xy 264.52833 -246.061233) (xy 264.486659 -246.028002) (xy 264.450407 -245.988931)
			(xy 264.420383 -245.944894) (xy 264.397257 -245.896873) (xy 264.381547 -245.845943) (xy 264.373604 -245.793239)
			(xy 257.541024 -245.793239) (xy 257.533081 -245.845943) (xy 257.517371 -245.896873) (xy 257.494245 -245.944894)
			(xy 257.464221 -245.988931) (xy 257.427969 -246.028002) (xy 257.386298 -246.061233) (xy 257.34014 -246.087882)
			(xy 257.290526 -246.107354) (xy 257.238564 -246.119214) (xy 257.185414 -246.123198) (xy 257.132264 -246.119214)
			(xy 257.080302 -246.107354) (xy 257.030688 -246.087882) (xy 256.98453 -246.061233) (xy 256.942859 -246.028002)
			(xy 256.906607 -245.988931) (xy 256.876583 -245.944894) (xy 256.853457 -245.896873) (xy 256.837747 -245.845943)
			(xy 256.829804 -245.793239) (xy 254 -245.793239) (xy 254 -246.643377) (xy 268.473672 -246.643377)
			(xy 268.473672 -246.590079) (xy 268.481615 -246.537375) (xy 268.497325 -246.486445) (xy 268.520451 -246.438424)
			(xy 268.550475 -246.394387) (xy 268.586727 -246.355316) (xy 268.628398 -246.322085) (xy 268.674556 -246.295436)
			(xy 268.72417 -246.275964) (xy 268.776132 -246.264104) (xy 268.829282 -246.260121) (xy 268.882432 -246.264104)
			(xy 268.934394 -246.275964) (xy 268.984008 -246.295436) (xy 269.030166 -246.322085) (xy 269.071837 -246.355316)
			(xy 269.108089 -246.394387) (xy 269.138113 -246.438424) (xy 269.161239 -246.486445) (xy 269.176949 -246.537375)
			(xy 269.184892 -246.590079) (xy 269.18539 -246.616728) (xy 269.184892 -246.643377) (xy 283.561272 -246.643377)
			(xy 283.561272 -246.590079) (xy 283.569215 -246.537375) (xy 283.584925 -246.486445) (xy 283.608051 -246.438424)
			(xy 283.638075 -246.394387) (xy 283.674327 -246.355316) (xy 283.715998 -246.322085) (xy 283.762156 -246.295436)
			(xy 283.81177 -246.275964) (xy 283.863732 -246.264104) (xy 283.916882 -246.260121) (xy 283.970032 -246.264104)
			(xy 284.021994 -246.275964) (xy 284.071608 -246.295436) (xy 284.117766 -246.322085) (xy 284.159437 -246.355316)
			(xy 284.195689 -246.394387) (xy 284.225713 -246.438424) (xy 284.248839 -246.486445) (xy 284.264549 -246.537375)
			(xy 284.272492 -246.590079) (xy 284.27299 -246.616728) (xy 284.272492 -246.643377) (xy 298.648872 -246.643377)
			(xy 298.648872 -246.590079) (xy 298.656815 -246.537375) (xy 298.672525 -246.486445) (xy 298.695651 -246.438424)
			(xy 298.725675 -246.394387) (xy 298.761927 -246.355316) (xy 298.803598 -246.322085) (xy 298.849756 -246.295436)
			(xy 298.89937 -246.275964) (xy 298.951332 -246.264104) (xy 299.004482 -246.260121) (xy 299.057632 -246.264104)
			(xy 299.109594 -246.275964) (xy 299.159208 -246.295436) (xy 299.205366 -246.322085) (xy 299.247037 -246.355316)
			(xy 299.283289 -246.394387) (xy 299.313313 -246.438424) (xy 299.336439 -246.486445) (xy 299.352149 -246.537375)
			(xy 299.360092 -246.590079) (xy 299.36059 -246.616728) (xy 299.360092 -246.643377) (xy 299.352149 -246.696081)
			(xy 299.336439 -246.747011) (xy 299.313313 -246.795032) (xy 299.283289 -246.839069) (xy 299.247037 -246.87814)
			(xy 299.205366 -246.911371) (xy 299.159208 -246.93802) (xy 299.109594 -246.957492) (xy 299.057632 -246.969352)
			(xy 299.004482 -246.973336) (xy 298.951332 -246.969352) (xy 298.89937 -246.957492) (xy 298.849756 -246.93802)
			(xy 298.803598 -246.911371) (xy 298.761927 -246.87814) (xy 298.725675 -246.839069) (xy 298.695651 -246.795032)
			(xy 298.672525 -246.747011) (xy 298.656815 -246.696081) (xy 298.648872 -246.643377) (xy 284.272492 -246.643377)
			(xy 284.264549 -246.696081) (xy 284.248839 -246.747011) (xy 284.225713 -246.795032) (xy 284.195689 -246.839069)
			(xy 284.159437 -246.87814) (xy 284.117766 -246.911371) (xy 284.071608 -246.93802) (xy 284.021994 -246.957492)
			(xy 283.970032 -246.969352) (xy 283.916882 -246.973336) (xy 283.863732 -246.969352) (xy 283.81177 -246.957492)
			(xy 283.762156 -246.93802) (xy 283.715998 -246.911371) (xy 283.674327 -246.87814) (xy 283.638075 -246.839069)
			(xy 283.608051 -246.795032) (xy 283.584925 -246.747011) (xy 283.569215 -246.696081) (xy 283.561272 -246.643377)
			(xy 269.184892 -246.643377) (xy 269.176949 -246.696081) (xy 269.161239 -246.747011) (xy 269.138113 -246.795032)
			(xy 269.108089 -246.839069) (xy 269.071837 -246.87814) (xy 269.030166 -246.911371) (xy 268.984008 -246.93802)
			(xy 268.934394 -246.957492) (xy 268.882432 -246.969352) (xy 268.829282 -246.973336) (xy 268.776132 -246.969352)
			(xy 268.72417 -246.957492) (xy 268.674556 -246.93802) (xy 268.628398 -246.911371) (xy 268.586727 -246.87814)
			(xy 268.550475 -246.839069) (xy 268.520451 -246.795032) (xy 268.497325 -246.747011) (xy 268.481615 -246.696081)
			(xy 268.473672 -246.643377) (xy 254 -246.643377) (xy 254 -247.493261) (xy 264.373604 -247.493261)
			(xy 264.373604 -247.439963) (xy 264.381547 -247.387259) (xy 264.397257 -247.336329) (xy 264.420383 -247.288308)
			(xy 264.450407 -247.244271) (xy 264.486659 -247.2052) (xy 264.52833 -247.171969) (xy 264.574488 -247.14532)
			(xy 264.624102 -247.125848) (xy 264.676064 -247.113988) (xy 264.729214 -247.110005) (xy 264.782364 -247.113988)
			(xy 264.834326 -247.125848) (xy 264.88394 -247.14532) (xy 264.930098 -247.171969) (xy 264.971769 -247.2052)
			(xy 265.008021 -247.244271) (xy 265.038045 -247.288308) (xy 265.061171 -247.336329) (xy 265.076881 -247.387259)
			(xy 265.084824 -247.439963) (xy 265.085322 -247.466612) (xy 265.084824 -247.493261) (xy 279.461204 -247.493261)
			(xy 279.461204 -247.439963) (xy 279.469147 -247.387259) (xy 279.484857 -247.336329) (xy 279.507983 -247.288308)
			(xy 279.538007 -247.244271) (xy 279.574259 -247.2052) (xy 279.61593 -247.171969) (xy 279.662088 -247.14532)
			(xy 279.711702 -247.125848) (xy 279.763664 -247.113988) (xy 279.816814 -247.110005) (xy 279.869964 -247.113988)
			(xy 279.921926 -247.125848) (xy 279.97154 -247.14532) (xy 280.017698 -247.171969) (xy 280.059369 -247.2052)
			(xy 280.095621 -247.244271) (xy 280.125645 -247.288308) (xy 280.148771 -247.336329) (xy 280.164481 -247.387259)
			(xy 280.172424 -247.439963) (xy 280.172922 -247.466612) (xy 280.172424 -247.493261) (xy 294.548804 -247.493261)
			(xy 294.548804 -247.439963) (xy 294.556747 -247.387259) (xy 294.572457 -247.336329) (xy 294.595583 -247.288308)
			(xy 294.625607 -247.244271) (xy 294.661859 -247.2052) (xy 294.70353 -247.171969) (xy 294.749688 -247.14532)
			(xy 294.799302 -247.125848) (xy 294.851264 -247.113988) (xy 294.904414 -247.110005) (xy 294.957564 -247.113988)
			(xy 295.009526 -247.125848) (xy 295.05914 -247.14532) (xy 295.105298 -247.171969) (xy 295.146969 -247.2052)
			(xy 295.183221 -247.244271) (xy 295.213245 -247.288308) (xy 295.236371 -247.336329) (xy 295.252081 -247.387259)
			(xy 295.260024 -247.439963) (xy 295.260522 -247.466612) (xy 295.260024 -247.493261) (xy 295.252081 -247.545965)
			(xy 295.236371 -247.596895) (xy 295.213245 -247.644916) (xy 295.183221 -247.688953) (xy 295.146969 -247.728024)
			(xy 295.105298 -247.761255) (xy 295.05914 -247.787904) (xy 295.009526 -247.807376) (xy 294.957564 -247.819236)
			(xy 294.904414 -247.82322) (xy 294.851264 -247.819236) (xy 294.799302 -247.807376) (xy 294.749688 -247.787904)
			(xy 294.70353 -247.761255) (xy 294.661859 -247.728024) (xy 294.625607 -247.688953) (xy 294.595583 -247.644916)
			(xy 294.572457 -247.596895) (xy 294.556747 -247.545965) (xy 294.548804 -247.493261) (xy 280.172424 -247.493261)
			(xy 280.164481 -247.545965) (xy 280.148771 -247.596895) (xy 280.125645 -247.644916) (xy 280.095621 -247.688953)
			(xy 280.059369 -247.728024) (xy 280.017698 -247.761255) (xy 279.97154 -247.787904) (xy 279.921926 -247.807376)
			(xy 279.869964 -247.819236) (xy 279.816814 -247.82322) (xy 279.763664 -247.819236) (xy 279.711702 -247.807376)
			(xy 279.662088 -247.787904) (xy 279.61593 -247.761255) (xy 279.574259 -247.728024) (xy 279.538007 -247.688953)
			(xy 279.507983 -247.644916) (xy 279.484857 -247.596895) (xy 279.469147 -247.545965) (xy 279.461204 -247.493261)
			(xy 265.084824 -247.493261) (xy 265.076881 -247.545965) (xy 265.061171 -247.596895) (xy 265.038045 -247.644916)
			(xy 265.008021 -247.688953) (xy 264.971769 -247.728024) (xy 264.930098 -247.761255) (xy 264.88394 -247.787904)
			(xy 264.834326 -247.807376) (xy 264.782364 -247.819236) (xy 264.729214 -247.82322) (xy 264.676064 -247.819236)
			(xy 264.624102 -247.807376) (xy 264.574488 -247.787904) (xy 264.52833 -247.761255) (xy 264.486659 -247.728024)
			(xy 264.450407 -247.688953) (xy 264.420383 -247.644916) (xy 264.397257 -247.596895) (xy 264.381547 -247.545965)
			(xy 264.373604 -247.493261) (xy 254 -247.493261) (xy 254 -248.343399) (xy 268.473672 -248.343399)
			(xy 268.473672 -248.290101) (xy 268.481615 -248.237397) (xy 268.497325 -248.186467) (xy 268.520451 -248.138446)
			(xy 268.550475 -248.094409) (xy 268.586727 -248.055338) (xy 268.628398 -248.022107) (xy 268.674556 -247.995458)
			(xy 268.72417 -247.975986) (xy 268.776132 -247.964126) (xy 268.829282 -247.960143) (xy 268.882432 -247.964126)
			(xy 268.934394 -247.975986) (xy 268.984008 -247.995458) (xy 269.030166 -248.022107) (xy 269.071837 -248.055338)
			(xy 269.108089 -248.094409) (xy 269.138113 -248.138446) (xy 269.161239 -248.186467) (xy 269.176949 -248.237397)
			(xy 269.184892 -248.290101) (xy 269.18539 -248.31675) (xy 269.184892 -248.343399) (xy 283.561272 -248.343399)
			(xy 283.561272 -248.290101) (xy 283.569215 -248.237397) (xy 283.584925 -248.186467) (xy 283.608051 -248.138446)
			(xy 283.638075 -248.094409) (xy 283.674327 -248.055338) (xy 283.715998 -248.022107) (xy 283.762156 -247.995458)
			(xy 283.81177 -247.975986) (xy 283.863732 -247.964126) (xy 283.916882 -247.960143) (xy 283.970032 -247.964126)
			(xy 284.021994 -247.975986) (xy 284.071608 -247.995458) (xy 284.117766 -248.022107) (xy 284.159437 -248.055338)
			(xy 284.195689 -248.094409) (xy 284.225713 -248.138446) (xy 284.248839 -248.186467) (xy 284.264549 -248.237397)
			(xy 284.272492 -248.290101) (xy 284.27299 -248.31675) (xy 284.272492 -248.343399) (xy 298.648872 -248.343399)
			(xy 298.648872 -248.290101) (xy 298.656815 -248.237397) (xy 298.672525 -248.186467) (xy 298.695651 -248.138446)
			(xy 298.725675 -248.094409) (xy 298.761927 -248.055338) (xy 298.803598 -248.022107) (xy 298.849756 -247.995458)
			(xy 298.89937 -247.975986) (xy 298.951332 -247.964126) (xy 299.004482 -247.960143) (xy 299.057632 -247.964126)
			(xy 299.109594 -247.975986) (xy 299.159208 -247.995458) (xy 299.205366 -248.022107) (xy 299.247037 -248.055338)
			(xy 299.283289 -248.094409) (xy 299.313313 -248.138446) (xy 299.336439 -248.186467) (xy 299.352149 -248.237397)
			(xy 299.360092 -248.290101) (xy 299.36059 -248.31675) (xy 299.360092 -248.343399) (xy 299.352149 -248.396103)
			(xy 299.336439 -248.447033) (xy 299.313313 -248.495054) (xy 299.283289 -248.539091) (xy 299.247037 -248.578162)
			(xy 299.205366 -248.611393) (xy 299.159208 -248.638042) (xy 299.109594 -248.657514) (xy 299.057632 -248.669374)
			(xy 299.004482 -248.673358) (xy 298.951332 -248.669374) (xy 298.89937 -248.657514) (xy 298.849756 -248.638042)
			(xy 298.803598 -248.611393) (xy 298.761927 -248.578162) (xy 298.725675 -248.539091) (xy 298.695651 -248.495054)
			(xy 298.672525 -248.447033) (xy 298.656815 -248.396103) (xy 298.648872 -248.343399) (xy 284.272492 -248.343399)
			(xy 284.264549 -248.396103) (xy 284.248839 -248.447033) (xy 284.225713 -248.495054) (xy 284.195689 -248.539091)
			(xy 284.159437 -248.578162) (xy 284.117766 -248.611393) (xy 284.071608 -248.638042) (xy 284.021994 -248.657514)
			(xy 283.970032 -248.669374) (xy 283.916882 -248.673358) (xy 283.863732 -248.669374) (xy 283.81177 -248.657514)
			(xy 283.762156 -248.638042) (xy 283.715998 -248.611393) (xy 283.674327 -248.578162) (xy 283.638075 -248.539091)
			(xy 283.608051 -248.495054) (xy 283.584925 -248.447033) (xy 283.569215 -248.396103) (xy 283.561272 -248.343399)
			(xy 269.184892 -248.343399) (xy 269.176949 -248.396103) (xy 269.161239 -248.447033) (xy 269.138113 -248.495054)
			(xy 269.108089 -248.539091) (xy 269.071837 -248.578162) (xy 269.030166 -248.611393) (xy 268.984008 -248.638042)
			(xy 268.934394 -248.657514) (xy 268.882432 -248.669374) (xy 268.829282 -248.673358) (xy 268.776132 -248.669374)
			(xy 268.72417 -248.657514) (xy 268.674556 -248.638042) (xy 268.628398 -248.611393) (xy 268.586727 -248.578162)
			(xy 268.550475 -248.539091) (xy 268.520451 -248.495054) (xy 268.497325 -248.447033) (xy 268.481615 -248.396103)
			(xy 268.473672 -248.343399) (xy 254 -248.343399) (xy 254 -249.193283) (xy 264.373604 -249.193283)
			(xy 264.373604 -249.139985) (xy 264.381547 -249.087281) (xy 264.397257 -249.036351) (xy 264.420383 -248.98833)
			(xy 264.450407 -248.944293) (xy 264.486659 -248.905222) (xy 264.52833 -248.871991) (xy 264.574488 -248.845342)
			(xy 264.624102 -248.82587) (xy 264.676064 -248.81401) (xy 264.729214 -248.810027) (xy 264.782364 -248.81401)
			(xy 264.834326 -248.82587) (xy 264.88394 -248.845342) (xy 264.930098 -248.871991) (xy 264.971769 -248.905222)
			(xy 265.008021 -248.944293) (xy 265.038045 -248.98833) (xy 265.061171 -249.036351) (xy 265.076881 -249.087281)
			(xy 265.084824 -249.139985) (xy 265.085322 -249.166634) (xy 265.084824 -249.193283) (xy 279.461204 -249.193283)
			(xy 279.461204 -249.139985) (xy 279.469147 -249.087281) (xy 279.484857 -249.036351) (xy 279.507983 -248.98833)
			(xy 279.538007 -248.944293) (xy 279.574259 -248.905222) (xy 279.61593 -248.871991) (xy 279.662088 -248.845342)
			(xy 279.711702 -248.82587) (xy 279.763664 -248.81401) (xy 279.816814 -248.810027) (xy 279.869964 -248.81401)
			(xy 279.921926 -248.82587) (xy 279.97154 -248.845342) (xy 280.017698 -248.871991) (xy 280.059369 -248.905222)
			(xy 280.095621 -248.944293) (xy 280.125645 -248.98833) (xy 280.148771 -249.036351) (xy 280.164481 -249.087281)
			(xy 280.172424 -249.139985) (xy 280.172922 -249.166634) (xy 280.172424 -249.193283) (xy 294.548804 -249.193283)
			(xy 294.548804 -249.139985) (xy 294.556747 -249.087281) (xy 294.572457 -249.036351) (xy 294.595583 -248.98833)
			(xy 294.625607 -248.944293) (xy 294.661859 -248.905222) (xy 294.70353 -248.871991) (xy 294.749688 -248.845342)
			(xy 294.799302 -248.82587) (xy 294.851264 -248.81401) (xy 294.904414 -248.810027) (xy 294.957564 -248.81401)
			(xy 295.009526 -248.82587) (xy 295.05914 -248.845342) (xy 295.105298 -248.871991) (xy 295.146969 -248.905222)
			(xy 295.183221 -248.944293) (xy 295.213245 -248.98833) (xy 295.236371 -249.036351) (xy 295.252081 -249.087281)
			(xy 295.260024 -249.139985) (xy 295.260522 -249.166634) (xy 295.260024 -249.193283) (xy 295.252081 -249.245987)
			(xy 295.236371 -249.296917) (xy 295.213245 -249.344938) (xy 295.183221 -249.388975) (xy 295.146969 -249.428046)
			(xy 295.105298 -249.461277) (xy 295.05914 -249.487926) (xy 295.009526 -249.507398) (xy 294.957564 -249.519258)
			(xy 294.904414 -249.523242) (xy 294.851264 -249.519258) (xy 294.799302 -249.507398) (xy 294.749688 -249.487926)
			(xy 294.70353 -249.461277) (xy 294.661859 -249.428046) (xy 294.625607 -249.388975) (xy 294.595583 -249.344938)
			(xy 294.572457 -249.296917) (xy 294.556747 -249.245987) (xy 294.548804 -249.193283) (xy 280.172424 -249.193283)
			(xy 280.164481 -249.245987) (xy 280.148771 -249.296917) (xy 280.125645 -249.344938) (xy 280.095621 -249.388975)
			(xy 280.059369 -249.428046) (xy 280.017698 -249.461277) (xy 279.97154 -249.487926) (xy 279.921926 -249.507398)
			(xy 279.869964 -249.519258) (xy 279.816814 -249.523242) (xy 279.763664 -249.519258) (xy 279.711702 -249.507398)
			(xy 279.662088 -249.487926) (xy 279.61593 -249.461277) (xy 279.574259 -249.428046) (xy 279.538007 -249.388975)
			(xy 279.507983 -249.344938) (xy 279.484857 -249.296917) (xy 279.469147 -249.245987) (xy 279.461204 -249.193283)
			(xy 265.084824 -249.193283) (xy 265.076881 -249.245987) (xy 265.061171 -249.296917) (xy 265.038045 -249.344938)
			(xy 265.008021 -249.388975) (xy 264.971769 -249.428046) (xy 264.930098 -249.461277) (xy 264.88394 -249.487926)
			(xy 264.834326 -249.507398) (xy 264.782364 -249.519258) (xy 264.729214 -249.523242) (xy 264.676064 -249.519258)
			(xy 264.624102 -249.507398) (xy 264.574488 -249.487926) (xy 264.52833 -249.461277) (xy 264.486659 -249.428046)
			(xy 264.450407 -249.388975) (xy 264.420383 -249.344938) (xy 264.397257 -249.296917) (xy 264.381547 -249.245987)
			(xy 264.373604 -249.193283) (xy 254 -249.193283) (xy 254 -250.043421) (xy 268.473672 -250.043421)
			(xy 268.473672 -249.990123) (xy 268.481615 -249.937419) (xy 268.497325 -249.886489) (xy 268.520451 -249.838468)
			(xy 268.550475 -249.794431) (xy 268.586727 -249.75536) (xy 268.628398 -249.722129) (xy 268.674556 -249.69548)
			(xy 268.72417 -249.676008) (xy 268.776132 -249.664148) (xy 268.829282 -249.660165) (xy 268.882432 -249.664148)
			(xy 268.934394 -249.676008) (xy 268.984008 -249.69548) (xy 269.030166 -249.722129) (xy 269.071837 -249.75536)
			(xy 269.108089 -249.794431) (xy 269.138113 -249.838468) (xy 269.161239 -249.886489) (xy 269.176949 -249.937419)
			(xy 269.184892 -249.990123) (xy 269.18539 -250.016772) (xy 269.184892 -250.043421) (xy 283.561272 -250.043421)
			(xy 283.561272 -249.990123) (xy 283.569215 -249.937419) (xy 283.584925 -249.886489) (xy 283.608051 -249.838468)
			(xy 283.638075 -249.794431) (xy 283.674327 -249.75536) (xy 283.715998 -249.722129) (xy 283.762156 -249.69548)
			(xy 283.81177 -249.676008) (xy 283.863732 -249.664148) (xy 283.916882 -249.660165) (xy 283.970032 -249.664148)
			(xy 284.021994 -249.676008) (xy 284.071608 -249.69548) (xy 284.117766 -249.722129) (xy 284.159437 -249.75536)
			(xy 284.195689 -249.794431) (xy 284.225713 -249.838468) (xy 284.248839 -249.886489) (xy 284.264549 -249.937419)
			(xy 284.272492 -249.990123) (xy 284.27299 -250.016772) (xy 284.272492 -250.043421) (xy 298.648872 -250.043421)
			(xy 298.648872 -249.990123) (xy 298.656815 -249.937419) (xy 298.672525 -249.886489) (xy 298.695651 -249.838468)
			(xy 298.725675 -249.794431) (xy 298.761927 -249.75536) (xy 298.803598 -249.722129) (xy 298.849756 -249.69548)
			(xy 298.89937 -249.676008) (xy 298.951332 -249.664148) (xy 299.004482 -249.660165) (xy 299.057632 -249.664148)
			(xy 299.109594 -249.676008) (xy 299.159208 -249.69548) (xy 299.205366 -249.722129) (xy 299.247037 -249.75536)
			(xy 299.283289 -249.794431) (xy 299.313313 -249.838468) (xy 299.336439 -249.886489) (xy 299.352149 -249.937419)
			(xy 299.360092 -249.990123) (xy 299.36059 -250.016772) (xy 299.360092 -250.043421) (xy 299.352149 -250.096125)
			(xy 299.336439 -250.147055) (xy 299.313313 -250.195076) (xy 299.283289 -250.239113) (xy 299.247037 -250.278184)
			(xy 299.205366 -250.311415) (xy 299.159208 -250.338064) (xy 299.109594 -250.357536) (xy 299.057632 -250.369396)
			(xy 299.004482 -250.37338) (xy 298.951332 -250.369396) (xy 298.89937 -250.357536) (xy 298.849756 -250.338064)
			(xy 298.803598 -250.311415) (xy 298.761927 -250.278184) (xy 298.725675 -250.239113) (xy 298.695651 -250.195076)
			(xy 298.672525 -250.147055) (xy 298.656815 -250.096125) (xy 298.648872 -250.043421) (xy 284.272492 -250.043421)
			(xy 284.264549 -250.096125) (xy 284.248839 -250.147055) (xy 284.225713 -250.195076) (xy 284.195689 -250.239113)
			(xy 284.159437 -250.278184) (xy 284.117766 -250.311415) (xy 284.071608 -250.338064) (xy 284.021994 -250.357536)
			(xy 283.970032 -250.369396) (xy 283.916882 -250.37338) (xy 283.863732 -250.369396) (xy 283.81177 -250.357536)
			(xy 283.762156 -250.338064) (xy 283.715998 -250.311415) (xy 283.674327 -250.278184) (xy 283.638075 -250.239113)
			(xy 283.608051 -250.195076) (xy 283.584925 -250.147055) (xy 283.569215 -250.096125) (xy 283.561272 -250.043421)
			(xy 269.184892 -250.043421) (xy 269.176949 -250.096125) (xy 269.161239 -250.147055) (xy 269.138113 -250.195076)
			(xy 269.108089 -250.239113) (xy 269.071837 -250.278184) (xy 269.030166 -250.311415) (xy 268.984008 -250.338064)
			(xy 268.934394 -250.357536) (xy 268.882432 -250.369396) (xy 268.829282 -250.37338) (xy 268.776132 -250.369396)
			(xy 268.72417 -250.357536) (xy 268.674556 -250.338064) (xy 268.628398 -250.311415) (xy 268.586727 -250.278184)
			(xy 268.550475 -250.239113) (xy 268.520451 -250.195076) (xy 268.497325 -250.147055) (xy 268.481615 -250.096125)
			(xy 268.473672 -250.043421) (xy 254 -250.043421) (xy 254 -250.893305) (xy 264.373604 -250.893305)
			(xy 264.373604 -250.840007) (xy 264.381547 -250.787303) (xy 264.397257 -250.736373) (xy 264.420383 -250.688352)
			(xy 264.450407 -250.644315) (xy 264.486659 -250.605244) (xy 264.52833 -250.572013) (xy 264.574488 -250.545364)
			(xy 264.624102 -250.525892) (xy 264.676064 -250.514032) (xy 264.729214 -250.510049) (xy 264.782364 -250.514032)
			(xy 264.834326 -250.525892) (xy 264.88394 -250.545364) (xy 264.930098 -250.572013) (xy 264.971769 -250.605244)
			(xy 265.008021 -250.644315) (xy 265.038045 -250.688352) (xy 265.061171 -250.736373) (xy 265.076881 -250.787303)
			(xy 265.084824 -250.840007) (xy 265.085322 -250.866656) (xy 265.084824 -250.893305) (xy 279.461204 -250.893305)
			(xy 279.461204 -250.840007) (xy 279.469147 -250.787303) (xy 279.484857 -250.736373) (xy 279.507983 -250.688352)
			(xy 279.538007 -250.644315) (xy 279.574259 -250.605244) (xy 279.61593 -250.572013) (xy 279.662088 -250.545364)
			(xy 279.711702 -250.525892) (xy 279.763664 -250.514032) (xy 279.816814 -250.510049) (xy 279.869964 -250.514032)
			(xy 279.921926 -250.525892) (xy 279.97154 -250.545364) (xy 280.017698 -250.572013) (xy 280.059369 -250.605244)
			(xy 280.095621 -250.644315) (xy 280.125645 -250.688352) (xy 280.148771 -250.736373) (xy 280.164481 -250.787303)
			(xy 280.172424 -250.840007) (xy 280.172922 -250.866656) (xy 280.172424 -250.893305) (xy 294.548804 -250.893305)
			(xy 294.548804 -250.840007) (xy 294.556747 -250.787303) (xy 294.572457 -250.736373) (xy 294.595583 -250.688352)
			(xy 294.625607 -250.644315) (xy 294.661859 -250.605244) (xy 294.70353 -250.572013) (xy 294.749688 -250.545364)
			(xy 294.799302 -250.525892) (xy 294.851264 -250.514032) (xy 294.904414 -250.510049) (xy 294.957564 -250.514032)
			(xy 295.009526 -250.525892) (xy 295.05914 -250.545364) (xy 295.105298 -250.572013) (xy 295.146969 -250.605244)
			(xy 295.183221 -250.644315) (xy 295.213245 -250.688352) (xy 295.236371 -250.736373) (xy 295.252081 -250.787303)
			(xy 295.260024 -250.840007) (xy 295.260522 -250.866656) (xy 295.260024 -250.893305) (xy 295.252081 -250.946009)
			(xy 295.236371 -250.996939) (xy 295.213245 -251.04496) (xy 295.183221 -251.088997) (xy 295.146969 -251.128068)
			(xy 295.105298 -251.161299) (xy 295.05914 -251.187948) (xy 295.009526 -251.20742) (xy 294.957564 -251.21928)
			(xy 294.904414 -251.223264) (xy 294.851264 -251.21928) (xy 294.799302 -251.20742) (xy 294.749688 -251.187948)
			(xy 294.70353 -251.161299) (xy 294.661859 -251.128068) (xy 294.625607 -251.088997) (xy 294.595583 -251.04496)
			(xy 294.572457 -250.996939) (xy 294.556747 -250.946009) (xy 294.548804 -250.893305) (xy 280.172424 -250.893305)
			(xy 280.164481 -250.946009) (xy 280.148771 -250.996939) (xy 280.125645 -251.04496) (xy 280.095621 -251.088997)
			(xy 280.059369 -251.128068) (xy 280.017698 -251.161299) (xy 279.97154 -251.187948) (xy 279.921926 -251.20742)
			(xy 279.869964 -251.21928) (xy 279.816814 -251.223264) (xy 279.763664 -251.21928) (xy 279.711702 -251.20742)
			(xy 279.662088 -251.187948) (xy 279.61593 -251.161299) (xy 279.574259 -251.128068) (xy 279.538007 -251.088997)
			(xy 279.507983 -251.04496) (xy 279.484857 -250.996939) (xy 279.469147 -250.946009) (xy 279.461204 -250.893305)
			(xy 265.084824 -250.893305) (xy 265.076881 -250.946009) (xy 265.061171 -250.996939) (xy 265.038045 -251.04496)
			(xy 265.008021 -251.088997) (xy 264.971769 -251.128068) (xy 264.930098 -251.161299) (xy 264.88394 -251.187948)
			(xy 264.834326 -251.20742) (xy 264.782364 -251.21928) (xy 264.729214 -251.223264) (xy 264.676064 -251.21928)
			(xy 264.624102 -251.20742) (xy 264.574488 -251.187948) (xy 264.52833 -251.161299) (xy 264.486659 -251.128068)
			(xy 264.450407 -251.088997) (xy 264.420383 -251.04496) (xy 264.397257 -250.996939) (xy 264.381547 -250.946009)
			(xy 264.373604 -250.893305) (xy 254 -250.893305) (xy 254 -251.743443) (xy 268.473672 -251.743443)
			(xy 268.473672 -251.690145) (xy 268.481615 -251.637441) (xy 268.497325 -251.586511) (xy 268.520451 -251.53849)
			(xy 268.550475 -251.494453) (xy 268.586727 -251.455382) (xy 268.628398 -251.422151) (xy 268.674556 -251.395502)
			(xy 268.72417 -251.37603) (xy 268.776132 -251.36417) (xy 268.829282 -251.360187) (xy 268.882432 -251.36417)
			(xy 268.934394 -251.37603) (xy 268.984008 -251.395502) (xy 269.030166 -251.422151) (xy 269.071837 -251.455382)
			(xy 269.108089 -251.494453) (xy 269.138113 -251.53849) (xy 269.161239 -251.586511) (xy 269.176949 -251.637441)
			(xy 269.184892 -251.690145) (xy 269.18539 -251.716794) (xy 269.184892 -251.743443) (xy 283.561272 -251.743443)
			(xy 283.561272 -251.690145) (xy 283.569215 -251.637441) (xy 283.584925 -251.586511) (xy 283.608051 -251.53849)
			(xy 283.638075 -251.494453) (xy 283.674327 -251.455382) (xy 283.715998 -251.422151) (xy 283.762156 -251.395502)
			(xy 283.81177 -251.37603) (xy 283.863732 -251.36417) (xy 283.916882 -251.360187) (xy 283.970032 -251.36417)
			(xy 284.021994 -251.37603) (xy 284.071608 -251.395502) (xy 284.117766 -251.422151) (xy 284.159437 -251.455382)
			(xy 284.195689 -251.494453) (xy 284.225713 -251.53849) (xy 284.248839 -251.586511) (xy 284.264549 -251.637441)
			(xy 284.272492 -251.690145) (xy 284.27299 -251.716794) (xy 284.272492 -251.743443) (xy 298.648872 -251.743443)
			(xy 298.648872 -251.690145) (xy 298.656815 -251.637441) (xy 298.672525 -251.586511) (xy 298.695651 -251.53849)
			(xy 298.725675 -251.494453) (xy 298.761927 -251.455382) (xy 298.803598 -251.422151) (xy 298.849756 -251.395502)
			(xy 298.89937 -251.37603) (xy 298.951332 -251.36417) (xy 299.004482 -251.360187) (xy 299.057632 -251.36417)
			(xy 299.109594 -251.37603) (xy 299.159208 -251.395502) (xy 299.205366 -251.422151) (xy 299.247037 -251.455382)
			(xy 299.283289 -251.494453) (xy 299.313313 -251.53849) (xy 299.336439 -251.586511) (xy 299.352149 -251.637441)
			(xy 299.360092 -251.690145) (xy 299.36059 -251.716794) (xy 299.360092 -251.743443) (xy 299.352149 -251.796147)
			(xy 299.336439 -251.847077) (xy 299.313313 -251.895098) (xy 299.283289 -251.939135) (xy 299.247037 -251.978206)
			(xy 299.205366 -252.011437) (xy 299.159208 -252.038086) (xy 299.109594 -252.057558) (xy 299.057632 -252.069418)
			(xy 299.004482 -252.073402) (xy 298.951332 -252.069418) (xy 298.89937 -252.057558) (xy 298.849756 -252.038086)
			(xy 298.803598 -252.011437) (xy 298.761927 -251.978206) (xy 298.725675 -251.939135) (xy 298.695651 -251.895098)
			(xy 298.672525 -251.847077) (xy 298.656815 -251.796147) (xy 298.648872 -251.743443) (xy 284.272492 -251.743443)
			(xy 284.264549 -251.796147) (xy 284.248839 -251.847077) (xy 284.225713 -251.895098) (xy 284.195689 -251.939135)
			(xy 284.159437 -251.978206) (xy 284.117766 -252.011437) (xy 284.071608 -252.038086) (xy 284.021994 -252.057558)
			(xy 283.970032 -252.069418) (xy 283.916882 -252.073402) (xy 283.863732 -252.069418) (xy 283.81177 -252.057558)
			(xy 283.762156 -252.038086) (xy 283.715998 -252.011437) (xy 283.674327 -251.978206) (xy 283.638075 -251.939135)
			(xy 283.608051 -251.895098) (xy 283.584925 -251.847077) (xy 283.569215 -251.796147) (xy 283.561272 -251.743443)
			(xy 269.184892 -251.743443) (xy 269.176949 -251.796147) (xy 269.161239 -251.847077) (xy 269.138113 -251.895098)
			(xy 269.108089 -251.939135) (xy 269.071837 -251.978206) (xy 269.030166 -252.011437) (xy 268.984008 -252.038086)
			(xy 268.934394 -252.057558) (xy 268.882432 -252.069418) (xy 268.829282 -252.073402) (xy 268.776132 -252.069418)
			(xy 268.72417 -252.057558) (xy 268.674556 -252.038086) (xy 268.628398 -252.011437) (xy 268.586727 -251.978206)
			(xy 268.550475 -251.939135) (xy 268.520451 -251.895098) (xy 268.497325 -251.847077) (xy 268.481615 -251.796147)
			(xy 268.473672 -251.743443) (xy 254 -251.743443) (xy 254 -252.593327) (xy 258.720072 -252.593327)
			(xy 258.720072 -252.540029) (xy 258.728015 -252.487325) (xy 258.743725 -252.436395) (xy 258.766851 -252.388374)
			(xy 258.796875 -252.344337) (xy 258.833127 -252.305266) (xy 258.874798 -252.272035) (xy 258.920956 -252.245386)
			(xy 258.97057 -252.225914) (xy 259.022532 -252.214054) (xy 259.075682 -252.210071) (xy 259.128832 -252.214054)
			(xy 259.180794 -252.225914) (xy 259.230408 -252.245386) (xy 259.276566 -252.272035) (xy 259.318237 -252.305266)
			(xy 259.354489 -252.344337) (xy 259.384513 -252.388374) (xy 259.407639 -252.436395) (xy 259.423349 -252.487325)
			(xy 259.431292 -252.540029) (xy 259.43179 -252.566678) (xy 259.431292 -252.593327) (xy 264.373604 -252.593327)
			(xy 264.373604 -252.540029) (xy 264.381547 -252.487325) (xy 264.397257 -252.436395) (xy 264.420383 -252.388374)
			(xy 264.450407 -252.344337) (xy 264.486659 -252.305266) (xy 264.52833 -252.272035) (xy 264.574488 -252.245386)
			(xy 264.624102 -252.225914) (xy 264.676064 -252.214054) (xy 264.729214 -252.210071) (xy 264.782364 -252.214054)
			(xy 264.834326 -252.225914) (xy 264.88394 -252.245386) (xy 264.930098 -252.272035) (xy 264.971769 -252.305266)
			(xy 265.008021 -252.344337) (xy 265.038045 -252.388374) (xy 265.061171 -252.436395) (xy 265.076881 -252.487325)
			(xy 265.084824 -252.540029) (xy 265.085322 -252.566678) (xy 265.084824 -252.593327) (xy 268.473672 -252.593327)
			(xy 268.473672 -252.540029) (xy 268.481615 -252.487325) (xy 268.497325 -252.436395) (xy 268.520451 -252.388374)
			(xy 268.550475 -252.344337) (xy 268.586727 -252.305266) (xy 268.628398 -252.272035) (xy 268.674556 -252.245386)
			(xy 268.72417 -252.225914) (xy 268.776132 -252.214054) (xy 268.829282 -252.210071) (xy 268.882432 -252.214054)
			(xy 268.934394 -252.225914) (xy 268.984008 -252.245386) (xy 269.030166 -252.272035) (xy 269.071837 -252.305266)
			(xy 269.108089 -252.344337) (xy 269.138113 -252.388374) (xy 269.161239 -252.436395) (xy 269.176949 -252.487325)
			(xy 269.184892 -252.540029) (xy 269.18539 -252.566678) (xy 269.184892 -252.593327) (xy 273.807672 -252.593327)
			(xy 273.807672 -252.540029) (xy 273.815615 -252.487325) (xy 273.831325 -252.436395) (xy 273.854451 -252.388374)
			(xy 273.884475 -252.344337) (xy 273.920727 -252.305266) (xy 273.962398 -252.272035) (xy 274.008556 -252.245386)
			(xy 274.05817 -252.225914) (xy 274.110132 -252.214054) (xy 274.163282 -252.210071) (xy 274.216432 -252.214054)
			(xy 274.268394 -252.225914) (xy 274.318008 -252.245386) (xy 274.364166 -252.272035) (xy 274.405837 -252.305266)
			(xy 274.442089 -252.344337) (xy 274.472113 -252.388374) (xy 274.495239 -252.436395) (xy 274.510949 -252.487325)
			(xy 274.518892 -252.540029) (xy 274.51939 -252.566678) (xy 274.518892 -252.593327) (xy 279.461204 -252.593327)
			(xy 279.461204 -252.540029) (xy 279.469147 -252.487325) (xy 279.484857 -252.436395) (xy 279.507983 -252.388374)
			(xy 279.538007 -252.344337) (xy 279.574259 -252.305266) (xy 279.61593 -252.272035) (xy 279.662088 -252.245386)
			(xy 279.711702 -252.225914) (xy 279.763664 -252.214054) (xy 279.816814 -252.210071) (xy 279.869964 -252.214054)
			(xy 279.921926 -252.225914) (xy 279.97154 -252.245386) (xy 280.017698 -252.272035) (xy 280.059369 -252.305266)
			(xy 280.095621 -252.344337) (xy 280.125645 -252.388374) (xy 280.148771 -252.436395) (xy 280.164481 -252.487325)
			(xy 280.172424 -252.540029) (xy 280.172922 -252.566678) (xy 280.172424 -252.593327) (xy 283.561272 -252.593327)
			(xy 283.561272 -252.540029) (xy 283.569215 -252.487325) (xy 283.584925 -252.436395) (xy 283.608051 -252.388374)
			(xy 283.638075 -252.344337) (xy 283.674327 -252.305266) (xy 283.715998 -252.272035) (xy 283.762156 -252.245386)
			(xy 283.81177 -252.225914) (xy 283.863732 -252.214054) (xy 283.916882 -252.210071) (xy 283.970032 -252.214054)
			(xy 284.021994 -252.225914) (xy 284.071608 -252.245386) (xy 284.117766 -252.272035) (xy 284.159437 -252.305266)
			(xy 284.195689 -252.344337) (xy 284.225713 -252.388374) (xy 284.248839 -252.436395) (xy 284.264549 -252.487325)
			(xy 284.272492 -252.540029) (xy 284.27299 -252.566678) (xy 284.272492 -252.593327) (xy 288.895272 -252.593327)
			(xy 288.895272 -252.540029) (xy 288.903215 -252.487325) (xy 288.918925 -252.436395) (xy 288.942051 -252.388374)
			(xy 288.972075 -252.344337) (xy 289.008327 -252.305266) (xy 289.049998 -252.272035) (xy 289.096156 -252.245386)
			(xy 289.14577 -252.225914) (xy 289.197732 -252.214054) (xy 289.250882 -252.210071) (xy 289.304032 -252.214054)
			(xy 289.355994 -252.225914) (xy 289.405608 -252.245386) (xy 289.451766 -252.272035) (xy 289.493437 -252.305266)
			(xy 289.529689 -252.344337) (xy 289.559713 -252.388374) (xy 289.582839 -252.436395) (xy 289.598549 -252.487325)
			(xy 289.606492 -252.540029) (xy 289.60699 -252.566678) (xy 289.606492 -252.593327) (xy 294.548804 -252.593327)
			(xy 294.548804 -252.540029) (xy 294.556747 -252.487325) (xy 294.572457 -252.436395) (xy 294.595583 -252.388374)
			(xy 294.625607 -252.344337) (xy 294.661859 -252.305266) (xy 294.70353 -252.272035) (xy 294.749688 -252.245386)
			(xy 294.799302 -252.225914) (xy 294.851264 -252.214054) (xy 294.904414 -252.210071) (xy 294.957564 -252.214054)
			(xy 295.009526 -252.225914) (xy 295.05914 -252.245386) (xy 295.105298 -252.272035) (xy 295.146969 -252.305266)
			(xy 295.183221 -252.344337) (xy 295.213245 -252.388374) (xy 295.236371 -252.436395) (xy 295.252081 -252.487325)
			(xy 295.260024 -252.540029) (xy 295.260522 -252.566678) (xy 295.260024 -252.593327) (xy 298.648872 -252.593327)
			(xy 298.648872 -252.540029) (xy 298.656815 -252.487325) (xy 298.672525 -252.436395) (xy 298.695651 -252.388374)
			(xy 298.725675 -252.344337) (xy 298.761927 -252.305266) (xy 298.803598 -252.272035) (xy 298.849756 -252.245386)
			(xy 298.89937 -252.225914) (xy 298.951332 -252.214054) (xy 299.004482 -252.210071) (xy 299.057632 -252.214054)
			(xy 299.109594 -252.225914) (xy 299.159208 -252.245386) (xy 299.205366 -252.272035) (xy 299.247037 -252.305266)
			(xy 299.283289 -252.344337) (xy 299.313313 -252.388374) (xy 299.336439 -252.436395) (xy 299.352149 -252.487325)
			(xy 299.360092 -252.540029) (xy 299.36059 -252.566678) (xy 299.360092 -252.593327) (xy 303.982872 -252.593327)
			(xy 303.982872 -252.540029) (xy 303.990815 -252.487325) (xy 304.006525 -252.436395) (xy 304.029651 -252.388374)
			(xy 304.059675 -252.344337) (xy 304.095927 -252.305266) (xy 304.137598 -252.272035) (xy 304.183756 -252.245386)
			(xy 304.23337 -252.225914) (xy 304.285332 -252.214054) (xy 304.338482 -252.210071) (xy 304.391632 -252.214054)
			(xy 304.443594 -252.225914) (xy 304.493208 -252.245386) (xy 304.539366 -252.272035) (xy 304.581037 -252.305266)
			(xy 304.617289 -252.344337) (xy 304.647313 -252.388374) (xy 304.670439 -252.436395) (xy 304.686149 -252.487325)
			(xy 304.694092 -252.540029) (xy 304.69459 -252.566678) (xy 304.694092 -252.593327) (xy 311.526672 -252.593327)
			(xy 311.526672 -252.540029) (xy 311.534615 -252.487325) (xy 311.550325 -252.436395) (xy 311.573451 -252.388374)
			(xy 311.603475 -252.344337) (xy 311.639727 -252.305266) (xy 311.681398 -252.272035) (xy 311.727556 -252.245386)
			(xy 311.77717 -252.225914) (xy 311.829132 -252.214054) (xy 311.882282 -252.210071) (xy 311.935432 -252.214054)
			(xy 311.987394 -252.225914) (xy 312.037008 -252.245386) (xy 312.083166 -252.272035) (xy 312.124837 -252.305266)
			(xy 312.161089 -252.344337) (xy 312.191113 -252.388374) (xy 312.214239 -252.436395) (xy 312.229949 -252.487325)
			(xy 312.237892 -252.540029) (xy 312.23839 -252.566678) (xy 312.237892 -252.593327) (xy 312.229949 -252.646031)
			(xy 312.214239 -252.696961) (xy 312.191113 -252.744982) (xy 312.161089 -252.789019) (xy 312.124837 -252.82809)
			(xy 312.083166 -252.861321) (xy 312.037008 -252.88797) (xy 311.987394 -252.907442) (xy 311.935432 -252.919302)
			(xy 311.882282 -252.923286) (xy 311.829132 -252.919302) (xy 311.77717 -252.907442) (xy 311.727556 -252.88797)
			(xy 311.681398 -252.861321) (xy 311.639727 -252.82809) (xy 311.603475 -252.789019) (xy 311.573451 -252.744982)
			(xy 311.550325 -252.696961) (xy 311.534615 -252.646031) (xy 311.526672 -252.593327) (xy 304.694092 -252.593327)
			(xy 304.686149 -252.646031) (xy 304.670439 -252.696961) (xy 304.647313 -252.744982) (xy 304.617289 -252.789019)
			(xy 304.581037 -252.82809) (xy 304.539366 -252.861321) (xy 304.493208 -252.88797) (xy 304.443594 -252.907442)
			(xy 304.391632 -252.919302) (xy 304.338482 -252.923286) (xy 304.285332 -252.919302) (xy 304.23337 -252.907442)
			(xy 304.183756 -252.88797) (xy 304.137598 -252.861321) (xy 304.095927 -252.82809) (xy 304.059675 -252.789019)
			(xy 304.029651 -252.744982) (xy 304.006525 -252.696961) (xy 303.990815 -252.646031) (xy 303.982872 -252.593327)
			(xy 299.360092 -252.593327) (xy 299.352149 -252.646031) (xy 299.336439 -252.696961) (xy 299.313313 -252.744982)
			(xy 299.283289 -252.789019) (xy 299.247037 -252.82809) (xy 299.205366 -252.861321) (xy 299.159208 -252.88797)
			(xy 299.109594 -252.907442) (xy 299.057632 -252.919302) (xy 299.004482 -252.923286) (xy 298.951332 -252.919302)
			(xy 298.89937 -252.907442) (xy 298.849756 -252.88797) (xy 298.803598 -252.861321) (xy 298.761927 -252.82809)
			(xy 298.725675 -252.789019) (xy 298.695651 -252.744982) (xy 298.672525 -252.696961) (xy 298.656815 -252.646031)
			(xy 298.648872 -252.593327) (xy 295.260024 -252.593327) (xy 295.252081 -252.646031) (xy 295.236371 -252.696961)
			(xy 295.213245 -252.744982) (xy 295.183221 -252.789019) (xy 295.146969 -252.82809) (xy 295.105298 -252.861321)
			(xy 295.05914 -252.88797) (xy 295.009526 -252.907442) (xy 294.957564 -252.919302) (xy 294.904414 -252.923286)
			(xy 294.851264 -252.919302) (xy 294.799302 -252.907442) (xy 294.749688 -252.88797) (xy 294.70353 -252.861321)
			(xy 294.661859 -252.82809) (xy 294.625607 -252.789019) (xy 294.595583 -252.744982) (xy 294.572457 -252.696961)
			(xy 294.556747 -252.646031) (xy 294.548804 -252.593327) (xy 289.606492 -252.593327) (xy 289.598549 -252.646031)
			(xy 289.582839 -252.696961) (xy 289.559713 -252.744982) (xy 289.529689 -252.789019) (xy 289.493437 -252.82809)
			(xy 289.451766 -252.861321) (xy 289.405608 -252.88797) (xy 289.355994 -252.907442) (xy 289.304032 -252.919302)
			(xy 289.250882 -252.923286) (xy 289.197732 -252.919302) (xy 289.14577 -252.907442) (xy 289.096156 -252.88797)
			(xy 289.049998 -252.861321) (xy 289.008327 -252.82809) (xy 288.972075 -252.789019) (xy 288.942051 -252.744982)
			(xy 288.918925 -252.696961) (xy 288.903215 -252.646031) (xy 288.895272 -252.593327) (xy 284.272492 -252.593327)
			(xy 284.264549 -252.646031) (xy 284.248839 -252.696961) (xy 284.225713 -252.744982) (xy 284.195689 -252.789019)
			(xy 284.159437 -252.82809) (xy 284.117766 -252.861321) (xy 284.071608 -252.88797) (xy 284.021994 -252.907442)
			(xy 283.970032 -252.919302) (xy 283.916882 -252.923286) (xy 283.863732 -252.919302) (xy 283.81177 -252.907442)
			(xy 283.762156 -252.88797) (xy 283.715998 -252.861321) (xy 283.674327 -252.82809) (xy 283.638075 -252.789019)
			(xy 283.608051 -252.744982) (xy 283.584925 -252.696961) (xy 283.569215 -252.646031) (xy 283.561272 -252.593327)
			(xy 280.172424 -252.593327) (xy 280.164481 -252.646031) (xy 280.148771 -252.696961) (xy 280.125645 -252.744982)
			(xy 280.095621 -252.789019) (xy 280.059369 -252.82809) (xy 280.017698 -252.861321) (xy 279.97154 -252.88797)
			(xy 279.921926 -252.907442) (xy 279.869964 -252.919302) (xy 279.816814 -252.923286) (xy 279.763664 -252.919302)
			(xy 279.711702 -252.907442) (xy 279.662088 -252.88797) (xy 279.61593 -252.861321) (xy 279.574259 -252.82809)
			(xy 279.538007 -252.789019) (xy 279.507983 -252.744982) (xy 279.484857 -252.696961) (xy 279.469147 -252.646031)
			(xy 279.461204 -252.593327) (xy 274.518892 -252.593327) (xy 274.510949 -252.646031) (xy 274.495239 -252.696961)
			(xy 274.472113 -252.744982) (xy 274.442089 -252.789019) (xy 274.405837 -252.82809) (xy 274.364166 -252.861321)
			(xy 274.318008 -252.88797) (xy 274.268394 -252.907442) (xy 274.216432 -252.919302) (xy 274.163282 -252.923286)
			(xy 274.110132 -252.919302) (xy 274.05817 -252.907442) (xy 274.008556 -252.88797) (xy 273.962398 -252.861321)
			(xy 273.920727 -252.82809) (xy 273.884475 -252.789019) (xy 273.854451 -252.744982) (xy 273.831325 -252.696961)
			(xy 273.815615 -252.646031) (xy 273.807672 -252.593327) (xy 269.184892 -252.593327) (xy 269.176949 -252.646031)
			(xy 269.161239 -252.696961) (xy 269.138113 -252.744982) (xy 269.108089 -252.789019) (xy 269.071837 -252.82809)
			(xy 269.030166 -252.861321) (xy 268.984008 -252.88797) (xy 268.934394 -252.907442) (xy 268.882432 -252.919302)
			(xy 268.829282 -252.923286) (xy 268.776132 -252.919302) (xy 268.72417 -252.907442) (xy 268.674556 -252.88797)
			(xy 268.628398 -252.861321) (xy 268.586727 -252.82809) (xy 268.550475 -252.789019) (xy 268.520451 -252.744982)
			(xy 268.497325 -252.696961) (xy 268.481615 -252.646031) (xy 268.473672 -252.593327) (xy 265.084824 -252.593327)
			(xy 265.076881 -252.646031) (xy 265.061171 -252.696961) (xy 265.038045 -252.744982) (xy 265.008021 -252.789019)
			(xy 264.971769 -252.82809) (xy 264.930098 -252.861321) (xy 264.88394 -252.88797) (xy 264.834326 -252.907442)
			(xy 264.782364 -252.919302) (xy 264.729214 -252.923286) (xy 264.676064 -252.919302) (xy 264.624102 -252.907442)
			(xy 264.574488 -252.88797) (xy 264.52833 -252.861321) (xy 264.486659 -252.82809) (xy 264.450407 -252.789019)
			(xy 264.420383 -252.744982) (xy 264.397257 -252.696961) (xy 264.381547 -252.646031) (xy 264.373604 -252.593327)
			(xy 259.431292 -252.593327) (xy 259.423349 -252.646031) (xy 259.407639 -252.696961) (xy 259.384513 -252.744982)
			(xy 259.354489 -252.789019) (xy 259.318237 -252.82809) (xy 259.276566 -252.861321) (xy 259.230408 -252.88797)
			(xy 259.180794 -252.907442) (xy 259.128832 -252.919302) (xy 259.075682 -252.923286) (xy 259.022532 -252.919302)
			(xy 258.97057 -252.907442) (xy 258.920956 -252.88797) (xy 258.874798 -252.861321) (xy 258.833127 -252.82809)
			(xy 258.796875 -252.789019) (xy 258.766851 -252.744982) (xy 258.743725 -252.696961) (xy 258.728015 -252.646031)
			(xy 258.720072 -252.593327) (xy 254 -252.593327) (xy 254 -254.6495) (xy 305.72177 -254.6495) (xy 305.725754 -254.596349)
			(xy 305.737614 -254.544385) (xy 305.757086 -254.494769) (xy 305.783735 -254.448609) (xy 305.816966 -254.406937)
			(xy 305.856037 -254.370682) (xy 305.900075 -254.340656) (xy 305.948096 -254.317528) (xy 305.999027 -254.301815)
			(xy 306.051732 -254.293869) (xy 306.078382 -254.29337) (xy 306.105702 -254.29391) (xy 306.159702 -254.302245)
			(xy 306.211798 -254.318722) (xy 306.26077 -254.342955) (xy 306.305471 -254.374377) (xy 306.325524 -254.392938)
			(xy 306.337146 -254.403335) (xy 306.36508 -254.417159) (xy 306.395882 -254.421915) (xy 306.426684 -254.417159)
			(xy 306.454618 -254.403335) (xy 306.46624 -254.392938) (xy 306.48625 -254.374321) (xy 306.530943 -254.342864)
			(xy 306.579922 -254.318614) (xy 306.632035 -254.302144) (xy 306.686055 -254.29384) (xy 306.713382 -254.29337)
			(xy 306.740702 -254.29391) (xy 306.794702 -254.302245) (xy 306.846798 -254.318722) (xy 306.89577 -254.342955)
			(xy 306.940471 -254.374377) (xy 306.960524 -254.392938) (xy 306.972146 -254.403335) (xy 307.00008 -254.417159)
			(xy 307.030882 -254.421915) (xy 307.061684 -254.417159) (xy 307.089618 -254.403335) (xy 307.10124 -254.392938)
			(xy 307.12125 -254.374321) (xy 307.165943 -254.342864) (xy 307.214922 -254.318614) (xy 307.267035 -254.302144)
			(xy 307.321055 -254.29384) (xy 307.348382 -254.29337) (xy 307.375702 -254.29391) (xy 307.429702 -254.302245)
			(xy 307.481798 -254.318722) (xy 307.53077 -254.342955) (xy 307.575471 -254.374377) (xy 307.595524 -254.392938)
			(xy 307.607146 -254.403335) (xy 307.63508 -254.417159) (xy 307.665882 -254.421915) (xy 307.696684 -254.417159)
			(xy 307.724618 -254.403335) (xy 307.73624 -254.392938) (xy 307.755464 -254.375081) (xy 307.798185 -254.344619)
			(xy 307.844918 -254.320766) (xy 307.894648 -254.304039) (xy 307.92039 -254.298958) (xy 307.933561 -254.296141)
			(xy 307.957888 -254.284605) (xy 307.978361 -254.267118) (xy 307.993558 -254.244893) (xy 308.002426 -254.219471)
			(xy 308.00435 -254.192616) (xy 308.002178 -254.179324) (xy 307.999094 -254.162411) (xy 307.995783 -254.128189)
			(xy 307.995574 -254.110998) (xy 307.996139 -254.083016) (xy 308.004894 -254.02774) (xy 308.022188 -253.974515)
			(xy 308.047594 -253.92465) (xy 308.080489 -253.879373) (xy 308.120061 -253.839799) (xy 308.165336 -253.806903)
			(xy 308.2152 -253.781494) (xy 308.268425 -253.764198) (xy 308.3237 -253.75544) (xy 308.351682 -253.75489)
			(xy 308.381014 -253.755495) (xy 308.438887 -253.765102) (xy 308.494399 -253.784074) (xy 308.546045 -253.811899)
			(xy 308.592425 -253.847821) (xy 308.612794 -253.868936) (xy 308.622804 -253.879069) (xy 308.647183 -253.893779)
			(xy 308.674677 -253.90118) (xy 308.703146 -253.900698) (xy 308.730374 -253.892369) (xy 308.75424 -253.876843)
			(xy 308.763924 -253.866396) (xy 308.780916 -253.847572) (xy 308.819315 -253.81445) (xy 308.862024 -253.78711)
			(xy 308.90818 -253.766107) (xy 308.956849 -253.751864) (xy 309.007047 -253.74467) (xy 309.032402 -253.744222)
			(xy 309.059053 -253.74466) (xy 309.111761 -253.752605) (xy 309.162696 -253.768316) (xy 309.21072 -253.791444)
			(xy 309.254761 -253.82147) (xy 309.293834 -253.857726) (xy 309.327068 -253.8994) (xy 309.35372 -253.945561)
			(xy 309.373193 -253.99518) (xy 309.385054 -254.047146) (xy 309.389038 -254.1003) (xy 309.385054 -254.153454)
			(xy 309.373193 -254.20542) (xy 309.35372 -254.255039) (xy 309.327068 -254.3012) (xy 309.293834 -254.342874)
			(xy 309.254761 -254.37913) (xy 309.21072 -254.409156) (xy 309.162696 -254.432284) (xy 309.111761 -254.447995)
			(xy 309.059053 -254.45594) (xy 309.032402 -254.456438) (xy 309.00307 -254.455835) (xy 308.945197 -254.446226)
			(xy 308.889686 -254.427252) (xy 308.83804 -254.399428) (xy 308.791659 -254.363507) (xy 308.77129 -254.342392)
			(xy 308.761291 -254.33225) (xy 308.736906 -254.317552) (xy 308.709411 -254.310158) (xy 308.680944 -254.310643)
			(xy 308.653717 -254.318969) (xy 308.629847 -254.334489) (xy 308.62016 -254.344932) (xy 308.604044 -254.362845)
			(xy 308.567789 -254.394585) (xy 308.527583 -254.421142) (xy 308.484161 -254.44203) (xy 308.438317 -254.456867)
			(xy 308.414674 -254.461518) (xy 308.401505 -254.464338) (xy 308.377182 -254.475878) (xy 308.356713 -254.493366)
			(xy 308.341517 -254.515589) (xy 308.332647 -254.541008) (xy 308.330717 -254.567861) (xy 308.332886 -254.581152)
			(xy 308.33598 -254.598064) (xy 308.339284 -254.632287) (xy 308.33949 -254.649478) (xy 308.338967 -254.677464)
			(xy 308.330214 -254.732746) (xy 308.31292 -254.785979) (xy 308.287511 -254.83585) (xy 308.254613 -254.881132)
			(xy 308.215035 -254.92071) (xy 308.169754 -254.953609) (xy 308.119882 -254.979019) (xy 308.06665 -254.996313)
			(xy 308.011368 -255.005067) (xy 307.983382 -255.005586) (xy 307.956061 -255.00508) (xy 307.902058 -254.996739)
			(xy 307.849961 -254.980255) (xy 307.80099 -254.956013) (xy 307.756292 -254.924583) (xy 307.73624 -254.906018)
			(xy 307.724618 -254.895621) (xy 307.696684 -254.881797) (xy 307.665882 -254.877041) (xy 307.63508 -254.881797)
			(xy 307.607146 -254.895621) (xy 307.595524 -254.906018) (xy 307.575496 -254.924614) (xy 307.530807 -254.956072)
			(xy 307.481832 -254.980324) (xy 307.429723 -254.9968) (xy 307.375708 -255.005111) (xy 307.348382 -255.005586)
			(xy 307.321061 -255.00508) (xy 307.267058 -254.996739) (xy 307.214961 -254.980255) (xy 307.16599 -254.956013)
			(xy 307.121292 -254.924583) (xy 307.10124 -254.906018) (xy 307.089618 -254.895621) (xy 307.061684 -254.881797)
			(xy 307.030882 -254.877041) (xy 307.00008 -254.881797) (xy 306.972146 -254.895621) (xy 306.960524 -254.906018)
			(xy 306.940496 -254.924614) (xy 306.895807 -254.956072) (xy 306.846832 -254.980324) (xy 306.794723 -254.9968)
			(xy 306.740708 -255.005111) (xy 306.713382 -255.005586) (xy 306.686061 -255.00508) (xy 306.632058 -254.996739)
			(xy 306.579961 -254.980255) (xy 306.53099 -254.956013) (xy 306.486292 -254.924583) (xy 306.46624 -254.906018)
			(xy 306.454618 -254.895621) (xy 306.426684 -254.881797) (xy 306.395882 -254.877041) (xy 306.36508 -254.881797)
			(xy 306.337146 -254.895621) (xy 306.325524 -254.906018) (xy 306.305496 -254.924614) (xy 306.260807 -254.956072)
			(xy 306.211832 -254.980324) (xy 306.159723 -254.9968) (xy 306.105708 -255.005111) (xy 306.078382 -255.005586)
			(xy 306.051732 -255.005131) (xy 305.999027 -254.997185) (xy 305.948096 -254.981472) (xy 305.900075 -254.958344)
			(xy 305.856037 -254.928318) (xy 305.816966 -254.892063) (xy 305.783735 -254.850391) (xy 305.757086 -254.804231)
			(xy 305.737614 -254.754615) (xy 305.725754 -254.702651) (xy 305.72177 -254.6495) (xy 254 -254.6495)
			(xy 254 -259.393415) (xy 260.929872 -259.393415) (xy 260.929872 -259.340117) (xy 260.937815 -259.287413)
			(xy 260.953525 -259.236483) (xy 260.976651 -259.188462) (xy 261.006675 -259.144425) (xy 261.042927 -259.105354)
			(xy 261.084598 -259.072123) (xy 261.130756 -259.045474) (xy 261.18037 -259.026002) (xy 261.232332 -259.014142)
			(xy 261.285482 -259.010159) (xy 261.338632 -259.014142) (xy 261.390594 -259.026002) (xy 261.440208 -259.045474)
			(xy 261.486366 -259.072123) (xy 261.528037 -259.105354) (xy 261.564289 -259.144425) (xy 261.594313 -259.188462)
			(xy 261.617439 -259.236483) (xy 261.633149 -259.287413) (xy 261.641092 -259.340117) (xy 261.64159 -259.366766)
			(xy 261.641092 -259.393415) (xy 264.373604 -259.393415) (xy 264.373604 -259.340117) (xy 264.381547 -259.287413)
			(xy 264.397257 -259.236483) (xy 264.420383 -259.188462) (xy 264.450407 -259.144425) (xy 264.486659 -259.105354)
			(xy 264.52833 -259.072123) (xy 264.574488 -259.045474) (xy 264.624102 -259.026002) (xy 264.676064 -259.014142)
			(xy 264.729214 -259.010159) (xy 264.782364 -259.014142) (xy 264.834326 -259.026002) (xy 264.88394 -259.045474)
			(xy 264.930098 -259.072123) (xy 264.971769 -259.105354) (xy 265.008021 -259.144425) (xy 265.038045 -259.188462)
			(xy 265.061171 -259.236483) (xy 265.076881 -259.287413) (xy 265.084824 -259.340117) (xy 265.085322 -259.366766)
			(xy 265.084824 -259.393415) (xy 268.473672 -259.393415) (xy 268.473672 -259.340117) (xy 268.481615 -259.287413)
			(xy 268.497325 -259.236483) (xy 268.520451 -259.188462) (xy 268.550475 -259.144425) (xy 268.586727 -259.105354)
			(xy 268.628398 -259.072123) (xy 268.674556 -259.045474) (xy 268.72417 -259.026002) (xy 268.776132 -259.014142)
			(xy 268.829282 -259.010159) (xy 268.882432 -259.014142) (xy 268.934394 -259.026002) (xy 268.984008 -259.045474)
			(xy 269.030166 -259.072123) (xy 269.071837 -259.105354) (xy 269.108089 -259.144425) (xy 269.138113 -259.188462)
			(xy 269.161239 -259.236483) (xy 269.176949 -259.287413) (xy 269.184892 -259.340117) (xy 269.18539 -259.366766)
			(xy 269.184892 -259.393415) (xy 276.017472 -259.393415) (xy 276.017472 -259.340117) (xy 276.025415 -259.287413)
			(xy 276.041125 -259.236483) (xy 276.064251 -259.188462) (xy 276.094275 -259.144425) (xy 276.130527 -259.105354)
			(xy 276.172198 -259.072123) (xy 276.218356 -259.045474) (xy 276.26797 -259.026002) (xy 276.319932 -259.014142)
			(xy 276.373082 -259.010159) (xy 276.426232 -259.014142) (xy 276.478194 -259.026002) (xy 276.527808 -259.045474)
			(xy 276.573966 -259.072123) (xy 276.615637 -259.105354) (xy 276.651889 -259.144425) (xy 276.681913 -259.188462)
			(xy 276.705039 -259.236483) (xy 276.720749 -259.287413) (xy 276.728692 -259.340117) (xy 276.72919 -259.366766)
			(xy 276.728692 -259.393415) (xy 279.461204 -259.393415) (xy 279.461204 -259.340117) (xy 279.469147 -259.287413)
			(xy 279.484857 -259.236483) (xy 279.507983 -259.188462) (xy 279.538007 -259.144425) (xy 279.574259 -259.105354)
			(xy 279.61593 -259.072123) (xy 279.662088 -259.045474) (xy 279.711702 -259.026002) (xy 279.763664 -259.014142)
			(xy 279.816814 -259.010159) (xy 279.869964 -259.014142) (xy 279.921926 -259.026002) (xy 279.97154 -259.045474)
			(xy 280.017698 -259.072123) (xy 280.059369 -259.105354) (xy 280.095621 -259.144425) (xy 280.125645 -259.188462)
			(xy 280.148771 -259.236483) (xy 280.164481 -259.287413) (xy 280.172424 -259.340117) (xy 280.172922 -259.366766)
			(xy 280.172424 -259.393415) (xy 283.561272 -259.393415) (xy 283.561272 -259.340117) (xy 283.569215 -259.287413)
			(xy 283.584925 -259.236483) (xy 283.608051 -259.188462) (xy 283.638075 -259.144425) (xy 283.674327 -259.105354)
			(xy 283.715998 -259.072123) (xy 283.762156 -259.045474) (xy 283.81177 -259.026002) (xy 283.863732 -259.014142)
			(xy 283.916882 -259.010159) (xy 283.970032 -259.014142) (xy 284.021994 -259.026002) (xy 284.071608 -259.045474)
			(xy 284.117766 -259.072123) (xy 284.159437 -259.105354) (xy 284.195689 -259.144425) (xy 284.225713 -259.188462)
			(xy 284.248839 -259.236483) (xy 284.264549 -259.287413) (xy 284.272492 -259.340117) (xy 284.27299 -259.366766)
			(xy 284.272492 -259.393415) (xy 291.105072 -259.393415) (xy 291.105072 -259.340117) (xy 291.113015 -259.287413)
			(xy 291.128725 -259.236483) (xy 291.151851 -259.188462) (xy 291.181875 -259.144425) (xy 291.218127 -259.105354)
			(xy 291.259798 -259.072123) (xy 291.305956 -259.045474) (xy 291.35557 -259.026002) (xy 291.407532 -259.014142)
			(xy 291.460682 -259.010159) (xy 291.513832 -259.014142) (xy 291.565794 -259.026002) (xy 291.615408 -259.045474)
			(xy 291.661566 -259.072123) (xy 291.703237 -259.105354) (xy 291.739489 -259.144425) (xy 291.769513 -259.188462)
			(xy 291.792639 -259.236483) (xy 291.808349 -259.287413) (xy 291.816292 -259.340117) (xy 291.81679 -259.366766)
			(xy 291.816292 -259.393415) (xy 294.548804 -259.393415) (xy 294.548804 -259.340117) (xy 294.556747 -259.287413)
			(xy 294.572457 -259.236483) (xy 294.595583 -259.188462) (xy 294.625607 -259.144425) (xy 294.661859 -259.105354)
			(xy 294.70353 -259.072123) (xy 294.749688 -259.045474) (xy 294.799302 -259.026002) (xy 294.851264 -259.014142)
			(xy 294.904414 -259.010159) (xy 294.957564 -259.014142) (xy 295.009526 -259.026002) (xy 295.05914 -259.045474)
			(xy 295.105298 -259.072123) (xy 295.146969 -259.105354) (xy 295.183221 -259.144425) (xy 295.213245 -259.188462)
			(xy 295.236371 -259.236483) (xy 295.252081 -259.287413) (xy 295.260024 -259.340117) (xy 295.260522 -259.366766)
			(xy 295.260024 -259.393415) (xy 298.674272 -259.393415) (xy 298.674272 -259.340117) (xy 298.682215 -259.287413)
			(xy 298.697925 -259.236483) (xy 298.721051 -259.188462) (xy 298.751075 -259.144425) (xy 298.787327 -259.105354)
			(xy 298.828998 -259.072123) (xy 298.875156 -259.045474) (xy 298.92477 -259.026002) (xy 298.976732 -259.014142)
			(xy 299.029882 -259.010159) (xy 299.083032 -259.014142) (xy 299.134994 -259.026002) (xy 299.184608 -259.045474)
			(xy 299.230766 -259.072123) (xy 299.272437 -259.105354) (xy 299.308689 -259.144425) (xy 299.338713 -259.188462)
			(xy 299.361839 -259.236483) (xy 299.377549 -259.287413) (xy 299.385492 -259.340117) (xy 299.38599 -259.366766)
			(xy 299.385492 -259.393415) (xy 299.377549 -259.446119) (xy 299.361839 -259.497049) (xy 299.338713 -259.54507)
			(xy 299.308689 -259.589107) (xy 299.272437 -259.628178) (xy 299.230766 -259.661409) (xy 299.184608 -259.688058)
			(xy 299.134994 -259.70753) (xy 299.083032 -259.71939) (xy 299.029882 -259.723374) (xy 298.976732 -259.71939)
			(xy 298.92477 -259.70753) (xy 298.875156 -259.688058) (xy 298.828998 -259.661409) (xy 298.787327 -259.628178)
			(xy 298.751075 -259.589107) (xy 298.721051 -259.54507) (xy 298.697925 -259.497049) (xy 298.682215 -259.446119)
			(xy 298.674272 -259.393415) (xy 295.260024 -259.393415) (xy 295.252081 -259.446119) (xy 295.236371 -259.497049)
			(xy 295.213245 -259.54507) (xy 295.183221 -259.589107) (xy 295.146969 -259.628178) (xy 295.105298 -259.661409)
			(xy 295.05914 -259.688058) (xy 295.009526 -259.70753) (xy 294.957564 -259.71939) (xy 294.904414 -259.723374)
			(xy 294.851264 -259.71939) (xy 294.799302 -259.70753) (xy 294.749688 -259.688058) (xy 294.70353 -259.661409)
			(xy 294.661859 -259.628178) (xy 294.625607 -259.589107) (xy 294.595583 -259.54507) (xy 294.572457 -259.497049)
			(xy 294.556747 -259.446119) (xy 294.548804 -259.393415) (xy 291.816292 -259.393415) (xy 291.808349 -259.446119)
			(xy 291.792639 -259.497049) (xy 291.769513 -259.54507) (xy 291.739489 -259.589107) (xy 291.703237 -259.628178)
			(xy 291.661566 -259.661409) (xy 291.615408 -259.688058) (xy 291.565794 -259.70753) (xy 291.513832 -259.71939)
			(xy 291.460682 -259.723374) (xy 291.407532 -259.71939) (xy 291.35557 -259.70753) (xy 291.305956 -259.688058)
			(xy 291.259798 -259.661409) (xy 291.218127 -259.628178) (xy 291.181875 -259.589107) (xy 291.151851 -259.54507)
			(xy 291.128725 -259.497049) (xy 291.113015 -259.446119) (xy 291.105072 -259.393415) (xy 284.272492 -259.393415)
			(xy 284.264549 -259.446119) (xy 284.248839 -259.497049) (xy 284.225713 -259.54507) (xy 284.195689 -259.589107)
			(xy 284.159437 -259.628178) (xy 284.117766 -259.661409) (xy 284.071608 -259.688058) (xy 284.021994 -259.70753)
			(xy 283.970032 -259.71939) (xy 283.916882 -259.723374) (xy 283.863732 -259.71939) (xy 283.81177 -259.70753)
			(xy 283.762156 -259.688058) (xy 283.715998 -259.661409) (xy 283.674327 -259.628178) (xy 283.638075 -259.589107)
			(xy 283.608051 -259.54507) (xy 283.584925 -259.497049) (xy 283.569215 -259.446119) (xy 283.561272 -259.393415)
			(xy 280.172424 -259.393415) (xy 280.164481 -259.446119) (xy 280.148771 -259.497049) (xy 280.125645 -259.54507)
			(xy 280.095621 -259.589107) (xy 280.059369 -259.628178) (xy 280.017698 -259.661409) (xy 279.97154 -259.688058)
			(xy 279.921926 -259.70753) (xy 279.869964 -259.71939) (xy 279.816814 -259.723374) (xy 279.763664 -259.71939)
			(xy 279.711702 -259.70753) (xy 279.662088 -259.688058) (xy 279.61593 -259.661409) (xy 279.574259 -259.628178)
			(xy 279.538007 -259.589107) (xy 279.507983 -259.54507) (xy 279.484857 -259.497049) (xy 279.469147 -259.446119)
			(xy 279.461204 -259.393415) (xy 276.728692 -259.393415) (xy 276.720749 -259.446119) (xy 276.705039 -259.497049)
			(xy 276.681913 -259.54507) (xy 276.651889 -259.589107) (xy 276.615637 -259.628178) (xy 276.573966 -259.661409)
			(xy 276.527808 -259.688058) (xy 276.478194 -259.70753) (xy 276.426232 -259.71939) (xy 276.373082 -259.723374)
			(xy 276.319932 -259.71939) (xy 276.26797 -259.70753) (xy 276.218356 -259.688058) (xy 276.172198 -259.661409)
			(xy 276.130527 -259.628178) (xy 276.094275 -259.589107) (xy 276.064251 -259.54507) (xy 276.041125 -259.497049)
			(xy 276.025415 -259.446119) (xy 276.017472 -259.393415) (xy 269.184892 -259.393415) (xy 269.176949 -259.446119)
			(xy 269.161239 -259.497049) (xy 269.138113 -259.54507) (xy 269.108089 -259.589107) (xy 269.071837 -259.628178)
			(xy 269.030166 -259.661409) (xy 268.984008 -259.688058) (xy 268.934394 -259.70753) (xy 268.882432 -259.71939)
			(xy 268.829282 -259.723374) (xy 268.776132 -259.71939) (xy 268.72417 -259.70753) (xy 268.674556 -259.688058)
			(xy 268.628398 -259.661409) (xy 268.586727 -259.628178) (xy 268.550475 -259.589107) (xy 268.520451 -259.54507)
			(xy 268.497325 -259.497049) (xy 268.481615 -259.446119) (xy 268.473672 -259.393415) (xy 265.084824 -259.393415)
			(xy 265.076881 -259.446119) (xy 265.061171 -259.497049) (xy 265.038045 -259.54507) (xy 265.008021 -259.589107)
			(xy 264.971769 -259.628178) (xy 264.930098 -259.661409) (xy 264.88394 -259.688058) (xy 264.834326 -259.70753)
			(xy 264.782364 -259.71939) (xy 264.729214 -259.723374) (xy 264.676064 -259.71939) (xy 264.624102 -259.70753)
			(xy 264.574488 -259.688058) (xy 264.52833 -259.661409) (xy 264.486659 -259.628178) (xy 264.450407 -259.589107)
			(xy 264.420383 -259.54507) (xy 264.397257 -259.497049) (xy 264.381547 -259.446119) (xy 264.373604 -259.393415)
			(xy 261.641092 -259.393415) (xy 261.633149 -259.446119) (xy 261.617439 -259.497049) (xy 261.594313 -259.54507)
			(xy 261.564289 -259.589107) (xy 261.528037 -259.628178) (xy 261.486366 -259.661409) (xy 261.440208 -259.688058)
			(xy 261.390594 -259.70753) (xy 261.338632 -259.71939) (xy 261.285482 -259.723374) (xy 261.232332 -259.71939)
			(xy 261.18037 -259.70753) (xy 261.130756 -259.688058) (xy 261.084598 -259.661409) (xy 261.042927 -259.628178)
			(xy 261.006675 -259.589107) (xy 260.976651 -259.54507) (xy 260.953525 -259.497049) (xy 260.937815 -259.446119)
			(xy 260.929872 -259.393415) (xy 254 -259.393415) (xy 254 -260.243299) (xy 260.929872 -260.243299)
			(xy 260.929872 -260.190001) (xy 260.937815 -260.137297) (xy 260.953525 -260.086367) (xy 260.976651 -260.038346)
			(xy 261.006675 -259.994309) (xy 261.042927 -259.955238) (xy 261.084598 -259.922007) (xy 261.130756 -259.895358)
			(xy 261.18037 -259.875886) (xy 261.232332 -259.864026) (xy 261.285482 -259.860043) (xy 261.338632 -259.864026)
			(xy 261.390594 -259.875886) (xy 261.440208 -259.895358) (xy 261.486366 -259.922007) (xy 261.528037 -259.955238)
			(xy 261.564289 -259.994309) (xy 261.594313 -260.038346) (xy 261.617439 -260.086367) (xy 261.633149 -260.137297)
			(xy 261.641092 -260.190001) (xy 261.64159 -260.21665) (xy 261.641092 -260.243299) (xy 268.473672 -260.243299)
			(xy 268.473672 -260.190001) (xy 268.481615 -260.137297) (xy 268.497325 -260.086367) (xy 268.520451 -260.038346)
			(xy 268.550475 -259.994309) (xy 268.586727 -259.955238) (xy 268.628398 -259.922007) (xy 268.674556 -259.895358)
			(xy 268.72417 -259.875886) (xy 268.776132 -259.864026) (xy 268.829282 -259.860043) (xy 268.882432 -259.864026)
			(xy 268.934394 -259.875886) (xy 268.984008 -259.895358) (xy 269.030166 -259.922007) (xy 269.071837 -259.955238)
			(xy 269.108089 -259.994309) (xy 269.138113 -260.038346) (xy 269.161239 -260.086367) (xy 269.176949 -260.137297)
			(xy 269.184892 -260.190001) (xy 269.18539 -260.21665) (xy 269.184892 -260.243299) (xy 276.017472 -260.243299)
			(xy 276.017472 -260.190001) (xy 276.025415 -260.137297) (xy 276.041125 -260.086367) (xy 276.064251 -260.038346)
			(xy 276.094275 -259.994309) (xy 276.130527 -259.955238) (xy 276.172198 -259.922007) (xy 276.218356 -259.895358)
			(xy 276.26797 -259.875886) (xy 276.319932 -259.864026) (xy 276.373082 -259.860043) (xy 276.426232 -259.864026)
			(xy 276.478194 -259.875886) (xy 276.527808 -259.895358) (xy 276.573966 -259.922007) (xy 276.615637 -259.955238)
			(xy 276.651889 -259.994309) (xy 276.681913 -260.038346) (xy 276.705039 -260.086367) (xy 276.720749 -260.137297)
			(xy 276.728692 -260.190001) (xy 276.72919 -260.21665) (xy 276.728692 -260.243299) (xy 283.561272 -260.243299)
			(xy 283.561272 -260.190001) (xy 283.569215 -260.137297) (xy 283.584925 -260.086367) (xy 283.608051 -260.038346)
			(xy 283.638075 -259.994309) (xy 283.674327 -259.955238) (xy 283.715998 -259.922007) (xy 283.762156 -259.895358)
			(xy 283.81177 -259.875886) (xy 283.863732 -259.864026) (xy 283.916882 -259.860043) (xy 283.970032 -259.864026)
			(xy 284.021994 -259.875886) (xy 284.071608 -259.895358) (xy 284.117766 -259.922007) (xy 284.159437 -259.955238)
			(xy 284.195689 -259.994309) (xy 284.225713 -260.038346) (xy 284.248839 -260.086367) (xy 284.264549 -260.137297)
			(xy 284.272492 -260.190001) (xy 284.27299 -260.21665) (xy 284.272492 -260.243299) (xy 291.105072 -260.243299)
			(xy 291.105072 -260.190001) (xy 291.113015 -260.137297) (xy 291.128725 -260.086367) (xy 291.151851 -260.038346)
			(xy 291.181875 -259.994309) (xy 291.218127 -259.955238) (xy 291.259798 -259.922007) (xy 291.305956 -259.895358)
			(xy 291.35557 -259.875886) (xy 291.407532 -259.864026) (xy 291.460682 -259.860043) (xy 291.513832 -259.864026)
			(xy 291.565794 -259.875886) (xy 291.615408 -259.895358) (xy 291.661566 -259.922007) (xy 291.703237 -259.955238)
			(xy 291.739489 -259.994309) (xy 291.769513 -260.038346) (xy 291.792639 -260.086367) (xy 291.808349 -260.137297)
			(xy 291.816292 -260.190001) (xy 291.81679 -260.21665) (xy 291.816292 -260.243299) (xy 298.674272 -260.243299)
			(xy 298.674272 -260.190001) (xy 298.682215 -260.137297) (xy 298.697925 -260.086367) (xy 298.721051 -260.038346)
			(xy 298.751075 -259.994309) (xy 298.787327 -259.955238) (xy 298.828998 -259.922007) (xy 298.875156 -259.895358)
			(xy 298.92477 -259.875886) (xy 298.976732 -259.864026) (xy 299.029882 -259.860043) (xy 299.083032 -259.864026)
			(xy 299.134994 -259.875886) (xy 299.184608 -259.895358) (xy 299.230766 -259.922007) (xy 299.272437 -259.955238)
			(xy 299.308689 -259.994309) (xy 299.338713 -260.038346) (xy 299.361839 -260.086367) (xy 299.377549 -260.137297)
			(xy 299.385492 -260.190001) (xy 299.38599 -260.21665) (xy 299.385492 -260.243299) (xy 299.377549 -260.296003)
			(xy 299.361839 -260.346933) (xy 299.338713 -260.394954) (xy 299.308689 -260.438991) (xy 299.272437 -260.478062)
			(xy 299.230766 -260.511293) (xy 299.184608 -260.537942) (xy 299.134994 -260.557414) (xy 299.083032 -260.569274)
			(xy 299.029882 -260.573258) (xy 298.976732 -260.569274) (xy 298.92477 -260.557414) (xy 298.875156 -260.537942)
			(xy 298.828998 -260.511293) (xy 298.787327 -260.478062) (xy 298.751075 -260.438991) (xy 298.721051 -260.394954)
			(xy 298.697925 -260.346933) (xy 298.682215 -260.296003) (xy 298.674272 -260.243299) (xy 291.816292 -260.243299)
			(xy 291.808349 -260.296003) (xy 291.792639 -260.346933) (xy 291.769513 -260.394954) (xy 291.739489 -260.438991)
			(xy 291.703237 -260.478062) (xy 291.661566 -260.511293) (xy 291.615408 -260.537942) (xy 291.565794 -260.557414)
			(xy 291.513832 -260.569274) (xy 291.460682 -260.573258) (xy 291.407532 -260.569274) (xy 291.35557 -260.557414)
			(xy 291.305956 -260.537942) (xy 291.259798 -260.511293) (xy 291.218127 -260.478062) (xy 291.181875 -260.438991)
			(xy 291.151851 -260.394954) (xy 291.128725 -260.346933) (xy 291.113015 -260.296003) (xy 291.105072 -260.243299)
			(xy 284.272492 -260.243299) (xy 284.264549 -260.296003) (xy 284.248839 -260.346933) (xy 284.225713 -260.394954)
			(xy 284.195689 -260.438991) (xy 284.159437 -260.478062) (xy 284.117766 -260.511293) (xy 284.071608 -260.537942)
			(xy 284.021994 -260.557414) (xy 283.970032 -260.569274) (xy 283.916882 -260.573258) (xy 283.863732 -260.569274)
			(xy 283.81177 -260.557414) (xy 283.762156 -260.537942) (xy 283.715998 -260.511293) (xy 283.674327 -260.478062)
			(xy 283.638075 -260.438991) (xy 283.608051 -260.394954) (xy 283.584925 -260.346933) (xy 283.569215 -260.296003)
			(xy 283.561272 -260.243299) (xy 276.728692 -260.243299) (xy 276.720749 -260.296003) (xy 276.705039 -260.346933)
			(xy 276.681913 -260.394954) (xy 276.651889 -260.438991) (xy 276.615637 -260.478062) (xy 276.573966 -260.511293)
			(xy 276.527808 -260.537942) (xy 276.478194 -260.557414) (xy 276.426232 -260.569274) (xy 276.373082 -260.573258)
			(xy 276.319932 -260.569274) (xy 276.26797 -260.557414) (xy 276.218356 -260.537942) (xy 276.172198 -260.511293)
			(xy 276.130527 -260.478062) (xy 276.094275 -260.438991) (xy 276.064251 -260.394954) (xy 276.041125 -260.346933)
			(xy 276.025415 -260.296003) (xy 276.017472 -260.243299) (xy 269.184892 -260.243299) (xy 269.176949 -260.296003)
			(xy 269.161239 -260.346933) (xy 269.138113 -260.394954) (xy 269.108089 -260.438991) (xy 269.071837 -260.478062)
			(xy 269.030166 -260.511293) (xy 268.984008 -260.537942) (xy 268.934394 -260.557414) (xy 268.882432 -260.569274)
			(xy 268.829282 -260.573258) (xy 268.776132 -260.569274) (xy 268.72417 -260.557414) (xy 268.674556 -260.537942)
			(xy 268.628398 -260.511293) (xy 268.586727 -260.478062) (xy 268.550475 -260.438991) (xy 268.520451 -260.394954)
			(xy 268.497325 -260.346933) (xy 268.481615 -260.296003) (xy 268.473672 -260.243299) (xy 261.641092 -260.243299)
			(xy 261.633149 -260.296003) (xy 261.617439 -260.346933) (xy 261.594313 -260.394954) (xy 261.564289 -260.438991)
			(xy 261.528037 -260.478062) (xy 261.486366 -260.511293) (xy 261.440208 -260.537942) (xy 261.390594 -260.557414)
			(xy 261.338632 -260.569274) (xy 261.285482 -260.573258) (xy 261.232332 -260.569274) (xy 261.18037 -260.557414)
			(xy 261.130756 -260.537942) (xy 261.084598 -260.511293) (xy 261.042927 -260.478062) (xy 261.006675 -260.438991)
			(xy 260.976651 -260.394954) (xy 260.953525 -260.346933) (xy 260.937815 -260.296003) (xy 260.929872 -260.243299)
			(xy 254 -260.243299) (xy 254 -261.093437) (xy 264.373604 -261.093437) (xy 264.373604 -261.040139)
			(xy 264.381547 -260.987435) (xy 264.397257 -260.936505) (xy 264.420383 -260.888484) (xy 264.450407 -260.844447)
			(xy 264.486659 -260.805376) (xy 264.52833 -260.772145) (xy 264.574488 -260.745496) (xy 264.624102 -260.726024)
			(xy 264.676064 -260.714164) (xy 264.729214 -260.710181) (xy 264.782364 -260.714164) (xy 264.834326 -260.726024)
			(xy 264.88394 -260.745496) (xy 264.930098 -260.772145) (xy 264.971769 -260.805376) (xy 265.008021 -260.844447)
			(xy 265.038045 -260.888484) (xy 265.061171 -260.936505) (xy 265.076881 -260.987435) (xy 265.084824 -261.040139)
			(xy 265.085322 -261.066788) (xy 265.084824 -261.093437) (xy 279.461204 -261.093437) (xy 279.461204 -261.040139)
			(xy 279.469147 -260.987435) (xy 279.484857 -260.936505) (xy 279.507983 -260.888484) (xy 279.538007 -260.844447)
			(xy 279.574259 -260.805376) (xy 279.61593 -260.772145) (xy 279.662088 -260.745496) (xy 279.711702 -260.726024)
			(xy 279.763664 -260.714164) (xy 279.816814 -260.710181) (xy 279.869964 -260.714164) (xy 279.921926 -260.726024)
			(xy 279.97154 -260.745496) (xy 280.017698 -260.772145) (xy 280.059369 -260.805376) (xy 280.095621 -260.844447)
			(xy 280.125645 -260.888484) (xy 280.148771 -260.936505) (xy 280.164481 -260.987435) (xy 280.172424 -261.040139)
			(xy 280.172922 -261.066788) (xy 280.172424 -261.093437) (xy 294.548804 -261.093437) (xy 294.548804 -261.040139)
			(xy 294.556747 -260.987435) (xy 294.572457 -260.936505) (xy 294.595583 -260.888484) (xy 294.625607 -260.844447)
			(xy 294.661859 -260.805376) (xy 294.70353 -260.772145) (xy 294.749688 -260.745496) (xy 294.799302 -260.726024)
			(xy 294.851264 -260.714164) (xy 294.904414 -260.710181) (xy 294.957564 -260.714164) (xy 295.009526 -260.726024)
			(xy 295.05914 -260.745496) (xy 295.105298 -260.772145) (xy 295.146969 -260.805376) (xy 295.183221 -260.844447)
			(xy 295.213245 -260.888484) (xy 295.236371 -260.936505) (xy 295.252081 -260.987435) (xy 295.260024 -261.040139)
			(xy 295.260522 -261.066788) (xy 295.260024 -261.093437) (xy 295.252081 -261.146141) (xy 295.236371 -261.197071)
			(xy 295.213245 -261.245092) (xy 295.183221 -261.289129) (xy 295.146969 -261.3282) (xy 295.105298 -261.361431)
			(xy 295.05914 -261.38808) (xy 295.009526 -261.407552) (xy 294.957564 -261.419412) (xy 294.904414 -261.423396)
			(xy 294.851264 -261.419412) (xy 294.799302 -261.407552) (xy 294.749688 -261.38808) (xy 294.70353 -261.361431)
			(xy 294.661859 -261.3282) (xy 294.625607 -261.289129) (xy 294.595583 -261.245092) (xy 294.572457 -261.197071)
			(xy 294.556747 -261.146141) (xy 294.548804 -261.093437) (xy 280.172424 -261.093437) (xy 280.164481 -261.146141)
			(xy 280.148771 -261.197071) (xy 280.125645 -261.245092) (xy 280.095621 -261.289129) (xy 280.059369 -261.3282)
			(xy 280.017698 -261.361431) (xy 279.97154 -261.38808) (xy 279.921926 -261.407552) (xy 279.869964 -261.419412)
			(xy 279.816814 -261.423396) (xy 279.763664 -261.419412) (xy 279.711702 -261.407552) (xy 279.662088 -261.38808)
			(xy 279.61593 -261.361431) (xy 279.574259 -261.3282) (xy 279.538007 -261.289129) (xy 279.507983 -261.245092)
			(xy 279.484857 -261.197071) (xy 279.469147 -261.146141) (xy 279.461204 -261.093437) (xy 265.084824 -261.093437)
			(xy 265.076881 -261.146141) (xy 265.061171 -261.197071) (xy 265.038045 -261.245092) (xy 265.008021 -261.289129)
			(xy 264.971769 -261.3282) (xy 264.930098 -261.361431) (xy 264.88394 -261.38808) (xy 264.834326 -261.407552)
			(xy 264.782364 -261.419412) (xy 264.729214 -261.423396) (xy 264.676064 -261.419412) (xy 264.624102 -261.407552)
			(xy 264.574488 -261.38808) (xy 264.52833 -261.361431) (xy 264.486659 -261.3282) (xy 264.450407 -261.289129)
			(xy 264.420383 -261.245092) (xy 264.397257 -261.197071) (xy 264.381547 -261.146141) (xy 264.373604 -261.093437)
			(xy 254 -261.093437) (xy 254 -261.943321) (xy 268.473672 -261.943321) (xy 268.473672 -261.890023)
			(xy 268.481615 -261.837319) (xy 268.497325 -261.786389) (xy 268.520451 -261.738368) (xy 268.550475 -261.694331)
			(xy 268.586727 -261.65526) (xy 268.628398 -261.622029) (xy 268.674556 -261.59538) (xy 268.72417 -261.575908)
			(xy 268.776132 -261.564048) (xy 268.829282 -261.560065) (xy 268.882432 -261.564048) (xy 268.934394 -261.575908)
			(xy 268.984008 -261.59538) (xy 269.030166 -261.622029) (xy 269.071837 -261.65526) (xy 269.108089 -261.694331)
			(xy 269.138113 -261.738368) (xy 269.161239 -261.786389) (xy 269.176949 -261.837319) (xy 269.184892 -261.890023)
			(xy 269.18539 -261.916672) (xy 269.184892 -261.943321) (xy 283.561272 -261.943321) (xy 283.561272 -261.890023)
			(xy 283.569215 -261.837319) (xy 283.584925 -261.786389) (xy 283.608051 -261.738368) (xy 283.638075 -261.694331)
			(xy 283.674327 -261.65526) (xy 283.715998 -261.622029) (xy 283.762156 -261.59538) (xy 283.81177 -261.575908)
			(xy 283.863732 -261.564048) (xy 283.916882 -261.560065) (xy 283.970032 -261.564048) (xy 284.021994 -261.575908)
			(xy 284.071608 -261.59538) (xy 284.117766 -261.622029) (xy 284.159437 -261.65526) (xy 284.195689 -261.694331)
			(xy 284.225713 -261.738368) (xy 284.248839 -261.786389) (xy 284.264549 -261.837319) (xy 284.272492 -261.890023)
			(xy 284.27299 -261.916672) (xy 284.272492 -261.943321) (xy 298.674272 -261.943321) (xy 298.674272 -261.890023)
			(xy 298.682215 -261.837319) (xy 298.697925 -261.786389) (xy 298.721051 -261.738368) (xy 298.751075 -261.694331)
			(xy 298.787327 -261.65526) (xy 298.828998 -261.622029) (xy 298.875156 -261.59538) (xy 298.92477 -261.575908)
			(xy 298.976732 -261.564048) (xy 299.029882 -261.560065) (xy 299.083032 -261.564048) (xy 299.134994 -261.575908)
			(xy 299.184608 -261.59538) (xy 299.230766 -261.622029) (xy 299.272437 -261.65526) (xy 299.308689 -261.694331)
			(xy 299.338713 -261.738368) (xy 299.361839 -261.786389) (xy 299.377549 -261.837319) (xy 299.385492 -261.890023)
			(xy 299.38599 -261.916672) (xy 299.385492 -261.943321) (xy 299.377549 -261.996025) (xy 299.361839 -262.046955)
			(xy 299.338713 -262.094976) (xy 299.308689 -262.139013) (xy 299.272437 -262.178084) (xy 299.230766 -262.211315)
			(xy 299.184608 -262.237964) (xy 299.134994 -262.257436) (xy 299.083032 -262.269296) (xy 299.029882 -262.27328)
			(xy 298.976732 -262.269296) (xy 298.92477 -262.257436) (xy 298.875156 -262.237964) (xy 298.828998 -262.211315)
			(xy 298.787327 -262.178084) (xy 298.751075 -262.139013) (xy 298.721051 -262.094976) (xy 298.697925 -262.046955)
			(xy 298.682215 -261.996025) (xy 298.674272 -261.943321) (xy 284.272492 -261.943321) (xy 284.264549 -261.996025)
			(xy 284.248839 -262.046955) (xy 284.225713 -262.094976) (xy 284.195689 -262.139013) (xy 284.159437 -262.178084)
			(xy 284.117766 -262.211315) (xy 284.071608 -262.237964) (xy 284.021994 -262.257436) (xy 283.970032 -262.269296)
			(xy 283.916882 -262.27328) (xy 283.863732 -262.269296) (xy 283.81177 -262.257436) (xy 283.762156 -262.237964)
			(xy 283.715998 -262.211315) (xy 283.674327 -262.178084) (xy 283.638075 -262.139013) (xy 283.608051 -262.094976)
			(xy 283.584925 -262.046955) (xy 283.569215 -261.996025) (xy 283.561272 -261.943321) (xy 269.184892 -261.943321)
			(xy 269.176949 -261.996025) (xy 269.161239 -262.046955) (xy 269.138113 -262.094976) (xy 269.108089 -262.139013)
			(xy 269.071837 -262.178084) (xy 269.030166 -262.211315) (xy 268.984008 -262.237964) (xy 268.934394 -262.257436)
			(xy 268.882432 -262.269296) (xy 268.829282 -262.27328) (xy 268.776132 -262.269296) (xy 268.72417 -262.257436)
			(xy 268.674556 -262.237964) (xy 268.628398 -262.211315) (xy 268.586727 -262.178084) (xy 268.550475 -262.139013)
			(xy 268.520451 -262.094976) (xy 268.497325 -262.046955) (xy 268.481615 -261.996025) (xy 268.473672 -261.943321)
			(xy 254 -261.943321) (xy 254 -262.793459) (xy 264.373604 -262.793459) (xy 264.373604 -262.740161)
			(xy 264.381547 -262.687457) (xy 264.397257 -262.636527) (xy 264.420383 -262.588506) (xy 264.450407 -262.544469)
			(xy 264.486659 -262.505398) (xy 264.52833 -262.472167) (xy 264.574488 -262.445518) (xy 264.624102 -262.426046)
			(xy 264.676064 -262.414186) (xy 264.729214 -262.410203) (xy 264.782364 -262.414186) (xy 264.834326 -262.426046)
			(xy 264.88394 -262.445518) (xy 264.930098 -262.472167) (xy 264.971769 -262.505398) (xy 265.008021 -262.544469)
			(xy 265.038045 -262.588506) (xy 265.061171 -262.636527) (xy 265.076881 -262.687457) (xy 265.084824 -262.740161)
			(xy 265.085322 -262.76681) (xy 265.084824 -262.793459) (xy 279.461204 -262.793459) (xy 279.461204 -262.740161)
			(xy 279.469147 -262.687457) (xy 279.484857 -262.636527) (xy 279.507983 -262.588506) (xy 279.538007 -262.544469)
			(xy 279.574259 -262.505398) (xy 279.61593 -262.472167) (xy 279.662088 -262.445518) (xy 279.711702 -262.426046)
			(xy 279.763664 -262.414186) (xy 279.816814 -262.410203) (xy 279.869964 -262.414186) (xy 279.921926 -262.426046)
			(xy 279.97154 -262.445518) (xy 280.017698 -262.472167) (xy 280.059369 -262.505398) (xy 280.095621 -262.544469)
			(xy 280.125645 -262.588506) (xy 280.148771 -262.636527) (xy 280.164481 -262.687457) (xy 280.172424 -262.740161)
			(xy 280.172922 -262.76681) (xy 280.172424 -262.793459) (xy 294.548804 -262.793459) (xy 294.548804 -262.740161)
			(xy 294.556747 -262.687457) (xy 294.572457 -262.636527) (xy 294.595583 -262.588506) (xy 294.625607 -262.544469)
			(xy 294.661859 -262.505398) (xy 294.70353 -262.472167) (xy 294.749688 -262.445518) (xy 294.799302 -262.426046)
			(xy 294.851264 -262.414186) (xy 294.904414 -262.410203) (xy 294.957564 -262.414186) (xy 295.009526 -262.426046)
			(xy 295.05914 -262.445518) (xy 295.105298 -262.472167) (xy 295.146969 -262.505398) (xy 295.183221 -262.544469)
			(xy 295.213245 -262.588506) (xy 295.236371 -262.636527) (xy 295.252081 -262.687457) (xy 295.260024 -262.740161)
			(xy 295.260522 -262.76681) (xy 295.260024 -262.793459) (xy 295.252081 -262.846163) (xy 295.236371 -262.897093)
			(xy 295.213245 -262.945114) (xy 295.183221 -262.989151) (xy 295.146969 -263.028222) (xy 295.105298 -263.061453)
			(xy 295.05914 -263.088102) (xy 295.009526 -263.107574) (xy 294.957564 -263.119434) (xy 294.904414 -263.123418)
			(xy 294.851264 -263.119434) (xy 294.799302 -263.107574) (xy 294.749688 -263.088102) (xy 294.70353 -263.061453)
			(xy 294.661859 -263.028222) (xy 294.625607 -262.989151) (xy 294.595583 -262.945114) (xy 294.572457 -262.897093)
			(xy 294.556747 -262.846163) (xy 294.548804 -262.793459) (xy 280.172424 -262.793459) (xy 280.164481 -262.846163)
			(xy 280.148771 -262.897093) (xy 280.125645 -262.945114) (xy 280.095621 -262.989151) (xy 280.059369 -263.028222)
			(xy 280.017698 -263.061453) (xy 279.97154 -263.088102) (xy 279.921926 -263.107574) (xy 279.869964 -263.119434)
			(xy 279.816814 -263.123418) (xy 279.763664 -263.119434) (xy 279.711702 -263.107574) (xy 279.662088 -263.088102)
			(xy 279.61593 -263.061453) (xy 279.574259 -263.028222) (xy 279.538007 -262.989151) (xy 279.507983 -262.945114)
			(xy 279.484857 -262.897093) (xy 279.469147 -262.846163) (xy 279.461204 -262.793459) (xy 265.084824 -262.793459)
			(xy 265.076881 -262.846163) (xy 265.061171 -262.897093) (xy 265.038045 -262.945114) (xy 265.008021 -262.989151)
			(xy 264.971769 -263.028222) (xy 264.930098 -263.061453) (xy 264.88394 -263.088102) (xy 264.834326 -263.107574)
			(xy 264.782364 -263.119434) (xy 264.729214 -263.123418) (xy 264.676064 -263.119434) (xy 264.624102 -263.107574)
			(xy 264.574488 -263.088102) (xy 264.52833 -263.061453) (xy 264.486659 -263.028222) (xy 264.450407 -262.989151)
			(xy 264.420383 -262.945114) (xy 264.397257 -262.897093) (xy 264.381547 -262.846163) (xy 264.373604 -262.793459)
			(xy 254 -262.793459) (xy 254 -263.643343) (xy 268.473672 -263.643343) (xy 268.473672 -263.590045)
			(xy 268.481615 -263.537341) (xy 268.497325 -263.486411) (xy 268.520451 -263.43839) (xy 268.550475 -263.394353)
			(xy 268.586727 -263.355282) (xy 268.628398 -263.322051) (xy 268.674556 -263.295402) (xy 268.72417 -263.27593)
			(xy 268.776132 -263.26407) (xy 268.829282 -263.260087) (xy 268.882432 -263.26407) (xy 268.934394 -263.27593)
			(xy 268.984008 -263.295402) (xy 269.030166 -263.322051) (xy 269.071837 -263.355282) (xy 269.108089 -263.394353)
			(xy 269.138113 -263.43839) (xy 269.161239 -263.486411) (xy 269.176949 -263.537341) (xy 269.184892 -263.590045)
			(xy 269.18539 -263.616694) (xy 269.184892 -263.643343) (xy 283.561272 -263.643343) (xy 283.561272 -263.590045)
			(xy 283.569215 -263.537341) (xy 283.584925 -263.486411) (xy 283.608051 -263.43839) (xy 283.638075 -263.394353)
			(xy 283.674327 -263.355282) (xy 283.715998 -263.322051) (xy 283.762156 -263.295402) (xy 283.81177 -263.27593)
			(xy 283.863732 -263.26407) (xy 283.916882 -263.260087) (xy 283.970032 -263.26407) (xy 284.021994 -263.27593)
			(xy 284.071608 -263.295402) (xy 284.117766 -263.322051) (xy 284.159437 -263.355282) (xy 284.195689 -263.394353)
			(xy 284.225713 -263.43839) (xy 284.248839 -263.486411) (xy 284.264549 -263.537341) (xy 284.272492 -263.590045)
			(xy 284.27299 -263.616694) (xy 284.272492 -263.643343) (xy 298.674272 -263.643343) (xy 298.674272 -263.590045)
			(xy 298.682215 -263.537341) (xy 298.697925 -263.486411) (xy 298.721051 -263.43839) (xy 298.751075 -263.394353)
			(xy 298.787327 -263.355282) (xy 298.828998 -263.322051) (xy 298.875156 -263.295402) (xy 298.92477 -263.27593)
			(xy 298.976732 -263.26407) (xy 299.029882 -263.260087) (xy 299.083032 -263.26407) (xy 299.134994 -263.27593)
			(xy 299.184608 -263.295402) (xy 299.230766 -263.322051) (xy 299.272437 -263.355282) (xy 299.308689 -263.394353)
			(xy 299.338713 -263.43839) (xy 299.361839 -263.486411) (xy 299.377549 -263.537341) (xy 299.385492 -263.590045)
			(xy 299.38599 -263.616694) (xy 299.385492 -263.643343) (xy 299.377549 -263.696047) (xy 299.361839 -263.746977)
			(xy 299.338713 -263.794998) (xy 299.308689 -263.839035) (xy 299.272437 -263.878106) (xy 299.230766 -263.911337)
			(xy 299.184608 -263.937986) (xy 299.134994 -263.957458) (xy 299.083032 -263.969318) (xy 299.029882 -263.973302)
			(xy 298.976732 -263.969318) (xy 298.92477 -263.957458) (xy 298.875156 -263.937986) (xy 298.828998 -263.911337)
			(xy 298.787327 -263.878106) (xy 298.751075 -263.839035) (xy 298.721051 -263.794998) (xy 298.697925 -263.746977)
			(xy 298.682215 -263.696047) (xy 298.674272 -263.643343) (xy 284.272492 -263.643343) (xy 284.264549 -263.696047)
			(xy 284.248839 -263.746977) (xy 284.225713 -263.794998) (xy 284.195689 -263.839035) (xy 284.159437 -263.878106)
			(xy 284.117766 -263.911337) (xy 284.071608 -263.937986) (xy 284.021994 -263.957458) (xy 283.970032 -263.969318)
			(xy 283.916882 -263.973302) (xy 283.863732 -263.969318) (xy 283.81177 -263.957458) (xy 283.762156 -263.937986)
			(xy 283.715998 -263.911337) (xy 283.674327 -263.878106) (xy 283.638075 -263.839035) (xy 283.608051 -263.794998)
			(xy 283.584925 -263.746977) (xy 283.569215 -263.696047) (xy 283.561272 -263.643343) (xy 269.184892 -263.643343)
			(xy 269.176949 -263.696047) (xy 269.161239 -263.746977) (xy 269.138113 -263.794998) (xy 269.108089 -263.839035)
			(xy 269.071837 -263.878106) (xy 269.030166 -263.911337) (xy 268.984008 -263.937986) (xy 268.934394 -263.957458)
			(xy 268.882432 -263.969318) (xy 268.829282 -263.973302) (xy 268.776132 -263.969318) (xy 268.72417 -263.957458)
			(xy 268.674556 -263.937986) (xy 268.628398 -263.911337) (xy 268.586727 -263.878106) (xy 268.550475 -263.839035)
			(xy 268.520451 -263.794998) (xy 268.497325 -263.746977) (xy 268.481615 -263.696047) (xy 268.473672 -263.643343)
			(xy 254 -263.643343) (xy 254 -264.493227) (xy 264.373604 -264.493227) (xy 264.373604 -264.439929)
			(xy 264.381547 -264.387225) (xy 264.397257 -264.336295) (xy 264.420383 -264.288274) (xy 264.450407 -264.244237)
			(xy 264.486659 -264.205166) (xy 264.52833 -264.171935) (xy 264.574488 -264.145286) (xy 264.624102 -264.125814)
			(xy 264.676064 -264.113954) (xy 264.729214 -264.109971) (xy 264.782364 -264.113954) (xy 264.834326 -264.125814)
			(xy 264.88394 -264.145286) (xy 264.930098 -264.171935) (xy 264.971769 -264.205166) (xy 265.008021 -264.244237)
			(xy 265.038045 -264.288274) (xy 265.061171 -264.336295) (xy 265.076881 -264.387225) (xy 265.084824 -264.439929)
			(xy 265.085322 -264.466578) (xy 265.084824 -264.493227) (xy 279.461204 -264.493227) (xy 279.461204 -264.439929)
			(xy 279.469147 -264.387225) (xy 279.484857 -264.336295) (xy 279.507983 -264.288274) (xy 279.538007 -264.244237)
			(xy 279.574259 -264.205166) (xy 279.61593 -264.171935) (xy 279.662088 -264.145286) (xy 279.711702 -264.125814)
			(xy 279.763664 -264.113954) (xy 279.816814 -264.109971) (xy 279.869964 -264.113954) (xy 279.921926 -264.125814)
			(xy 279.97154 -264.145286) (xy 280.017698 -264.171935) (xy 280.059369 -264.205166) (xy 280.095621 -264.244237)
			(xy 280.125645 -264.288274) (xy 280.148771 -264.336295) (xy 280.164481 -264.387225) (xy 280.172424 -264.439929)
			(xy 280.172922 -264.466578) (xy 280.172424 -264.493227) (xy 294.548804 -264.493227) (xy 294.548804 -264.439929)
			(xy 294.556747 -264.387225) (xy 294.572457 -264.336295) (xy 294.595583 -264.288274) (xy 294.625607 -264.244237)
			(xy 294.661859 -264.205166) (xy 294.70353 -264.171935) (xy 294.749688 -264.145286) (xy 294.799302 -264.125814)
			(xy 294.851264 -264.113954) (xy 294.904414 -264.109971) (xy 294.957564 -264.113954) (xy 295.009526 -264.125814)
			(xy 295.05914 -264.145286) (xy 295.105298 -264.171935) (xy 295.146969 -264.205166) (xy 295.183221 -264.244237)
			(xy 295.213245 -264.288274) (xy 295.236371 -264.336295) (xy 295.252081 -264.387225) (xy 295.260024 -264.439929)
			(xy 295.260522 -264.466578) (xy 295.260024 -264.493227) (xy 295.252081 -264.545931) (xy 295.236371 -264.596861)
			(xy 295.213245 -264.644882) (xy 295.183221 -264.688919) (xy 295.146969 -264.72799) (xy 295.105298 -264.761221)
			(xy 295.05914 -264.78787) (xy 295.009526 -264.807342) (xy 294.957564 -264.819202) (xy 294.904414 -264.823186)
			(xy 294.851264 -264.819202) (xy 294.799302 -264.807342) (xy 294.749688 -264.78787) (xy 294.70353 -264.761221)
			(xy 294.661859 -264.72799) (xy 294.625607 -264.688919) (xy 294.595583 -264.644882) (xy 294.572457 -264.596861)
			(xy 294.556747 -264.545931) (xy 294.548804 -264.493227) (xy 280.172424 -264.493227) (xy 280.164481 -264.545931)
			(xy 280.148771 -264.596861) (xy 280.125645 -264.644882) (xy 280.095621 -264.688919) (xy 280.059369 -264.72799)
			(xy 280.017698 -264.761221) (xy 279.97154 -264.78787) (xy 279.921926 -264.807342) (xy 279.869964 -264.819202)
			(xy 279.816814 -264.823186) (xy 279.763664 -264.819202) (xy 279.711702 -264.807342) (xy 279.662088 -264.78787)
			(xy 279.61593 -264.761221) (xy 279.574259 -264.72799) (xy 279.538007 -264.688919) (xy 279.507983 -264.644882)
			(xy 279.484857 -264.596861) (xy 279.469147 -264.545931) (xy 279.461204 -264.493227) (xy 265.084824 -264.493227)
			(xy 265.076881 -264.545931) (xy 265.061171 -264.596861) (xy 265.038045 -264.644882) (xy 265.008021 -264.688919)
			(xy 264.971769 -264.72799) (xy 264.930098 -264.761221) (xy 264.88394 -264.78787) (xy 264.834326 -264.807342)
			(xy 264.782364 -264.819202) (xy 264.729214 -264.823186) (xy 264.676064 -264.819202) (xy 264.624102 -264.807342)
			(xy 264.574488 -264.78787) (xy 264.52833 -264.761221) (xy 264.486659 -264.72799) (xy 264.450407 -264.688919)
			(xy 264.420383 -264.644882) (xy 264.397257 -264.596861) (xy 264.381547 -264.545931) (xy 264.373604 -264.493227)
			(xy 254 -264.493227) (xy 254 -265.343365) (xy 268.473672 -265.343365) (xy 268.473672 -265.290067)
			(xy 268.481615 -265.237363) (xy 268.497325 -265.186433) (xy 268.520451 -265.138412) (xy 268.550475 -265.094375)
			(xy 268.586727 -265.055304) (xy 268.628398 -265.022073) (xy 268.674556 -264.995424) (xy 268.72417 -264.975952)
			(xy 268.776132 -264.964092) (xy 268.829282 -264.960109) (xy 268.882432 -264.964092) (xy 268.934394 -264.975952)
			(xy 268.984008 -264.995424) (xy 269.030166 -265.022073) (xy 269.071837 -265.055304) (xy 269.108089 -265.094375)
			(xy 269.138113 -265.138412) (xy 269.161239 -265.186433) (xy 269.176949 -265.237363) (xy 269.184892 -265.290067)
			(xy 269.18539 -265.316716) (xy 269.184892 -265.343365) (xy 283.561272 -265.343365) (xy 283.561272 -265.290067)
			(xy 283.569215 -265.237363) (xy 283.584925 -265.186433) (xy 283.608051 -265.138412) (xy 283.638075 -265.094375)
			(xy 283.674327 -265.055304) (xy 283.715998 -265.022073) (xy 283.762156 -264.995424) (xy 283.81177 -264.975952)
			(xy 283.863732 -264.964092) (xy 283.916882 -264.960109) (xy 283.970032 -264.964092) (xy 284.021994 -264.975952)
			(xy 284.071608 -264.995424) (xy 284.117766 -265.022073) (xy 284.159437 -265.055304) (xy 284.195689 -265.094375)
			(xy 284.225713 -265.138412) (xy 284.248839 -265.186433) (xy 284.264549 -265.237363) (xy 284.272492 -265.290067)
			(xy 284.27299 -265.316716) (xy 284.272492 -265.343365) (xy 298.674272 -265.343365) (xy 298.674272 -265.290067)
			(xy 298.682215 -265.237363) (xy 298.697925 -265.186433) (xy 298.721051 -265.138412) (xy 298.751075 -265.094375)
			(xy 298.787327 -265.055304) (xy 298.828998 -265.022073) (xy 298.875156 -264.995424) (xy 298.92477 -264.975952)
			(xy 298.976732 -264.964092) (xy 299.029882 -264.960109) (xy 299.083032 -264.964092) (xy 299.134994 -264.975952)
			(xy 299.184608 -264.995424) (xy 299.230766 -265.022073) (xy 299.272437 -265.055304) (xy 299.308689 -265.094375)
			(xy 299.338713 -265.138412) (xy 299.361839 -265.186433) (xy 299.377549 -265.237363) (xy 299.385492 -265.290067)
			(xy 299.38599 -265.316716) (xy 299.385492 -265.343365) (xy 299.377549 -265.396069) (xy 299.361839 -265.446999)
			(xy 299.338713 -265.49502) (xy 299.308689 -265.539057) (xy 299.272437 -265.578128) (xy 299.230766 -265.611359)
			(xy 299.184608 -265.638008) (xy 299.134994 -265.65748) (xy 299.083032 -265.66934) (xy 299.029882 -265.673324)
			(xy 298.976732 -265.66934) (xy 298.92477 -265.65748) (xy 298.875156 -265.638008) (xy 298.828998 -265.611359)
			(xy 298.787327 -265.578128) (xy 298.751075 -265.539057) (xy 298.721051 -265.49502) (xy 298.697925 -265.446999)
			(xy 298.682215 -265.396069) (xy 298.674272 -265.343365) (xy 284.272492 -265.343365) (xy 284.264549 -265.396069)
			(xy 284.248839 -265.446999) (xy 284.225713 -265.49502) (xy 284.195689 -265.539057) (xy 284.159437 -265.578128)
			(xy 284.117766 -265.611359) (xy 284.071608 -265.638008) (xy 284.021994 -265.65748) (xy 283.970032 -265.66934)
			(xy 283.916882 -265.673324) (xy 283.863732 -265.66934) (xy 283.81177 -265.65748) (xy 283.762156 -265.638008)
			(xy 283.715998 -265.611359) (xy 283.674327 -265.578128) (xy 283.638075 -265.539057) (xy 283.608051 -265.49502)
			(xy 283.584925 -265.446999) (xy 283.569215 -265.396069) (xy 283.561272 -265.343365) (xy 269.184892 -265.343365)
			(xy 269.176949 -265.396069) (xy 269.161239 -265.446999) (xy 269.138113 -265.49502) (xy 269.108089 -265.539057)
			(xy 269.071837 -265.578128) (xy 269.030166 -265.611359) (xy 268.984008 -265.638008) (xy 268.934394 -265.65748)
			(xy 268.882432 -265.66934) (xy 268.829282 -265.673324) (xy 268.776132 -265.66934) (xy 268.72417 -265.65748)
			(xy 268.674556 -265.638008) (xy 268.628398 -265.611359) (xy 268.586727 -265.578128) (xy 268.550475 -265.539057)
			(xy 268.520451 -265.49502) (xy 268.497325 -265.446999) (xy 268.481615 -265.396069) (xy 268.473672 -265.343365)
			(xy 254 -265.343365) (xy 254 -266.193249) (xy 264.373604 -266.193249) (xy 264.373604 -266.139951)
			(xy 264.381547 -266.087247) (xy 264.397257 -266.036317) (xy 264.420383 -265.988296) (xy 264.450407 -265.944259)
			(xy 264.486659 -265.905188) (xy 264.52833 -265.871957) (xy 264.574488 -265.845308) (xy 264.624102 -265.825836)
			(xy 264.676064 -265.813976) (xy 264.729214 -265.809993) (xy 264.782364 -265.813976) (xy 264.834326 -265.825836)
			(xy 264.88394 -265.845308) (xy 264.930098 -265.871957) (xy 264.971769 -265.905188) (xy 265.008021 -265.944259)
			(xy 265.038045 -265.988296) (xy 265.061171 -266.036317) (xy 265.076881 -266.087247) (xy 265.084824 -266.139951)
			(xy 265.085322 -266.1666) (xy 265.084824 -266.193249) (xy 279.461204 -266.193249) (xy 279.461204 -266.139951)
			(xy 279.469147 -266.087247) (xy 279.484857 -266.036317) (xy 279.507983 -265.988296) (xy 279.538007 -265.944259)
			(xy 279.574259 -265.905188) (xy 279.61593 -265.871957) (xy 279.662088 -265.845308) (xy 279.711702 -265.825836)
			(xy 279.763664 -265.813976) (xy 279.816814 -265.809993) (xy 279.869964 -265.813976) (xy 279.921926 -265.825836)
			(xy 279.97154 -265.845308) (xy 280.017698 -265.871957) (xy 280.059369 -265.905188) (xy 280.095621 -265.944259)
			(xy 280.125645 -265.988296) (xy 280.148771 -266.036317) (xy 280.164481 -266.087247) (xy 280.172424 -266.139951)
			(xy 280.172922 -266.1666) (xy 280.172424 -266.193249) (xy 294.548804 -266.193249) (xy 294.548804 -266.139951)
			(xy 294.556747 -266.087247) (xy 294.572457 -266.036317) (xy 294.595583 -265.988296) (xy 294.625607 -265.944259)
			(xy 294.661859 -265.905188) (xy 294.70353 -265.871957) (xy 294.749688 -265.845308) (xy 294.799302 -265.825836)
			(xy 294.851264 -265.813976) (xy 294.904414 -265.809993) (xy 294.957564 -265.813976) (xy 295.009526 -265.825836)
			(xy 295.05914 -265.845308) (xy 295.105298 -265.871957) (xy 295.146969 -265.905188) (xy 295.183221 -265.944259)
			(xy 295.213245 -265.988296) (xy 295.236371 -266.036317) (xy 295.252081 -266.087247) (xy 295.260024 -266.139951)
			(xy 295.260522 -266.1666) (xy 295.260024 -266.193249) (xy 295.252081 -266.245953) (xy 295.236371 -266.296883)
			(xy 295.213245 -266.344904) (xy 295.183221 -266.388941) (xy 295.146969 -266.428012) (xy 295.105298 -266.461243)
			(xy 295.05914 -266.487892) (xy 295.009526 -266.507364) (xy 294.957564 -266.519224) (xy 294.904414 -266.523208)
			(xy 294.851264 -266.519224) (xy 294.799302 -266.507364) (xy 294.749688 -266.487892) (xy 294.70353 -266.461243)
			(xy 294.661859 -266.428012) (xy 294.625607 -266.388941) (xy 294.595583 -266.344904) (xy 294.572457 -266.296883)
			(xy 294.556747 -266.245953) (xy 294.548804 -266.193249) (xy 280.172424 -266.193249) (xy 280.164481 -266.245953)
			(xy 280.148771 -266.296883) (xy 280.125645 -266.344904) (xy 280.095621 -266.388941) (xy 280.059369 -266.428012)
			(xy 280.017698 -266.461243) (xy 279.97154 -266.487892) (xy 279.921926 -266.507364) (xy 279.869964 -266.519224)
			(xy 279.816814 -266.523208) (xy 279.763664 -266.519224) (xy 279.711702 -266.507364) (xy 279.662088 -266.487892)
			(xy 279.61593 -266.461243) (xy 279.574259 -266.428012) (xy 279.538007 -266.388941) (xy 279.507983 -266.344904)
			(xy 279.484857 -266.296883) (xy 279.469147 -266.245953) (xy 279.461204 -266.193249) (xy 265.084824 -266.193249)
			(xy 265.076881 -266.245953) (xy 265.061171 -266.296883) (xy 265.038045 -266.344904) (xy 265.008021 -266.388941)
			(xy 264.971769 -266.428012) (xy 264.930098 -266.461243) (xy 264.88394 -266.487892) (xy 264.834326 -266.507364)
			(xy 264.782364 -266.519224) (xy 264.729214 -266.523208) (xy 264.676064 -266.519224) (xy 264.624102 -266.507364)
			(xy 264.574488 -266.487892) (xy 264.52833 -266.461243) (xy 264.486659 -266.428012) (xy 264.450407 -266.388941)
			(xy 264.420383 -266.344904) (xy 264.397257 -266.296883) (xy 264.381547 -266.245953) (xy 264.373604 -266.193249)
			(xy 254 -266.193249) (xy 254 -267.043387) (xy 260.929872 -267.043387) (xy 260.929872 -266.990089)
			(xy 260.937815 -266.937385) (xy 260.953525 -266.886455) (xy 260.976651 -266.838434) (xy 261.006675 -266.794397)
			(xy 261.042927 -266.755326) (xy 261.084598 -266.722095) (xy 261.130756 -266.695446) (xy 261.18037 -266.675974)
			(xy 261.232332 -266.664114) (xy 261.285482 -266.660131) (xy 261.338632 -266.664114) (xy 261.390594 -266.675974)
			(xy 261.440208 -266.695446) (xy 261.486366 -266.722095) (xy 261.528037 -266.755326) (xy 261.564289 -266.794397)
			(xy 261.594313 -266.838434) (xy 261.617439 -266.886455) (xy 261.633149 -266.937385) (xy 261.641092 -266.990089)
			(xy 261.64159 -267.016738) (xy 261.641092 -267.043387) (xy 268.473672 -267.043387) (xy 268.473672 -266.990089)
			(xy 268.481615 -266.937385) (xy 268.497325 -266.886455) (xy 268.520451 -266.838434) (xy 268.550475 -266.794397)
			(xy 268.586727 -266.755326) (xy 268.628398 -266.722095) (xy 268.674556 -266.695446) (xy 268.72417 -266.675974)
			(xy 268.776132 -266.664114) (xy 268.829282 -266.660131) (xy 268.882432 -266.664114) (xy 268.934394 -266.675974)
			(xy 268.984008 -266.695446) (xy 269.030166 -266.722095) (xy 269.071837 -266.755326) (xy 269.108089 -266.794397)
			(xy 269.138113 -266.838434) (xy 269.161239 -266.886455) (xy 269.176949 -266.937385) (xy 269.184892 -266.990089)
			(xy 269.18539 -267.016738) (xy 269.184892 -267.043387) (xy 276.017472 -267.043387) (xy 276.017472 -266.990089)
			(xy 276.025415 -266.937385) (xy 276.041125 -266.886455) (xy 276.064251 -266.838434) (xy 276.094275 -266.794397)
			(xy 276.130527 -266.755326) (xy 276.172198 -266.722095) (xy 276.218356 -266.695446) (xy 276.26797 -266.675974)
			(xy 276.319932 -266.664114) (xy 276.373082 -266.660131) (xy 276.426232 -266.664114) (xy 276.478194 -266.675974)
			(xy 276.527808 -266.695446) (xy 276.573966 -266.722095) (xy 276.615637 -266.755326) (xy 276.651889 -266.794397)
			(xy 276.681913 -266.838434) (xy 276.705039 -266.886455) (xy 276.720749 -266.937385) (xy 276.728692 -266.990089)
			(xy 276.72919 -267.016738) (xy 276.728692 -267.043387) (xy 283.561272 -267.043387) (xy 283.561272 -266.990089)
			(xy 283.569215 -266.937385) (xy 283.584925 -266.886455) (xy 283.608051 -266.838434) (xy 283.638075 -266.794397)
			(xy 283.674327 -266.755326) (xy 283.715998 -266.722095) (xy 283.762156 -266.695446) (xy 283.81177 -266.675974)
			(xy 283.863732 -266.664114) (xy 283.916882 -266.660131) (xy 283.970032 -266.664114) (xy 284.021994 -266.675974)
			(xy 284.071608 -266.695446) (xy 284.117766 -266.722095) (xy 284.159437 -266.755326) (xy 284.195689 -266.794397)
			(xy 284.225713 -266.838434) (xy 284.248839 -266.886455) (xy 284.264549 -266.937385) (xy 284.272492 -266.990089)
			(xy 284.27299 -267.016738) (xy 284.272492 -267.043387) (xy 291.105072 -267.043387) (xy 291.105072 -266.990089)
			(xy 291.113015 -266.937385) (xy 291.128725 -266.886455) (xy 291.151851 -266.838434) (xy 291.181875 -266.794397)
			(xy 291.218127 -266.755326) (xy 291.259798 -266.722095) (xy 291.305956 -266.695446) (xy 291.35557 -266.675974)
			(xy 291.407532 -266.664114) (xy 291.460682 -266.660131) (xy 291.513832 -266.664114) (xy 291.565794 -266.675974)
			(xy 291.615408 -266.695446) (xy 291.661566 -266.722095) (xy 291.703237 -266.755326) (xy 291.739489 -266.794397)
			(xy 291.769513 -266.838434) (xy 291.792639 -266.886455) (xy 291.808349 -266.937385) (xy 291.816292 -266.990089)
			(xy 291.81679 -267.016738) (xy 291.816292 -267.043387) (xy 298.674272 -267.043387) (xy 298.674272 -266.990089)
			(xy 298.682215 -266.937385) (xy 298.697925 -266.886455) (xy 298.721051 -266.838434) (xy 298.751075 -266.794397)
			(xy 298.787327 -266.755326) (xy 298.828998 -266.722095) (xy 298.875156 -266.695446) (xy 298.92477 -266.675974)
			(xy 298.976732 -266.664114) (xy 299.029882 -266.660131) (xy 299.083032 -266.664114) (xy 299.134994 -266.675974)
			(xy 299.184608 -266.695446) (xy 299.230766 -266.722095) (xy 299.272437 -266.755326) (xy 299.308689 -266.794397)
			(xy 299.338713 -266.838434) (xy 299.361839 -266.886455) (xy 299.377549 -266.937385) (xy 299.385492 -266.990089)
			(xy 299.38599 -267.016738) (xy 299.385492 -267.043387) (xy 299.377549 -267.096091) (xy 299.361839 -267.147021)
			(xy 299.338713 -267.195042) (xy 299.308689 -267.239079) (xy 299.272437 -267.27815) (xy 299.230766 -267.311381)
			(xy 299.184608 -267.33803) (xy 299.134994 -267.357502) (xy 299.083032 -267.369362) (xy 299.029882 -267.373346)
			(xy 298.976732 -267.369362) (xy 298.92477 -267.357502) (xy 298.875156 -267.33803) (xy 298.828998 -267.311381)
			(xy 298.787327 -267.27815) (xy 298.751075 -267.239079) (xy 298.721051 -267.195042) (xy 298.697925 -267.147021)
			(xy 298.682215 -267.096091) (xy 298.674272 -267.043387) (xy 291.816292 -267.043387) (xy 291.808349 -267.096091)
			(xy 291.792639 -267.147021) (xy 291.769513 -267.195042) (xy 291.739489 -267.239079) (xy 291.703237 -267.27815)
			(xy 291.661566 -267.311381) (xy 291.615408 -267.33803) (xy 291.565794 -267.357502) (xy 291.513832 -267.369362)
			(xy 291.460682 -267.373346) (xy 291.407532 -267.369362) (xy 291.35557 -267.357502) (xy 291.305956 -267.33803)
			(xy 291.259798 -267.311381) (xy 291.218127 -267.27815) (xy 291.181875 -267.239079) (xy 291.151851 -267.195042)
			(xy 291.128725 -267.147021) (xy 291.113015 -267.096091) (xy 291.105072 -267.043387) (xy 284.272492 -267.043387)
			(xy 284.264549 -267.096091) (xy 284.248839 -267.147021) (xy 284.225713 -267.195042) (xy 284.195689 -267.239079)
			(xy 284.159437 -267.27815) (xy 284.117766 -267.311381) (xy 284.071608 -267.33803) (xy 284.021994 -267.357502)
			(xy 283.970032 -267.369362) (xy 283.916882 -267.373346) (xy 283.863732 -267.369362) (xy 283.81177 -267.357502)
			(xy 283.762156 -267.33803) (xy 283.715998 -267.311381) (xy 283.674327 -267.27815) (xy 283.638075 -267.239079)
			(xy 283.608051 -267.195042) (xy 283.584925 -267.147021) (xy 283.569215 -267.096091) (xy 283.561272 -267.043387)
			(xy 276.728692 -267.043387) (xy 276.720749 -267.096091) (xy 276.705039 -267.147021) (xy 276.681913 -267.195042)
			(xy 276.651889 -267.239079) (xy 276.615637 -267.27815) (xy 276.573966 -267.311381) (xy 276.527808 -267.33803)
			(xy 276.478194 -267.357502) (xy 276.426232 -267.369362) (xy 276.373082 -267.373346) (xy 276.319932 -267.369362)
			(xy 276.26797 -267.357502) (xy 276.218356 -267.33803) (xy 276.172198 -267.311381) (xy 276.130527 -267.27815)
			(xy 276.094275 -267.239079) (xy 276.064251 -267.195042) (xy 276.041125 -267.147021) (xy 276.025415 -267.096091)
			(xy 276.017472 -267.043387) (xy 269.184892 -267.043387) (xy 269.176949 -267.096091) (xy 269.161239 -267.147021)
			(xy 269.138113 -267.195042) (xy 269.108089 -267.239079) (xy 269.071837 -267.27815) (xy 269.030166 -267.311381)
			(xy 268.984008 -267.33803) (xy 268.934394 -267.357502) (xy 268.882432 -267.369362) (xy 268.829282 -267.373346)
			(xy 268.776132 -267.369362) (xy 268.72417 -267.357502) (xy 268.674556 -267.33803) (xy 268.628398 -267.311381)
			(xy 268.586727 -267.27815) (xy 268.550475 -267.239079) (xy 268.520451 -267.195042) (xy 268.497325 -267.147021)
			(xy 268.481615 -267.096091) (xy 268.473672 -267.043387) (xy 261.641092 -267.043387) (xy 261.633149 -267.096091)
			(xy 261.617439 -267.147021) (xy 261.594313 -267.195042) (xy 261.564289 -267.239079) (xy 261.528037 -267.27815)
			(xy 261.486366 -267.311381) (xy 261.440208 -267.33803) (xy 261.390594 -267.357502) (xy 261.338632 -267.369362)
			(xy 261.285482 -267.373346) (xy 261.232332 -267.369362) (xy 261.18037 -267.357502) (xy 261.130756 -267.33803)
			(xy 261.084598 -267.311381) (xy 261.042927 -267.27815) (xy 261.006675 -267.239079) (xy 260.976651 -267.195042)
			(xy 260.953525 -267.147021) (xy 260.937815 -267.096091) (xy 260.929872 -267.043387) (xy 254 -267.043387)
			(xy 254 -267.893271) (xy 256.829804 -267.893271) (xy 256.829804 -267.839973) (xy 256.837747 -267.787269)
			(xy 256.853457 -267.736339) (xy 256.876583 -267.688318) (xy 256.906607 -267.644281) (xy 256.942859 -267.60521)
			(xy 256.98453 -267.571979) (xy 257.030688 -267.54533) (xy 257.080302 -267.525858) (xy 257.132264 -267.513998)
			(xy 257.185414 -267.510015) (xy 257.238564 -267.513998) (xy 257.290526 -267.525858) (xy 257.34014 -267.54533)
			(xy 257.386298 -267.571979) (xy 257.427969 -267.60521) (xy 257.464221 -267.644281) (xy 257.494245 -267.688318)
			(xy 257.517371 -267.736339) (xy 257.533081 -267.787269) (xy 257.541024 -267.839973) (xy 257.541522 -267.866622)
			(xy 257.541024 -267.893271) (xy 264.373604 -267.893271) (xy 264.373604 -267.839973) (xy 264.381547 -267.787269)
			(xy 264.397257 -267.736339) (xy 264.420383 -267.688318) (xy 264.450407 -267.644281) (xy 264.486659 -267.60521)
			(xy 264.52833 -267.571979) (xy 264.574488 -267.54533) (xy 264.624102 -267.525858) (xy 264.676064 -267.513998)
			(xy 264.729214 -267.510015) (xy 264.782364 -267.513998) (xy 264.834326 -267.525858) (xy 264.88394 -267.54533)
			(xy 264.930098 -267.571979) (xy 264.971769 -267.60521) (xy 265.008021 -267.644281) (xy 265.038045 -267.688318)
			(xy 265.061171 -267.736339) (xy 265.076881 -267.787269) (xy 265.084824 -267.839973) (xy 265.085322 -267.866622)
			(xy 265.084824 -267.893271) (xy 271.917404 -267.893271) (xy 271.917404 -267.839973) (xy 271.925347 -267.787269)
			(xy 271.941057 -267.736339) (xy 271.964183 -267.688318) (xy 271.994207 -267.644281) (xy 272.030459 -267.60521)
			(xy 272.07213 -267.571979) (xy 272.118288 -267.54533) (xy 272.167902 -267.525858) (xy 272.219864 -267.513998)
			(xy 272.273014 -267.510015) (xy 272.326164 -267.513998) (xy 272.378126 -267.525858) (xy 272.42774 -267.54533)
			(xy 272.473898 -267.571979) (xy 272.515569 -267.60521) (xy 272.551821 -267.644281) (xy 272.581845 -267.688318)
			(xy 272.604971 -267.736339) (xy 272.620681 -267.787269) (xy 272.628624 -267.839973) (xy 272.629122 -267.866622)
			(xy 272.628624 -267.893271) (xy 279.461204 -267.893271) (xy 279.461204 -267.839973) (xy 279.469147 -267.787269)
			(xy 279.484857 -267.736339) (xy 279.507983 -267.688318) (xy 279.538007 -267.644281) (xy 279.574259 -267.60521)
			(xy 279.61593 -267.571979) (xy 279.662088 -267.54533) (xy 279.711702 -267.525858) (xy 279.763664 -267.513998)
			(xy 279.816814 -267.510015) (xy 279.869964 -267.513998) (xy 279.921926 -267.525858) (xy 279.97154 -267.54533)
			(xy 280.017698 -267.571979) (xy 280.059369 -267.60521) (xy 280.095621 -267.644281) (xy 280.125645 -267.688318)
			(xy 280.148771 -267.736339) (xy 280.164481 -267.787269) (xy 280.172424 -267.839973) (xy 280.172922 -267.866622)
			(xy 280.172424 -267.893271) (xy 287.005004 -267.893271) (xy 287.005004 -267.839973) (xy 287.012947 -267.787269)
			(xy 287.028657 -267.736339) (xy 287.051783 -267.688318) (xy 287.081807 -267.644281) (xy 287.118059 -267.60521)
			(xy 287.15973 -267.571979) (xy 287.205888 -267.54533) (xy 287.255502 -267.525858) (xy 287.307464 -267.513998)
			(xy 287.360614 -267.510015) (xy 287.413764 -267.513998) (xy 287.465726 -267.525858) (xy 287.51534 -267.54533)
			(xy 287.561498 -267.571979) (xy 287.603169 -267.60521) (xy 287.639421 -267.644281) (xy 287.669445 -267.688318)
			(xy 287.692571 -267.736339) (xy 287.708281 -267.787269) (xy 287.716224 -267.839973) (xy 287.716722 -267.866622)
			(xy 287.716224 -267.893271) (xy 294.548804 -267.893271) (xy 294.548804 -267.839973) (xy 294.556747 -267.787269)
			(xy 294.572457 -267.736339) (xy 294.595583 -267.688318) (xy 294.625607 -267.644281) (xy 294.661859 -267.60521)
			(xy 294.70353 -267.571979) (xy 294.749688 -267.54533) (xy 294.799302 -267.525858) (xy 294.851264 -267.513998)
			(xy 294.904414 -267.510015) (xy 294.957564 -267.513998) (xy 295.009526 -267.525858) (xy 295.05914 -267.54533)
			(xy 295.105298 -267.571979) (xy 295.146969 -267.60521) (xy 295.183221 -267.644281) (xy 295.213245 -267.688318)
			(xy 295.236371 -267.736339) (xy 295.252081 -267.787269) (xy 295.260024 -267.839973) (xy 295.260522 -267.866622)
			(xy 295.260024 -267.893271) (xy 295.252081 -267.945975) (xy 295.236371 -267.996905) (xy 295.213245 -268.044926)
			(xy 295.183221 -268.088963) (xy 295.146969 -268.128034) (xy 295.105298 -268.161265) (xy 295.05914 -268.187914)
			(xy 295.009526 -268.207386) (xy 294.957564 -268.219246) (xy 294.904414 -268.22323) (xy 294.851264 -268.219246)
			(xy 294.799302 -268.207386) (xy 294.749688 -268.187914) (xy 294.70353 -268.161265) (xy 294.661859 -268.128034)
			(xy 294.625607 -268.088963) (xy 294.595583 -268.044926) (xy 294.572457 -267.996905) (xy 294.556747 -267.945975)
			(xy 294.548804 -267.893271) (xy 287.716224 -267.893271) (xy 287.708281 -267.945975) (xy 287.692571 -267.996905)
			(xy 287.669445 -268.044926) (xy 287.639421 -268.088963) (xy 287.603169 -268.128034) (xy 287.561498 -268.161265)
			(xy 287.51534 -268.187914) (xy 287.465726 -268.207386) (xy 287.413764 -268.219246) (xy 287.360614 -268.22323)
			(xy 287.307464 -268.219246) (xy 287.255502 -268.207386) (xy 287.205888 -268.187914) (xy 287.15973 -268.161265)
			(xy 287.118059 -268.128034) (xy 287.081807 -268.088963) (xy 287.051783 -268.044926) (xy 287.028657 -267.996905)
			(xy 287.012947 -267.945975) (xy 287.005004 -267.893271) (xy 280.172424 -267.893271) (xy 280.164481 -267.945975)
			(xy 280.148771 -267.996905) (xy 280.125645 -268.044926) (xy 280.095621 -268.088963) (xy 280.059369 -268.128034)
			(xy 280.017698 -268.161265) (xy 279.97154 -268.187914) (xy 279.921926 -268.207386) (xy 279.869964 -268.219246)
			(xy 279.816814 -268.22323) (xy 279.763664 -268.219246) (xy 279.711702 -268.207386) (xy 279.662088 -268.187914)
			(xy 279.61593 -268.161265) (xy 279.574259 -268.128034) (xy 279.538007 -268.088963) (xy 279.507983 -268.044926)
			(xy 279.484857 -267.996905) (xy 279.469147 -267.945975) (xy 279.461204 -267.893271) (xy 272.628624 -267.893271)
			(xy 272.620681 -267.945975) (xy 272.604971 -267.996905) (xy 272.581845 -268.044926) (xy 272.551821 -268.088963)
			(xy 272.515569 -268.128034) (xy 272.473898 -268.161265) (xy 272.42774 -268.187914) (xy 272.378126 -268.207386)
			(xy 272.326164 -268.219246) (xy 272.273014 -268.22323) (xy 272.219864 -268.219246) (xy 272.167902 -268.207386)
			(xy 272.118288 -268.187914) (xy 272.07213 -268.161265) (xy 272.030459 -268.128034) (xy 271.994207 -268.088963)
			(xy 271.964183 -268.044926) (xy 271.941057 -267.996905) (xy 271.925347 -267.945975) (xy 271.917404 -267.893271)
			(xy 265.084824 -267.893271) (xy 265.076881 -267.945975) (xy 265.061171 -267.996905) (xy 265.038045 -268.044926)
			(xy 265.008021 -268.088963) (xy 264.971769 -268.128034) (xy 264.930098 -268.161265) (xy 264.88394 -268.187914)
			(xy 264.834326 -268.207386) (xy 264.782364 -268.219246) (xy 264.729214 -268.22323) (xy 264.676064 -268.219246)
			(xy 264.624102 -268.207386) (xy 264.574488 -268.187914) (xy 264.52833 -268.161265) (xy 264.486659 -268.128034)
			(xy 264.450407 -268.088963) (xy 264.420383 -268.044926) (xy 264.397257 -267.996905) (xy 264.381547 -267.945975)
			(xy 264.373604 -267.893271) (xy 257.541024 -267.893271) (xy 257.533081 -267.945975) (xy 257.517371 -267.996905)
			(xy 257.494245 -268.044926) (xy 257.464221 -268.088963) (xy 257.427969 -268.128034) (xy 257.386298 -268.161265)
			(xy 257.34014 -268.187914) (xy 257.290526 -268.207386) (xy 257.238564 -268.219246) (xy 257.185414 -268.22323)
			(xy 257.132264 -268.219246) (xy 257.080302 -268.207386) (xy 257.030688 -268.187914) (xy 256.98453 -268.161265)
			(xy 256.942859 -268.128034) (xy 256.906607 -268.088963) (xy 256.876583 -268.044926) (xy 256.853457 -267.996905)
			(xy 256.837747 -267.945975) (xy 256.829804 -267.893271) (xy 254 -267.893271) (xy 254 -268.743409)
			(xy 283.561272 -268.743409) (xy 283.561272 -268.690111) (xy 283.569215 -268.637407) (xy 283.584925 -268.586477)
			(xy 283.608051 -268.538456) (xy 283.638075 -268.494419) (xy 283.674327 -268.455348) (xy 283.715998 -268.422117)
			(xy 283.762156 -268.395468) (xy 283.81177 -268.375996) (xy 283.863732 -268.364136) (xy 283.916882 -268.360153)
			(xy 283.970032 -268.364136) (xy 284.021994 -268.375996) (xy 284.071608 -268.395468) (xy 284.117766 -268.422117)
			(xy 284.159437 -268.455348) (xy 284.195689 -268.494419) (xy 284.225713 -268.538456) (xy 284.248839 -268.586477)
			(xy 284.264549 -268.637407) (xy 284.272492 -268.690111) (xy 284.27299 -268.71676) (xy 284.272492 -268.743409)
			(xy 284.264549 -268.796113) (xy 284.248839 -268.847043) (xy 284.225713 -268.895064) (xy 284.195689 -268.939101)
			(xy 284.159437 -268.978172) (xy 284.117766 -269.011403) (xy 284.071608 -269.038052) (xy 284.021994 -269.057524)
			(xy 283.970032 -269.069384) (xy 283.916882 -269.073368) (xy 283.863732 -269.069384) (xy 283.81177 -269.057524)
			(xy 283.762156 -269.038052) (xy 283.715998 -269.011403) (xy 283.674327 -268.978172) (xy 283.638075 -268.939101)
			(xy 283.608051 -268.895064) (xy 283.584925 -268.847043) (xy 283.569215 -268.796113) (xy 283.561272 -268.743409)
			(xy 254 -268.743409) (xy 254 -269.593293) (xy 264.373604 -269.593293) (xy 264.373604 -269.539995)
			(xy 264.381547 -269.487291) (xy 264.397257 -269.436361) (xy 264.420383 -269.38834) (xy 264.450407 -269.344303)
			(xy 264.486659 -269.305232) (xy 264.52833 -269.272001) (xy 264.574488 -269.245352) (xy 264.624102 -269.22588)
			(xy 264.676064 -269.21402) (xy 264.729214 -269.210037) (xy 264.782364 -269.21402) (xy 264.834326 -269.22588)
			(xy 264.88394 -269.245352) (xy 264.930098 -269.272001) (xy 264.971769 -269.305232) (xy 265.008021 -269.344303)
			(xy 265.038045 -269.38834) (xy 265.061171 -269.436361) (xy 265.076881 -269.487291) (xy 265.084824 -269.539995)
			(xy 265.085322 -269.566644) (xy 265.084824 -269.593293) (xy 279.461204 -269.593293) (xy 279.461204 -269.539995)
			(xy 279.469147 -269.487291) (xy 279.484857 -269.436361) (xy 279.507983 -269.38834) (xy 279.538007 -269.344303)
			(xy 279.574259 -269.305232) (xy 279.61593 -269.272001) (xy 279.662088 -269.245352) (xy 279.711702 -269.22588)
			(xy 279.763664 -269.21402) (xy 279.816814 -269.210037) (xy 279.869964 -269.21402) (xy 279.921926 -269.22588)
			(xy 279.97154 -269.245352) (xy 280.017698 -269.272001) (xy 280.059369 -269.305232) (xy 280.095621 -269.344303)
			(xy 280.125645 -269.38834) (xy 280.148771 -269.436361) (xy 280.164481 -269.487291) (xy 280.172424 -269.539995)
			(xy 280.172922 -269.566644) (xy 280.172424 -269.593293) (xy 294.548804 -269.593293) (xy 294.548804 -269.539995)
			(xy 294.556747 -269.487291) (xy 294.572457 -269.436361) (xy 294.595583 -269.38834) (xy 294.625607 -269.344303)
			(xy 294.661859 -269.305232) (xy 294.70353 -269.272001) (xy 294.749688 -269.245352) (xy 294.799302 -269.22588)
			(xy 294.851264 -269.21402) (xy 294.904414 -269.210037) (xy 294.957564 -269.21402) (xy 295.009526 -269.22588)
			(xy 295.05914 -269.245352) (xy 295.105298 -269.272001) (xy 295.146969 -269.305232) (xy 295.183221 -269.344303)
			(xy 295.213245 -269.38834) (xy 295.236371 -269.436361) (xy 295.252081 -269.487291) (xy 295.260024 -269.539995)
			(xy 295.260522 -269.566644) (xy 295.260024 -269.593293) (xy 309.636404 -269.593293) (xy 309.636404 -269.539995)
			(xy 309.644347 -269.487291) (xy 309.660057 -269.436361) (xy 309.683183 -269.38834) (xy 309.713207 -269.344303)
			(xy 309.749459 -269.305232) (xy 309.79113 -269.272001) (xy 309.837288 -269.245352) (xy 309.886902 -269.22588)
			(xy 309.938864 -269.21402) (xy 309.992014 -269.210037) (xy 310.045164 -269.21402) (xy 310.097126 -269.22588)
			(xy 310.14674 -269.245352) (xy 310.192898 -269.272001) (xy 310.234569 -269.305232) (xy 310.270821 -269.344303)
			(xy 310.300845 -269.38834) (xy 310.323971 -269.436361) (xy 310.339681 -269.487291) (xy 310.347624 -269.539995)
			(xy 310.348122 -269.566644) (xy 310.347624 -269.593293) (xy 310.339681 -269.645997) (xy 310.323971 -269.696927)
			(xy 310.300845 -269.744948) (xy 310.270821 -269.788985) (xy 310.234569 -269.828056) (xy 310.192898 -269.861287)
			(xy 310.14674 -269.887936) (xy 310.097126 -269.907408) (xy 310.045164 -269.919268) (xy 309.992014 -269.923252)
			(xy 309.938864 -269.919268) (xy 309.886902 -269.907408) (xy 309.837288 -269.887936) (xy 309.79113 -269.861287)
			(xy 309.749459 -269.828056) (xy 309.713207 -269.788985) (xy 309.683183 -269.744948) (xy 309.660057 -269.696927)
			(xy 309.644347 -269.645997) (xy 309.636404 -269.593293) (xy 295.260024 -269.593293) (xy 295.252081 -269.645997)
			(xy 295.236371 -269.696927) (xy 295.213245 -269.744948) (xy 295.183221 -269.788985) (xy 295.146969 -269.828056)
			(xy 295.105298 -269.861287) (xy 295.05914 -269.887936) (xy 295.009526 -269.907408) (xy 294.957564 -269.919268)
			(xy 294.904414 -269.923252) (xy 294.851264 -269.919268) (xy 294.799302 -269.907408) (xy 294.749688 -269.887936)
			(xy 294.70353 -269.861287) (xy 294.661859 -269.828056) (xy 294.625607 -269.788985) (xy 294.595583 -269.744948)
			(xy 294.572457 -269.696927) (xy 294.556747 -269.645997) (xy 294.548804 -269.593293) (xy 280.172424 -269.593293)
			(xy 280.164481 -269.645997) (xy 280.148771 -269.696927) (xy 280.125645 -269.744948) (xy 280.095621 -269.788985)
			(xy 280.059369 -269.828056) (xy 280.017698 -269.861287) (xy 279.97154 -269.887936) (xy 279.921926 -269.907408)
			(xy 279.869964 -269.919268) (xy 279.816814 -269.923252) (xy 279.763664 -269.919268) (xy 279.711702 -269.907408)
			(xy 279.662088 -269.887936) (xy 279.61593 -269.861287) (xy 279.574259 -269.828056) (xy 279.538007 -269.788985)
			(xy 279.507983 -269.744948) (xy 279.484857 -269.696927) (xy 279.469147 -269.645997) (xy 279.461204 -269.593293)
			(xy 265.084824 -269.593293) (xy 265.076881 -269.645997) (xy 265.061171 -269.696927) (xy 265.038045 -269.744948)
			(xy 265.008021 -269.788985) (xy 264.971769 -269.828056) (xy 264.930098 -269.861287) (xy 264.88394 -269.887936)
			(xy 264.834326 -269.907408) (xy 264.782364 -269.919268) (xy 264.729214 -269.923252) (xy 264.676064 -269.919268)
			(xy 264.624102 -269.907408) (xy 264.574488 -269.887936) (xy 264.52833 -269.861287) (xy 264.486659 -269.828056)
			(xy 264.450407 -269.788985) (xy 264.420383 -269.744948) (xy 264.397257 -269.696927) (xy 264.381547 -269.645997)
			(xy 264.373604 -269.593293) (xy 254 -269.593293) (xy 254 -270.443431) (xy 268.473672 -270.443431)
			(xy 268.473672 -270.390133) (xy 268.481615 -270.337429) (xy 268.497325 -270.286499) (xy 268.520451 -270.238478)
			(xy 268.550475 -270.194441) (xy 268.586727 -270.15537) (xy 268.628398 -270.122139) (xy 268.674556 -270.09549)
			(xy 268.72417 -270.076018) (xy 268.776132 -270.064158) (xy 268.829282 -270.060175) (xy 268.882432 -270.064158)
			(xy 268.934394 -270.076018) (xy 268.984008 -270.09549) (xy 269.030166 -270.122139) (xy 269.071837 -270.15537)
			(xy 269.108089 -270.194441) (xy 269.138113 -270.238478) (xy 269.161239 -270.286499) (xy 269.176949 -270.337429)
			(xy 269.184892 -270.390133) (xy 269.18539 -270.416782) (xy 269.184892 -270.443431) (xy 283.561272 -270.443431)
			(xy 283.561272 -270.390133) (xy 283.569215 -270.337429) (xy 283.584925 -270.286499) (xy 283.608051 -270.238478)
			(xy 283.638075 -270.194441) (xy 283.674327 -270.15537) (xy 283.715998 -270.122139) (xy 283.762156 -270.09549)
			(xy 283.81177 -270.076018) (xy 283.863732 -270.064158) (xy 283.916882 -270.060175) (xy 283.970032 -270.064158)
			(xy 284.021994 -270.076018) (xy 284.071608 -270.09549) (xy 284.117766 -270.122139) (xy 284.159437 -270.15537)
			(xy 284.195689 -270.194441) (xy 284.225713 -270.238478) (xy 284.248839 -270.286499) (xy 284.264549 -270.337429)
			(xy 284.272492 -270.390133) (xy 284.27299 -270.416782) (xy 284.272492 -270.443431) (xy 298.674272 -270.443431)
			(xy 298.674272 -270.390133) (xy 298.682215 -270.337429) (xy 298.697925 -270.286499) (xy 298.721051 -270.238478)
			(xy 298.751075 -270.194441) (xy 298.787327 -270.15537) (xy 298.828998 -270.122139) (xy 298.875156 -270.09549)
			(xy 298.92477 -270.076018) (xy 298.976732 -270.064158) (xy 299.029882 -270.060175) (xy 299.083032 -270.064158)
			(xy 299.134994 -270.076018) (xy 299.184608 -270.09549) (xy 299.230766 -270.122139) (xy 299.272437 -270.15537)
			(xy 299.308689 -270.194441) (xy 299.338713 -270.238478) (xy 299.361839 -270.286499) (xy 299.377549 -270.337429)
			(xy 299.385492 -270.390133) (xy 299.38599 -270.416782) (xy 299.385492 -270.443431) (xy 299.377549 -270.496135)
			(xy 299.361839 -270.547065) (xy 299.338713 -270.595086) (xy 299.308689 -270.639123) (xy 299.272437 -270.678194)
			(xy 299.230766 -270.711425) (xy 299.184608 -270.738074) (xy 299.134994 -270.757546) (xy 299.083032 -270.769406)
			(xy 299.029882 -270.77339) (xy 298.976732 -270.769406) (xy 298.92477 -270.757546) (xy 298.875156 -270.738074)
			(xy 298.828998 -270.711425) (xy 298.787327 -270.678194) (xy 298.751075 -270.639123) (xy 298.721051 -270.595086)
			(xy 298.697925 -270.547065) (xy 298.682215 -270.496135) (xy 298.674272 -270.443431) (xy 284.272492 -270.443431)
			(xy 284.264549 -270.496135) (xy 284.248839 -270.547065) (xy 284.225713 -270.595086) (xy 284.195689 -270.639123)
			(xy 284.159437 -270.678194) (xy 284.117766 -270.711425) (xy 284.071608 -270.738074) (xy 284.021994 -270.757546)
			(xy 283.970032 -270.769406) (xy 283.916882 -270.77339) (xy 283.863732 -270.769406) (xy 283.81177 -270.757546)
			(xy 283.762156 -270.738074) (xy 283.715998 -270.711425) (xy 283.674327 -270.678194) (xy 283.638075 -270.639123)
			(xy 283.608051 -270.595086) (xy 283.584925 -270.547065) (xy 283.569215 -270.496135) (xy 283.561272 -270.443431)
			(xy 269.184892 -270.443431) (xy 269.176949 -270.496135) (xy 269.161239 -270.547065) (xy 269.138113 -270.595086)
			(xy 269.108089 -270.639123) (xy 269.071837 -270.678194) (xy 269.030166 -270.711425) (xy 268.984008 -270.738074)
			(xy 268.934394 -270.757546) (xy 268.882432 -270.769406) (xy 268.829282 -270.77339) (xy 268.776132 -270.769406)
			(xy 268.72417 -270.757546) (xy 268.674556 -270.738074) (xy 268.628398 -270.711425) (xy 268.586727 -270.678194)
			(xy 268.550475 -270.639123) (xy 268.520451 -270.595086) (xy 268.497325 -270.547065) (xy 268.481615 -270.496135)
			(xy 268.473672 -270.443431) (xy 254 -270.443431) (xy 254 -271.293315) (xy 264.373604 -271.293315)
			(xy 264.373604 -271.240017) (xy 264.381547 -271.187313) (xy 264.397257 -271.136383) (xy 264.420383 -271.088362)
			(xy 264.450407 -271.044325) (xy 264.486659 -271.005254) (xy 264.52833 -270.972023) (xy 264.574488 -270.945374)
			(xy 264.624102 -270.925902) (xy 264.676064 -270.914042) (xy 264.729214 -270.910059) (xy 264.782364 -270.914042)
			(xy 264.834326 -270.925902) (xy 264.88394 -270.945374) (xy 264.930098 -270.972023) (xy 264.971769 -271.005254)
			(xy 265.008021 -271.044325) (xy 265.038045 -271.088362) (xy 265.061171 -271.136383) (xy 265.076881 -271.187313)
			(xy 265.084824 -271.240017) (xy 265.085322 -271.266666) (xy 265.084824 -271.293315) (xy 279.461204 -271.293315)
			(xy 279.461204 -271.240017) (xy 279.469147 -271.187313) (xy 279.484857 -271.136383) (xy 279.507983 -271.088362)
			(xy 279.538007 -271.044325) (xy 279.574259 -271.005254) (xy 279.61593 -270.972023) (xy 279.662088 -270.945374)
			(xy 279.711702 -270.925902) (xy 279.763664 -270.914042) (xy 279.816814 -270.910059) (xy 279.869964 -270.914042)
			(xy 279.921926 -270.925902) (xy 279.97154 -270.945374) (xy 280.017698 -270.972023) (xy 280.059369 -271.005254)
			(xy 280.095621 -271.044325) (xy 280.125645 -271.088362) (xy 280.148771 -271.136383) (xy 280.164481 -271.187313)
			(xy 280.172424 -271.240017) (xy 280.172922 -271.266666) (xy 280.172424 -271.293315) (xy 294.548804 -271.293315)
			(xy 294.548804 -271.240017) (xy 294.556747 -271.187313) (xy 294.572457 -271.136383) (xy 294.595583 -271.088362)
			(xy 294.625607 -271.044325) (xy 294.661859 -271.005254) (xy 294.70353 -270.972023) (xy 294.749688 -270.945374)
			(xy 294.799302 -270.925902) (xy 294.851264 -270.914042) (xy 294.904414 -270.910059) (xy 294.957564 -270.914042)
			(xy 295.009526 -270.925902) (xy 295.05914 -270.945374) (xy 295.105298 -270.972023) (xy 295.146969 -271.005254)
			(xy 295.183221 -271.044325) (xy 295.213245 -271.088362) (xy 295.236371 -271.136383) (xy 295.252081 -271.187313)
			(xy 295.260024 -271.240017) (xy 295.260522 -271.266666) (xy 295.260024 -271.293315) (xy 295.252081 -271.346019)
			(xy 295.236371 -271.396949) (xy 295.213245 -271.44497) (xy 295.183221 -271.489007) (xy 295.146969 -271.528078)
			(xy 295.105298 -271.561309) (xy 295.05914 -271.587958) (xy 295.009526 -271.60743) (xy 294.957564 -271.61929)
			(xy 294.904414 -271.623274) (xy 294.851264 -271.61929) (xy 294.799302 -271.60743) (xy 294.749688 -271.587958)
			(xy 294.70353 -271.561309) (xy 294.661859 -271.528078) (xy 294.625607 -271.489007) (xy 294.595583 -271.44497)
			(xy 294.572457 -271.396949) (xy 294.556747 -271.346019) (xy 294.548804 -271.293315) (xy 280.172424 -271.293315)
			(xy 280.164481 -271.346019) (xy 280.148771 -271.396949) (xy 280.125645 -271.44497) (xy 280.095621 -271.489007)
			(xy 280.059369 -271.528078) (xy 280.017698 -271.561309) (xy 279.97154 -271.587958) (xy 279.921926 -271.60743)
			(xy 279.869964 -271.61929) (xy 279.816814 -271.623274) (xy 279.763664 -271.61929) (xy 279.711702 -271.60743)
			(xy 279.662088 -271.587958) (xy 279.61593 -271.561309) (xy 279.574259 -271.528078) (xy 279.538007 -271.489007)
			(xy 279.507983 -271.44497) (xy 279.484857 -271.396949) (xy 279.469147 -271.346019) (xy 279.461204 -271.293315)
			(xy 265.084824 -271.293315) (xy 265.076881 -271.346019) (xy 265.061171 -271.396949) (xy 265.038045 -271.44497)
			(xy 265.008021 -271.489007) (xy 264.971769 -271.528078) (xy 264.930098 -271.561309) (xy 264.88394 -271.587958)
			(xy 264.834326 -271.60743) (xy 264.782364 -271.61929) (xy 264.729214 -271.623274) (xy 264.676064 -271.61929)
			(xy 264.624102 -271.60743) (xy 264.574488 -271.587958) (xy 264.52833 -271.561309) (xy 264.486659 -271.528078)
			(xy 264.450407 -271.489007) (xy 264.420383 -271.44497) (xy 264.397257 -271.396949) (xy 264.381547 -271.346019)
			(xy 264.373604 -271.293315) (xy 254 -271.293315) (xy 254 -272.143453) (xy 268.473672 -272.143453)
			(xy 268.473672 -272.090155) (xy 268.481615 -272.037451) (xy 268.497325 -271.986521) (xy 268.520451 -271.9385)
			(xy 268.550475 -271.894463) (xy 268.586727 -271.855392) (xy 268.628398 -271.822161) (xy 268.674556 -271.795512)
			(xy 268.72417 -271.77604) (xy 268.776132 -271.76418) (xy 268.829282 -271.760197) (xy 268.882432 -271.76418)
			(xy 268.934394 -271.77604) (xy 268.984008 -271.795512) (xy 269.030166 -271.822161) (xy 269.071837 -271.855392)
			(xy 269.108089 -271.894463) (xy 269.138113 -271.9385) (xy 269.161239 -271.986521) (xy 269.176949 -272.037451)
			(xy 269.184892 -272.090155) (xy 269.18539 -272.116804) (xy 269.184892 -272.143453) (xy 283.561272 -272.143453)
			(xy 283.561272 -272.090155) (xy 283.569215 -272.037451) (xy 283.584925 -271.986521) (xy 283.608051 -271.9385)
			(xy 283.638075 -271.894463) (xy 283.674327 -271.855392) (xy 283.715998 -271.822161) (xy 283.762156 -271.795512)
			(xy 283.81177 -271.77604) (xy 283.863732 -271.76418) (xy 283.916882 -271.760197) (xy 283.970032 -271.76418)
			(xy 284.021994 -271.77604) (xy 284.071608 -271.795512) (xy 284.117766 -271.822161) (xy 284.159437 -271.855392)
			(xy 284.195689 -271.894463) (xy 284.225713 -271.9385) (xy 284.248839 -271.986521) (xy 284.264549 -272.037451)
			(xy 284.272492 -272.090155) (xy 284.27299 -272.116804) (xy 284.272492 -272.143453) (xy 298.674272 -272.143453)
			(xy 298.674272 -272.090155) (xy 298.682215 -272.037451) (xy 298.697925 -271.986521) (xy 298.721051 -271.9385)
			(xy 298.751075 -271.894463) (xy 298.787327 -271.855392) (xy 298.828998 -271.822161) (xy 298.875156 -271.795512)
			(xy 298.92477 -271.77604) (xy 298.976732 -271.76418) (xy 299.029882 -271.760197) (xy 299.083032 -271.76418)
			(xy 299.134994 -271.77604) (xy 299.184608 -271.795512) (xy 299.230766 -271.822161) (xy 299.272437 -271.855392)
			(xy 299.308689 -271.894463) (xy 299.338713 -271.9385) (xy 299.361839 -271.986521) (xy 299.377549 -272.037451)
			(xy 299.385492 -272.090155) (xy 299.38599 -272.116804) (xy 299.385492 -272.143453) (xy 299.377549 -272.196157)
			(xy 299.361839 -272.247087) (xy 299.338713 -272.295108) (xy 299.308689 -272.339145) (xy 299.272437 -272.378216)
			(xy 299.230766 -272.411447) (xy 299.184608 -272.438096) (xy 299.134994 -272.457568) (xy 299.083032 -272.469428)
			(xy 299.029882 -272.473412) (xy 298.976732 -272.469428) (xy 298.92477 -272.457568) (xy 298.875156 -272.438096)
			(xy 298.828998 -272.411447) (xy 298.787327 -272.378216) (xy 298.751075 -272.339145) (xy 298.721051 -272.295108)
			(xy 298.697925 -272.247087) (xy 298.682215 -272.196157) (xy 298.674272 -272.143453) (xy 284.272492 -272.143453)
			(xy 284.264549 -272.196157) (xy 284.248839 -272.247087) (xy 284.225713 -272.295108) (xy 284.195689 -272.339145)
			(xy 284.159437 -272.378216) (xy 284.117766 -272.411447) (xy 284.071608 -272.438096) (xy 284.021994 -272.457568)
			(xy 283.970032 -272.469428) (xy 283.916882 -272.473412) (xy 283.863732 -272.469428) (xy 283.81177 -272.457568)
			(xy 283.762156 -272.438096) (xy 283.715998 -272.411447) (xy 283.674327 -272.378216) (xy 283.638075 -272.339145)
			(xy 283.608051 -272.295108) (xy 283.584925 -272.247087) (xy 283.569215 -272.196157) (xy 283.561272 -272.143453)
			(xy 269.184892 -272.143453) (xy 269.176949 -272.196157) (xy 269.161239 -272.247087) (xy 269.138113 -272.295108)
			(xy 269.108089 -272.339145) (xy 269.071837 -272.378216) (xy 269.030166 -272.411447) (xy 268.984008 -272.438096)
			(xy 268.934394 -272.457568) (xy 268.882432 -272.469428) (xy 268.829282 -272.473412) (xy 268.776132 -272.469428)
			(xy 268.72417 -272.457568) (xy 268.674556 -272.438096) (xy 268.628398 -272.411447) (xy 268.586727 -272.378216)
			(xy 268.550475 -272.339145) (xy 268.520451 -272.295108) (xy 268.497325 -272.247087) (xy 268.481615 -272.196157)
			(xy 268.473672 -272.143453) (xy 254 -272.143453) (xy 254 -272.993337) (xy 264.373604 -272.993337)
			(xy 264.373604 -272.940039) (xy 264.381547 -272.887335) (xy 264.397257 -272.836405) (xy 264.420383 -272.788384)
			(xy 264.450407 -272.744347) (xy 264.486659 -272.705276) (xy 264.52833 -272.672045) (xy 264.574488 -272.645396)
			(xy 264.624102 -272.625924) (xy 264.676064 -272.614064) (xy 264.729214 -272.610081) (xy 264.782364 -272.614064)
			(xy 264.834326 -272.625924) (xy 264.88394 -272.645396) (xy 264.930098 -272.672045) (xy 264.971769 -272.705276)
			(xy 265.008021 -272.744347) (xy 265.038045 -272.788384) (xy 265.061171 -272.836405) (xy 265.076881 -272.887335)
			(xy 265.084824 -272.940039) (xy 265.085322 -272.966688) (xy 265.084824 -272.993337) (xy 279.461204 -272.993337)
			(xy 279.461204 -272.940039) (xy 279.469147 -272.887335) (xy 279.484857 -272.836405) (xy 279.507983 -272.788384)
			(xy 279.538007 -272.744347) (xy 279.574259 -272.705276) (xy 279.61593 -272.672045) (xy 279.662088 -272.645396)
			(xy 279.711702 -272.625924) (xy 279.763664 -272.614064) (xy 279.816814 -272.610081) (xy 279.869964 -272.614064)
			(xy 279.921926 -272.625924) (xy 279.97154 -272.645396) (xy 280.017698 -272.672045) (xy 280.059369 -272.705276)
			(xy 280.095621 -272.744347) (xy 280.125645 -272.788384) (xy 280.148771 -272.836405) (xy 280.164481 -272.887335)
			(xy 280.172424 -272.940039) (xy 280.172922 -272.966688) (xy 280.172424 -272.993337) (xy 294.548804 -272.993337)
			(xy 294.548804 -272.940039) (xy 294.556747 -272.887335) (xy 294.572457 -272.836405) (xy 294.595583 -272.788384)
			(xy 294.625607 -272.744347) (xy 294.661859 -272.705276) (xy 294.70353 -272.672045) (xy 294.749688 -272.645396)
			(xy 294.799302 -272.625924) (xy 294.851264 -272.614064) (xy 294.904414 -272.610081) (xy 294.957564 -272.614064)
			(xy 295.009526 -272.625924) (xy 295.05914 -272.645396) (xy 295.105298 -272.672045) (xy 295.146969 -272.705276)
			(xy 295.183221 -272.744347) (xy 295.213245 -272.788384) (xy 295.236371 -272.836405) (xy 295.252081 -272.887335)
			(xy 295.260024 -272.940039) (xy 295.260522 -272.966688) (xy 295.260024 -272.993337) (xy 295.252081 -273.046041)
			(xy 295.236371 -273.096971) (xy 295.213245 -273.144992) (xy 295.183221 -273.189029) (xy 295.146969 -273.2281)
			(xy 295.105298 -273.261331) (xy 295.05914 -273.28798) (xy 295.009526 -273.307452) (xy 294.957564 -273.319312)
			(xy 294.904414 -273.323296) (xy 294.851264 -273.319312) (xy 294.799302 -273.307452) (xy 294.749688 -273.28798)
			(xy 294.70353 -273.261331) (xy 294.661859 -273.2281) (xy 294.625607 -273.189029) (xy 294.595583 -273.144992)
			(xy 294.572457 -273.096971) (xy 294.556747 -273.046041) (xy 294.548804 -272.993337) (xy 280.172424 -272.993337)
			(xy 280.164481 -273.046041) (xy 280.148771 -273.096971) (xy 280.125645 -273.144992) (xy 280.095621 -273.189029)
			(xy 280.059369 -273.2281) (xy 280.017698 -273.261331) (xy 279.97154 -273.28798) (xy 279.921926 -273.307452)
			(xy 279.869964 -273.319312) (xy 279.816814 -273.323296) (xy 279.763664 -273.319312) (xy 279.711702 -273.307452)
			(xy 279.662088 -273.28798) (xy 279.61593 -273.261331) (xy 279.574259 -273.2281) (xy 279.538007 -273.189029)
			(xy 279.507983 -273.144992) (xy 279.484857 -273.096971) (xy 279.469147 -273.046041) (xy 279.461204 -272.993337)
			(xy 265.084824 -272.993337) (xy 265.076881 -273.046041) (xy 265.061171 -273.096971) (xy 265.038045 -273.144992)
			(xy 265.008021 -273.189029) (xy 264.971769 -273.2281) (xy 264.930098 -273.261331) (xy 264.88394 -273.28798)
			(xy 264.834326 -273.307452) (xy 264.782364 -273.319312) (xy 264.729214 -273.323296) (xy 264.676064 -273.319312)
			(xy 264.624102 -273.307452) (xy 264.574488 -273.28798) (xy 264.52833 -273.261331) (xy 264.486659 -273.2281)
			(xy 264.450407 -273.189029) (xy 264.420383 -273.144992) (xy 264.397257 -273.096971) (xy 264.381547 -273.046041)
			(xy 264.373604 -272.993337) (xy 254 -272.993337) (xy 254 -273.843221) (xy 268.473672 -273.843221)
			(xy 268.473672 -273.789923) (xy 268.481615 -273.737219) (xy 268.497325 -273.686289) (xy 268.520451 -273.638268)
			(xy 268.550475 -273.594231) (xy 268.586727 -273.55516) (xy 268.628398 -273.521929) (xy 268.674556 -273.49528)
			(xy 268.72417 -273.475808) (xy 268.776132 -273.463948) (xy 268.829282 -273.459965) (xy 268.882432 -273.463948)
			(xy 268.934394 -273.475808) (xy 268.984008 -273.49528) (xy 269.030166 -273.521929) (xy 269.071837 -273.55516)
			(xy 269.108089 -273.594231) (xy 269.138113 -273.638268) (xy 269.161239 -273.686289) (xy 269.176949 -273.737219)
			(xy 269.184892 -273.789923) (xy 269.18539 -273.816572) (xy 269.184892 -273.843221) (xy 283.561272 -273.843221)
			(xy 283.561272 -273.789923) (xy 283.569215 -273.737219) (xy 283.584925 -273.686289) (xy 283.608051 -273.638268)
			(xy 283.638075 -273.594231) (xy 283.674327 -273.55516) (xy 283.715998 -273.521929) (xy 283.762156 -273.49528)
			(xy 283.81177 -273.475808) (xy 283.863732 -273.463948) (xy 283.916882 -273.459965) (xy 283.970032 -273.463948)
			(xy 284.021994 -273.475808) (xy 284.071608 -273.49528) (xy 284.117766 -273.521929) (xy 284.159437 -273.55516)
			(xy 284.195689 -273.594231) (xy 284.225713 -273.638268) (xy 284.248839 -273.686289) (xy 284.264549 -273.737219)
			(xy 284.272492 -273.789923) (xy 284.27299 -273.816572) (xy 284.272492 -273.843221) (xy 298.674272 -273.843221)
			(xy 298.674272 -273.789923) (xy 298.682215 -273.737219) (xy 298.697925 -273.686289) (xy 298.721051 -273.638268)
			(xy 298.751075 -273.594231) (xy 298.787327 -273.55516) (xy 298.828998 -273.521929) (xy 298.875156 -273.49528)
			(xy 298.92477 -273.475808) (xy 298.976732 -273.463948) (xy 299.029882 -273.459965) (xy 299.083032 -273.463948)
			(xy 299.134994 -273.475808) (xy 299.184608 -273.49528) (xy 299.230766 -273.521929) (xy 299.272437 -273.55516)
			(xy 299.308689 -273.594231) (xy 299.338713 -273.638268) (xy 299.361839 -273.686289) (xy 299.377549 -273.737219)
			(xy 299.385492 -273.789923) (xy 299.38599 -273.816572) (xy 299.385492 -273.843221) (xy 299.377549 -273.895925)
			(xy 299.361839 -273.946855) (xy 299.338713 -273.994876) (xy 299.308689 -274.038913) (xy 299.272437 -274.077984)
			(xy 299.230766 -274.111215) (xy 299.184608 -274.137864) (xy 299.134994 -274.157336) (xy 299.083032 -274.169196)
			(xy 299.029882 -274.17318) (xy 298.976732 -274.169196) (xy 298.92477 -274.157336) (xy 298.875156 -274.137864)
			(xy 298.828998 -274.111215) (xy 298.787327 -274.077984) (xy 298.751075 -274.038913) (xy 298.721051 -273.994876)
			(xy 298.697925 -273.946855) (xy 298.682215 -273.895925) (xy 298.674272 -273.843221) (xy 284.272492 -273.843221)
			(xy 284.264549 -273.895925) (xy 284.248839 -273.946855) (xy 284.225713 -273.994876) (xy 284.195689 -274.038913)
			(xy 284.159437 -274.077984) (xy 284.117766 -274.111215) (xy 284.071608 -274.137864) (xy 284.021994 -274.157336)
			(xy 283.970032 -274.169196) (xy 283.916882 -274.17318) (xy 283.863732 -274.169196) (xy 283.81177 -274.157336)
			(xy 283.762156 -274.137864) (xy 283.715998 -274.111215) (xy 283.674327 -274.077984) (xy 283.638075 -274.038913)
			(xy 283.608051 -273.994876) (xy 283.584925 -273.946855) (xy 283.569215 -273.895925) (xy 283.561272 -273.843221)
			(xy 269.184892 -273.843221) (xy 269.176949 -273.895925) (xy 269.161239 -273.946855) (xy 269.138113 -273.994876)
			(xy 269.108089 -274.038913) (xy 269.071837 -274.077984) (xy 269.030166 -274.111215) (xy 268.984008 -274.137864)
			(xy 268.934394 -274.157336) (xy 268.882432 -274.169196) (xy 268.829282 -274.17318) (xy 268.776132 -274.169196)
			(xy 268.72417 -274.157336) (xy 268.674556 -274.137864) (xy 268.628398 -274.111215) (xy 268.586727 -274.077984)
			(xy 268.550475 -274.038913) (xy 268.520451 -273.994876) (xy 268.497325 -273.946855) (xy 268.481615 -273.895925)
			(xy 268.473672 -273.843221) (xy 254 -273.843221) (xy 254 -274.693359) (xy 264.373604 -274.693359)
			(xy 264.373604 -274.640061) (xy 264.381547 -274.587357) (xy 264.397257 -274.536427) (xy 264.420383 -274.488406)
			(xy 264.450407 -274.444369) (xy 264.486659 -274.405298) (xy 264.52833 -274.372067) (xy 264.574488 -274.345418)
			(xy 264.624102 -274.325946) (xy 264.676064 -274.314086) (xy 264.729214 -274.310103) (xy 264.782364 -274.314086)
			(xy 264.834326 -274.325946) (xy 264.88394 -274.345418) (xy 264.930098 -274.372067) (xy 264.971769 -274.405298)
			(xy 265.008021 -274.444369) (xy 265.038045 -274.488406) (xy 265.061171 -274.536427) (xy 265.076881 -274.587357)
			(xy 265.084824 -274.640061) (xy 265.085322 -274.66671) (xy 265.084824 -274.693359) (xy 268.473672 -274.693359)
			(xy 268.473672 -274.640061) (xy 268.481615 -274.587357) (xy 268.497325 -274.536427) (xy 268.520451 -274.488406)
			(xy 268.550475 -274.444369) (xy 268.586727 -274.405298) (xy 268.628398 -274.372067) (xy 268.674556 -274.345418)
			(xy 268.72417 -274.325946) (xy 268.776132 -274.314086) (xy 268.829282 -274.310103) (xy 268.882432 -274.314086)
			(xy 268.934394 -274.325946) (xy 268.984008 -274.345418) (xy 269.030166 -274.372067) (xy 269.071837 -274.405298)
			(xy 269.108089 -274.444369) (xy 269.138113 -274.488406) (xy 269.161239 -274.536427) (xy 269.176949 -274.587357)
			(xy 269.184892 -274.640061) (xy 269.18539 -274.66671) (xy 269.184892 -274.693359) (xy 279.461204 -274.693359)
			(xy 279.461204 -274.640061) (xy 279.469147 -274.587357) (xy 279.484857 -274.536427) (xy 279.507983 -274.488406)
			(xy 279.538007 -274.444369) (xy 279.574259 -274.405298) (xy 279.61593 -274.372067) (xy 279.662088 -274.345418)
			(xy 279.711702 -274.325946) (xy 279.763664 -274.314086) (xy 279.816814 -274.310103) (xy 279.869964 -274.314086)
			(xy 279.921926 -274.325946) (xy 279.97154 -274.345418) (xy 280.017698 -274.372067) (xy 280.059369 -274.405298)
			(xy 280.095621 -274.444369) (xy 280.125645 -274.488406) (xy 280.148771 -274.536427) (xy 280.164481 -274.587357)
			(xy 280.172424 -274.640061) (xy 280.172922 -274.66671) (xy 280.172424 -274.693359) (xy 283.561272 -274.693359)
			(xy 283.561272 -274.640061) (xy 283.569215 -274.587357) (xy 283.584925 -274.536427) (xy 283.608051 -274.488406)
			(xy 283.638075 -274.444369) (xy 283.674327 -274.405298) (xy 283.715998 -274.372067) (xy 283.762156 -274.345418)
			(xy 283.81177 -274.325946) (xy 283.863732 -274.314086) (xy 283.916882 -274.310103) (xy 283.970032 -274.314086)
			(xy 284.021994 -274.325946) (xy 284.071608 -274.345418) (xy 284.117766 -274.372067) (xy 284.159437 -274.405298)
			(xy 284.195689 -274.444369) (xy 284.225713 -274.488406) (xy 284.248839 -274.536427) (xy 284.264549 -274.587357)
			(xy 284.272492 -274.640061) (xy 284.27299 -274.66671) (xy 284.272492 -274.693359) (xy 294.548804 -274.693359)
			(xy 294.548804 -274.640061) (xy 294.556747 -274.587357) (xy 294.572457 -274.536427) (xy 294.595583 -274.488406)
			(xy 294.625607 -274.444369) (xy 294.661859 -274.405298) (xy 294.70353 -274.372067) (xy 294.749688 -274.345418)
			(xy 294.799302 -274.325946) (xy 294.851264 -274.314086) (xy 294.904414 -274.310103) (xy 294.957564 -274.314086)
			(xy 295.009526 -274.325946) (xy 295.05914 -274.345418) (xy 295.105298 -274.372067) (xy 295.146969 -274.405298)
			(xy 295.183221 -274.444369) (xy 295.213245 -274.488406) (xy 295.236371 -274.536427) (xy 295.252081 -274.587357)
			(xy 295.260024 -274.640061) (xy 295.260522 -274.66671) (xy 295.260024 -274.693359) (xy 295.259986 -274.693613)
			(xy 298.674272 -274.693613) (xy 298.674272 -274.640315) (xy 298.682215 -274.587611) (xy 298.697925 -274.536681)
			(xy 298.721051 -274.48866) (xy 298.751075 -274.444623) (xy 298.787327 -274.405552) (xy 298.828998 -274.372321)
			(xy 298.875156 -274.345672) (xy 298.92477 -274.3262) (xy 298.976732 -274.31434) (xy 299.029882 -274.310357)
			(xy 299.083032 -274.31434) (xy 299.134994 -274.3262) (xy 299.184608 -274.345672) (xy 299.230766 -274.372321)
			(xy 299.272437 -274.405552) (xy 299.308689 -274.444623) (xy 299.338713 -274.48866) (xy 299.361839 -274.536681)
			(xy 299.377549 -274.587611) (xy 299.385492 -274.640315) (xy 299.38599 -274.666964) (xy 299.385492 -274.693613)
			(xy 299.377549 -274.746317) (xy 299.361839 -274.797247) (xy 299.338713 -274.845268) (xy 299.308689 -274.889305)
			(xy 299.272437 -274.928376) (xy 299.230766 -274.961607) (xy 299.184608 -274.988256) (xy 299.134994 -275.007728)
			(xy 299.083032 -275.019588) (xy 299.029882 -275.023572) (xy 298.976732 -275.019588) (xy 298.92477 -275.007728)
			(xy 298.875156 -274.988256) (xy 298.828998 -274.961607) (xy 298.787327 -274.928376) (xy 298.751075 -274.889305)
			(xy 298.721051 -274.845268) (xy 298.697925 -274.797247) (xy 298.682215 -274.746317) (xy 298.674272 -274.693613)
			(xy 295.259986 -274.693613) (xy 295.252081 -274.746063) (xy 295.236371 -274.796993) (xy 295.213245 -274.845014)
			(xy 295.183221 -274.889051) (xy 295.146969 -274.928122) (xy 295.105298 -274.961353) (xy 295.05914 -274.988002)
			(xy 295.009526 -275.007474) (xy 294.957564 -275.019334) (xy 294.904414 -275.023318) (xy 294.851264 -275.019334)
			(xy 294.799302 -275.007474) (xy 294.749688 -274.988002) (xy 294.70353 -274.961353) (xy 294.661859 -274.928122)
			(xy 294.625607 -274.889051) (xy 294.595583 -274.845014) (xy 294.572457 -274.796993) (xy 294.556747 -274.746063)
			(xy 294.548804 -274.693359) (xy 284.272492 -274.693359) (xy 284.264549 -274.746063) (xy 284.248839 -274.796993)
			(xy 284.225713 -274.845014) (xy 284.195689 -274.889051) (xy 284.159437 -274.928122) (xy 284.117766 -274.961353)
			(xy 284.071608 -274.988002) (xy 284.021994 -275.007474) (xy 283.970032 -275.019334) (xy 283.916882 -275.023318)
			(xy 283.863732 -275.019334) (xy 283.81177 -275.007474) (xy 283.762156 -274.988002) (xy 283.715998 -274.961353)
			(xy 283.674327 -274.928122) (xy 283.638075 -274.889051) (xy 283.608051 -274.845014) (xy 283.584925 -274.796993)
			(xy 283.569215 -274.746063) (xy 283.561272 -274.693359) (xy 280.172424 -274.693359) (xy 280.164481 -274.746063)
			(xy 280.148771 -274.796993) (xy 280.125645 -274.845014) (xy 280.095621 -274.889051) (xy 280.059369 -274.928122)
			(xy 280.017698 -274.961353) (xy 279.97154 -274.988002) (xy 279.921926 -275.007474) (xy 279.869964 -275.019334)
			(xy 279.816814 -275.023318) (xy 279.763664 -275.019334) (xy 279.711702 -275.007474) (xy 279.662088 -274.988002)
			(xy 279.61593 -274.961353) (xy 279.574259 -274.928122) (xy 279.538007 -274.889051) (xy 279.507983 -274.845014)
			(xy 279.484857 -274.796993) (xy 279.469147 -274.746063) (xy 279.461204 -274.693359) (xy 269.184892 -274.693359)
			(xy 269.176949 -274.746063) (xy 269.161239 -274.796993) (xy 269.138113 -274.845014) (xy 269.108089 -274.889051)
			(xy 269.071837 -274.928122) (xy 269.030166 -274.961353) (xy 268.984008 -274.988002) (xy 268.934394 -275.007474)
			(xy 268.882432 -275.019334) (xy 268.829282 -275.023318) (xy 268.776132 -275.019334) (xy 268.72417 -275.007474)
			(xy 268.674556 -274.988002) (xy 268.628398 -274.961353) (xy 268.586727 -274.928122) (xy 268.550475 -274.889051)
			(xy 268.520451 -274.845014) (xy 268.497325 -274.796993) (xy 268.481615 -274.746063) (xy 268.473672 -274.693359)
			(xy 265.084824 -274.693359) (xy 265.076881 -274.746063) (xy 265.061171 -274.796993) (xy 265.038045 -274.845014)
			(xy 265.008021 -274.889051) (xy 264.971769 -274.928122) (xy 264.930098 -274.961353) (xy 264.88394 -274.988002)
			(xy 264.834326 -275.007474) (xy 264.782364 -275.019334) (xy 264.729214 -275.023318) (xy 264.676064 -275.019334)
			(xy 264.624102 -275.007474) (xy 264.574488 -274.988002) (xy 264.52833 -274.961353) (xy 264.486659 -274.928122)
			(xy 264.450407 -274.889051) (xy 264.420383 -274.845014) (xy 264.397257 -274.796993) (xy 264.381547 -274.746063)
			(xy 264.373604 -274.693359) (xy 254 -274.693359) (xy 254 -275.543243) (xy 264.373604 -275.543243)
			(xy 264.373604 -275.489945) (xy 264.381547 -275.437241) (xy 264.397257 -275.386311) (xy 264.420383 -275.33829)
			(xy 264.450407 -275.294253) (xy 264.486659 -275.255182) (xy 264.52833 -275.221951) (xy 264.574488 -275.195302)
			(xy 264.624102 -275.17583) (xy 264.676064 -275.16397) (xy 264.729214 -275.159987) (xy 264.782364 -275.16397)
			(xy 264.834326 -275.17583) (xy 264.88394 -275.195302) (xy 264.930098 -275.221951) (xy 264.971769 -275.255182)
			(xy 265.008021 -275.294253) (xy 265.038045 -275.33829) (xy 265.061171 -275.386311) (xy 265.076881 -275.437241)
			(xy 265.084824 -275.489945) (xy 265.085322 -275.516594) (xy 265.084824 -275.543243) (xy 279.461204 -275.543243)
			(xy 279.461204 -275.489945) (xy 279.469147 -275.437241) (xy 279.484857 -275.386311) (xy 279.507983 -275.33829)
			(xy 279.538007 -275.294253) (xy 279.574259 -275.255182) (xy 279.61593 -275.221951) (xy 279.662088 -275.195302)
			(xy 279.711702 -275.17583) (xy 279.763664 -275.16397) (xy 279.816814 -275.159987) (xy 279.869964 -275.16397)
			(xy 279.921926 -275.17583) (xy 279.97154 -275.195302) (xy 280.017698 -275.221951) (xy 280.059369 -275.255182)
			(xy 280.095621 -275.294253) (xy 280.125645 -275.33829) (xy 280.148771 -275.386311) (xy 280.164481 -275.437241)
			(xy 280.172424 -275.489945) (xy 280.172922 -275.516594) (xy 280.172424 -275.543243) (xy 294.548804 -275.543243)
			(xy 294.548804 -275.489945) (xy 294.556747 -275.437241) (xy 294.572457 -275.386311) (xy 294.595583 -275.33829)
			(xy 294.625607 -275.294253) (xy 294.661859 -275.255182) (xy 294.70353 -275.221951) (xy 294.749688 -275.195302)
			(xy 294.799302 -275.17583) (xy 294.851264 -275.16397) (xy 294.904414 -275.159987) (xy 294.957564 -275.16397)
			(xy 295.009526 -275.17583) (xy 295.05914 -275.195302) (xy 295.105298 -275.221951) (xy 295.146969 -275.255182)
			(xy 295.183221 -275.294253) (xy 295.213245 -275.33829) (xy 295.236371 -275.386311) (xy 295.252081 -275.437241)
			(xy 295.260024 -275.489945) (xy 295.260522 -275.516594) (xy 295.260024 -275.543243) (xy 295.252081 -275.595947)
			(xy 295.236371 -275.646877) (xy 295.213245 -275.694898) (xy 295.183221 -275.738935) (xy 295.146969 -275.778006)
			(xy 295.105298 -275.811237) (xy 295.05914 -275.837886) (xy 295.009526 -275.857358) (xy 294.957564 -275.869218)
			(xy 294.904414 -275.873202) (xy 294.851264 -275.869218) (xy 294.799302 -275.857358) (xy 294.749688 -275.837886)
			(xy 294.70353 -275.811237) (xy 294.661859 -275.778006) (xy 294.625607 -275.738935) (xy 294.595583 -275.694898)
			(xy 294.572457 -275.646877) (xy 294.556747 -275.595947) (xy 294.548804 -275.543243) (xy 280.172424 -275.543243)
			(xy 280.164481 -275.595947) (xy 280.148771 -275.646877) (xy 280.125645 -275.694898) (xy 280.095621 -275.738935)
			(xy 280.059369 -275.778006) (xy 280.017698 -275.811237) (xy 279.97154 -275.837886) (xy 279.921926 -275.857358)
			(xy 279.869964 -275.869218) (xy 279.816814 -275.873202) (xy 279.763664 -275.869218) (xy 279.711702 -275.857358)
			(xy 279.662088 -275.837886) (xy 279.61593 -275.811237) (xy 279.574259 -275.778006) (xy 279.538007 -275.738935)
			(xy 279.507983 -275.694898) (xy 279.484857 -275.646877) (xy 279.469147 -275.595947) (xy 279.461204 -275.543243)
			(xy 265.084824 -275.543243) (xy 265.076881 -275.595947) (xy 265.061171 -275.646877) (xy 265.038045 -275.694898)
			(xy 265.008021 -275.738935) (xy 264.971769 -275.778006) (xy 264.930098 -275.811237) (xy 264.88394 -275.837886)
			(xy 264.834326 -275.857358) (xy 264.782364 -275.869218) (xy 264.729214 -275.873202) (xy 264.676064 -275.869218)
			(xy 264.624102 -275.857358) (xy 264.574488 -275.837886) (xy 264.52833 -275.811237) (xy 264.486659 -275.778006)
			(xy 264.450407 -275.738935) (xy 264.420383 -275.694898) (xy 264.397257 -275.646877) (xy 264.381547 -275.595947)
			(xy 264.373604 -275.543243) (xy 254 -275.543243) (xy 254 -276.393381) (xy 268.473672 -276.393381)
			(xy 268.473672 -276.340083) (xy 268.481615 -276.287379) (xy 268.497325 -276.236449) (xy 268.520451 -276.188428)
			(xy 268.550475 -276.144391) (xy 268.586727 -276.10532) (xy 268.628398 -276.072089) (xy 268.674556 -276.04544)
			(xy 268.72417 -276.025968) (xy 268.776132 -276.014108) (xy 268.829282 -276.010125) (xy 268.882432 -276.014108)
			(xy 268.934394 -276.025968) (xy 268.984008 -276.04544) (xy 269.030166 -276.072089) (xy 269.071837 -276.10532)
			(xy 269.108089 -276.144391) (xy 269.138113 -276.188428) (xy 269.161239 -276.236449) (xy 269.176949 -276.287379)
			(xy 269.184892 -276.340083) (xy 269.18539 -276.366732) (xy 269.184892 -276.393381) (xy 283.561272 -276.393381)
			(xy 283.561272 -276.340083) (xy 283.569215 -276.287379) (xy 283.584925 -276.236449) (xy 283.608051 -276.188428)
			(xy 283.638075 -276.144391) (xy 283.674327 -276.10532) (xy 283.715998 -276.072089) (xy 283.762156 -276.04544)
			(xy 283.81177 -276.025968) (xy 283.863732 -276.014108) (xy 283.916882 -276.010125) (xy 283.970032 -276.014108)
			(xy 284.021994 -276.025968) (xy 284.071608 -276.04544) (xy 284.117766 -276.072089) (xy 284.159437 -276.10532)
			(xy 284.195689 -276.144391) (xy 284.225713 -276.188428) (xy 284.248839 -276.236449) (xy 284.264549 -276.287379)
			(xy 284.272492 -276.340083) (xy 284.27299 -276.366732) (xy 284.272492 -276.393381) (xy 284.272454 -276.393635)
			(xy 298.674272 -276.393635) (xy 298.674272 -276.340337) (xy 298.682215 -276.287633) (xy 298.697925 -276.236703)
			(xy 298.721051 -276.188682) (xy 298.751075 -276.144645) (xy 298.787327 -276.105574) (xy 298.828998 -276.072343)
			(xy 298.875156 -276.045694) (xy 298.92477 -276.026222) (xy 298.976732 -276.014362) (xy 299.029882 -276.010379)
			(xy 299.083032 -276.014362) (xy 299.134994 -276.026222) (xy 299.184608 -276.045694) (xy 299.230766 -276.072343)
			(xy 299.272437 -276.105574) (xy 299.308689 -276.144645) (xy 299.338713 -276.188682) (xy 299.361839 -276.236703)
			(xy 299.377549 -276.287633) (xy 299.385492 -276.340337) (xy 299.38599 -276.366986) (xy 299.385492 -276.393635)
			(xy 299.377549 -276.446339) (xy 299.361839 -276.497269) (xy 299.338713 -276.54529) (xy 299.308689 -276.589327)
			(xy 299.272437 -276.628398) (xy 299.230766 -276.661629) (xy 299.184608 -276.688278) (xy 299.134994 -276.70775)
			(xy 299.083032 -276.71961) (xy 299.029882 -276.723594) (xy 298.976732 -276.71961) (xy 298.92477 -276.70775)
			(xy 298.875156 -276.688278) (xy 298.828998 -276.661629) (xy 298.787327 -276.628398) (xy 298.751075 -276.589327)
			(xy 298.721051 -276.54529) (xy 298.697925 -276.497269) (xy 298.682215 -276.446339) (xy 298.674272 -276.393635)
			(xy 284.272454 -276.393635) (xy 284.264549 -276.446085) (xy 284.248839 -276.497015) (xy 284.225713 -276.545036)
			(xy 284.195689 -276.589073) (xy 284.159437 -276.628144) (xy 284.117766 -276.661375) (xy 284.071608 -276.688024)
			(xy 284.021994 -276.707496) (xy 283.970032 -276.719356) (xy 283.916882 -276.72334) (xy 283.863732 -276.719356)
			(xy 283.81177 -276.707496) (xy 283.762156 -276.688024) (xy 283.715998 -276.661375) (xy 283.674327 -276.628144)
			(xy 283.638075 -276.589073) (xy 283.608051 -276.545036) (xy 283.584925 -276.497015) (xy 283.569215 -276.446085)
			(xy 283.561272 -276.393381) (xy 269.184892 -276.393381) (xy 269.176949 -276.446085) (xy 269.161239 -276.497015)
			(xy 269.138113 -276.545036) (xy 269.108089 -276.589073) (xy 269.071837 -276.628144) (xy 269.030166 -276.661375)
			(xy 268.984008 -276.688024) (xy 268.934394 -276.707496) (xy 268.882432 -276.719356) (xy 268.829282 -276.72334)
			(xy 268.776132 -276.719356) (xy 268.72417 -276.707496) (xy 268.674556 -276.688024) (xy 268.628398 -276.661375)
			(xy 268.586727 -276.628144) (xy 268.550475 -276.589073) (xy 268.520451 -276.545036) (xy 268.497325 -276.497015)
			(xy 268.481615 -276.446085) (xy 268.473672 -276.393381) (xy 254 -276.393381) (xy 254 -277.243265)
			(xy 264.373604 -277.243265) (xy 264.373604 -277.189967) (xy 264.381547 -277.137263) (xy 264.397257 -277.086333)
			(xy 264.420383 -277.038312) (xy 264.450407 -276.994275) (xy 264.486659 -276.955204) (xy 264.52833 -276.921973)
			(xy 264.574488 -276.895324) (xy 264.624102 -276.875852) (xy 264.676064 -276.863992) (xy 264.729214 -276.860009)
			(xy 264.782364 -276.863992) (xy 264.834326 -276.875852) (xy 264.88394 -276.895324) (xy 264.930098 -276.921973)
			(xy 264.971769 -276.955204) (xy 265.008021 -276.994275) (xy 265.038045 -277.038312) (xy 265.061171 -277.086333)
			(xy 265.076881 -277.137263) (xy 265.084824 -277.189967) (xy 265.085322 -277.216616) (xy 265.084824 -277.243265)
			(xy 279.461204 -277.243265) (xy 279.461204 -277.189967) (xy 279.469147 -277.137263) (xy 279.484857 -277.086333)
			(xy 279.507983 -277.038312) (xy 279.538007 -276.994275) (xy 279.574259 -276.955204) (xy 279.61593 -276.921973)
			(xy 279.662088 -276.895324) (xy 279.711702 -276.875852) (xy 279.763664 -276.863992) (xy 279.816814 -276.860009)
			(xy 279.869964 -276.863992) (xy 279.921926 -276.875852) (xy 279.97154 -276.895324) (xy 280.017698 -276.921973)
			(xy 280.059369 -276.955204) (xy 280.095621 -276.994275) (xy 280.125645 -277.038312) (xy 280.148771 -277.086333)
			(xy 280.164481 -277.137263) (xy 280.172424 -277.189967) (xy 280.172922 -277.216616) (xy 280.172424 -277.243265)
			(xy 294.548804 -277.243265) (xy 294.548804 -277.189967) (xy 294.556747 -277.137263) (xy 294.572457 -277.086333)
			(xy 294.595583 -277.038312) (xy 294.625607 -276.994275) (xy 294.661859 -276.955204) (xy 294.70353 -276.921973)
			(xy 294.749688 -276.895324) (xy 294.799302 -276.875852) (xy 294.851264 -276.863992) (xy 294.904414 -276.860009)
			(xy 294.957564 -276.863992) (xy 295.009526 -276.875852) (xy 295.05914 -276.895324) (xy 295.105298 -276.921973)
			(xy 295.146969 -276.955204) (xy 295.183221 -276.994275) (xy 295.213245 -277.038312) (xy 295.236371 -277.086333)
			(xy 295.252081 -277.137263) (xy 295.260024 -277.189967) (xy 295.260522 -277.216616) (xy 295.260024 -277.243265)
			(xy 295.252081 -277.295969) (xy 295.236371 -277.346899) (xy 295.213245 -277.39492) (xy 295.183221 -277.438957)
			(xy 295.146969 -277.478028) (xy 295.105298 -277.511259) (xy 295.05914 -277.537908) (xy 295.009526 -277.55738)
			(xy 294.957564 -277.56924) (xy 294.904414 -277.573224) (xy 294.851264 -277.56924) (xy 294.799302 -277.55738)
			(xy 294.749688 -277.537908) (xy 294.70353 -277.511259) (xy 294.661859 -277.478028) (xy 294.625607 -277.438957)
			(xy 294.595583 -277.39492) (xy 294.572457 -277.346899) (xy 294.556747 -277.295969) (xy 294.548804 -277.243265)
			(xy 280.172424 -277.243265) (xy 280.164481 -277.295969) (xy 280.148771 -277.346899) (xy 280.125645 -277.39492)
			(xy 280.095621 -277.438957) (xy 280.059369 -277.478028) (xy 280.017698 -277.511259) (xy 279.97154 -277.537908)
			(xy 279.921926 -277.55738) (xy 279.869964 -277.56924) (xy 279.816814 -277.573224) (xy 279.763664 -277.56924)
			(xy 279.711702 -277.55738) (xy 279.662088 -277.537908) (xy 279.61593 -277.511259) (xy 279.574259 -277.478028)
			(xy 279.538007 -277.438957) (xy 279.507983 -277.39492) (xy 279.484857 -277.346899) (xy 279.469147 -277.295969)
			(xy 279.461204 -277.243265) (xy 265.084824 -277.243265) (xy 265.076881 -277.295969) (xy 265.061171 -277.346899)
			(xy 265.038045 -277.39492) (xy 265.008021 -277.438957) (xy 264.971769 -277.478028) (xy 264.930098 -277.511259)
			(xy 264.88394 -277.537908) (xy 264.834326 -277.55738) (xy 264.782364 -277.56924) (xy 264.729214 -277.573224)
			(xy 264.676064 -277.56924) (xy 264.624102 -277.55738) (xy 264.574488 -277.537908) (xy 264.52833 -277.511259)
			(xy 264.486659 -277.478028) (xy 264.450407 -277.438957) (xy 264.420383 -277.39492) (xy 264.397257 -277.346899)
			(xy 264.381547 -277.295969) (xy 264.373604 -277.243265) (xy 254 -277.243265) (xy 254 -278.093403)
			(xy 268.473672 -278.093403) (xy 268.473672 -278.040105) (xy 268.481615 -277.987401) (xy 268.497325 -277.936471)
			(xy 268.520451 -277.88845) (xy 268.550475 -277.844413) (xy 268.586727 -277.805342) (xy 268.628398 -277.772111)
			(xy 268.674556 -277.745462) (xy 268.72417 -277.72599) (xy 268.776132 -277.71413) (xy 268.829282 -277.710147)
			(xy 268.882432 -277.71413) (xy 268.934394 -277.72599) (xy 268.984008 -277.745462) (xy 269.030166 -277.772111)
			(xy 269.071837 -277.805342) (xy 269.108089 -277.844413) (xy 269.138113 -277.88845) (xy 269.161239 -277.936471)
			(xy 269.176949 -277.987401) (xy 269.184892 -278.040105) (xy 269.18539 -278.066754) (xy 269.184892 -278.093403)
			(xy 283.561272 -278.093403) (xy 283.561272 -278.040105) (xy 283.569215 -277.987401) (xy 283.584925 -277.936471)
			(xy 283.608051 -277.88845) (xy 283.638075 -277.844413) (xy 283.674327 -277.805342) (xy 283.715998 -277.772111)
			(xy 283.762156 -277.745462) (xy 283.81177 -277.72599) (xy 283.863732 -277.71413) (xy 283.916882 -277.710147)
			(xy 283.970032 -277.71413) (xy 284.021994 -277.72599) (xy 284.071608 -277.745462) (xy 284.117766 -277.772111)
			(xy 284.159437 -277.805342) (xy 284.195689 -277.844413) (xy 284.225713 -277.88845) (xy 284.248839 -277.936471)
			(xy 284.264549 -277.987401) (xy 284.272492 -278.040105) (xy 284.27299 -278.066754) (xy 284.272492 -278.093403)
			(xy 284.272454 -278.093657) (xy 298.674272 -278.093657) (xy 298.674272 -278.040359) (xy 298.682215 -277.987655)
			(xy 298.697925 -277.936725) (xy 298.721051 -277.888704) (xy 298.751075 -277.844667) (xy 298.787327 -277.805596)
			(xy 298.828998 -277.772365) (xy 298.875156 -277.745716) (xy 298.92477 -277.726244) (xy 298.976732 -277.714384)
			(xy 299.029882 -277.710401) (xy 299.083032 -277.714384) (xy 299.134994 -277.726244) (xy 299.184608 -277.745716)
			(xy 299.230766 -277.772365) (xy 299.272437 -277.805596) (xy 299.308689 -277.844667) (xy 299.338713 -277.888704)
			(xy 299.361839 -277.936725) (xy 299.377549 -277.987655) (xy 299.385492 -278.040359) (xy 299.38599 -278.067008)
			(xy 299.385492 -278.093657) (xy 299.377549 -278.146361) (xy 299.361839 -278.197291) (xy 299.338713 -278.245312)
			(xy 299.308689 -278.289349) (xy 299.272437 -278.32842) (xy 299.230766 -278.361651) (xy 299.184608 -278.3883)
			(xy 299.134994 -278.407772) (xy 299.083032 -278.419632) (xy 299.029882 -278.423616) (xy 298.976732 -278.419632)
			(xy 298.92477 -278.407772) (xy 298.875156 -278.3883) (xy 298.828998 -278.361651) (xy 298.787327 -278.32842)
			(xy 298.751075 -278.289349) (xy 298.721051 -278.245312) (xy 298.697925 -278.197291) (xy 298.682215 -278.146361)
			(xy 298.674272 -278.093657) (xy 284.272454 -278.093657) (xy 284.264549 -278.146107) (xy 284.248839 -278.197037)
			(xy 284.225713 -278.245058) (xy 284.195689 -278.289095) (xy 284.159437 -278.328166) (xy 284.117766 -278.361397)
			(xy 284.071608 -278.388046) (xy 284.021994 -278.407518) (xy 283.970032 -278.419378) (xy 283.916882 -278.423362)
			(xy 283.863732 -278.419378) (xy 283.81177 -278.407518) (xy 283.762156 -278.388046) (xy 283.715998 -278.361397)
			(xy 283.674327 -278.328166) (xy 283.638075 -278.289095) (xy 283.608051 -278.245058) (xy 283.584925 -278.197037)
			(xy 283.569215 -278.146107) (xy 283.561272 -278.093403) (xy 269.184892 -278.093403) (xy 269.176949 -278.146107)
			(xy 269.161239 -278.197037) (xy 269.138113 -278.245058) (xy 269.108089 -278.289095) (xy 269.071837 -278.328166)
			(xy 269.030166 -278.361397) (xy 268.984008 -278.388046) (xy 268.934394 -278.407518) (xy 268.882432 -278.419378)
			(xy 268.829282 -278.423362) (xy 268.776132 -278.419378) (xy 268.72417 -278.407518) (xy 268.674556 -278.388046)
			(xy 268.628398 -278.361397) (xy 268.586727 -278.328166) (xy 268.550475 -278.289095) (xy 268.520451 -278.245058)
			(xy 268.497325 -278.197037) (xy 268.481615 -278.146107) (xy 268.473672 -278.093403) (xy 254 -278.093403)
			(xy 254 -278.943287) (xy 264.373604 -278.943287) (xy 264.373604 -278.889989) (xy 264.381547 -278.837285)
			(xy 264.397257 -278.786355) (xy 264.420383 -278.738334) (xy 264.450407 -278.694297) (xy 264.486659 -278.655226)
			(xy 264.52833 -278.621995) (xy 264.574488 -278.595346) (xy 264.624102 -278.575874) (xy 264.676064 -278.564014)
			(xy 264.729214 -278.560031) (xy 264.782364 -278.564014) (xy 264.834326 -278.575874) (xy 264.88394 -278.595346)
			(xy 264.930098 -278.621995) (xy 264.971769 -278.655226) (xy 265.008021 -278.694297) (xy 265.038045 -278.738334)
			(xy 265.061171 -278.786355) (xy 265.076881 -278.837285) (xy 265.084824 -278.889989) (xy 265.085322 -278.916638)
			(xy 265.084824 -278.943287) (xy 279.461204 -278.943287) (xy 279.461204 -278.889989) (xy 279.469147 -278.837285)
			(xy 279.484857 -278.786355) (xy 279.507983 -278.738334) (xy 279.538007 -278.694297) (xy 279.574259 -278.655226)
			(xy 279.61593 -278.621995) (xy 279.662088 -278.595346) (xy 279.711702 -278.575874) (xy 279.763664 -278.564014)
			(xy 279.816814 -278.560031) (xy 279.869964 -278.564014) (xy 279.921926 -278.575874) (xy 279.97154 -278.595346)
			(xy 280.017698 -278.621995) (xy 280.059369 -278.655226) (xy 280.095621 -278.694297) (xy 280.125645 -278.738334)
			(xy 280.148771 -278.786355) (xy 280.164481 -278.837285) (xy 280.172424 -278.889989) (xy 280.172922 -278.916638)
			(xy 280.172424 -278.943287) (xy 294.548804 -278.943287) (xy 294.548804 -278.889989) (xy 294.556747 -278.837285)
			(xy 294.572457 -278.786355) (xy 294.595583 -278.738334) (xy 294.625607 -278.694297) (xy 294.661859 -278.655226)
			(xy 294.70353 -278.621995) (xy 294.749688 -278.595346) (xy 294.799302 -278.575874) (xy 294.851264 -278.564014)
			(xy 294.904414 -278.560031) (xy 294.957564 -278.564014) (xy 295.009526 -278.575874) (xy 295.05914 -278.595346)
			(xy 295.105298 -278.621995) (xy 295.146969 -278.655226) (xy 295.183221 -278.694297) (xy 295.213245 -278.738334)
			(xy 295.236371 -278.786355) (xy 295.252081 -278.837285) (xy 295.260024 -278.889989) (xy 295.260522 -278.916638)
			(xy 295.260024 -278.943287) (xy 295.252081 -278.995991) (xy 295.236371 -279.046921) (xy 295.213245 -279.094942)
			(xy 295.183221 -279.138979) (xy 295.146969 -279.17805) (xy 295.105298 -279.211281) (xy 295.05914 -279.23793)
			(xy 295.009526 -279.257402) (xy 294.957564 -279.269262) (xy 294.904414 -279.273246) (xy 294.851264 -279.269262)
			(xy 294.799302 -279.257402) (xy 294.749688 -279.23793) (xy 294.70353 -279.211281) (xy 294.661859 -279.17805)
			(xy 294.625607 -279.138979) (xy 294.595583 -279.094942) (xy 294.572457 -279.046921) (xy 294.556747 -278.995991)
			(xy 294.548804 -278.943287) (xy 280.172424 -278.943287) (xy 280.164481 -278.995991) (xy 280.148771 -279.046921)
			(xy 280.125645 -279.094942) (xy 280.095621 -279.138979) (xy 280.059369 -279.17805) (xy 280.017698 -279.211281)
			(xy 279.97154 -279.23793) (xy 279.921926 -279.257402) (xy 279.869964 -279.269262) (xy 279.816814 -279.273246)
			(xy 279.763664 -279.269262) (xy 279.711702 -279.257402) (xy 279.662088 -279.23793) (xy 279.61593 -279.211281)
			(xy 279.574259 -279.17805) (xy 279.538007 -279.138979) (xy 279.507983 -279.094942) (xy 279.484857 -279.046921)
			(xy 279.469147 -278.995991) (xy 279.461204 -278.943287) (xy 265.084824 -278.943287) (xy 265.076881 -278.995991)
			(xy 265.061171 -279.046921) (xy 265.038045 -279.094942) (xy 265.008021 -279.138979) (xy 264.971769 -279.17805)
			(xy 264.930098 -279.211281) (xy 264.88394 -279.23793) (xy 264.834326 -279.257402) (xy 264.782364 -279.269262)
			(xy 264.729214 -279.273246) (xy 264.676064 -279.269262) (xy 264.624102 -279.257402) (xy 264.574488 -279.23793)
			(xy 264.52833 -279.211281) (xy 264.486659 -279.17805) (xy 264.450407 -279.138979) (xy 264.420383 -279.094942)
			(xy 264.397257 -279.046921) (xy 264.381547 -278.995991) (xy 264.373604 -278.943287) (xy 254 -278.943287)
			(xy 254 -279.793425) (xy 268.473672 -279.793425) (xy 268.473672 -279.740127) (xy 268.481615 -279.687423)
			(xy 268.497325 -279.636493) (xy 268.520451 -279.588472) (xy 268.550475 -279.544435) (xy 268.586727 -279.505364)
			(xy 268.628398 -279.472133) (xy 268.674556 -279.445484) (xy 268.72417 -279.426012) (xy 268.776132 -279.414152)
			(xy 268.829282 -279.410169) (xy 268.882432 -279.414152) (xy 268.934394 -279.426012) (xy 268.984008 -279.445484)
			(xy 269.030166 -279.472133) (xy 269.071837 -279.505364) (xy 269.108089 -279.544435) (xy 269.138113 -279.588472)
			(xy 269.161239 -279.636493) (xy 269.176949 -279.687423) (xy 269.184892 -279.740127) (xy 269.18539 -279.766776)
			(xy 269.184892 -279.793425) (xy 283.561272 -279.793425) (xy 283.561272 -279.740127) (xy 283.569215 -279.687423)
			(xy 283.584925 -279.636493) (xy 283.608051 -279.588472) (xy 283.638075 -279.544435) (xy 283.674327 -279.505364)
			(xy 283.715998 -279.472133) (xy 283.762156 -279.445484) (xy 283.81177 -279.426012) (xy 283.863732 -279.414152)
			(xy 283.916882 -279.410169) (xy 283.970032 -279.414152) (xy 284.021994 -279.426012) (xy 284.071608 -279.445484)
			(xy 284.117766 -279.472133) (xy 284.159437 -279.505364) (xy 284.195689 -279.544435) (xy 284.225713 -279.588472)
			(xy 284.248839 -279.636493) (xy 284.264549 -279.687423) (xy 284.272492 -279.740127) (xy 284.27299 -279.766776)
			(xy 284.272492 -279.793425) (xy 298.674272 -279.793425) (xy 298.674272 -279.740127) (xy 298.682215 -279.687423)
			(xy 298.697925 -279.636493) (xy 298.721051 -279.588472) (xy 298.751075 -279.544435) (xy 298.787327 -279.505364)
			(xy 298.828998 -279.472133) (xy 298.875156 -279.445484) (xy 298.92477 -279.426012) (xy 298.976732 -279.414152)
			(xy 299.029882 -279.410169) (xy 299.083032 -279.414152) (xy 299.134994 -279.426012) (xy 299.184608 -279.445484)
			(xy 299.230766 -279.472133) (xy 299.272437 -279.505364) (xy 299.308689 -279.544435) (xy 299.338713 -279.588472)
			(xy 299.361839 -279.636493) (xy 299.377549 -279.687423) (xy 299.385492 -279.740127) (xy 299.38599 -279.766776)
			(xy 299.385492 -279.793425) (xy 299.377549 -279.846129) (xy 299.361839 -279.897059) (xy 299.338713 -279.94508)
			(xy 299.308689 -279.989117) (xy 299.272437 -280.028188) (xy 299.230766 -280.061419) (xy 299.184608 -280.088068)
			(xy 299.134994 -280.10754) (xy 299.083032 -280.1194) (xy 299.029882 -280.123384) (xy 298.976732 -280.1194)
			(xy 298.92477 -280.10754) (xy 298.875156 -280.088068) (xy 298.828998 -280.061419) (xy 298.787327 -280.028188)
			(xy 298.751075 -279.989117) (xy 298.721051 -279.94508) (xy 298.697925 -279.897059) (xy 298.682215 -279.846129)
			(xy 298.674272 -279.793425) (xy 284.272492 -279.793425) (xy 284.264549 -279.846129) (xy 284.248839 -279.897059)
			(xy 284.225713 -279.94508) (xy 284.195689 -279.989117) (xy 284.159437 -280.028188) (xy 284.117766 -280.061419)
			(xy 284.071608 -280.088068) (xy 284.021994 -280.10754) (xy 283.970032 -280.1194) (xy 283.916882 -280.123384)
			(xy 283.863732 -280.1194) (xy 283.81177 -280.10754) (xy 283.762156 -280.088068) (xy 283.715998 -280.061419)
			(xy 283.674327 -280.028188) (xy 283.638075 -279.989117) (xy 283.608051 -279.94508) (xy 283.584925 -279.897059)
			(xy 283.569215 -279.846129) (xy 283.561272 -279.793425) (xy 269.184892 -279.793425) (xy 269.176949 -279.846129)
			(xy 269.161239 -279.897059) (xy 269.138113 -279.94508) (xy 269.108089 -279.989117) (xy 269.071837 -280.028188)
			(xy 269.030166 -280.061419) (xy 268.984008 -280.088068) (xy 268.934394 -280.10754) (xy 268.882432 -280.1194)
			(xy 268.829282 -280.123384) (xy 268.776132 -280.1194) (xy 268.72417 -280.10754) (xy 268.674556 -280.088068)
			(xy 268.628398 -280.061419) (xy 268.586727 -280.028188) (xy 268.550475 -279.989117) (xy 268.520451 -279.94508)
			(xy 268.497325 -279.897059) (xy 268.481615 -279.846129) (xy 268.473672 -279.793425) (xy 254 -279.793425)
			(xy 254 -280.643309) (xy 264.373604 -280.643309) (xy 264.373604 -280.590011) (xy 264.381547 -280.537307)
			(xy 264.397257 -280.486377) (xy 264.420383 -280.438356) (xy 264.450407 -280.394319) (xy 264.486659 -280.355248)
			(xy 264.52833 -280.322017) (xy 264.574488 -280.295368) (xy 264.624102 -280.275896) (xy 264.676064 -280.264036)
			(xy 264.729214 -280.260053) (xy 264.782364 -280.264036) (xy 264.834326 -280.275896) (xy 264.88394 -280.295368)
			(xy 264.930098 -280.322017) (xy 264.971769 -280.355248) (xy 265.008021 -280.394319) (xy 265.038045 -280.438356)
			(xy 265.061171 -280.486377) (xy 265.076881 -280.537307) (xy 265.084824 -280.590011) (xy 265.085322 -280.61666)
			(xy 265.084824 -280.643309) (xy 279.461204 -280.643309) (xy 279.461204 -280.590011) (xy 279.469147 -280.537307)
			(xy 279.484857 -280.486377) (xy 279.507983 -280.438356) (xy 279.538007 -280.394319) (xy 279.574259 -280.355248)
			(xy 279.61593 -280.322017) (xy 279.662088 -280.295368) (xy 279.711702 -280.275896) (xy 279.763664 -280.264036)
			(xy 279.816814 -280.260053) (xy 279.869964 -280.264036) (xy 279.921926 -280.275896) (xy 279.97154 -280.295368)
			(xy 280.017698 -280.322017) (xy 280.059369 -280.355248) (xy 280.095621 -280.394319) (xy 280.125645 -280.438356)
			(xy 280.148771 -280.486377) (xy 280.164481 -280.537307) (xy 280.172424 -280.590011) (xy 280.172922 -280.61666)
			(xy 280.172424 -280.643309) (xy 294.548804 -280.643309) (xy 294.548804 -280.590011) (xy 294.556747 -280.537307)
			(xy 294.572457 -280.486377) (xy 294.595583 -280.438356) (xy 294.625607 -280.394319) (xy 294.661859 -280.355248)
			(xy 294.70353 -280.322017) (xy 294.749688 -280.295368) (xy 294.799302 -280.275896) (xy 294.851264 -280.264036)
			(xy 294.904414 -280.260053) (xy 294.957564 -280.264036) (xy 295.009526 -280.275896) (xy 295.05914 -280.295368)
			(xy 295.105298 -280.322017) (xy 295.146969 -280.355248) (xy 295.183221 -280.394319) (xy 295.213245 -280.438356)
			(xy 295.236371 -280.486377) (xy 295.252081 -280.537307) (xy 295.260024 -280.590011) (xy 295.260522 -280.61666)
			(xy 295.260024 -280.643309) (xy 295.252081 -280.696013) (xy 295.236371 -280.746943) (xy 295.213245 -280.794964)
			(xy 295.183221 -280.839001) (xy 295.146969 -280.878072) (xy 295.105298 -280.911303) (xy 295.05914 -280.937952)
			(xy 295.009526 -280.957424) (xy 294.957564 -280.969284) (xy 294.904414 -280.973268) (xy 294.851264 -280.969284)
			(xy 294.799302 -280.957424) (xy 294.749688 -280.937952) (xy 294.70353 -280.911303) (xy 294.661859 -280.878072)
			(xy 294.625607 -280.839001) (xy 294.595583 -280.794964) (xy 294.572457 -280.746943) (xy 294.556747 -280.696013)
			(xy 294.548804 -280.643309) (xy 280.172424 -280.643309) (xy 280.164481 -280.696013) (xy 280.148771 -280.746943)
			(xy 280.125645 -280.794964) (xy 280.095621 -280.839001) (xy 280.059369 -280.878072) (xy 280.017698 -280.911303)
			(xy 279.97154 -280.937952) (xy 279.921926 -280.957424) (xy 279.869964 -280.969284) (xy 279.816814 -280.973268)
			(xy 279.763664 -280.969284) (xy 279.711702 -280.957424) (xy 279.662088 -280.937952) (xy 279.61593 -280.911303)
			(xy 279.574259 -280.878072) (xy 279.538007 -280.839001) (xy 279.507983 -280.794964) (xy 279.484857 -280.746943)
			(xy 279.469147 -280.696013) (xy 279.461204 -280.643309) (xy 265.084824 -280.643309) (xy 265.076881 -280.696013)
			(xy 265.061171 -280.746943) (xy 265.038045 -280.794964) (xy 265.008021 -280.839001) (xy 264.971769 -280.878072)
			(xy 264.930098 -280.911303) (xy 264.88394 -280.937952) (xy 264.834326 -280.957424) (xy 264.782364 -280.969284)
			(xy 264.729214 -280.973268) (xy 264.676064 -280.969284) (xy 264.624102 -280.957424) (xy 264.574488 -280.937952)
			(xy 264.52833 -280.911303) (xy 264.486659 -280.878072) (xy 264.450407 -280.839001) (xy 264.420383 -280.794964)
			(xy 264.397257 -280.746943) (xy 264.381547 -280.696013) (xy 264.373604 -280.643309) (xy 254 -280.643309)
			(xy 254 -281.493447) (xy 268.473672 -281.493447) (xy 268.473672 -281.440149) (xy 268.481615 -281.387445)
			(xy 268.497325 -281.336515) (xy 268.520451 -281.288494) (xy 268.550475 -281.244457) (xy 268.586727 -281.205386)
			(xy 268.628398 -281.172155) (xy 268.674556 -281.145506) (xy 268.72417 -281.126034) (xy 268.776132 -281.114174)
			(xy 268.829282 -281.110191) (xy 268.882432 -281.114174) (xy 268.934394 -281.126034) (xy 268.984008 -281.145506)
			(xy 269.030166 -281.172155) (xy 269.071837 -281.205386) (xy 269.108089 -281.244457) (xy 269.138113 -281.288494)
			(xy 269.161239 -281.336515) (xy 269.176949 -281.387445) (xy 269.184892 -281.440149) (xy 269.18539 -281.466798)
			(xy 269.184892 -281.493447) (xy 283.561272 -281.493447) (xy 283.561272 -281.440149) (xy 283.569215 -281.387445)
			(xy 283.584925 -281.336515) (xy 283.608051 -281.288494) (xy 283.638075 -281.244457) (xy 283.674327 -281.205386)
			(xy 283.715998 -281.172155) (xy 283.762156 -281.145506) (xy 283.81177 -281.126034) (xy 283.863732 -281.114174)
			(xy 283.916882 -281.110191) (xy 283.970032 -281.114174) (xy 284.021994 -281.126034) (xy 284.071608 -281.145506)
			(xy 284.117766 -281.172155) (xy 284.159437 -281.205386) (xy 284.195689 -281.244457) (xy 284.225713 -281.288494)
			(xy 284.248839 -281.336515) (xy 284.264549 -281.387445) (xy 284.272492 -281.440149) (xy 284.27299 -281.466798)
			(xy 284.272492 -281.493447) (xy 298.674272 -281.493447) (xy 298.674272 -281.440149) (xy 298.682215 -281.387445)
			(xy 298.697925 -281.336515) (xy 298.721051 -281.288494) (xy 298.751075 -281.244457) (xy 298.787327 -281.205386)
			(xy 298.828998 -281.172155) (xy 298.875156 -281.145506) (xy 298.92477 -281.126034) (xy 298.976732 -281.114174)
			(xy 299.029882 -281.110191) (xy 299.083032 -281.114174) (xy 299.134994 -281.126034) (xy 299.184608 -281.145506)
			(xy 299.230766 -281.172155) (xy 299.272437 -281.205386) (xy 299.308689 -281.244457) (xy 299.338713 -281.288494)
			(xy 299.361839 -281.336515) (xy 299.377549 -281.387445) (xy 299.385492 -281.440149) (xy 299.38599 -281.466798)
			(xy 299.385492 -281.493447) (xy 299.377549 -281.546151) (xy 299.361839 -281.597081) (xy 299.338713 -281.645102)
			(xy 299.308689 -281.689139) (xy 299.272437 -281.72821) (xy 299.230766 -281.761441) (xy 299.184608 -281.78809)
			(xy 299.134994 -281.807562) (xy 299.083032 -281.819422) (xy 299.029882 -281.823406) (xy 298.976732 -281.819422)
			(xy 298.92477 -281.807562) (xy 298.875156 -281.78809) (xy 298.828998 -281.761441) (xy 298.787327 -281.72821)
			(xy 298.751075 -281.689139) (xy 298.721051 -281.645102) (xy 298.697925 -281.597081) (xy 298.682215 -281.546151)
			(xy 298.674272 -281.493447) (xy 284.272492 -281.493447) (xy 284.264549 -281.546151) (xy 284.248839 -281.597081)
			(xy 284.225713 -281.645102) (xy 284.195689 -281.689139) (xy 284.159437 -281.72821) (xy 284.117766 -281.761441)
			(xy 284.071608 -281.78809) (xy 284.021994 -281.807562) (xy 283.970032 -281.819422) (xy 283.916882 -281.823406)
			(xy 283.863732 -281.819422) (xy 283.81177 -281.807562) (xy 283.762156 -281.78809) (xy 283.715998 -281.761441)
			(xy 283.674327 -281.72821) (xy 283.638075 -281.689139) (xy 283.608051 -281.645102) (xy 283.584925 -281.597081)
			(xy 283.569215 -281.546151) (xy 283.561272 -281.493447) (xy 269.184892 -281.493447) (xy 269.176949 -281.546151)
			(xy 269.161239 -281.597081) (xy 269.138113 -281.645102) (xy 269.108089 -281.689139) (xy 269.071837 -281.72821)
			(xy 269.030166 -281.761441) (xy 268.984008 -281.78809) (xy 268.934394 -281.807562) (xy 268.882432 -281.819422)
			(xy 268.829282 -281.823406) (xy 268.776132 -281.819422) (xy 268.72417 -281.807562) (xy 268.674556 -281.78809)
			(xy 268.628398 -281.761441) (xy 268.586727 -281.72821) (xy 268.550475 -281.689139) (xy 268.520451 -281.645102)
			(xy 268.497325 -281.597081) (xy 268.481615 -281.546151) (xy 268.473672 -281.493447) (xy 254 -281.493447)
			(xy 254 -282.343331) (xy 264.373604 -282.343331) (xy 264.373604 -282.290033) (xy 264.381547 -282.237329)
			(xy 264.397257 -282.186399) (xy 264.420383 -282.138378) (xy 264.450407 -282.094341) (xy 264.486659 -282.05527)
			(xy 264.52833 -282.022039) (xy 264.574488 -281.99539) (xy 264.624102 -281.975918) (xy 264.676064 -281.964058)
			(xy 264.729214 -281.960075) (xy 264.782364 -281.964058) (xy 264.834326 -281.975918) (xy 264.88394 -281.99539)
			(xy 264.930098 -282.022039) (xy 264.971769 -282.05527) (xy 265.008021 -282.094341) (xy 265.038045 -282.138378)
			(xy 265.061171 -282.186399) (xy 265.076881 -282.237329) (xy 265.084824 -282.290033) (xy 265.085322 -282.316682)
			(xy 265.084824 -282.343331) (xy 279.461204 -282.343331) (xy 279.461204 -282.290033) (xy 279.469147 -282.237329)
			(xy 279.484857 -282.186399) (xy 279.507983 -282.138378) (xy 279.538007 -282.094341) (xy 279.574259 -282.05527)
			(xy 279.61593 -282.022039) (xy 279.662088 -281.99539) (xy 279.711702 -281.975918) (xy 279.763664 -281.964058)
			(xy 279.816814 -281.960075) (xy 279.869964 -281.964058) (xy 279.921926 -281.975918) (xy 279.97154 -281.99539)
			(xy 280.017698 -282.022039) (xy 280.059369 -282.05527) (xy 280.095621 -282.094341) (xy 280.125645 -282.138378)
			(xy 280.148771 -282.186399) (xy 280.164481 -282.237329) (xy 280.172424 -282.290033) (xy 280.172922 -282.316682)
			(xy 280.172424 -282.343331) (xy 294.548804 -282.343331) (xy 294.548804 -282.290033) (xy 294.556747 -282.237329)
			(xy 294.572457 -282.186399) (xy 294.595583 -282.138378) (xy 294.625607 -282.094341) (xy 294.661859 -282.05527)
			(xy 294.70353 -282.022039) (xy 294.749688 -281.99539) (xy 294.799302 -281.975918) (xy 294.851264 -281.964058)
			(xy 294.904414 -281.960075) (xy 294.957564 -281.964058) (xy 295.009526 -281.975918) (xy 295.05914 -281.99539)
			(xy 295.105298 -282.022039) (xy 295.146969 -282.05527) (xy 295.183221 -282.094341) (xy 295.213245 -282.138378)
			(xy 295.236371 -282.186399) (xy 295.252081 -282.237329) (xy 295.260024 -282.290033) (xy 295.260522 -282.316682)
			(xy 295.260024 -282.343331) (xy 295.252081 -282.396035) (xy 295.236371 -282.446965) (xy 295.213245 -282.494986)
			(xy 295.183221 -282.539023) (xy 295.146969 -282.578094) (xy 295.105298 -282.611325) (xy 295.05914 -282.637974)
			(xy 295.009526 -282.657446) (xy 294.957564 -282.669306) (xy 294.904414 -282.67329) (xy 294.851264 -282.669306)
			(xy 294.799302 -282.657446) (xy 294.749688 -282.637974) (xy 294.70353 -282.611325) (xy 294.661859 -282.578094)
			(xy 294.625607 -282.539023) (xy 294.595583 -282.494986) (xy 294.572457 -282.446965) (xy 294.556747 -282.396035)
			(xy 294.548804 -282.343331) (xy 280.172424 -282.343331) (xy 280.164481 -282.396035) (xy 280.148771 -282.446965)
			(xy 280.125645 -282.494986) (xy 280.095621 -282.539023) (xy 280.059369 -282.578094) (xy 280.017698 -282.611325)
			(xy 279.97154 -282.637974) (xy 279.921926 -282.657446) (xy 279.869964 -282.669306) (xy 279.816814 -282.67329)
			(xy 279.763664 -282.669306) (xy 279.711702 -282.657446) (xy 279.662088 -282.637974) (xy 279.61593 -282.611325)
			(xy 279.574259 -282.578094) (xy 279.538007 -282.539023) (xy 279.507983 -282.494986) (xy 279.484857 -282.446965)
			(xy 279.469147 -282.396035) (xy 279.461204 -282.343331) (xy 265.084824 -282.343331) (xy 265.076881 -282.396035)
			(xy 265.061171 -282.446965) (xy 265.038045 -282.494986) (xy 265.008021 -282.539023) (xy 264.971769 -282.578094)
			(xy 264.930098 -282.611325) (xy 264.88394 -282.637974) (xy 264.834326 -282.657446) (xy 264.782364 -282.669306)
			(xy 264.729214 -282.67329) (xy 264.676064 -282.669306) (xy 264.624102 -282.657446) (xy 264.574488 -282.637974)
			(xy 264.52833 -282.611325) (xy 264.486659 -282.578094) (xy 264.450407 -282.539023) (xy 264.420383 -282.494986)
			(xy 264.397257 -282.446965) (xy 264.381547 -282.396035) (xy 264.373604 -282.343331) (xy 254 -282.343331)
			(xy 254 -283.193215) (xy 268.473672 -283.193215) (xy 268.473672 -283.139917) (xy 268.481615 -283.087213)
			(xy 268.497325 -283.036283) (xy 268.520451 -282.988262) (xy 268.550475 -282.944225) (xy 268.586727 -282.905154)
			(xy 268.628398 -282.871923) (xy 268.674556 -282.845274) (xy 268.72417 -282.825802) (xy 268.776132 -282.813942)
			(xy 268.829282 -282.809959) (xy 268.882432 -282.813942) (xy 268.934394 -282.825802) (xy 268.984008 -282.845274)
			(xy 269.030166 -282.871923) (xy 269.071837 -282.905154) (xy 269.108089 -282.944225) (xy 269.138113 -282.988262)
			(xy 269.161239 -283.036283) (xy 269.176949 -283.087213) (xy 269.184892 -283.139917) (xy 269.18539 -283.166566)
			(xy 269.184892 -283.193215) (xy 283.561272 -283.193215) (xy 283.561272 -283.139917) (xy 283.569215 -283.087213)
			(xy 283.584925 -283.036283) (xy 283.608051 -282.988262) (xy 283.638075 -282.944225) (xy 283.674327 -282.905154)
			(xy 283.715998 -282.871923) (xy 283.762156 -282.845274) (xy 283.81177 -282.825802) (xy 283.863732 -282.813942)
			(xy 283.916882 -282.809959) (xy 283.970032 -282.813942) (xy 284.021994 -282.825802) (xy 284.071608 -282.845274)
			(xy 284.117766 -282.871923) (xy 284.159437 -282.905154) (xy 284.195689 -282.944225) (xy 284.225713 -282.988262)
			(xy 284.248839 -283.036283) (xy 284.264549 -283.087213) (xy 284.272492 -283.139917) (xy 284.27299 -283.166566)
			(xy 284.272492 -283.193215) (xy 284.272454 -283.193469) (xy 298.674272 -283.193469) (xy 298.674272 -283.140171)
			(xy 298.682215 -283.087467) (xy 298.697925 -283.036537) (xy 298.721051 -282.988516) (xy 298.751075 -282.944479)
			(xy 298.787327 -282.905408) (xy 298.828998 -282.872177) (xy 298.875156 -282.845528) (xy 298.92477 -282.826056)
			(xy 298.976732 -282.814196) (xy 299.029882 -282.810213) (xy 299.083032 -282.814196) (xy 299.134994 -282.826056)
			(xy 299.184608 -282.845528) (xy 299.230766 -282.872177) (xy 299.272437 -282.905408) (xy 299.308689 -282.944479)
			(xy 299.338713 -282.988516) (xy 299.361839 -283.036537) (xy 299.377549 -283.087467) (xy 299.385492 -283.140171)
			(xy 299.38599 -283.16682) (xy 299.385492 -283.193469) (xy 299.377549 -283.246173) (xy 299.361839 -283.297103)
			(xy 299.338713 -283.345124) (xy 299.308689 -283.389161) (xy 299.272437 -283.428232) (xy 299.230766 -283.461463)
			(xy 299.184608 -283.488112) (xy 299.134994 -283.507584) (xy 299.083032 -283.519444) (xy 299.029882 -283.523428)
			(xy 298.976732 -283.519444) (xy 298.92477 -283.507584) (xy 298.875156 -283.488112) (xy 298.828998 -283.461463)
			(xy 298.787327 -283.428232) (xy 298.751075 -283.389161) (xy 298.721051 -283.345124) (xy 298.697925 -283.297103)
			(xy 298.682215 -283.246173) (xy 298.674272 -283.193469) (xy 284.272454 -283.193469) (xy 284.264549 -283.245919)
			(xy 284.248839 -283.296849) (xy 284.225713 -283.34487) (xy 284.195689 -283.388907) (xy 284.159437 -283.427978)
			(xy 284.117766 -283.461209) (xy 284.071608 -283.487858) (xy 284.021994 -283.50733) (xy 283.970032 -283.51919)
			(xy 283.916882 -283.523174) (xy 283.863732 -283.51919) (xy 283.81177 -283.50733) (xy 283.762156 -283.487858)
			(xy 283.715998 -283.461209) (xy 283.674327 -283.427978) (xy 283.638075 -283.388907) (xy 283.608051 -283.34487)
			(xy 283.584925 -283.296849) (xy 283.569215 -283.245919) (xy 283.561272 -283.193215) (xy 269.184892 -283.193215)
			(xy 269.176949 -283.245919) (xy 269.161239 -283.296849) (xy 269.138113 -283.34487) (xy 269.108089 -283.388907)
			(xy 269.071837 -283.427978) (xy 269.030166 -283.461209) (xy 268.984008 -283.487858) (xy 268.934394 -283.50733)
			(xy 268.882432 -283.51919) (xy 268.829282 -283.523174) (xy 268.776132 -283.51919) (xy 268.72417 -283.50733)
			(xy 268.674556 -283.487858) (xy 268.628398 -283.461209) (xy 268.586727 -283.427978) (xy 268.550475 -283.388907)
			(xy 268.520451 -283.34487) (xy 268.497325 -283.296849) (xy 268.481615 -283.245919) (xy 268.473672 -283.193215)
			(xy 254 -283.193215) (xy 254 -284.043353) (xy 264.373604 -284.043353) (xy 264.373604 -283.990055)
			(xy 264.381547 -283.937351) (xy 264.397257 -283.886421) (xy 264.420383 -283.8384) (xy 264.450407 -283.794363)
			(xy 264.486659 -283.755292) (xy 264.52833 -283.722061) (xy 264.574488 -283.695412) (xy 264.624102 -283.67594)
			(xy 264.676064 -283.66408) (xy 264.729214 -283.660097) (xy 264.782364 -283.66408) (xy 264.834326 -283.67594)
			(xy 264.88394 -283.695412) (xy 264.930098 -283.722061) (xy 264.971769 -283.755292) (xy 265.008021 -283.794363)
			(xy 265.038045 -283.8384) (xy 265.061171 -283.886421) (xy 265.076881 -283.937351) (xy 265.084824 -283.990055)
			(xy 265.085322 -284.016704) (xy 265.084824 -284.043353) (xy 268.473672 -284.043353) (xy 268.473672 -283.990055)
			(xy 268.481615 -283.937351) (xy 268.497325 -283.886421) (xy 268.520451 -283.8384) (xy 268.550475 -283.794363)
			(xy 268.586727 -283.755292) (xy 268.628398 -283.722061) (xy 268.674556 -283.695412) (xy 268.72417 -283.67594)
			(xy 268.776132 -283.66408) (xy 268.829282 -283.660097) (xy 268.882432 -283.66408) (xy 268.934394 -283.67594)
			(xy 268.984008 -283.695412) (xy 269.030166 -283.722061) (xy 269.071837 -283.755292) (xy 269.108089 -283.794363)
			(xy 269.138113 -283.8384) (xy 269.161239 -283.886421) (xy 269.176949 -283.937351) (xy 269.184892 -283.990055)
			(xy 269.18539 -284.016704) (xy 269.184892 -284.043353) (xy 279.461204 -284.043353) (xy 279.461204 -283.990055)
			(xy 279.469147 -283.937351) (xy 279.484857 -283.886421) (xy 279.507983 -283.8384) (xy 279.538007 -283.794363)
			(xy 279.574259 -283.755292) (xy 279.61593 -283.722061) (xy 279.662088 -283.695412) (xy 279.711702 -283.67594)
			(xy 279.763664 -283.66408) (xy 279.816814 -283.660097) (xy 279.869964 -283.66408) (xy 279.921926 -283.67594)
			(xy 279.97154 -283.695412) (xy 280.017698 -283.722061) (xy 280.059369 -283.755292) (xy 280.095621 -283.794363)
			(xy 280.125645 -283.8384) (xy 280.148771 -283.886421) (xy 280.164481 -283.937351) (xy 280.172424 -283.990055)
			(xy 280.172922 -284.016704) (xy 280.172424 -284.043353) (xy 283.561272 -284.043353) (xy 283.561272 -283.990055)
			(xy 283.569215 -283.937351) (xy 283.584925 -283.886421) (xy 283.608051 -283.8384) (xy 283.638075 -283.794363)
			(xy 283.674327 -283.755292) (xy 283.715998 -283.722061) (xy 283.762156 -283.695412) (xy 283.81177 -283.67594)
			(xy 283.863732 -283.66408) (xy 283.916882 -283.660097) (xy 283.970032 -283.66408) (xy 284.021994 -283.67594)
			(xy 284.071608 -283.695412) (xy 284.117766 -283.722061) (xy 284.159437 -283.755292) (xy 284.195689 -283.794363)
			(xy 284.225713 -283.8384) (xy 284.248839 -283.886421) (xy 284.264549 -283.937351) (xy 284.272492 -283.990055)
			(xy 284.27299 -284.016704) (xy 284.272492 -284.043353) (xy 294.548804 -284.043353) (xy 294.548804 -283.990055)
			(xy 294.556747 -283.937351) (xy 294.572457 -283.886421) (xy 294.595583 -283.8384) (xy 294.625607 -283.794363)
			(xy 294.661859 -283.755292) (xy 294.70353 -283.722061) (xy 294.749688 -283.695412) (xy 294.799302 -283.67594)
			(xy 294.851264 -283.66408) (xy 294.904414 -283.660097) (xy 294.957564 -283.66408) (xy 295.009526 -283.67594)
			(xy 295.05914 -283.695412) (xy 295.105298 -283.722061) (xy 295.146969 -283.755292) (xy 295.183221 -283.794363)
			(xy 295.213245 -283.8384) (xy 295.236371 -283.886421) (xy 295.252081 -283.937351) (xy 295.260024 -283.990055)
			(xy 295.260522 -284.016704) (xy 295.260024 -284.043353) (xy 295.259986 -284.043607) (xy 298.674272 -284.043607)
			(xy 298.674272 -283.990309) (xy 298.682215 -283.937605) (xy 298.697925 -283.886675) (xy 298.721051 -283.838654)
			(xy 298.751075 -283.794617) (xy 298.787327 -283.755546) (xy 298.828998 -283.722315) (xy 298.875156 -283.695666)
			(xy 298.92477 -283.676194) (xy 298.976732 -283.664334) (xy 299.029882 -283.660351) (xy 299.083032 -283.664334)
			(xy 299.134994 -283.676194) (xy 299.184608 -283.695666) (xy 299.230766 -283.722315) (xy 299.272437 -283.755546)
			(xy 299.308689 -283.794617) (xy 299.338713 -283.838654) (xy 299.361839 -283.886675) (xy 299.377549 -283.937605)
			(xy 299.385492 -283.990309) (xy 299.38599 -284.016958) (xy 299.385492 -284.043607) (xy 299.377549 -284.096311)
			(xy 299.361839 -284.147241) (xy 299.338713 -284.195262) (xy 299.308689 -284.239299) (xy 299.272437 -284.27837)
			(xy 299.230766 -284.311601) (xy 299.184608 -284.33825) (xy 299.134994 -284.357722) (xy 299.083032 -284.369582)
			(xy 299.029882 -284.373566) (xy 298.976732 -284.369582) (xy 298.92477 -284.357722) (xy 298.875156 -284.33825)
			(xy 298.828998 -284.311601) (xy 298.787327 -284.27837) (xy 298.751075 -284.239299) (xy 298.721051 -284.195262)
			(xy 298.697925 -284.147241) (xy 298.682215 -284.096311) (xy 298.674272 -284.043607) (xy 295.259986 -284.043607)
			(xy 295.252081 -284.096057) (xy 295.236371 -284.146987) (xy 295.213245 -284.195008) (xy 295.183221 -284.239045)
			(xy 295.146969 -284.278116) (xy 295.105298 -284.311347) (xy 295.05914 -284.337996) (xy 295.009526 -284.357468)
			(xy 294.957564 -284.369328) (xy 294.904414 -284.373312) (xy 294.851264 -284.369328) (xy 294.799302 -284.357468)
			(xy 294.749688 -284.337996) (xy 294.70353 -284.311347) (xy 294.661859 -284.278116) (xy 294.625607 -284.239045)
			(xy 294.595583 -284.195008) (xy 294.572457 -284.146987) (xy 294.556747 -284.096057) (xy 294.548804 -284.043353)
			(xy 284.272492 -284.043353) (xy 284.264549 -284.096057) (xy 284.248839 -284.146987) (xy 284.225713 -284.195008)
			(xy 284.195689 -284.239045) (xy 284.159437 -284.278116) (xy 284.117766 -284.311347) (xy 284.071608 -284.337996)
			(xy 284.021994 -284.357468) (xy 283.970032 -284.369328) (xy 283.916882 -284.373312) (xy 283.863732 -284.369328)
			(xy 283.81177 -284.357468) (xy 283.762156 -284.337996) (xy 283.715998 -284.311347) (xy 283.674327 -284.278116)
			(xy 283.638075 -284.239045) (xy 283.608051 -284.195008) (xy 283.584925 -284.146987) (xy 283.569215 -284.096057)
			(xy 283.561272 -284.043353) (xy 280.172424 -284.043353) (xy 280.164481 -284.096057) (xy 280.148771 -284.146987)
			(xy 280.125645 -284.195008) (xy 280.095621 -284.239045) (xy 280.059369 -284.278116) (xy 280.017698 -284.311347)
			(xy 279.97154 -284.337996) (xy 279.921926 -284.357468) (xy 279.869964 -284.369328) (xy 279.816814 -284.373312)
			(xy 279.763664 -284.369328) (xy 279.711702 -284.357468) (xy 279.662088 -284.337996) (xy 279.61593 -284.311347)
			(xy 279.574259 -284.278116) (xy 279.538007 -284.239045) (xy 279.507983 -284.195008) (xy 279.484857 -284.146987)
			(xy 279.469147 -284.096057) (xy 279.461204 -284.043353) (xy 269.184892 -284.043353) (xy 269.176949 -284.096057)
			(xy 269.161239 -284.146987) (xy 269.138113 -284.195008) (xy 269.108089 -284.239045) (xy 269.071837 -284.278116)
			(xy 269.030166 -284.311347) (xy 268.984008 -284.337996) (xy 268.934394 -284.357468) (xy 268.882432 -284.369328)
			(xy 268.829282 -284.373312) (xy 268.776132 -284.369328) (xy 268.72417 -284.357468) (xy 268.674556 -284.337996)
			(xy 268.628398 -284.311347) (xy 268.586727 -284.278116) (xy 268.550475 -284.239045) (xy 268.520451 -284.195008)
			(xy 268.497325 -284.146987) (xy 268.481615 -284.096057) (xy 268.473672 -284.043353) (xy 265.084824 -284.043353)
			(xy 265.076881 -284.096057) (xy 265.061171 -284.146987) (xy 265.038045 -284.195008) (xy 265.008021 -284.239045)
			(xy 264.971769 -284.278116) (xy 264.930098 -284.311347) (xy 264.88394 -284.337996) (xy 264.834326 -284.357468)
			(xy 264.782364 -284.369328) (xy 264.729214 -284.373312) (xy 264.676064 -284.369328) (xy 264.624102 -284.357468)
			(xy 264.574488 -284.337996) (xy 264.52833 -284.311347) (xy 264.486659 -284.278116) (xy 264.450407 -284.239045)
			(xy 264.420383 -284.195008) (xy 264.397257 -284.146987) (xy 264.381547 -284.096057) (xy 264.373604 -284.043353)
			(xy 254 -284.043353) (xy 254 -284.893237) (xy 264.373604 -284.893237) (xy 264.373604 -284.839939)
			(xy 264.381547 -284.787235) (xy 264.397257 -284.736305) (xy 264.420383 -284.688284) (xy 264.450407 -284.644247)
			(xy 264.486659 -284.605176) (xy 264.52833 -284.571945) (xy 264.574488 -284.545296) (xy 264.624102 -284.525824)
			(xy 264.676064 -284.513964) (xy 264.729214 -284.509981) (xy 264.782364 -284.513964) (xy 264.834326 -284.525824)
			(xy 264.88394 -284.545296) (xy 264.930098 -284.571945) (xy 264.971769 -284.605176) (xy 265.008021 -284.644247)
			(xy 265.038045 -284.688284) (xy 265.061171 -284.736305) (xy 265.076881 -284.787235) (xy 265.084824 -284.839939)
			(xy 265.085322 -284.866588) (xy 265.084824 -284.893237) (xy 279.461204 -284.893237) (xy 279.461204 -284.839939)
			(xy 279.469147 -284.787235) (xy 279.484857 -284.736305) (xy 279.507983 -284.688284) (xy 279.538007 -284.644247)
			(xy 279.574259 -284.605176) (xy 279.61593 -284.571945) (xy 279.662088 -284.545296) (xy 279.711702 -284.525824)
			(xy 279.763664 -284.513964) (xy 279.816814 -284.509981) (xy 279.869964 -284.513964) (xy 279.921926 -284.525824)
			(xy 279.97154 -284.545296) (xy 280.017698 -284.571945) (xy 280.059369 -284.605176) (xy 280.095621 -284.644247)
			(xy 280.125645 -284.688284) (xy 280.148771 -284.736305) (xy 280.164481 -284.787235) (xy 280.172424 -284.839939)
			(xy 280.172922 -284.866588) (xy 280.172424 -284.893237) (xy 294.548804 -284.893237) (xy 294.548804 -284.839939)
			(xy 294.556747 -284.787235) (xy 294.572457 -284.736305) (xy 294.595583 -284.688284) (xy 294.625607 -284.644247)
			(xy 294.661859 -284.605176) (xy 294.70353 -284.571945) (xy 294.749688 -284.545296) (xy 294.799302 -284.525824)
			(xy 294.851264 -284.513964) (xy 294.904414 -284.509981) (xy 294.957564 -284.513964) (xy 295.009526 -284.525824)
			(xy 295.05914 -284.545296) (xy 295.105298 -284.571945) (xy 295.146969 -284.605176) (xy 295.183221 -284.644247)
			(xy 295.213245 -284.688284) (xy 295.236371 -284.736305) (xy 295.252081 -284.787235) (xy 295.260024 -284.839939)
			(xy 295.260522 -284.866588) (xy 295.260024 -284.893237) (xy 295.252081 -284.945941) (xy 295.236371 -284.996871)
			(xy 295.213245 -285.044892) (xy 295.183221 -285.088929) (xy 295.146969 -285.128) (xy 295.105298 -285.161231)
			(xy 295.05914 -285.18788) (xy 295.009526 -285.207352) (xy 294.957564 -285.219212) (xy 294.904414 -285.223196)
			(xy 294.851264 -285.219212) (xy 294.799302 -285.207352) (xy 294.749688 -285.18788) (xy 294.70353 -285.161231)
			(xy 294.661859 -285.128) (xy 294.625607 -285.088929) (xy 294.595583 -285.044892) (xy 294.572457 -284.996871)
			(xy 294.556747 -284.945941) (xy 294.548804 -284.893237) (xy 280.172424 -284.893237) (xy 280.164481 -284.945941)
			(xy 280.148771 -284.996871) (xy 280.125645 -285.044892) (xy 280.095621 -285.088929) (xy 280.059369 -285.128)
			(xy 280.017698 -285.161231) (xy 279.97154 -285.18788) (xy 279.921926 -285.207352) (xy 279.869964 -285.219212)
			(xy 279.816814 -285.223196) (xy 279.763664 -285.219212) (xy 279.711702 -285.207352) (xy 279.662088 -285.18788)
			(xy 279.61593 -285.161231) (xy 279.574259 -285.128) (xy 279.538007 -285.088929) (xy 279.507983 -285.044892)
			(xy 279.484857 -284.996871) (xy 279.469147 -284.945941) (xy 279.461204 -284.893237) (xy 265.084824 -284.893237)
			(xy 265.076881 -284.945941) (xy 265.061171 -284.996871) (xy 265.038045 -285.044892) (xy 265.008021 -285.088929)
			(xy 264.971769 -285.128) (xy 264.930098 -285.161231) (xy 264.88394 -285.18788) (xy 264.834326 -285.207352)
			(xy 264.782364 -285.219212) (xy 264.729214 -285.223196) (xy 264.676064 -285.219212) (xy 264.624102 -285.207352)
			(xy 264.574488 -285.18788) (xy 264.52833 -285.161231) (xy 264.486659 -285.128) (xy 264.450407 -285.088929)
			(xy 264.420383 -285.044892) (xy 264.397257 -284.996871) (xy 264.381547 -284.945941) (xy 264.373604 -284.893237)
			(xy 254 -284.893237) (xy 254 -285.743375) (xy 268.473672 -285.743375) (xy 268.473672 -285.690077)
			(xy 268.481615 -285.637373) (xy 268.497325 -285.586443) (xy 268.520451 -285.538422) (xy 268.550475 -285.494385)
			(xy 268.586727 -285.455314) (xy 268.628398 -285.422083) (xy 268.674556 -285.395434) (xy 268.72417 -285.375962)
			(xy 268.776132 -285.364102) (xy 268.829282 -285.360119) (xy 268.882432 -285.364102) (xy 268.934394 -285.375962)
			(xy 268.984008 -285.395434) (xy 269.030166 -285.422083) (xy 269.071837 -285.455314) (xy 269.108089 -285.494385)
			(xy 269.138113 -285.538422) (xy 269.161239 -285.586443) (xy 269.176949 -285.637373) (xy 269.184892 -285.690077)
			(xy 269.18539 -285.716726) (xy 269.184892 -285.743375) (xy 283.561272 -285.743375) (xy 283.561272 -285.690077)
			(xy 283.569215 -285.637373) (xy 283.584925 -285.586443) (xy 283.608051 -285.538422) (xy 283.638075 -285.494385)
			(xy 283.674327 -285.455314) (xy 283.715998 -285.422083) (xy 283.762156 -285.395434) (xy 283.81177 -285.375962)
			(xy 283.863732 -285.364102) (xy 283.916882 -285.360119) (xy 283.970032 -285.364102) (xy 284.021994 -285.375962)
			(xy 284.071608 -285.395434) (xy 284.117766 -285.422083) (xy 284.159437 -285.455314) (xy 284.195689 -285.494385)
			(xy 284.225713 -285.538422) (xy 284.248839 -285.586443) (xy 284.264549 -285.637373) (xy 284.272492 -285.690077)
			(xy 284.27299 -285.716726) (xy 284.272492 -285.743375) (xy 298.648872 -285.743375) (xy 298.648872 -285.690077)
			(xy 298.656815 -285.637373) (xy 298.672525 -285.586443) (xy 298.695651 -285.538422) (xy 298.725675 -285.494385)
			(xy 298.761927 -285.455314) (xy 298.803598 -285.422083) (xy 298.849756 -285.395434) (xy 298.89937 -285.375962)
			(xy 298.951332 -285.364102) (xy 299.004482 -285.360119) (xy 299.057632 -285.364102) (xy 299.109594 -285.375962)
			(xy 299.159208 -285.395434) (xy 299.205366 -285.422083) (xy 299.247037 -285.455314) (xy 299.283289 -285.494385)
			(xy 299.313313 -285.538422) (xy 299.336439 -285.586443) (xy 299.352149 -285.637373) (xy 299.360092 -285.690077)
			(xy 299.36059 -285.716726) (xy 299.360092 -285.743375) (xy 299.352149 -285.796079) (xy 299.336439 -285.847009)
			(xy 299.313313 -285.89503) (xy 299.283289 -285.939067) (xy 299.247037 -285.978138) (xy 299.205366 -286.011369)
			(xy 299.159208 -286.038018) (xy 299.109594 -286.05749) (xy 299.057632 -286.06935) (xy 299.004482 -286.073334)
			(xy 298.951332 -286.06935) (xy 298.89937 -286.05749) (xy 298.849756 -286.038018) (xy 298.803598 -286.011369)
			(xy 298.761927 -285.978138) (xy 298.725675 -285.939067) (xy 298.695651 -285.89503) (xy 298.672525 -285.847009)
			(xy 298.656815 -285.796079) (xy 298.648872 -285.743375) (xy 284.272492 -285.743375) (xy 284.264549 -285.796079)
			(xy 284.248839 -285.847009) (xy 284.225713 -285.89503) (xy 284.195689 -285.939067) (xy 284.159437 -285.978138)
			(xy 284.117766 -286.011369) (xy 284.071608 -286.038018) (xy 284.021994 -286.05749) (xy 283.970032 -286.06935)
			(xy 283.916882 -286.073334) (xy 283.863732 -286.06935) (xy 283.81177 -286.05749) (xy 283.762156 -286.038018)
			(xy 283.715998 -286.011369) (xy 283.674327 -285.978138) (xy 283.638075 -285.939067) (xy 283.608051 -285.89503)
			(xy 283.584925 -285.847009) (xy 283.569215 -285.796079) (xy 283.561272 -285.743375) (xy 269.184892 -285.743375)
			(xy 269.176949 -285.796079) (xy 269.161239 -285.847009) (xy 269.138113 -285.89503) (xy 269.108089 -285.939067)
			(xy 269.071837 -285.978138) (xy 269.030166 -286.011369) (xy 268.984008 -286.038018) (xy 268.934394 -286.05749)
			(xy 268.882432 -286.06935) (xy 268.829282 -286.073334) (xy 268.776132 -286.06935) (xy 268.72417 -286.05749)
			(xy 268.674556 -286.038018) (xy 268.628398 -286.011369) (xy 268.586727 -285.978138) (xy 268.550475 -285.939067)
			(xy 268.520451 -285.89503) (xy 268.497325 -285.847009) (xy 268.481615 -285.796079) (xy 268.473672 -285.743375)
			(xy 254 -285.743375) (xy 254 -286.593259) (xy 264.373604 -286.593259) (xy 264.373604 -286.539961)
			(xy 264.381547 -286.487257) (xy 264.397257 -286.436327) (xy 264.420383 -286.388306) (xy 264.450407 -286.344269)
			(xy 264.486659 -286.305198) (xy 264.52833 -286.271967) (xy 264.574488 -286.245318) (xy 264.624102 -286.225846)
			(xy 264.676064 -286.213986) (xy 264.729214 -286.210003) (xy 264.782364 -286.213986) (xy 264.834326 -286.225846)
			(xy 264.88394 -286.245318) (xy 264.930098 -286.271967) (xy 264.971769 -286.305198) (xy 265.008021 -286.344269)
			(xy 265.038045 -286.388306) (xy 265.061171 -286.436327) (xy 265.076881 -286.487257) (xy 265.084824 -286.539961)
			(xy 265.085322 -286.56661) (xy 265.084824 -286.593259) (xy 279.461204 -286.593259) (xy 279.461204 -286.539961)
			(xy 279.469147 -286.487257) (xy 279.484857 -286.436327) (xy 279.507983 -286.388306) (xy 279.538007 -286.344269)
			(xy 279.574259 -286.305198) (xy 279.61593 -286.271967) (xy 279.662088 -286.245318) (xy 279.711702 -286.225846)
			(xy 279.763664 -286.213986) (xy 279.816814 -286.210003) (xy 279.869964 -286.213986) (xy 279.921926 -286.225846)
			(xy 279.97154 -286.245318) (xy 280.017698 -286.271967) (xy 280.059369 -286.305198) (xy 280.095621 -286.344269)
			(xy 280.125645 -286.388306) (xy 280.148771 -286.436327) (xy 280.164481 -286.487257) (xy 280.172424 -286.539961)
			(xy 280.172922 -286.56661) (xy 280.172424 -286.593259) (xy 294.548804 -286.593259) (xy 294.548804 -286.539961)
			(xy 294.556747 -286.487257) (xy 294.572457 -286.436327) (xy 294.595583 -286.388306) (xy 294.625607 -286.344269)
			(xy 294.661859 -286.305198) (xy 294.70353 -286.271967) (xy 294.749688 -286.245318) (xy 294.799302 -286.225846)
			(xy 294.851264 -286.213986) (xy 294.904414 -286.210003) (xy 294.957564 -286.213986) (xy 295.009526 -286.225846)
			(xy 295.05914 -286.245318) (xy 295.105298 -286.271967) (xy 295.146969 -286.305198) (xy 295.183221 -286.344269)
			(xy 295.213245 -286.388306) (xy 295.236371 -286.436327) (xy 295.252081 -286.487257) (xy 295.260024 -286.539961)
			(xy 295.260522 -286.56661) (xy 295.260024 -286.593259) (xy 295.252081 -286.645963) (xy 295.236371 -286.696893)
			(xy 295.213245 -286.744914) (xy 295.183221 -286.788951) (xy 295.146969 -286.828022) (xy 295.105298 -286.861253)
			(xy 295.05914 -286.887902) (xy 295.009526 -286.907374) (xy 294.957564 -286.919234) (xy 294.904414 -286.923218)
			(xy 294.851264 -286.919234) (xy 294.799302 -286.907374) (xy 294.749688 -286.887902) (xy 294.70353 -286.861253)
			(xy 294.661859 -286.828022) (xy 294.625607 -286.788951) (xy 294.595583 -286.744914) (xy 294.572457 -286.696893)
			(xy 294.556747 -286.645963) (xy 294.548804 -286.593259) (xy 280.172424 -286.593259) (xy 280.164481 -286.645963)
			(xy 280.148771 -286.696893) (xy 280.125645 -286.744914) (xy 280.095621 -286.788951) (xy 280.059369 -286.828022)
			(xy 280.017698 -286.861253) (xy 279.97154 -286.887902) (xy 279.921926 -286.907374) (xy 279.869964 -286.919234)
			(xy 279.816814 -286.923218) (xy 279.763664 -286.919234) (xy 279.711702 -286.907374) (xy 279.662088 -286.887902)
			(xy 279.61593 -286.861253) (xy 279.574259 -286.828022) (xy 279.538007 -286.788951) (xy 279.507983 -286.744914)
			(xy 279.484857 -286.696893) (xy 279.469147 -286.645963) (xy 279.461204 -286.593259) (xy 265.084824 -286.593259)
			(xy 265.076881 -286.645963) (xy 265.061171 -286.696893) (xy 265.038045 -286.744914) (xy 265.008021 -286.788951)
			(xy 264.971769 -286.828022) (xy 264.930098 -286.861253) (xy 264.88394 -286.887902) (xy 264.834326 -286.907374)
			(xy 264.782364 -286.919234) (xy 264.729214 -286.923218) (xy 264.676064 -286.919234) (xy 264.624102 -286.907374)
			(xy 264.574488 -286.887902) (xy 264.52833 -286.861253) (xy 264.486659 -286.828022) (xy 264.450407 -286.788951)
			(xy 264.420383 -286.744914) (xy 264.397257 -286.696893) (xy 264.381547 -286.645963) (xy 264.373604 -286.593259)
			(xy 254 -286.593259) (xy 254 -287.443397) (xy 268.473672 -287.443397) (xy 268.473672 -287.390099)
			(xy 268.481615 -287.337395) (xy 268.497325 -287.286465) (xy 268.520451 -287.238444) (xy 268.550475 -287.194407)
			(xy 268.586727 -287.155336) (xy 268.628398 -287.122105) (xy 268.674556 -287.095456) (xy 268.72417 -287.075984)
			(xy 268.776132 -287.064124) (xy 268.829282 -287.060141) (xy 268.882432 -287.064124) (xy 268.934394 -287.075984)
			(xy 268.984008 -287.095456) (xy 269.030166 -287.122105) (xy 269.071837 -287.155336) (xy 269.108089 -287.194407)
			(xy 269.138113 -287.238444) (xy 269.161239 -287.286465) (xy 269.176949 -287.337395) (xy 269.184892 -287.390099)
			(xy 269.18539 -287.416748) (xy 269.184892 -287.443397) (xy 283.561272 -287.443397) (xy 283.561272 -287.390099)
			(xy 283.569215 -287.337395) (xy 283.584925 -287.286465) (xy 283.608051 -287.238444) (xy 283.638075 -287.194407)
			(xy 283.674327 -287.155336) (xy 283.715998 -287.122105) (xy 283.762156 -287.095456) (xy 283.81177 -287.075984)
			(xy 283.863732 -287.064124) (xy 283.916882 -287.060141) (xy 283.970032 -287.064124) (xy 284.021994 -287.075984)
			(xy 284.071608 -287.095456) (xy 284.117766 -287.122105) (xy 284.159437 -287.155336) (xy 284.195689 -287.194407)
			(xy 284.225713 -287.238444) (xy 284.248839 -287.286465) (xy 284.264549 -287.337395) (xy 284.272492 -287.390099)
			(xy 284.27299 -287.416748) (xy 284.272492 -287.443397) (xy 298.648872 -287.443397) (xy 298.648872 -287.390099)
			(xy 298.656815 -287.337395) (xy 298.672525 -287.286465) (xy 298.695651 -287.238444) (xy 298.725675 -287.194407)
			(xy 298.761927 -287.155336) (xy 298.803598 -287.122105) (xy 298.849756 -287.095456) (xy 298.89937 -287.075984)
			(xy 298.951332 -287.064124) (xy 299.004482 -287.060141) (xy 299.057632 -287.064124) (xy 299.109594 -287.075984)
			(xy 299.159208 -287.095456) (xy 299.205366 -287.122105) (xy 299.247037 -287.155336) (xy 299.283289 -287.194407)
			(xy 299.313313 -287.238444) (xy 299.336439 -287.286465) (xy 299.352149 -287.337395) (xy 299.360092 -287.390099)
			(xy 299.36059 -287.416748) (xy 299.360092 -287.443397) (xy 299.352149 -287.496101) (xy 299.336439 -287.547031)
			(xy 299.313313 -287.595052) (xy 299.283289 -287.639089) (xy 299.247037 -287.67816) (xy 299.205366 -287.711391)
			(xy 299.159208 -287.73804) (xy 299.109594 -287.757512) (xy 299.057632 -287.769372) (xy 299.004482 -287.773356)
			(xy 298.951332 -287.769372) (xy 298.89937 -287.757512) (xy 298.849756 -287.73804) (xy 298.803598 -287.711391)
			(xy 298.761927 -287.67816) (xy 298.725675 -287.639089) (xy 298.695651 -287.595052) (xy 298.672525 -287.547031)
			(xy 298.656815 -287.496101) (xy 298.648872 -287.443397) (xy 284.272492 -287.443397) (xy 284.264549 -287.496101)
			(xy 284.248839 -287.547031) (xy 284.225713 -287.595052) (xy 284.195689 -287.639089) (xy 284.159437 -287.67816)
			(xy 284.117766 -287.711391) (xy 284.071608 -287.73804) (xy 284.021994 -287.757512) (xy 283.970032 -287.769372)
			(xy 283.916882 -287.773356) (xy 283.863732 -287.769372) (xy 283.81177 -287.757512) (xy 283.762156 -287.73804)
			(xy 283.715998 -287.711391) (xy 283.674327 -287.67816) (xy 283.638075 -287.639089) (xy 283.608051 -287.595052)
			(xy 283.584925 -287.547031) (xy 283.569215 -287.496101) (xy 283.561272 -287.443397) (xy 269.184892 -287.443397)
			(xy 269.176949 -287.496101) (xy 269.161239 -287.547031) (xy 269.138113 -287.595052) (xy 269.108089 -287.639089)
			(xy 269.071837 -287.67816) (xy 269.030166 -287.711391) (xy 268.984008 -287.73804) (xy 268.934394 -287.757512)
			(xy 268.882432 -287.769372) (xy 268.829282 -287.773356) (xy 268.776132 -287.769372) (xy 268.72417 -287.757512)
			(xy 268.674556 -287.73804) (xy 268.628398 -287.711391) (xy 268.586727 -287.67816) (xy 268.550475 -287.639089)
			(xy 268.520451 -287.595052) (xy 268.497325 -287.547031) (xy 268.481615 -287.496101) (xy 268.473672 -287.443397)
			(xy 254 -287.443397) (xy 254 -288.293281) (xy 264.373604 -288.293281) (xy 264.373604 -288.239983)
			(xy 264.381547 -288.187279) (xy 264.397257 -288.136349) (xy 264.420383 -288.088328) (xy 264.450407 -288.044291)
			(xy 264.486659 -288.00522) (xy 264.52833 -287.971989) (xy 264.574488 -287.94534) (xy 264.624102 -287.925868)
			(xy 264.676064 -287.914008) (xy 264.729214 -287.910025) (xy 264.782364 -287.914008) (xy 264.834326 -287.925868)
			(xy 264.88394 -287.94534) (xy 264.930098 -287.971989) (xy 264.971769 -288.00522) (xy 265.008021 -288.044291)
			(xy 265.038045 -288.088328) (xy 265.061171 -288.136349) (xy 265.076881 -288.187279) (xy 265.084824 -288.239983)
			(xy 265.085322 -288.266632) (xy 265.084824 -288.293281) (xy 279.461204 -288.293281) (xy 279.461204 -288.239983)
			(xy 279.469147 -288.187279) (xy 279.484857 -288.136349) (xy 279.507983 -288.088328) (xy 279.538007 -288.044291)
			(xy 279.574259 -288.00522) (xy 279.61593 -287.971989) (xy 279.662088 -287.94534) (xy 279.711702 -287.925868)
			(xy 279.763664 -287.914008) (xy 279.816814 -287.910025) (xy 279.869964 -287.914008) (xy 279.921926 -287.925868)
			(xy 279.97154 -287.94534) (xy 280.017698 -287.971989) (xy 280.059369 -288.00522) (xy 280.095621 -288.044291)
			(xy 280.125645 -288.088328) (xy 280.148771 -288.136349) (xy 280.164481 -288.187279) (xy 280.172424 -288.239983)
			(xy 280.172922 -288.266632) (xy 280.172424 -288.293281) (xy 294.548804 -288.293281) (xy 294.548804 -288.239983)
			(xy 294.556747 -288.187279) (xy 294.572457 -288.136349) (xy 294.595583 -288.088328) (xy 294.625607 -288.044291)
			(xy 294.661859 -288.00522) (xy 294.70353 -287.971989) (xy 294.749688 -287.94534) (xy 294.799302 -287.925868)
			(xy 294.851264 -287.914008) (xy 294.904414 -287.910025) (xy 294.957564 -287.914008) (xy 295.009526 -287.925868)
			(xy 295.05914 -287.94534) (xy 295.105298 -287.971989) (xy 295.146969 -288.00522) (xy 295.183221 -288.044291)
			(xy 295.213245 -288.088328) (xy 295.236371 -288.136349) (xy 295.252081 -288.187279) (xy 295.260024 -288.239983)
			(xy 295.260522 -288.266632) (xy 295.260024 -288.293281) (xy 295.252081 -288.345985) (xy 295.236371 -288.396915)
			(xy 295.213245 -288.444936) (xy 295.183221 -288.488973) (xy 295.146969 -288.528044) (xy 295.105298 -288.561275)
			(xy 295.05914 -288.587924) (xy 295.009526 -288.607396) (xy 294.957564 -288.619256) (xy 294.904414 -288.62324)
			(xy 294.851264 -288.619256) (xy 294.799302 -288.607396) (xy 294.749688 -288.587924) (xy 294.70353 -288.561275)
			(xy 294.661859 -288.528044) (xy 294.625607 -288.488973) (xy 294.595583 -288.444936) (xy 294.572457 -288.396915)
			(xy 294.556747 -288.345985) (xy 294.548804 -288.293281) (xy 280.172424 -288.293281) (xy 280.164481 -288.345985)
			(xy 280.148771 -288.396915) (xy 280.125645 -288.444936) (xy 280.095621 -288.488973) (xy 280.059369 -288.528044)
			(xy 280.017698 -288.561275) (xy 279.97154 -288.587924) (xy 279.921926 -288.607396) (xy 279.869964 -288.619256)
			(xy 279.816814 -288.62324) (xy 279.763664 -288.619256) (xy 279.711702 -288.607396) (xy 279.662088 -288.587924)
			(xy 279.61593 -288.561275) (xy 279.574259 -288.528044) (xy 279.538007 -288.488973) (xy 279.507983 -288.444936)
			(xy 279.484857 -288.396915) (xy 279.469147 -288.345985) (xy 279.461204 -288.293281) (xy 265.084824 -288.293281)
			(xy 265.076881 -288.345985) (xy 265.061171 -288.396915) (xy 265.038045 -288.444936) (xy 265.008021 -288.488973)
			(xy 264.971769 -288.528044) (xy 264.930098 -288.561275) (xy 264.88394 -288.587924) (xy 264.834326 -288.607396)
			(xy 264.782364 -288.619256) (xy 264.729214 -288.62324) (xy 264.676064 -288.619256) (xy 264.624102 -288.607396)
			(xy 264.574488 -288.587924) (xy 264.52833 -288.561275) (xy 264.486659 -288.528044) (xy 264.450407 -288.488973)
			(xy 264.420383 -288.444936) (xy 264.397257 -288.396915) (xy 264.381547 -288.345985) (xy 264.373604 -288.293281)
			(xy 254 -288.293281) (xy 254 -289.143419) (xy 268.473672 -289.143419) (xy 268.473672 -289.090121)
			(xy 268.481615 -289.037417) (xy 268.497325 -288.986487) (xy 268.520451 -288.938466) (xy 268.550475 -288.894429)
			(xy 268.586727 -288.855358) (xy 268.628398 -288.822127) (xy 268.674556 -288.795478) (xy 268.72417 -288.776006)
			(xy 268.776132 -288.764146) (xy 268.829282 -288.760163) (xy 268.882432 -288.764146) (xy 268.934394 -288.776006)
			(xy 268.984008 -288.795478) (xy 269.030166 -288.822127) (xy 269.071837 -288.855358) (xy 269.108089 -288.894429)
			(xy 269.138113 -288.938466) (xy 269.161239 -288.986487) (xy 269.176949 -289.037417) (xy 269.184892 -289.090121)
			(xy 269.18539 -289.11677) (xy 269.184892 -289.143419) (xy 283.561272 -289.143419) (xy 283.561272 -289.090121)
			(xy 283.569215 -289.037417) (xy 283.584925 -288.986487) (xy 283.608051 -288.938466) (xy 283.638075 -288.894429)
			(xy 283.674327 -288.855358) (xy 283.715998 -288.822127) (xy 283.762156 -288.795478) (xy 283.81177 -288.776006)
			(xy 283.863732 -288.764146) (xy 283.916882 -288.760163) (xy 283.970032 -288.764146) (xy 284.021994 -288.776006)
			(xy 284.071608 -288.795478) (xy 284.117766 -288.822127) (xy 284.159437 -288.855358) (xy 284.195689 -288.894429)
			(xy 284.225713 -288.938466) (xy 284.248839 -288.986487) (xy 284.264549 -289.037417) (xy 284.272492 -289.090121)
			(xy 284.27299 -289.11677) (xy 284.272492 -289.143419) (xy 298.674272 -289.143419) (xy 298.674272 -289.090121)
			(xy 298.682215 -289.037417) (xy 298.697925 -288.986487) (xy 298.721051 -288.938466) (xy 298.751075 -288.894429)
			(xy 298.787327 -288.855358) (xy 298.828998 -288.822127) (xy 298.875156 -288.795478) (xy 298.92477 -288.776006)
			(xy 298.976732 -288.764146) (xy 299.029882 -288.760163) (xy 299.083032 -288.764146) (xy 299.134994 -288.776006)
			(xy 299.184608 -288.795478) (xy 299.230766 -288.822127) (xy 299.272437 -288.855358) (xy 299.308689 -288.894429)
			(xy 299.338713 -288.938466) (xy 299.361839 -288.986487) (xy 299.377549 -289.037417) (xy 299.385492 -289.090121)
			(xy 299.38599 -289.11677) (xy 299.385492 -289.143419) (xy 299.377549 -289.196123) (xy 299.361839 -289.247053)
			(xy 299.338713 -289.295074) (xy 299.308689 -289.339111) (xy 299.272437 -289.378182) (xy 299.230766 -289.411413)
			(xy 299.184608 -289.438062) (xy 299.134994 -289.457534) (xy 299.083032 -289.469394) (xy 299.029882 -289.473378)
			(xy 298.976732 -289.469394) (xy 298.92477 -289.457534) (xy 298.875156 -289.438062) (xy 298.828998 -289.411413)
			(xy 298.787327 -289.378182) (xy 298.751075 -289.339111) (xy 298.721051 -289.295074) (xy 298.697925 -289.247053)
			(xy 298.682215 -289.196123) (xy 298.674272 -289.143419) (xy 284.272492 -289.143419) (xy 284.264549 -289.196123)
			(xy 284.248839 -289.247053) (xy 284.225713 -289.295074) (xy 284.195689 -289.339111) (xy 284.159437 -289.378182)
			(xy 284.117766 -289.411413) (xy 284.071608 -289.438062) (xy 284.021994 -289.457534) (xy 283.970032 -289.469394)
			(xy 283.916882 -289.473378) (xy 283.863732 -289.469394) (xy 283.81177 -289.457534) (xy 283.762156 -289.438062)
			(xy 283.715998 -289.411413) (xy 283.674327 -289.378182) (xy 283.638075 -289.339111) (xy 283.608051 -289.295074)
			(xy 283.584925 -289.247053) (xy 283.569215 -289.196123) (xy 283.561272 -289.143419) (xy 269.184892 -289.143419)
			(xy 269.176949 -289.196123) (xy 269.161239 -289.247053) (xy 269.138113 -289.295074) (xy 269.108089 -289.339111)
			(xy 269.071837 -289.378182) (xy 269.030166 -289.411413) (xy 268.984008 -289.438062) (xy 268.934394 -289.457534)
			(xy 268.882432 -289.469394) (xy 268.829282 -289.473378) (xy 268.776132 -289.469394) (xy 268.72417 -289.457534)
			(xy 268.674556 -289.438062) (xy 268.628398 -289.411413) (xy 268.586727 -289.378182) (xy 268.550475 -289.339111)
			(xy 268.520451 -289.295074) (xy 268.497325 -289.247053) (xy 268.481615 -289.196123) (xy 268.473672 -289.143419)
			(xy 254 -289.143419) (xy 254 -289.993303) (xy 264.373604 -289.993303) (xy 264.373604 -289.940005)
			(xy 264.381547 -289.887301) (xy 264.397257 -289.836371) (xy 264.420383 -289.78835) (xy 264.450407 -289.744313)
			(xy 264.486659 -289.705242) (xy 264.52833 -289.672011) (xy 264.574488 -289.645362) (xy 264.624102 -289.62589)
			(xy 264.676064 -289.61403) (xy 264.729214 -289.610047) (xy 264.782364 -289.61403) (xy 264.834326 -289.62589)
			(xy 264.88394 -289.645362) (xy 264.930098 -289.672011) (xy 264.971769 -289.705242) (xy 265.008021 -289.744313)
			(xy 265.038045 -289.78835) (xy 265.061171 -289.836371) (xy 265.076881 -289.887301) (xy 265.084824 -289.940005)
			(xy 265.085322 -289.966654) (xy 265.084824 -289.993303) (xy 279.461204 -289.993303) (xy 279.461204 -289.940005)
			(xy 279.469147 -289.887301) (xy 279.484857 -289.836371) (xy 279.507983 -289.78835) (xy 279.538007 -289.744313)
			(xy 279.574259 -289.705242) (xy 279.61593 -289.672011) (xy 279.662088 -289.645362) (xy 279.711702 -289.62589)
			(xy 279.763664 -289.61403) (xy 279.816814 -289.610047) (xy 279.869964 -289.61403) (xy 279.921926 -289.62589)
			(xy 279.97154 -289.645362) (xy 280.017698 -289.672011) (xy 280.059369 -289.705242) (xy 280.095621 -289.744313)
			(xy 280.125645 -289.78835) (xy 280.148771 -289.836371) (xy 280.164481 -289.887301) (xy 280.172424 -289.940005)
			(xy 280.172922 -289.966654) (xy 280.172424 -289.993303) (xy 294.548804 -289.993303) (xy 294.548804 -289.940005)
			(xy 294.556747 -289.887301) (xy 294.572457 -289.836371) (xy 294.595583 -289.78835) (xy 294.625607 -289.744313)
			(xy 294.661859 -289.705242) (xy 294.70353 -289.672011) (xy 294.749688 -289.645362) (xy 294.799302 -289.62589)
			(xy 294.851264 -289.61403) (xy 294.904414 -289.610047) (xy 294.957564 -289.61403) (xy 295.009526 -289.62589)
			(xy 295.05914 -289.645362) (xy 295.105298 -289.672011) (xy 295.146969 -289.705242) (xy 295.183221 -289.744313)
			(xy 295.213245 -289.78835) (xy 295.236371 -289.836371) (xy 295.252081 -289.887301) (xy 295.260024 -289.940005)
			(xy 295.260522 -289.966654) (xy 295.260024 -289.993303) (xy 295.252081 -290.046007) (xy 295.236371 -290.096937)
			(xy 295.213245 -290.144958) (xy 295.183221 -290.188995) (xy 295.146969 -290.228066) (xy 295.105298 -290.261297)
			(xy 295.05914 -290.287946) (xy 295.009526 -290.307418) (xy 294.957564 -290.319278) (xy 294.904414 -290.323262)
			(xy 294.851264 -290.319278) (xy 294.799302 -290.307418) (xy 294.749688 -290.287946) (xy 294.70353 -290.261297)
			(xy 294.661859 -290.228066) (xy 294.625607 -290.188995) (xy 294.595583 -290.144958) (xy 294.572457 -290.096937)
			(xy 294.556747 -290.046007) (xy 294.548804 -289.993303) (xy 280.172424 -289.993303) (xy 280.164481 -290.046007)
			(xy 280.148771 -290.096937) (xy 280.125645 -290.144958) (xy 280.095621 -290.188995) (xy 280.059369 -290.228066)
			(xy 280.017698 -290.261297) (xy 279.97154 -290.287946) (xy 279.921926 -290.307418) (xy 279.869964 -290.319278)
			(xy 279.816814 -290.323262) (xy 279.763664 -290.319278) (xy 279.711702 -290.307418) (xy 279.662088 -290.287946)
			(xy 279.61593 -290.261297) (xy 279.574259 -290.228066) (xy 279.538007 -290.188995) (xy 279.507983 -290.144958)
			(xy 279.484857 -290.096937) (xy 279.469147 -290.046007) (xy 279.461204 -289.993303) (xy 265.084824 -289.993303)
			(xy 265.076881 -290.046007) (xy 265.061171 -290.096937) (xy 265.038045 -290.144958) (xy 265.008021 -290.188995)
			(xy 264.971769 -290.228066) (xy 264.930098 -290.261297) (xy 264.88394 -290.287946) (xy 264.834326 -290.307418)
			(xy 264.782364 -290.319278) (xy 264.729214 -290.323262) (xy 264.676064 -290.319278) (xy 264.624102 -290.307418)
			(xy 264.574488 -290.287946) (xy 264.52833 -290.261297) (xy 264.486659 -290.228066) (xy 264.450407 -290.188995)
			(xy 264.420383 -290.144958) (xy 264.397257 -290.096937) (xy 264.381547 -290.046007) (xy 264.373604 -289.993303)
			(xy 254 -289.993303) (xy 254 -290.843441) (xy 268.473672 -290.843441) (xy 268.473672 -290.790143)
			(xy 268.481615 -290.737439) (xy 268.497325 -290.686509) (xy 268.520451 -290.638488) (xy 268.550475 -290.594451)
			(xy 268.586727 -290.55538) (xy 268.628398 -290.522149) (xy 268.674556 -290.4955) (xy 268.72417 -290.476028)
			(xy 268.776132 -290.464168) (xy 268.829282 -290.460185) (xy 268.882432 -290.464168) (xy 268.934394 -290.476028)
			(xy 268.984008 -290.4955) (xy 269.030166 -290.522149) (xy 269.071837 -290.55538) (xy 269.108089 -290.594451)
			(xy 269.138113 -290.638488) (xy 269.161239 -290.686509) (xy 269.176949 -290.737439) (xy 269.184892 -290.790143)
			(xy 269.18539 -290.816792) (xy 269.184892 -290.843441) (xy 283.561272 -290.843441) (xy 283.561272 -290.790143)
			(xy 283.569215 -290.737439) (xy 283.584925 -290.686509) (xy 283.608051 -290.638488) (xy 283.638075 -290.594451)
			(xy 283.674327 -290.55538) (xy 283.715998 -290.522149) (xy 283.762156 -290.4955) (xy 283.81177 -290.476028)
			(xy 283.863732 -290.464168) (xy 283.916882 -290.460185) (xy 283.970032 -290.464168) (xy 284.021994 -290.476028)
			(xy 284.071608 -290.4955) (xy 284.117766 -290.522149) (xy 284.159437 -290.55538) (xy 284.195689 -290.594451)
			(xy 284.225713 -290.638488) (xy 284.248839 -290.686509) (xy 284.264549 -290.737439) (xy 284.272492 -290.790143)
			(xy 284.27299 -290.816792) (xy 284.272492 -290.843441) (xy 298.674272 -290.843441) (xy 298.674272 -290.790143)
			(xy 298.682215 -290.737439) (xy 298.697925 -290.686509) (xy 298.721051 -290.638488) (xy 298.751075 -290.594451)
			(xy 298.787327 -290.55538) (xy 298.828998 -290.522149) (xy 298.875156 -290.4955) (xy 298.92477 -290.476028)
			(xy 298.976732 -290.464168) (xy 299.029882 -290.460185) (xy 299.083032 -290.464168) (xy 299.134994 -290.476028)
			(xy 299.184608 -290.4955) (xy 299.230766 -290.522149) (xy 299.272437 -290.55538) (xy 299.308689 -290.594451)
			(xy 299.338713 -290.638488) (xy 299.361839 -290.686509) (xy 299.377549 -290.737439) (xy 299.385492 -290.790143)
			(xy 299.38599 -290.816792) (xy 299.385492 -290.843441) (xy 299.377549 -290.896145) (xy 299.361839 -290.947075)
			(xy 299.338713 -290.995096) (xy 299.308689 -291.039133) (xy 299.272437 -291.078204) (xy 299.230766 -291.111435)
			(xy 299.184608 -291.138084) (xy 299.134994 -291.157556) (xy 299.083032 -291.169416) (xy 299.029882 -291.1734)
			(xy 298.976732 -291.169416) (xy 298.92477 -291.157556) (xy 298.875156 -291.138084) (xy 298.828998 -291.111435)
			(xy 298.787327 -291.078204) (xy 298.751075 -291.039133) (xy 298.721051 -290.995096) (xy 298.697925 -290.947075)
			(xy 298.682215 -290.896145) (xy 298.674272 -290.843441) (xy 284.272492 -290.843441) (xy 284.264549 -290.896145)
			(xy 284.248839 -290.947075) (xy 284.225713 -290.995096) (xy 284.195689 -291.039133) (xy 284.159437 -291.078204)
			(xy 284.117766 -291.111435) (xy 284.071608 -291.138084) (xy 284.021994 -291.157556) (xy 283.970032 -291.169416)
			(xy 283.916882 -291.1734) (xy 283.863732 -291.169416) (xy 283.81177 -291.157556) (xy 283.762156 -291.138084)
			(xy 283.715998 -291.111435) (xy 283.674327 -291.078204) (xy 283.638075 -291.039133) (xy 283.608051 -290.995096)
			(xy 283.584925 -290.947075) (xy 283.569215 -290.896145) (xy 283.561272 -290.843441) (xy 269.184892 -290.843441)
			(xy 269.176949 -290.896145) (xy 269.161239 -290.947075) (xy 269.138113 -290.995096) (xy 269.108089 -291.039133)
			(xy 269.071837 -291.078204) (xy 269.030166 -291.111435) (xy 268.984008 -291.138084) (xy 268.934394 -291.157556)
			(xy 268.882432 -291.169416) (xy 268.829282 -291.1734) (xy 268.776132 -291.169416) (xy 268.72417 -291.157556)
			(xy 268.674556 -291.138084) (xy 268.628398 -291.111435) (xy 268.586727 -291.078204) (xy 268.550475 -291.039133)
			(xy 268.520451 -290.995096) (xy 268.497325 -290.947075) (xy 268.481615 -290.896145) (xy 268.473672 -290.843441)
			(xy 254 -290.843441) (xy 254 -291.693325) (xy 264.373604 -291.693325) (xy 264.373604 -291.640027)
			(xy 264.381547 -291.587323) (xy 264.397257 -291.536393) (xy 264.420383 -291.488372) (xy 264.450407 -291.444335)
			(xy 264.486659 -291.405264) (xy 264.52833 -291.372033) (xy 264.574488 -291.345384) (xy 264.624102 -291.325912)
			(xy 264.676064 -291.314052) (xy 264.729214 -291.310069) (xy 264.782364 -291.314052) (xy 264.834326 -291.325912)
			(xy 264.88394 -291.345384) (xy 264.930098 -291.372033) (xy 264.971769 -291.405264) (xy 265.008021 -291.444335)
			(xy 265.038045 -291.488372) (xy 265.061171 -291.536393) (xy 265.076881 -291.587323) (xy 265.084824 -291.640027)
			(xy 265.085322 -291.666676) (xy 265.084824 -291.693325) (xy 279.461204 -291.693325) (xy 279.461204 -291.640027)
			(xy 279.469147 -291.587323) (xy 279.484857 -291.536393) (xy 279.507983 -291.488372) (xy 279.538007 -291.444335)
			(xy 279.574259 -291.405264) (xy 279.61593 -291.372033) (xy 279.662088 -291.345384) (xy 279.711702 -291.325912)
			(xy 279.763664 -291.314052) (xy 279.816814 -291.310069) (xy 279.869964 -291.314052) (xy 279.921926 -291.325912)
			(xy 279.97154 -291.345384) (xy 280.017698 -291.372033) (xy 280.059369 -291.405264) (xy 280.095621 -291.444335)
			(xy 280.125645 -291.488372) (xy 280.148771 -291.536393) (xy 280.164481 -291.587323) (xy 280.172424 -291.640027)
			(xy 280.172922 -291.666676) (xy 280.172424 -291.693325) (xy 294.548804 -291.693325) (xy 294.548804 -291.640027)
			(xy 294.556747 -291.587323) (xy 294.572457 -291.536393) (xy 294.595583 -291.488372) (xy 294.625607 -291.444335)
			(xy 294.661859 -291.405264) (xy 294.70353 -291.372033) (xy 294.749688 -291.345384) (xy 294.799302 -291.325912)
			(xy 294.851264 -291.314052) (xy 294.904414 -291.310069) (xy 294.957564 -291.314052) (xy 295.009526 -291.325912)
			(xy 295.05914 -291.345384) (xy 295.105298 -291.372033) (xy 295.146969 -291.405264) (xy 295.183221 -291.444335)
			(xy 295.213245 -291.488372) (xy 295.236371 -291.536393) (xy 295.252081 -291.587323) (xy 295.260024 -291.640027)
			(xy 295.260522 -291.666676) (xy 295.260024 -291.693325) (xy 295.252081 -291.746029) (xy 295.236371 -291.796959)
			(xy 295.213245 -291.84498) (xy 295.183221 -291.889017) (xy 295.146969 -291.928088) (xy 295.105298 -291.961319)
			(xy 295.05914 -291.987968) (xy 295.009526 -292.00744) (xy 294.957564 -292.0193) (xy 294.904414 -292.023284)
			(xy 294.851264 -292.0193) (xy 294.799302 -292.00744) (xy 294.749688 -291.987968) (xy 294.70353 -291.961319)
			(xy 294.661859 -291.928088) (xy 294.625607 -291.889017) (xy 294.595583 -291.84498) (xy 294.572457 -291.796959)
			(xy 294.556747 -291.746029) (xy 294.548804 -291.693325) (xy 280.172424 -291.693325) (xy 280.164481 -291.746029)
			(xy 280.148771 -291.796959) (xy 280.125645 -291.84498) (xy 280.095621 -291.889017) (xy 280.059369 -291.928088)
			(xy 280.017698 -291.961319) (xy 279.97154 -291.987968) (xy 279.921926 -292.00744) (xy 279.869964 -292.0193)
			(xy 279.816814 -292.023284) (xy 279.763664 -292.0193) (xy 279.711702 -292.00744) (xy 279.662088 -291.987968)
			(xy 279.61593 -291.961319) (xy 279.574259 -291.928088) (xy 279.538007 -291.889017) (xy 279.507983 -291.84498)
			(xy 279.484857 -291.796959) (xy 279.469147 -291.746029) (xy 279.461204 -291.693325) (xy 265.084824 -291.693325)
			(xy 265.076881 -291.746029) (xy 265.061171 -291.796959) (xy 265.038045 -291.84498) (xy 265.008021 -291.889017)
			(xy 264.971769 -291.928088) (xy 264.930098 -291.961319) (xy 264.88394 -291.987968) (xy 264.834326 -292.00744)
			(xy 264.782364 -292.0193) (xy 264.729214 -292.023284) (xy 264.676064 -292.0193) (xy 264.624102 -292.00744)
			(xy 264.574488 -291.987968) (xy 264.52833 -291.961319) (xy 264.486659 -291.928088) (xy 264.450407 -291.889017)
			(xy 264.420383 -291.84498) (xy 264.397257 -291.796959) (xy 264.381547 -291.746029) (xy 264.373604 -291.693325)
			(xy 254 -291.693325) (xy 254 -292.543463) (xy 268.473672 -292.543463) (xy 268.473672 -292.490165)
			(xy 268.481615 -292.437461) (xy 268.497325 -292.386531) (xy 268.520451 -292.33851) (xy 268.550475 -292.294473)
			(xy 268.586727 -292.255402) (xy 268.628398 -292.222171) (xy 268.674556 -292.195522) (xy 268.72417 -292.17605)
			(xy 268.776132 -292.16419) (xy 268.829282 -292.160207) (xy 268.882432 -292.16419) (xy 268.934394 -292.17605)
			(xy 268.984008 -292.195522) (xy 269.030166 -292.222171) (xy 269.071837 -292.255402) (xy 269.108089 -292.294473)
			(xy 269.138113 -292.33851) (xy 269.161239 -292.386531) (xy 269.176949 -292.437461) (xy 269.184892 -292.490165)
			(xy 269.18539 -292.516814) (xy 269.184892 -292.543463) (xy 283.561272 -292.543463) (xy 283.561272 -292.490165)
			(xy 283.569215 -292.437461) (xy 283.584925 -292.386531) (xy 283.608051 -292.33851) (xy 283.638075 -292.294473)
			(xy 283.674327 -292.255402) (xy 283.715998 -292.222171) (xy 283.762156 -292.195522) (xy 283.81177 -292.17605)
			(xy 283.863732 -292.16419) (xy 283.916882 -292.160207) (xy 283.970032 -292.16419) (xy 284.021994 -292.17605)
			(xy 284.071608 -292.195522) (xy 284.117766 -292.222171) (xy 284.159437 -292.255402) (xy 284.195689 -292.294473)
			(xy 284.225713 -292.33851) (xy 284.248839 -292.386531) (xy 284.264549 -292.437461) (xy 284.272492 -292.490165)
			(xy 284.27299 -292.516814) (xy 284.272492 -292.543463) (xy 298.674272 -292.543463) (xy 298.674272 -292.490165)
			(xy 298.682215 -292.437461) (xy 298.697925 -292.386531) (xy 298.721051 -292.33851) (xy 298.751075 -292.294473)
			(xy 298.787327 -292.255402) (xy 298.828998 -292.222171) (xy 298.875156 -292.195522) (xy 298.92477 -292.17605)
			(xy 298.976732 -292.16419) (xy 299.029882 -292.160207) (xy 299.083032 -292.16419) (xy 299.134994 -292.17605)
			(xy 299.184608 -292.195522) (xy 299.230766 -292.222171) (xy 299.272437 -292.255402) (xy 299.308689 -292.294473)
			(xy 299.338713 -292.33851) (xy 299.361839 -292.386531) (xy 299.377549 -292.437461) (xy 299.385492 -292.490165)
			(xy 299.38599 -292.516814) (xy 299.385492 -292.543463) (xy 299.377549 -292.596167) (xy 299.361839 -292.647097)
			(xy 299.338713 -292.695118) (xy 299.308689 -292.739155) (xy 299.272437 -292.778226) (xy 299.230766 -292.811457)
			(xy 299.184608 -292.838106) (xy 299.134994 -292.857578) (xy 299.083032 -292.869438) (xy 299.029882 -292.873422)
			(xy 298.976732 -292.869438) (xy 298.92477 -292.857578) (xy 298.875156 -292.838106) (xy 298.828998 -292.811457)
			(xy 298.787327 -292.778226) (xy 298.751075 -292.739155) (xy 298.721051 -292.695118) (xy 298.697925 -292.647097)
			(xy 298.682215 -292.596167) (xy 298.674272 -292.543463) (xy 284.272492 -292.543463) (xy 284.264549 -292.596167)
			(xy 284.248839 -292.647097) (xy 284.225713 -292.695118) (xy 284.195689 -292.739155) (xy 284.159437 -292.778226)
			(xy 284.117766 -292.811457) (xy 284.071608 -292.838106) (xy 284.021994 -292.857578) (xy 283.970032 -292.869438)
			(xy 283.916882 -292.873422) (xy 283.863732 -292.869438) (xy 283.81177 -292.857578) (xy 283.762156 -292.838106)
			(xy 283.715998 -292.811457) (xy 283.674327 -292.778226) (xy 283.638075 -292.739155) (xy 283.608051 -292.695118)
			(xy 283.584925 -292.647097) (xy 283.569215 -292.596167) (xy 283.561272 -292.543463) (xy 269.184892 -292.543463)
			(xy 269.176949 -292.596167) (xy 269.161239 -292.647097) (xy 269.138113 -292.695118) (xy 269.108089 -292.739155)
			(xy 269.071837 -292.778226) (xy 269.030166 -292.811457) (xy 268.984008 -292.838106) (xy 268.934394 -292.857578)
			(xy 268.882432 -292.869438) (xy 268.829282 -292.873422) (xy 268.776132 -292.869438) (xy 268.72417 -292.857578)
			(xy 268.674556 -292.838106) (xy 268.628398 -292.811457) (xy 268.586727 -292.778226) (xy 268.550475 -292.739155)
			(xy 268.520451 -292.695118) (xy 268.497325 -292.647097) (xy 268.481615 -292.596167) (xy 268.473672 -292.543463)
			(xy 254 -292.543463) (xy 254 -293.393347) (xy 264.373604 -293.393347) (xy 264.373604 -293.340049)
			(xy 264.381547 -293.287345) (xy 264.397257 -293.236415) (xy 264.420383 -293.188394) (xy 264.450407 -293.144357)
			(xy 264.486659 -293.105286) (xy 264.52833 -293.072055) (xy 264.574488 -293.045406) (xy 264.624102 -293.025934)
			(xy 264.676064 -293.014074) (xy 264.729214 -293.010091) (xy 264.782364 -293.014074) (xy 264.834326 -293.025934)
			(xy 264.88394 -293.045406) (xy 264.930098 -293.072055) (xy 264.971769 -293.105286) (xy 265.008021 -293.144357)
			(xy 265.038045 -293.188394) (xy 265.061171 -293.236415) (xy 265.076881 -293.287345) (xy 265.084824 -293.340049)
			(xy 265.085322 -293.366698) (xy 265.084824 -293.393347) (xy 268.473672 -293.393347) (xy 268.473672 -293.340049)
			(xy 268.481615 -293.287345) (xy 268.497325 -293.236415) (xy 268.520451 -293.188394) (xy 268.550475 -293.144357)
			(xy 268.586727 -293.105286) (xy 268.628398 -293.072055) (xy 268.674556 -293.045406) (xy 268.72417 -293.025934)
			(xy 268.776132 -293.014074) (xy 268.829282 -293.010091) (xy 268.882432 -293.014074) (xy 268.934394 -293.025934)
			(xy 268.984008 -293.045406) (xy 269.030166 -293.072055) (xy 269.071837 -293.105286) (xy 269.108089 -293.144357)
			(xy 269.138113 -293.188394) (xy 269.161239 -293.236415) (xy 269.176949 -293.287345) (xy 269.184892 -293.340049)
			(xy 269.18539 -293.366698) (xy 269.184892 -293.393347) (xy 279.461204 -293.393347) (xy 279.461204 -293.340049)
			(xy 279.469147 -293.287345) (xy 279.484857 -293.236415) (xy 279.507983 -293.188394) (xy 279.538007 -293.144357)
			(xy 279.574259 -293.105286) (xy 279.61593 -293.072055) (xy 279.662088 -293.045406) (xy 279.711702 -293.025934)
			(xy 279.763664 -293.014074) (xy 279.816814 -293.010091) (xy 279.869964 -293.014074) (xy 279.921926 -293.025934)
			(xy 279.97154 -293.045406) (xy 280.017698 -293.072055) (xy 280.059369 -293.105286) (xy 280.095621 -293.144357)
			(xy 280.125645 -293.188394) (xy 280.148771 -293.236415) (xy 280.164481 -293.287345) (xy 280.172424 -293.340049)
			(xy 280.172922 -293.366698) (xy 280.172424 -293.393347) (xy 283.561272 -293.393347) (xy 283.561272 -293.340049)
			(xy 283.569215 -293.287345) (xy 283.584925 -293.236415) (xy 283.608051 -293.188394) (xy 283.638075 -293.144357)
			(xy 283.674327 -293.105286) (xy 283.715998 -293.072055) (xy 283.762156 -293.045406) (xy 283.81177 -293.025934)
			(xy 283.863732 -293.014074) (xy 283.916882 -293.010091) (xy 283.970032 -293.014074) (xy 284.021994 -293.025934)
			(xy 284.071608 -293.045406) (xy 284.117766 -293.072055) (xy 284.159437 -293.105286) (xy 284.195689 -293.144357)
			(xy 284.225713 -293.188394) (xy 284.248839 -293.236415) (xy 284.264549 -293.287345) (xy 284.272492 -293.340049)
			(xy 284.27299 -293.366698) (xy 284.272492 -293.393347) (xy 294.548804 -293.393347) (xy 294.548804 -293.340049)
			(xy 294.556747 -293.287345) (xy 294.572457 -293.236415) (xy 294.595583 -293.188394) (xy 294.625607 -293.144357)
			(xy 294.661859 -293.105286) (xy 294.70353 -293.072055) (xy 294.749688 -293.045406) (xy 294.799302 -293.025934)
			(xy 294.851264 -293.014074) (xy 294.904414 -293.010091) (xy 294.957564 -293.014074) (xy 295.009526 -293.025934)
			(xy 295.05914 -293.045406) (xy 295.105298 -293.072055) (xy 295.146969 -293.105286) (xy 295.183221 -293.144357)
			(xy 295.213245 -293.188394) (xy 295.236371 -293.236415) (xy 295.252081 -293.287345) (xy 295.260024 -293.340049)
			(xy 295.260522 -293.366698) (xy 295.260024 -293.393347) (xy 295.259986 -293.393601) (xy 298.674272 -293.393601)
			(xy 298.674272 -293.340303) (xy 298.682215 -293.287599) (xy 298.697925 -293.236669) (xy 298.721051 -293.188648)
			(xy 298.751075 -293.144611) (xy 298.787327 -293.10554) (xy 298.828998 -293.072309) (xy 298.875156 -293.04566)
			(xy 298.92477 -293.026188) (xy 298.976732 -293.014328) (xy 299.029882 -293.010345) (xy 299.083032 -293.014328)
			(xy 299.134994 -293.026188) (xy 299.184608 -293.04566) (xy 299.230766 -293.072309) (xy 299.272437 -293.10554)
			(xy 299.308689 -293.144611) (xy 299.338713 -293.188648) (xy 299.361839 -293.236669) (xy 299.377549 -293.287599)
			(xy 299.385492 -293.340303) (xy 299.38599 -293.366952) (xy 299.385492 -293.393601) (xy 299.377549 -293.446305)
			(xy 299.361839 -293.497235) (xy 299.338713 -293.545256) (xy 299.308689 -293.589293) (xy 299.272437 -293.628364)
			(xy 299.230766 -293.661595) (xy 299.184608 -293.688244) (xy 299.134994 -293.707716) (xy 299.083032 -293.719576)
			(xy 299.029882 -293.72356) (xy 298.976732 -293.719576) (xy 298.92477 -293.707716) (xy 298.875156 -293.688244)
			(xy 298.828998 -293.661595) (xy 298.787327 -293.628364) (xy 298.751075 -293.589293) (xy 298.721051 -293.545256)
			(xy 298.697925 -293.497235) (xy 298.682215 -293.446305) (xy 298.674272 -293.393601) (xy 295.259986 -293.393601)
			(xy 295.252081 -293.446051) (xy 295.236371 -293.496981) (xy 295.213245 -293.545002) (xy 295.183221 -293.589039)
			(xy 295.146969 -293.62811) (xy 295.105298 -293.661341) (xy 295.05914 -293.68799) (xy 295.009526 -293.707462)
			(xy 294.957564 -293.719322) (xy 294.904414 -293.723306) (xy 294.851264 -293.719322) (xy 294.799302 -293.707462)
			(xy 294.749688 -293.68799) (xy 294.70353 -293.661341) (xy 294.661859 -293.62811) (xy 294.625607 -293.589039)
			(xy 294.595583 -293.545002) (xy 294.572457 -293.496981) (xy 294.556747 -293.446051) (xy 294.548804 -293.393347)
			(xy 284.272492 -293.393347) (xy 284.264549 -293.446051) (xy 284.248839 -293.496981) (xy 284.225713 -293.545002)
			(xy 284.195689 -293.589039) (xy 284.159437 -293.62811) (xy 284.117766 -293.661341) (xy 284.071608 -293.68799)
			(xy 284.021994 -293.707462) (xy 283.970032 -293.719322) (xy 283.916882 -293.723306) (xy 283.863732 -293.719322)
			(xy 283.81177 -293.707462) (xy 283.762156 -293.68799) (xy 283.715998 -293.661341) (xy 283.674327 -293.62811)
			(xy 283.638075 -293.589039) (xy 283.608051 -293.545002) (xy 283.584925 -293.496981) (xy 283.569215 -293.446051)
			(xy 283.561272 -293.393347) (xy 280.172424 -293.393347) (xy 280.164481 -293.446051) (xy 280.148771 -293.496981)
			(xy 280.125645 -293.545002) (xy 280.095621 -293.589039) (xy 280.059369 -293.62811) (xy 280.017698 -293.661341)
			(xy 279.97154 -293.68799) (xy 279.921926 -293.707462) (xy 279.869964 -293.719322) (xy 279.816814 -293.723306)
			(xy 279.763664 -293.719322) (xy 279.711702 -293.707462) (xy 279.662088 -293.68799) (xy 279.61593 -293.661341)
			(xy 279.574259 -293.62811) (xy 279.538007 -293.589039) (xy 279.507983 -293.545002) (xy 279.484857 -293.496981)
			(xy 279.469147 -293.446051) (xy 279.461204 -293.393347) (xy 269.184892 -293.393347) (xy 269.176949 -293.446051)
			(xy 269.161239 -293.496981) (xy 269.138113 -293.545002) (xy 269.108089 -293.589039) (xy 269.071837 -293.62811)
			(xy 269.030166 -293.661341) (xy 268.984008 -293.68799) (xy 268.934394 -293.707462) (xy 268.882432 -293.719322)
			(xy 268.829282 -293.723306) (xy 268.776132 -293.719322) (xy 268.72417 -293.707462) (xy 268.674556 -293.68799)
			(xy 268.628398 -293.661341) (xy 268.586727 -293.62811) (xy 268.550475 -293.589039) (xy 268.520451 -293.545002)
			(xy 268.497325 -293.496981) (xy 268.481615 -293.446051) (xy 268.473672 -293.393347) (xy 265.084824 -293.393347)
			(xy 265.076881 -293.446051) (xy 265.061171 -293.496981) (xy 265.038045 -293.545002) (xy 265.008021 -293.589039)
			(xy 264.971769 -293.62811) (xy 264.930098 -293.661341) (xy 264.88394 -293.68799) (xy 264.834326 -293.707462)
			(xy 264.782364 -293.719322) (xy 264.729214 -293.723306) (xy 264.676064 -293.719322) (xy 264.624102 -293.707462)
			(xy 264.574488 -293.68799) (xy 264.52833 -293.661341) (xy 264.486659 -293.62811) (xy 264.450407 -293.589039)
			(xy 264.420383 -293.545002) (xy 264.397257 -293.496981) (xy 264.381547 -293.446051) (xy 264.373604 -293.393347)
			(xy 254 -293.393347) (xy 254 -294.243231) (xy 264.373604 -294.243231) (xy 264.373604 -294.189933)
			(xy 264.381547 -294.137229) (xy 264.397257 -294.086299) (xy 264.420383 -294.038278) (xy 264.450407 -293.994241)
			(xy 264.486659 -293.95517) (xy 264.52833 -293.921939) (xy 264.574488 -293.89529) (xy 264.624102 -293.875818)
			(xy 264.676064 -293.863958) (xy 264.729214 -293.859975) (xy 264.782364 -293.863958) (xy 264.834326 -293.875818)
			(xy 264.88394 -293.89529) (xy 264.930098 -293.921939) (xy 264.971769 -293.95517) (xy 265.008021 -293.994241)
			(xy 265.038045 -294.038278) (xy 265.061171 -294.086299) (xy 265.076881 -294.137229) (xy 265.084824 -294.189933)
			(xy 265.085322 -294.216582) (xy 265.084824 -294.243231) (xy 279.461204 -294.243231) (xy 279.461204 -294.189933)
			(xy 279.469147 -294.137229) (xy 279.484857 -294.086299) (xy 279.507983 -294.038278) (xy 279.538007 -293.994241)
			(xy 279.574259 -293.95517) (xy 279.61593 -293.921939) (xy 279.662088 -293.89529) (xy 279.711702 -293.875818)
			(xy 279.763664 -293.863958) (xy 279.816814 -293.859975) (xy 279.869964 -293.863958) (xy 279.921926 -293.875818)
			(xy 279.97154 -293.89529) (xy 280.017698 -293.921939) (xy 280.059369 -293.95517) (xy 280.095621 -293.994241)
			(xy 280.125645 -294.038278) (xy 280.148771 -294.086299) (xy 280.164481 -294.137229) (xy 280.172424 -294.189933)
			(xy 280.172922 -294.216582) (xy 280.172424 -294.243231) (xy 294.548804 -294.243231) (xy 294.548804 -294.189933)
			(xy 294.556747 -294.137229) (xy 294.572457 -294.086299) (xy 294.595583 -294.038278) (xy 294.625607 -293.994241)
			(xy 294.661859 -293.95517) (xy 294.70353 -293.921939) (xy 294.749688 -293.89529) (xy 294.799302 -293.875818)
			(xy 294.851264 -293.863958) (xy 294.904414 -293.859975) (xy 294.957564 -293.863958) (xy 295.009526 -293.875818)
			(xy 295.05914 -293.89529) (xy 295.105298 -293.921939) (xy 295.146969 -293.95517) (xy 295.183221 -293.994241)
			(xy 295.213245 -294.038278) (xy 295.236371 -294.086299) (xy 295.252081 -294.137229) (xy 295.260024 -294.189933)
			(xy 295.260522 -294.216582) (xy 295.260024 -294.243231) (xy 295.252081 -294.295935) (xy 295.236371 -294.346865)
			(xy 295.213245 -294.394886) (xy 295.183221 -294.438923) (xy 295.146969 -294.477994) (xy 295.105298 -294.511225)
			(xy 295.05914 -294.537874) (xy 295.009526 -294.557346) (xy 294.957564 -294.569206) (xy 294.904414 -294.57319)
			(xy 294.851264 -294.569206) (xy 294.799302 -294.557346) (xy 294.749688 -294.537874) (xy 294.70353 -294.511225)
			(xy 294.661859 -294.477994) (xy 294.625607 -294.438923) (xy 294.595583 -294.394886) (xy 294.572457 -294.346865)
			(xy 294.556747 -294.295935) (xy 294.548804 -294.243231) (xy 280.172424 -294.243231) (xy 280.164481 -294.295935)
			(xy 280.148771 -294.346865) (xy 280.125645 -294.394886) (xy 280.095621 -294.438923) (xy 280.059369 -294.477994)
			(xy 280.017698 -294.511225) (xy 279.97154 -294.537874) (xy 279.921926 -294.557346) (xy 279.869964 -294.569206)
			(xy 279.816814 -294.57319) (xy 279.763664 -294.569206) (xy 279.711702 -294.557346) (xy 279.662088 -294.537874)
			(xy 279.61593 -294.511225) (xy 279.574259 -294.477994) (xy 279.538007 -294.438923) (xy 279.507983 -294.394886)
			(xy 279.484857 -294.346865) (xy 279.469147 -294.295935) (xy 279.461204 -294.243231) (xy 265.084824 -294.243231)
			(xy 265.076881 -294.295935) (xy 265.061171 -294.346865) (xy 265.038045 -294.394886) (xy 265.008021 -294.438923)
			(xy 264.971769 -294.477994) (xy 264.930098 -294.511225) (xy 264.88394 -294.537874) (xy 264.834326 -294.557346)
			(xy 264.782364 -294.569206) (xy 264.729214 -294.57319) (xy 264.676064 -294.569206) (xy 264.624102 -294.557346)
			(xy 264.574488 -294.537874) (xy 264.52833 -294.511225) (xy 264.486659 -294.477994) (xy 264.450407 -294.438923)
			(xy 264.420383 -294.394886) (xy 264.397257 -294.346865) (xy 264.381547 -294.295935) (xy 264.373604 -294.243231)
			(xy 254 -294.243231) (xy 254 -295.093369) (xy 268.473672 -295.093369) (xy 268.473672 -295.040071)
			(xy 268.481615 -294.987367) (xy 268.497325 -294.936437) (xy 268.520451 -294.888416) (xy 268.550475 -294.844379)
			(xy 268.586727 -294.805308) (xy 268.628398 -294.772077) (xy 268.674556 -294.745428) (xy 268.72417 -294.725956)
			(xy 268.776132 -294.714096) (xy 268.829282 -294.710113) (xy 268.882432 -294.714096) (xy 268.934394 -294.725956)
			(xy 268.984008 -294.745428) (xy 269.030166 -294.772077) (xy 269.071837 -294.805308) (xy 269.108089 -294.844379)
			(xy 269.138113 -294.888416) (xy 269.161239 -294.936437) (xy 269.176949 -294.987367) (xy 269.184892 -295.040071)
			(xy 269.18539 -295.06672) (xy 269.184892 -295.093369) (xy 283.561272 -295.093369) (xy 283.561272 -295.040071)
			(xy 283.569215 -294.987367) (xy 283.584925 -294.936437) (xy 283.608051 -294.888416) (xy 283.638075 -294.844379)
			(xy 283.674327 -294.805308) (xy 283.715998 -294.772077) (xy 283.762156 -294.745428) (xy 283.81177 -294.725956)
			(xy 283.863732 -294.714096) (xy 283.916882 -294.710113) (xy 283.970032 -294.714096) (xy 284.021994 -294.725956)
			(xy 284.071608 -294.745428) (xy 284.117766 -294.772077) (xy 284.159437 -294.805308) (xy 284.195689 -294.844379)
			(xy 284.225713 -294.888416) (xy 284.248839 -294.936437) (xy 284.264549 -294.987367) (xy 284.272492 -295.040071)
			(xy 284.27299 -295.06672) (xy 284.272492 -295.093369) (xy 298.674272 -295.093369) (xy 298.674272 -295.040071)
			(xy 298.682215 -294.987367) (xy 298.697925 -294.936437) (xy 298.721051 -294.888416) (xy 298.751075 -294.844379)
			(xy 298.787327 -294.805308) (xy 298.828998 -294.772077) (xy 298.875156 -294.745428) (xy 298.92477 -294.725956)
			(xy 298.976732 -294.714096) (xy 299.029882 -294.710113) (xy 299.083032 -294.714096) (xy 299.134994 -294.725956)
			(xy 299.184608 -294.745428) (xy 299.230766 -294.772077) (xy 299.272437 -294.805308) (xy 299.308689 -294.844379)
			(xy 299.338713 -294.888416) (xy 299.361839 -294.936437) (xy 299.377549 -294.987367) (xy 299.385492 -295.040071)
			(xy 299.38599 -295.06672) (xy 299.385492 -295.093369) (xy 299.377549 -295.146073) (xy 299.361839 -295.197003)
			(xy 299.338713 -295.245024) (xy 299.308689 -295.289061) (xy 299.272437 -295.328132) (xy 299.230766 -295.361363)
			(xy 299.184608 -295.388012) (xy 299.134994 -295.407484) (xy 299.083032 -295.419344) (xy 299.029882 -295.423328)
			(xy 298.976732 -295.419344) (xy 298.92477 -295.407484) (xy 298.875156 -295.388012) (xy 298.828998 -295.361363)
			(xy 298.787327 -295.328132) (xy 298.751075 -295.289061) (xy 298.721051 -295.245024) (xy 298.697925 -295.197003)
			(xy 298.682215 -295.146073) (xy 298.674272 -295.093369) (xy 284.272492 -295.093369) (xy 284.264549 -295.146073)
			(xy 284.248839 -295.197003) (xy 284.225713 -295.245024) (xy 284.195689 -295.289061) (xy 284.159437 -295.328132)
			(xy 284.117766 -295.361363) (xy 284.071608 -295.388012) (xy 284.021994 -295.407484) (xy 283.970032 -295.419344)
			(xy 283.916882 -295.423328) (xy 283.863732 -295.419344) (xy 283.81177 -295.407484) (xy 283.762156 -295.388012)
			(xy 283.715998 -295.361363) (xy 283.674327 -295.328132) (xy 283.638075 -295.289061) (xy 283.608051 -295.245024)
			(xy 283.584925 -295.197003) (xy 283.569215 -295.146073) (xy 283.561272 -295.093369) (xy 269.184892 -295.093369)
			(xy 269.176949 -295.146073) (xy 269.161239 -295.197003) (xy 269.138113 -295.245024) (xy 269.108089 -295.289061)
			(xy 269.071837 -295.328132) (xy 269.030166 -295.361363) (xy 268.984008 -295.388012) (xy 268.934394 -295.407484)
			(xy 268.882432 -295.419344) (xy 268.829282 -295.423328) (xy 268.776132 -295.419344) (xy 268.72417 -295.407484)
			(xy 268.674556 -295.388012) (xy 268.628398 -295.361363) (xy 268.586727 -295.328132) (xy 268.550475 -295.289061)
			(xy 268.520451 -295.245024) (xy 268.497325 -295.197003) (xy 268.481615 -295.146073) (xy 268.473672 -295.093369)
			(xy 254 -295.093369) (xy 254 -295.943253) (xy 264.373604 -295.943253) (xy 264.373604 -295.889955)
			(xy 264.381547 -295.837251) (xy 264.397257 -295.786321) (xy 264.420383 -295.7383) (xy 264.450407 -295.694263)
			(xy 264.486659 -295.655192) (xy 264.52833 -295.621961) (xy 264.574488 -295.595312) (xy 264.624102 -295.57584)
			(xy 264.676064 -295.56398) (xy 264.729214 -295.559997) (xy 264.782364 -295.56398) (xy 264.834326 -295.57584)
			(xy 264.88394 -295.595312) (xy 264.930098 -295.621961) (xy 264.971769 -295.655192) (xy 265.008021 -295.694263)
			(xy 265.038045 -295.7383) (xy 265.061171 -295.786321) (xy 265.076881 -295.837251) (xy 265.084824 -295.889955)
			(xy 265.085322 -295.916604) (xy 265.084824 -295.943253) (xy 279.461204 -295.943253) (xy 279.461204 -295.889955)
			(xy 279.469147 -295.837251) (xy 279.484857 -295.786321) (xy 279.507983 -295.7383) (xy 279.538007 -295.694263)
			(xy 279.574259 -295.655192) (xy 279.61593 -295.621961) (xy 279.662088 -295.595312) (xy 279.711702 -295.57584)
			(xy 279.763664 -295.56398) (xy 279.816814 -295.559997) (xy 279.869964 -295.56398) (xy 279.921926 -295.57584)
			(xy 279.97154 -295.595312) (xy 280.017698 -295.621961) (xy 280.059369 -295.655192) (xy 280.095621 -295.694263)
			(xy 280.125645 -295.7383) (xy 280.148771 -295.786321) (xy 280.164481 -295.837251) (xy 280.172424 -295.889955)
			(xy 280.172922 -295.916604) (xy 280.172424 -295.943253) (xy 294.548804 -295.943253) (xy 294.548804 -295.889955)
			(xy 294.556747 -295.837251) (xy 294.572457 -295.786321) (xy 294.595583 -295.7383) (xy 294.625607 -295.694263)
			(xy 294.661859 -295.655192) (xy 294.70353 -295.621961) (xy 294.749688 -295.595312) (xy 294.799302 -295.57584)
			(xy 294.851264 -295.56398) (xy 294.904414 -295.559997) (xy 294.957564 -295.56398) (xy 295.009526 -295.57584)
			(xy 295.05914 -295.595312) (xy 295.105298 -295.621961) (xy 295.146969 -295.655192) (xy 295.183221 -295.694263)
			(xy 295.213245 -295.7383) (xy 295.236371 -295.786321) (xy 295.252081 -295.837251) (xy 295.260024 -295.889955)
			(xy 295.260522 -295.916604) (xy 295.260024 -295.943253) (xy 295.252081 -295.995957) (xy 295.236371 -296.046887)
			(xy 295.213245 -296.094908) (xy 295.183221 -296.138945) (xy 295.146969 -296.178016) (xy 295.105298 -296.211247)
			(xy 295.05914 -296.237896) (xy 295.009526 -296.257368) (xy 294.957564 -296.269228) (xy 294.904414 -296.273212)
			(xy 294.851264 -296.269228) (xy 294.799302 -296.257368) (xy 294.749688 -296.237896) (xy 294.70353 -296.211247)
			(xy 294.661859 -296.178016) (xy 294.625607 -296.138945) (xy 294.595583 -296.094908) (xy 294.572457 -296.046887)
			(xy 294.556747 -295.995957) (xy 294.548804 -295.943253) (xy 280.172424 -295.943253) (xy 280.164481 -295.995957)
			(xy 280.148771 -296.046887) (xy 280.125645 -296.094908) (xy 280.095621 -296.138945) (xy 280.059369 -296.178016)
			(xy 280.017698 -296.211247) (xy 279.97154 -296.237896) (xy 279.921926 -296.257368) (xy 279.869964 -296.269228)
			(xy 279.816814 -296.273212) (xy 279.763664 -296.269228) (xy 279.711702 -296.257368) (xy 279.662088 -296.237896)
			(xy 279.61593 -296.211247) (xy 279.574259 -296.178016) (xy 279.538007 -296.138945) (xy 279.507983 -296.094908)
			(xy 279.484857 -296.046887) (xy 279.469147 -295.995957) (xy 279.461204 -295.943253) (xy 265.084824 -295.943253)
			(xy 265.076881 -295.995957) (xy 265.061171 -296.046887) (xy 265.038045 -296.094908) (xy 265.008021 -296.138945)
			(xy 264.971769 -296.178016) (xy 264.930098 -296.211247) (xy 264.88394 -296.237896) (xy 264.834326 -296.257368)
			(xy 264.782364 -296.269228) (xy 264.729214 -296.273212) (xy 264.676064 -296.269228) (xy 264.624102 -296.257368)
			(xy 264.574488 -296.237896) (xy 264.52833 -296.211247) (xy 264.486659 -296.178016) (xy 264.450407 -296.138945)
			(xy 264.420383 -296.094908) (xy 264.397257 -296.046887) (xy 264.381547 -295.995957) (xy 264.373604 -295.943253)
			(xy 254 -295.943253) (xy 254 -296.793391) (xy 268.473672 -296.793391) (xy 268.473672 -296.740093)
			(xy 268.481615 -296.687389) (xy 268.497325 -296.636459) (xy 268.520451 -296.588438) (xy 268.550475 -296.544401)
			(xy 268.586727 -296.50533) (xy 268.628398 -296.472099) (xy 268.674556 -296.44545) (xy 268.72417 -296.425978)
			(xy 268.776132 -296.414118) (xy 268.829282 -296.410135) (xy 268.882432 -296.414118) (xy 268.934394 -296.425978)
			(xy 268.984008 -296.44545) (xy 269.030166 -296.472099) (xy 269.071837 -296.50533) (xy 269.108089 -296.544401)
			(xy 269.138113 -296.588438) (xy 269.161239 -296.636459) (xy 269.176949 -296.687389) (xy 269.184892 -296.740093)
			(xy 269.18539 -296.766742) (xy 269.184892 -296.793391) (xy 283.561272 -296.793391) (xy 283.561272 -296.740093)
			(xy 283.569215 -296.687389) (xy 283.584925 -296.636459) (xy 283.608051 -296.588438) (xy 283.638075 -296.544401)
			(xy 283.674327 -296.50533) (xy 283.715998 -296.472099) (xy 283.762156 -296.44545) (xy 283.81177 -296.425978)
			(xy 283.863732 -296.414118) (xy 283.916882 -296.410135) (xy 283.970032 -296.414118) (xy 284.021994 -296.425978)
			(xy 284.071608 -296.44545) (xy 284.117766 -296.472099) (xy 284.159437 -296.50533) (xy 284.195689 -296.544401)
			(xy 284.225713 -296.588438) (xy 284.248839 -296.636459) (xy 284.264549 -296.687389) (xy 284.272492 -296.740093)
			(xy 284.27299 -296.766742) (xy 284.272492 -296.793391) (xy 298.674272 -296.793391) (xy 298.674272 -296.740093)
			(xy 298.682215 -296.687389) (xy 298.697925 -296.636459) (xy 298.721051 -296.588438) (xy 298.751075 -296.544401)
			(xy 298.787327 -296.50533) (xy 298.828998 -296.472099) (xy 298.875156 -296.44545) (xy 298.92477 -296.425978)
			(xy 298.976732 -296.414118) (xy 299.029882 -296.410135) (xy 299.083032 -296.414118) (xy 299.134994 -296.425978)
			(xy 299.184608 -296.44545) (xy 299.230766 -296.472099) (xy 299.272437 -296.50533) (xy 299.308689 -296.544401)
			(xy 299.338713 -296.588438) (xy 299.361839 -296.636459) (xy 299.377549 -296.687389) (xy 299.385492 -296.740093)
			(xy 299.38599 -296.766742) (xy 299.385492 -296.793391) (xy 299.377549 -296.846095) (xy 299.361839 -296.897025)
			(xy 299.338713 -296.945046) (xy 299.308689 -296.989083) (xy 299.272437 -297.028154) (xy 299.230766 -297.061385)
			(xy 299.184608 -297.088034) (xy 299.134994 -297.107506) (xy 299.083032 -297.119366) (xy 299.029882 -297.12335)
			(xy 298.976732 -297.119366) (xy 298.92477 -297.107506) (xy 298.875156 -297.088034) (xy 298.828998 -297.061385)
			(xy 298.787327 -297.028154) (xy 298.751075 -296.989083) (xy 298.721051 -296.945046) (xy 298.697925 -296.897025)
			(xy 298.682215 -296.846095) (xy 298.674272 -296.793391) (xy 284.272492 -296.793391) (xy 284.264549 -296.846095)
			(xy 284.248839 -296.897025) (xy 284.225713 -296.945046) (xy 284.195689 -296.989083) (xy 284.159437 -297.028154)
			(xy 284.117766 -297.061385) (xy 284.071608 -297.088034) (xy 284.021994 -297.107506) (xy 283.970032 -297.119366)
			(xy 283.916882 -297.12335) (xy 283.863732 -297.119366) (xy 283.81177 -297.107506) (xy 283.762156 -297.088034)
			(xy 283.715998 -297.061385) (xy 283.674327 -297.028154) (xy 283.638075 -296.989083) (xy 283.608051 -296.945046)
			(xy 283.584925 -296.897025) (xy 283.569215 -296.846095) (xy 283.561272 -296.793391) (xy 269.184892 -296.793391)
			(xy 269.176949 -296.846095) (xy 269.161239 -296.897025) (xy 269.138113 -296.945046) (xy 269.108089 -296.989083)
			(xy 269.071837 -297.028154) (xy 269.030166 -297.061385) (xy 268.984008 -297.088034) (xy 268.934394 -297.107506)
			(xy 268.882432 -297.119366) (xy 268.829282 -297.12335) (xy 268.776132 -297.119366) (xy 268.72417 -297.107506)
			(xy 268.674556 -297.088034) (xy 268.628398 -297.061385) (xy 268.586727 -297.028154) (xy 268.550475 -296.989083)
			(xy 268.520451 -296.945046) (xy 268.497325 -296.897025) (xy 268.481615 -296.846095) (xy 268.473672 -296.793391)
			(xy 254 -296.793391) (xy 254 -297.643275) (xy 264.373604 -297.643275) (xy 264.373604 -297.589977)
			(xy 264.381547 -297.537273) (xy 264.397257 -297.486343) (xy 264.420383 -297.438322) (xy 264.450407 -297.394285)
			(xy 264.486659 -297.355214) (xy 264.52833 -297.321983) (xy 264.574488 -297.295334) (xy 264.624102 -297.275862)
			(xy 264.676064 -297.264002) (xy 264.729214 -297.260019) (xy 264.782364 -297.264002) (xy 264.834326 -297.275862)
			(xy 264.88394 -297.295334) (xy 264.930098 -297.321983) (xy 264.971769 -297.355214) (xy 265.008021 -297.394285)
			(xy 265.038045 -297.438322) (xy 265.061171 -297.486343) (xy 265.076881 -297.537273) (xy 265.084824 -297.589977)
			(xy 265.085322 -297.616626) (xy 265.084824 -297.643275) (xy 279.461204 -297.643275) (xy 279.461204 -297.589977)
			(xy 279.469147 -297.537273) (xy 279.484857 -297.486343) (xy 279.507983 -297.438322) (xy 279.538007 -297.394285)
			(xy 279.574259 -297.355214) (xy 279.61593 -297.321983) (xy 279.662088 -297.295334) (xy 279.711702 -297.275862)
			(xy 279.763664 -297.264002) (xy 279.816814 -297.260019) (xy 279.869964 -297.264002) (xy 279.921926 -297.275862)
			(xy 279.97154 -297.295334) (xy 280.017698 -297.321983) (xy 280.059369 -297.355214) (xy 280.095621 -297.394285)
			(xy 280.125645 -297.438322) (xy 280.148771 -297.486343) (xy 280.164481 -297.537273) (xy 280.172424 -297.589977)
			(xy 280.172922 -297.616626) (xy 280.172424 -297.643275) (xy 294.548804 -297.643275) (xy 294.548804 -297.589977)
			(xy 294.556747 -297.537273) (xy 294.572457 -297.486343) (xy 294.595583 -297.438322) (xy 294.625607 -297.394285)
			(xy 294.661859 -297.355214) (xy 294.70353 -297.321983) (xy 294.749688 -297.295334) (xy 294.799302 -297.275862)
			(xy 294.851264 -297.264002) (xy 294.904414 -297.260019) (xy 294.957564 -297.264002) (xy 295.009526 -297.275862)
			(xy 295.05914 -297.295334) (xy 295.105298 -297.321983) (xy 295.146969 -297.355214) (xy 295.183221 -297.394285)
			(xy 295.213245 -297.438322) (xy 295.236371 -297.486343) (xy 295.252081 -297.537273) (xy 295.260024 -297.589977)
			(xy 295.260522 -297.616626) (xy 295.260024 -297.643275) (xy 295.252081 -297.695979) (xy 295.236371 -297.746909)
			(xy 295.213245 -297.79493) (xy 295.183221 -297.838967) (xy 295.146969 -297.878038) (xy 295.105298 -297.911269)
			(xy 295.05914 -297.937918) (xy 295.009526 -297.95739) (xy 294.957564 -297.96925) (xy 294.904414 -297.973234)
			(xy 294.851264 -297.96925) (xy 294.799302 -297.95739) (xy 294.749688 -297.937918) (xy 294.70353 -297.911269)
			(xy 294.661859 -297.878038) (xy 294.625607 -297.838967) (xy 294.595583 -297.79493) (xy 294.572457 -297.746909)
			(xy 294.556747 -297.695979) (xy 294.548804 -297.643275) (xy 280.172424 -297.643275) (xy 280.164481 -297.695979)
			(xy 280.148771 -297.746909) (xy 280.125645 -297.79493) (xy 280.095621 -297.838967) (xy 280.059369 -297.878038)
			(xy 280.017698 -297.911269) (xy 279.97154 -297.937918) (xy 279.921926 -297.95739) (xy 279.869964 -297.96925)
			(xy 279.816814 -297.973234) (xy 279.763664 -297.96925) (xy 279.711702 -297.95739) (xy 279.662088 -297.937918)
			(xy 279.61593 -297.911269) (xy 279.574259 -297.878038) (xy 279.538007 -297.838967) (xy 279.507983 -297.79493)
			(xy 279.484857 -297.746909) (xy 279.469147 -297.695979) (xy 279.461204 -297.643275) (xy 265.084824 -297.643275)
			(xy 265.076881 -297.695979) (xy 265.061171 -297.746909) (xy 265.038045 -297.79493) (xy 265.008021 -297.838967)
			(xy 264.971769 -297.878038) (xy 264.930098 -297.911269) (xy 264.88394 -297.937918) (xy 264.834326 -297.95739)
			(xy 264.782364 -297.96925) (xy 264.729214 -297.973234) (xy 264.676064 -297.96925) (xy 264.624102 -297.95739)
			(xy 264.574488 -297.937918) (xy 264.52833 -297.911269) (xy 264.486659 -297.878038) (xy 264.450407 -297.838967)
			(xy 264.420383 -297.79493) (xy 264.397257 -297.746909) (xy 264.381547 -297.695979) (xy 264.373604 -297.643275)
			(xy 254 -297.643275) (xy 254 -298.493413) (xy 268.473672 -298.493413) (xy 268.473672 -298.440115)
			(xy 268.481615 -298.387411) (xy 268.497325 -298.336481) (xy 268.520451 -298.28846) (xy 268.550475 -298.244423)
			(xy 268.586727 -298.205352) (xy 268.628398 -298.172121) (xy 268.674556 -298.145472) (xy 268.72417 -298.126)
			(xy 268.776132 -298.11414) (xy 268.829282 -298.110157) (xy 268.882432 -298.11414) (xy 268.934394 -298.126)
			(xy 268.984008 -298.145472) (xy 269.030166 -298.172121) (xy 269.071837 -298.205352) (xy 269.108089 -298.244423)
			(xy 269.138113 -298.28846) (xy 269.161239 -298.336481) (xy 269.176949 -298.387411) (xy 269.184892 -298.440115)
			(xy 269.18539 -298.466764) (xy 269.184892 -298.493413) (xy 283.561272 -298.493413) (xy 283.561272 -298.440115)
			(xy 283.569215 -298.387411) (xy 283.584925 -298.336481) (xy 283.608051 -298.28846) (xy 283.638075 -298.244423)
			(xy 283.674327 -298.205352) (xy 283.715998 -298.172121) (xy 283.762156 -298.145472) (xy 283.81177 -298.126)
			(xy 283.863732 -298.11414) (xy 283.916882 -298.110157) (xy 283.970032 -298.11414) (xy 284.021994 -298.126)
			(xy 284.071608 -298.145472) (xy 284.117766 -298.172121) (xy 284.159437 -298.205352) (xy 284.195689 -298.244423)
			(xy 284.225713 -298.28846) (xy 284.248839 -298.336481) (xy 284.264549 -298.387411) (xy 284.272492 -298.440115)
			(xy 284.27299 -298.466764) (xy 284.272492 -298.493413) (xy 298.674272 -298.493413) (xy 298.674272 -298.440115)
			(xy 298.682215 -298.387411) (xy 298.697925 -298.336481) (xy 298.721051 -298.28846) (xy 298.751075 -298.244423)
			(xy 298.787327 -298.205352) (xy 298.828998 -298.172121) (xy 298.875156 -298.145472) (xy 298.92477 -298.126)
			(xy 298.976732 -298.11414) (xy 299.029882 -298.110157) (xy 299.083032 -298.11414) (xy 299.134994 -298.126)
			(xy 299.184608 -298.145472) (xy 299.230766 -298.172121) (xy 299.272437 -298.205352) (xy 299.308689 -298.244423)
			(xy 299.338713 -298.28846) (xy 299.361839 -298.336481) (xy 299.377549 -298.387411) (xy 299.385492 -298.440115)
			(xy 299.38599 -298.466764) (xy 299.385492 -298.493413) (xy 299.377549 -298.546117) (xy 299.361839 -298.597047)
			(xy 299.338713 -298.645068) (xy 299.308689 -298.689105) (xy 299.272437 -298.728176) (xy 299.230766 -298.761407)
			(xy 299.184608 -298.788056) (xy 299.134994 -298.807528) (xy 299.083032 -298.819388) (xy 299.029882 -298.823372)
			(xy 298.976732 -298.819388) (xy 298.92477 -298.807528) (xy 298.875156 -298.788056) (xy 298.828998 -298.761407)
			(xy 298.787327 -298.728176) (xy 298.751075 -298.689105) (xy 298.721051 -298.645068) (xy 298.697925 -298.597047)
			(xy 298.682215 -298.546117) (xy 298.674272 -298.493413) (xy 284.272492 -298.493413) (xy 284.264549 -298.546117)
			(xy 284.248839 -298.597047) (xy 284.225713 -298.645068) (xy 284.195689 -298.689105) (xy 284.159437 -298.728176)
			(xy 284.117766 -298.761407) (xy 284.071608 -298.788056) (xy 284.021994 -298.807528) (xy 283.970032 -298.819388)
			(xy 283.916882 -298.823372) (xy 283.863732 -298.819388) (xy 283.81177 -298.807528) (xy 283.762156 -298.788056)
			(xy 283.715998 -298.761407) (xy 283.674327 -298.728176) (xy 283.638075 -298.689105) (xy 283.608051 -298.645068)
			(xy 283.584925 -298.597047) (xy 283.569215 -298.546117) (xy 283.561272 -298.493413) (xy 269.184892 -298.493413)
			(xy 269.176949 -298.546117) (xy 269.161239 -298.597047) (xy 269.138113 -298.645068) (xy 269.108089 -298.689105)
			(xy 269.071837 -298.728176) (xy 269.030166 -298.761407) (xy 268.984008 -298.788056) (xy 268.934394 -298.807528)
			(xy 268.882432 -298.819388) (xy 268.829282 -298.823372) (xy 268.776132 -298.819388) (xy 268.72417 -298.807528)
			(xy 268.674556 -298.788056) (xy 268.628398 -298.761407) (xy 268.586727 -298.728176) (xy 268.550475 -298.689105)
			(xy 268.520451 -298.645068) (xy 268.497325 -298.597047) (xy 268.481615 -298.546117) (xy 268.473672 -298.493413)
			(xy 254 -298.493413) (xy 254 -299.343297) (xy 264.373604 -299.343297) (xy 264.373604 -299.289999)
			(xy 264.381547 -299.237295) (xy 264.397257 -299.186365) (xy 264.420383 -299.138344) (xy 264.450407 -299.094307)
			(xy 264.486659 -299.055236) (xy 264.52833 -299.022005) (xy 264.574488 -298.995356) (xy 264.624102 -298.975884)
			(xy 264.676064 -298.964024) (xy 264.729214 -298.960041) (xy 264.782364 -298.964024) (xy 264.834326 -298.975884)
			(xy 264.88394 -298.995356) (xy 264.930098 -299.022005) (xy 264.971769 -299.055236) (xy 265.008021 -299.094307)
			(xy 265.038045 -299.138344) (xy 265.061171 -299.186365) (xy 265.076881 -299.237295) (xy 265.084824 -299.289999)
			(xy 265.085322 -299.316648) (xy 265.084824 -299.343297) (xy 279.461204 -299.343297) (xy 279.461204 -299.289999)
			(xy 279.469147 -299.237295) (xy 279.484857 -299.186365) (xy 279.507983 -299.138344) (xy 279.538007 -299.094307)
			(xy 279.574259 -299.055236) (xy 279.61593 -299.022005) (xy 279.662088 -298.995356) (xy 279.711702 -298.975884)
			(xy 279.763664 -298.964024) (xy 279.816814 -298.960041) (xy 279.869964 -298.964024) (xy 279.921926 -298.975884)
			(xy 279.97154 -298.995356) (xy 280.017698 -299.022005) (xy 280.059369 -299.055236) (xy 280.095621 -299.094307)
			(xy 280.125645 -299.138344) (xy 280.148771 -299.186365) (xy 280.164481 -299.237295) (xy 280.172424 -299.289999)
			(xy 280.172922 -299.316648) (xy 280.172424 -299.343297) (xy 294.548804 -299.343297) (xy 294.548804 -299.289999)
			(xy 294.556747 -299.237295) (xy 294.572457 -299.186365) (xy 294.595583 -299.138344) (xy 294.625607 -299.094307)
			(xy 294.661859 -299.055236) (xy 294.70353 -299.022005) (xy 294.749688 -298.995356) (xy 294.799302 -298.975884)
			(xy 294.851264 -298.964024) (xy 294.904414 -298.960041) (xy 294.957564 -298.964024) (xy 295.009526 -298.975884)
			(xy 295.05914 -298.995356) (xy 295.105298 -299.022005) (xy 295.146969 -299.055236) (xy 295.183221 -299.094307)
			(xy 295.213245 -299.138344) (xy 295.236371 -299.186365) (xy 295.252081 -299.237295) (xy 295.260024 -299.289999)
			(xy 295.260522 -299.316648) (xy 295.260024 -299.343297) (xy 309.636404 -299.343297) (xy 309.636404 -299.289999)
			(xy 309.644347 -299.237295) (xy 309.660057 -299.186365) (xy 309.683183 -299.138344) (xy 309.713207 -299.094307)
			(xy 309.749459 -299.055236) (xy 309.79113 -299.022005) (xy 309.837288 -298.995356) (xy 309.886902 -298.975884)
			(xy 309.938864 -298.964024) (xy 309.992014 -298.960041) (xy 310.045164 -298.964024) (xy 310.097126 -298.975884)
			(xy 310.14674 -298.995356) (xy 310.192898 -299.022005) (xy 310.234569 -299.055236) (xy 310.270821 -299.094307)
			(xy 310.300845 -299.138344) (xy 310.323971 -299.186365) (xy 310.339681 -299.237295) (xy 310.347624 -299.289999)
			(xy 310.348122 -299.316648) (xy 310.347624 -299.343297) (xy 310.339681 -299.396001) (xy 310.323971 -299.446931)
			(xy 310.300845 -299.494952) (xy 310.270821 -299.538989) (xy 310.234569 -299.57806) (xy 310.192898 -299.611291)
			(xy 310.14674 -299.63794) (xy 310.097126 -299.657412) (xy 310.045164 -299.669272) (xy 309.992014 -299.673256)
			(xy 309.938864 -299.669272) (xy 309.886902 -299.657412) (xy 309.837288 -299.63794) (xy 309.79113 -299.611291)
			(xy 309.749459 -299.57806) (xy 309.713207 -299.538989) (xy 309.683183 -299.494952) (xy 309.660057 -299.446931)
			(xy 309.644347 -299.396001) (xy 309.636404 -299.343297) (xy 295.260024 -299.343297) (xy 295.252081 -299.396001)
			(xy 295.236371 -299.446931) (xy 295.213245 -299.494952) (xy 295.183221 -299.538989) (xy 295.146969 -299.57806)
			(xy 295.105298 -299.611291) (xy 295.05914 -299.63794) (xy 295.009526 -299.657412) (xy 294.957564 -299.669272)
			(xy 294.904414 -299.673256) (xy 294.851264 -299.669272) (xy 294.799302 -299.657412) (xy 294.749688 -299.63794)
			(xy 294.70353 -299.611291) (xy 294.661859 -299.57806) (xy 294.625607 -299.538989) (xy 294.595583 -299.494952)
			(xy 294.572457 -299.446931) (xy 294.556747 -299.396001) (xy 294.548804 -299.343297) (xy 280.172424 -299.343297)
			(xy 280.164481 -299.396001) (xy 280.148771 -299.446931) (xy 280.125645 -299.494952) (xy 280.095621 -299.538989)
			(xy 280.059369 -299.57806) (xy 280.017698 -299.611291) (xy 279.97154 -299.63794) (xy 279.921926 -299.657412)
			(xy 279.869964 -299.669272) (xy 279.816814 -299.673256) (xy 279.763664 -299.669272) (xy 279.711702 -299.657412)
			(xy 279.662088 -299.63794) (xy 279.61593 -299.611291) (xy 279.574259 -299.57806) (xy 279.538007 -299.538989)
			(xy 279.507983 -299.494952) (xy 279.484857 -299.446931) (xy 279.469147 -299.396001) (xy 279.461204 -299.343297)
			(xy 265.084824 -299.343297) (xy 265.076881 -299.396001) (xy 265.061171 -299.446931) (xy 265.038045 -299.494952)
			(xy 265.008021 -299.538989) (xy 264.971769 -299.57806) (xy 264.930098 -299.611291) (xy 264.88394 -299.63794)
			(xy 264.834326 -299.657412) (xy 264.782364 -299.669272) (xy 264.729214 -299.673256) (xy 264.676064 -299.669272)
			(xy 264.624102 -299.657412) (xy 264.574488 -299.63794) (xy 264.52833 -299.611291) (xy 264.486659 -299.57806)
			(xy 264.450407 -299.538989) (xy 264.420383 -299.494952) (xy 264.397257 -299.446931) (xy 264.381547 -299.396001)
			(xy 264.373604 -299.343297) (xy 254 -299.343297) (xy 254 -300.193435) (xy 268.473672 -300.193435)
			(xy 268.473672 -300.140137) (xy 268.481615 -300.087433) (xy 268.497325 -300.036503) (xy 268.520451 -299.988482)
			(xy 268.550475 -299.944445) (xy 268.586727 -299.905374) (xy 268.628398 -299.872143) (xy 268.674556 -299.845494)
			(xy 268.72417 -299.826022) (xy 268.776132 -299.814162) (xy 268.829282 -299.810179) (xy 268.882432 -299.814162)
			(xy 268.934394 -299.826022) (xy 268.984008 -299.845494) (xy 269.030166 -299.872143) (xy 269.071837 -299.905374)
			(xy 269.108089 -299.944445) (xy 269.138113 -299.988482) (xy 269.161239 -300.036503) (xy 269.176949 -300.087433)
			(xy 269.184892 -300.140137) (xy 269.18539 -300.166786) (xy 269.184892 -300.193435) (xy 283.561272 -300.193435)
			(xy 283.561272 -300.140137) (xy 283.569215 -300.087433) (xy 283.584925 -300.036503) (xy 283.608051 -299.988482)
			(xy 283.638075 -299.944445) (xy 283.674327 -299.905374) (xy 283.715998 -299.872143) (xy 283.762156 -299.845494)
			(xy 283.81177 -299.826022) (xy 283.863732 -299.814162) (xy 283.916882 -299.810179) (xy 283.970032 -299.814162)
			(xy 284.021994 -299.826022) (xy 284.071608 -299.845494) (xy 284.117766 -299.872143) (xy 284.159437 -299.905374)
			(xy 284.195689 -299.944445) (xy 284.225713 -299.988482) (xy 284.248839 -300.036503) (xy 284.264549 -300.087433)
			(xy 284.272492 -300.140137) (xy 284.27299 -300.166786) (xy 284.272492 -300.193435) (xy 298.674272 -300.193435)
			(xy 298.674272 -300.140137) (xy 298.682215 -300.087433) (xy 298.697925 -300.036503) (xy 298.721051 -299.988482)
			(xy 298.751075 -299.944445) (xy 298.787327 -299.905374) (xy 298.828998 -299.872143) (xy 298.875156 -299.845494)
			(xy 298.92477 -299.826022) (xy 298.976732 -299.814162) (xy 299.029882 -299.810179) (xy 299.083032 -299.814162)
			(xy 299.134994 -299.826022) (xy 299.184608 -299.845494) (xy 299.230766 -299.872143) (xy 299.272437 -299.905374)
			(xy 299.308689 -299.944445) (xy 299.338713 -299.988482) (xy 299.361839 -300.036503) (xy 299.377549 -300.087433)
			(xy 299.385492 -300.140137) (xy 299.38599 -300.166786) (xy 299.385492 -300.193435) (xy 299.377549 -300.246139)
			(xy 299.361839 -300.297069) (xy 299.338713 -300.34509) (xy 299.308689 -300.389127) (xy 299.272437 -300.428198)
			(xy 299.230766 -300.461429) (xy 299.184608 -300.488078) (xy 299.134994 -300.50755) (xy 299.083032 -300.51941)
			(xy 299.029882 -300.523394) (xy 298.976732 -300.51941) (xy 298.92477 -300.50755) (xy 298.875156 -300.488078)
			(xy 298.828998 -300.461429) (xy 298.787327 -300.428198) (xy 298.751075 -300.389127) (xy 298.721051 -300.34509)
			(xy 298.697925 -300.297069) (xy 298.682215 -300.246139) (xy 298.674272 -300.193435) (xy 284.272492 -300.193435)
			(xy 284.264549 -300.246139) (xy 284.248839 -300.297069) (xy 284.225713 -300.34509) (xy 284.195689 -300.389127)
			(xy 284.159437 -300.428198) (xy 284.117766 -300.461429) (xy 284.071608 -300.488078) (xy 284.021994 -300.50755)
			(xy 283.970032 -300.51941) (xy 283.916882 -300.523394) (xy 283.863732 -300.51941) (xy 283.81177 -300.50755)
			(xy 283.762156 -300.488078) (xy 283.715998 -300.461429) (xy 283.674327 -300.428198) (xy 283.638075 -300.389127)
			(xy 283.608051 -300.34509) (xy 283.584925 -300.297069) (xy 283.569215 -300.246139) (xy 283.561272 -300.193435)
			(xy 269.184892 -300.193435) (xy 269.176949 -300.246139) (xy 269.161239 -300.297069) (xy 269.138113 -300.34509)
			(xy 269.108089 -300.389127) (xy 269.071837 -300.428198) (xy 269.030166 -300.461429) (xy 268.984008 -300.488078)
			(xy 268.934394 -300.50755) (xy 268.882432 -300.51941) (xy 268.829282 -300.523394) (xy 268.776132 -300.51941)
			(xy 268.72417 -300.50755) (xy 268.674556 -300.488078) (xy 268.628398 -300.461429) (xy 268.586727 -300.428198)
			(xy 268.550475 -300.389127) (xy 268.520451 -300.34509) (xy 268.497325 -300.297069) (xy 268.481615 -300.246139)
			(xy 268.473672 -300.193435) (xy 254 -300.193435) (xy 254 -301.043319) (xy 264.373604 -301.043319)
			(xy 264.373604 -300.990021) (xy 264.381547 -300.937317) (xy 264.397257 -300.886387) (xy 264.420383 -300.838366)
			(xy 264.450407 -300.794329) (xy 264.486659 -300.755258) (xy 264.52833 -300.722027) (xy 264.574488 -300.695378)
			(xy 264.624102 -300.675906) (xy 264.676064 -300.664046) (xy 264.729214 -300.660063) (xy 264.782364 -300.664046)
			(xy 264.834326 -300.675906) (xy 264.88394 -300.695378) (xy 264.930098 -300.722027) (xy 264.971769 -300.755258)
			(xy 265.008021 -300.794329) (xy 265.038045 -300.838366) (xy 265.061171 -300.886387) (xy 265.076881 -300.937317)
			(xy 265.084824 -300.990021) (xy 265.085322 -301.01667) (xy 265.084824 -301.043319) (xy 279.461204 -301.043319)
			(xy 279.461204 -300.990021) (xy 279.469147 -300.937317) (xy 279.484857 -300.886387) (xy 279.507983 -300.838366)
			(xy 279.538007 -300.794329) (xy 279.574259 -300.755258) (xy 279.61593 -300.722027) (xy 279.662088 -300.695378)
			(xy 279.711702 -300.675906) (xy 279.763664 -300.664046) (xy 279.816814 -300.660063) (xy 279.869964 -300.664046)
			(xy 279.921926 -300.675906) (xy 279.97154 -300.695378) (xy 280.017698 -300.722027) (xy 280.059369 -300.755258)
			(xy 280.095621 -300.794329) (xy 280.125645 -300.838366) (xy 280.148771 -300.886387) (xy 280.164481 -300.937317)
			(xy 280.172424 -300.990021) (xy 280.172922 -301.01667) (xy 280.172424 -301.043319) (xy 294.548804 -301.043319)
			(xy 294.548804 -300.990021) (xy 294.556747 -300.937317) (xy 294.572457 -300.886387) (xy 294.595583 -300.838366)
			(xy 294.625607 -300.794329) (xy 294.661859 -300.755258) (xy 294.70353 -300.722027) (xy 294.749688 -300.695378)
			(xy 294.799302 -300.675906) (xy 294.851264 -300.664046) (xy 294.904414 -300.660063) (xy 294.957564 -300.664046)
			(xy 295.009526 -300.675906) (xy 295.05914 -300.695378) (xy 295.105298 -300.722027) (xy 295.146969 -300.755258)
			(xy 295.183221 -300.794329) (xy 295.213245 -300.838366) (xy 295.236371 -300.886387) (xy 295.252081 -300.937317)
			(xy 295.260024 -300.990021) (xy 295.260522 -301.01667) (xy 295.260024 -301.043319) (xy 309.636404 -301.043319)
			(xy 309.636404 -300.990021) (xy 309.644347 -300.937317) (xy 309.660057 -300.886387) (xy 309.683183 -300.838366)
			(xy 309.713207 -300.794329) (xy 309.749459 -300.755258) (xy 309.79113 -300.722027) (xy 309.837288 -300.695378)
			(xy 309.886902 -300.675906) (xy 309.938864 -300.664046) (xy 309.992014 -300.660063) (xy 310.045164 -300.664046)
			(xy 310.097126 -300.675906) (xy 310.14674 -300.695378) (xy 310.192898 -300.722027) (xy 310.234569 -300.755258)
			(xy 310.270821 -300.794329) (xy 310.300845 -300.838366) (xy 310.323971 -300.886387) (xy 310.339681 -300.937317)
			(xy 310.347624 -300.990021) (xy 310.348122 -301.01667) (xy 310.347624 -301.043319) (xy 310.339681 -301.096023)
			(xy 310.323971 -301.146953) (xy 310.300845 -301.194974) (xy 310.270821 -301.239011) (xy 310.234569 -301.278082)
			(xy 310.192898 -301.311313) (xy 310.14674 -301.337962) (xy 310.097126 -301.357434) (xy 310.045164 -301.369294)
			(xy 309.992014 -301.373278) (xy 309.938864 -301.369294) (xy 309.886902 -301.357434) (xy 309.837288 -301.337962)
			(xy 309.79113 -301.311313) (xy 309.749459 -301.278082) (xy 309.713207 -301.239011) (xy 309.683183 -301.194974)
			(xy 309.660057 -301.146953) (xy 309.644347 -301.096023) (xy 309.636404 -301.043319) (xy 295.260024 -301.043319)
			(xy 295.252081 -301.096023) (xy 295.236371 -301.146953) (xy 295.213245 -301.194974) (xy 295.183221 -301.239011)
			(xy 295.146969 -301.278082) (xy 295.105298 -301.311313) (xy 295.05914 -301.337962) (xy 295.009526 -301.357434)
			(xy 294.957564 -301.369294) (xy 294.904414 -301.373278) (xy 294.851264 -301.369294) (xy 294.799302 -301.357434)
			(xy 294.749688 -301.337962) (xy 294.70353 -301.311313) (xy 294.661859 -301.278082) (xy 294.625607 -301.239011)
			(xy 294.595583 -301.194974) (xy 294.572457 -301.146953) (xy 294.556747 -301.096023) (xy 294.548804 -301.043319)
			(xy 280.172424 -301.043319) (xy 280.164481 -301.096023) (xy 280.148771 -301.146953) (xy 280.125645 -301.194974)
			(xy 280.095621 -301.239011) (xy 280.059369 -301.278082) (xy 280.017698 -301.311313) (xy 279.97154 -301.337962)
			(xy 279.921926 -301.357434) (xy 279.869964 -301.369294) (xy 279.816814 -301.373278) (xy 279.763664 -301.369294)
			(xy 279.711702 -301.357434) (xy 279.662088 -301.337962) (xy 279.61593 -301.311313) (xy 279.574259 -301.278082)
			(xy 279.538007 -301.239011) (xy 279.507983 -301.194974) (xy 279.484857 -301.146953) (xy 279.469147 -301.096023)
			(xy 279.461204 -301.043319) (xy 265.084824 -301.043319) (xy 265.076881 -301.096023) (xy 265.061171 -301.146953)
			(xy 265.038045 -301.194974) (xy 265.008021 -301.239011) (xy 264.971769 -301.278082) (xy 264.930098 -301.311313)
			(xy 264.88394 -301.337962) (xy 264.834326 -301.357434) (xy 264.782364 -301.369294) (xy 264.729214 -301.373278)
			(xy 264.676064 -301.369294) (xy 264.624102 -301.357434) (xy 264.574488 -301.337962) (xy 264.52833 -301.311313)
			(xy 264.486659 -301.278082) (xy 264.450407 -301.239011) (xy 264.420383 -301.194974) (xy 264.397257 -301.146953)
			(xy 264.381547 -301.096023) (xy 264.373604 -301.043319) (xy 254 -301.043319) (xy 254 -301.893457)
			(xy 268.473672 -301.893457) (xy 268.473672 -301.840159) (xy 268.481615 -301.787455) (xy 268.497325 -301.736525)
			(xy 268.520451 -301.688504) (xy 268.550475 -301.644467) (xy 268.586727 -301.605396) (xy 268.628398 -301.572165)
			(xy 268.674556 -301.545516) (xy 268.72417 -301.526044) (xy 268.776132 -301.514184) (xy 268.829282 -301.510201)
			(xy 268.882432 -301.514184) (xy 268.934394 -301.526044) (xy 268.984008 -301.545516) (xy 269.030166 -301.572165)
			(xy 269.071837 -301.605396) (xy 269.108089 -301.644467) (xy 269.138113 -301.688504) (xy 269.161239 -301.736525)
			(xy 269.176949 -301.787455) (xy 269.184892 -301.840159) (xy 269.18539 -301.866808) (xy 269.184892 -301.893457)
			(xy 283.561272 -301.893457) (xy 283.561272 -301.840159) (xy 283.569215 -301.787455) (xy 283.584925 -301.736525)
			(xy 283.608051 -301.688504) (xy 283.638075 -301.644467) (xy 283.674327 -301.605396) (xy 283.715998 -301.572165)
			(xy 283.762156 -301.545516) (xy 283.81177 -301.526044) (xy 283.863732 -301.514184) (xy 283.916882 -301.510201)
			(xy 283.970032 -301.514184) (xy 284.021994 -301.526044) (xy 284.071608 -301.545516) (xy 284.117766 -301.572165)
			(xy 284.159437 -301.605396) (xy 284.195689 -301.644467) (xy 284.225713 -301.688504) (xy 284.248839 -301.736525)
			(xy 284.264549 -301.787455) (xy 284.272492 -301.840159) (xy 284.27299 -301.866808) (xy 284.272492 -301.893457)
			(xy 298.674272 -301.893457) (xy 298.674272 -301.840159) (xy 298.682215 -301.787455) (xy 298.697925 -301.736525)
			(xy 298.721051 -301.688504) (xy 298.751075 -301.644467) (xy 298.787327 -301.605396) (xy 298.828998 -301.572165)
			(xy 298.875156 -301.545516) (xy 298.92477 -301.526044) (xy 298.976732 -301.514184) (xy 299.029882 -301.510201)
			(xy 299.083032 -301.514184) (xy 299.134994 -301.526044) (xy 299.184608 -301.545516) (xy 299.230766 -301.572165)
			(xy 299.272437 -301.605396) (xy 299.308689 -301.644467) (xy 299.338713 -301.688504) (xy 299.361839 -301.736525)
			(xy 299.377549 -301.787455) (xy 299.385492 -301.840159) (xy 299.38599 -301.866808) (xy 299.385492 -301.893457)
			(xy 299.377549 -301.946161) (xy 299.361839 -301.997091) (xy 299.338713 -302.045112) (xy 299.308689 -302.089149)
			(xy 299.272437 -302.12822) (xy 299.230766 -302.161451) (xy 299.184608 -302.1881) (xy 299.134994 -302.207572)
			(xy 299.083032 -302.219432) (xy 299.029882 -302.223416) (xy 298.976732 -302.219432) (xy 298.92477 -302.207572)
			(xy 298.875156 -302.1881) (xy 298.828998 -302.161451) (xy 298.787327 -302.12822) (xy 298.751075 -302.089149)
			(xy 298.721051 -302.045112) (xy 298.697925 -301.997091) (xy 298.682215 -301.946161) (xy 298.674272 -301.893457)
			(xy 284.272492 -301.893457) (xy 284.264549 -301.946161) (xy 284.248839 -301.997091) (xy 284.225713 -302.045112)
			(xy 284.195689 -302.089149) (xy 284.159437 -302.12822) (xy 284.117766 -302.161451) (xy 284.071608 -302.1881)
			(xy 284.021994 -302.207572) (xy 283.970032 -302.219432) (xy 283.916882 -302.223416) (xy 283.863732 -302.219432)
			(xy 283.81177 -302.207572) (xy 283.762156 -302.1881) (xy 283.715998 -302.161451) (xy 283.674327 -302.12822)
			(xy 283.638075 -302.089149) (xy 283.608051 -302.045112) (xy 283.584925 -301.997091) (xy 283.569215 -301.946161)
			(xy 283.561272 -301.893457) (xy 269.184892 -301.893457) (xy 269.176949 -301.946161) (xy 269.161239 -301.997091)
			(xy 269.138113 -302.045112) (xy 269.108089 -302.089149) (xy 269.071837 -302.12822) (xy 269.030166 -302.161451)
			(xy 268.984008 -302.1881) (xy 268.934394 -302.207572) (xy 268.882432 -302.219432) (xy 268.829282 -302.223416)
			(xy 268.776132 -302.219432) (xy 268.72417 -302.207572) (xy 268.674556 -302.1881) (xy 268.628398 -302.161451)
			(xy 268.586727 -302.12822) (xy 268.550475 -302.089149) (xy 268.520451 -302.045112) (xy 268.497325 -301.997091)
			(xy 268.481615 -301.946161) (xy 268.473672 -301.893457) (xy 254 -301.893457) (xy 254 -302.743341)
			(xy 264.373604 -302.743341) (xy 264.373604 -302.690043) (xy 264.381547 -302.637339) (xy 264.397257 -302.586409)
			(xy 264.420383 -302.538388) (xy 264.450407 -302.494351) (xy 264.486659 -302.45528) (xy 264.52833 -302.422049)
			(xy 264.574488 -302.3954) (xy 264.624102 -302.375928) (xy 264.676064 -302.364068) (xy 264.729214 -302.360085)
			(xy 264.782364 -302.364068) (xy 264.834326 -302.375928) (xy 264.88394 -302.3954) (xy 264.930098 -302.422049)
			(xy 264.971769 -302.45528) (xy 265.008021 -302.494351) (xy 265.038045 -302.538388) (xy 265.061171 -302.586409)
			(xy 265.076881 -302.637339) (xy 265.084824 -302.690043) (xy 265.085322 -302.716692) (xy 265.084824 -302.743341)
			(xy 268.473672 -302.743341) (xy 268.473672 -302.690043) (xy 268.481615 -302.637339) (xy 268.497325 -302.586409)
			(xy 268.520451 -302.538388) (xy 268.550475 -302.494351) (xy 268.586727 -302.45528) (xy 268.628398 -302.422049)
			(xy 268.674556 -302.3954) (xy 268.72417 -302.375928) (xy 268.776132 -302.364068) (xy 268.829282 -302.360085)
			(xy 268.882432 -302.364068) (xy 268.934394 -302.375928) (xy 268.984008 -302.3954) (xy 269.030166 -302.422049)
			(xy 269.071837 -302.45528) (xy 269.108089 -302.494351) (xy 269.138113 -302.538388) (xy 269.161239 -302.586409)
			(xy 269.176949 -302.637339) (xy 269.184892 -302.690043) (xy 269.18539 -302.716692) (xy 269.184892 -302.743341)
			(xy 279.461204 -302.743341) (xy 279.461204 -302.690043) (xy 279.469147 -302.637339) (xy 279.484857 -302.586409)
			(xy 279.507983 -302.538388) (xy 279.538007 -302.494351) (xy 279.574259 -302.45528) (xy 279.61593 -302.422049)
			(xy 279.662088 -302.3954) (xy 279.711702 -302.375928) (xy 279.763664 -302.364068) (xy 279.816814 -302.360085)
			(xy 279.869964 -302.364068) (xy 279.921926 -302.375928) (xy 279.97154 -302.3954) (xy 280.017698 -302.422049)
			(xy 280.059369 -302.45528) (xy 280.095621 -302.494351) (xy 280.125645 -302.538388) (xy 280.148771 -302.586409)
			(xy 280.164481 -302.637339) (xy 280.172424 -302.690043) (xy 280.172922 -302.716692) (xy 280.172424 -302.743341)
			(xy 283.561272 -302.743341) (xy 283.561272 -302.690043) (xy 283.569215 -302.637339) (xy 283.584925 -302.586409)
			(xy 283.608051 -302.538388) (xy 283.638075 -302.494351) (xy 283.674327 -302.45528) (xy 283.715998 -302.422049)
			(xy 283.762156 -302.3954) (xy 283.81177 -302.375928) (xy 283.863732 -302.364068) (xy 283.916882 -302.360085)
			(xy 283.970032 -302.364068) (xy 284.021994 -302.375928) (xy 284.071608 -302.3954) (xy 284.117766 -302.422049)
			(xy 284.159437 -302.45528) (xy 284.195689 -302.494351) (xy 284.225713 -302.538388) (xy 284.248839 -302.586409)
			(xy 284.264549 -302.637339) (xy 284.272492 -302.690043) (xy 284.27299 -302.716692) (xy 284.272492 -302.743341)
			(xy 294.548804 -302.743341) (xy 294.548804 -302.690043) (xy 294.556747 -302.637339) (xy 294.572457 -302.586409)
			(xy 294.595583 -302.538388) (xy 294.625607 -302.494351) (xy 294.661859 -302.45528) (xy 294.70353 -302.422049)
			(xy 294.749688 -302.3954) (xy 294.799302 -302.375928) (xy 294.851264 -302.364068) (xy 294.904414 -302.360085)
			(xy 294.957564 -302.364068) (xy 295.009526 -302.375928) (xy 295.05914 -302.3954) (xy 295.105298 -302.422049)
			(xy 295.146969 -302.45528) (xy 295.183221 -302.494351) (xy 295.213245 -302.538388) (xy 295.236371 -302.586409)
			(xy 295.252081 -302.637339) (xy 295.260024 -302.690043) (xy 295.260522 -302.716692) (xy 295.260024 -302.743341)
			(xy 295.259986 -302.743595) (xy 298.674272 -302.743595) (xy 298.674272 -302.690297) (xy 298.682215 -302.637593)
			(xy 298.697925 -302.586663) (xy 298.721051 -302.538642) (xy 298.751075 -302.494605) (xy 298.787327 -302.455534)
			(xy 298.828998 -302.422303) (xy 298.875156 -302.395654) (xy 298.92477 -302.376182) (xy 298.976732 -302.364322)
			(xy 299.029882 -302.360339) (xy 299.083032 -302.364322) (xy 299.134994 -302.376182) (xy 299.184608 -302.395654)
			(xy 299.230766 -302.422303) (xy 299.272437 -302.455534) (xy 299.308689 -302.494605) (xy 299.338713 -302.538642)
			(xy 299.361839 -302.586663) (xy 299.377549 -302.637593) (xy 299.385492 -302.690297) (xy 299.38599 -302.716946)
			(xy 299.385497 -302.743341) (xy 309.636404 -302.743341) (xy 309.636404 -302.690043) (xy 309.644347 -302.637339)
			(xy 309.660057 -302.586409) (xy 309.683183 -302.538388) (xy 309.713207 -302.494351) (xy 309.749459 -302.45528)
			(xy 309.79113 -302.422049) (xy 309.837288 -302.3954) (xy 309.886902 -302.375928) (xy 309.938864 -302.364068)
			(xy 309.992014 -302.360085) (xy 310.045164 -302.364068) (xy 310.097126 -302.375928) (xy 310.14674 -302.3954)
			(xy 310.192898 -302.422049) (xy 310.234569 -302.45528) (xy 310.270821 -302.494351) (xy 310.300845 -302.538388)
			(xy 310.323971 -302.586409) (xy 310.339681 -302.637339) (xy 310.347624 -302.690043) (xy 310.348122 -302.716692)
			(xy 310.347624 -302.743341) (xy 310.339681 -302.796045) (xy 310.323971 -302.846975) (xy 310.300845 -302.894996)
			(xy 310.270821 -302.939033) (xy 310.234569 -302.978104) (xy 310.192898 -303.011335) (xy 310.14674 -303.037984)
			(xy 310.097126 -303.057456) (xy 310.045164 -303.069316) (xy 309.992014 -303.0733) (xy 309.938864 -303.069316)
			(xy 309.886902 -303.057456) (xy 309.837288 -303.037984) (xy 309.79113 -303.011335) (xy 309.749459 -302.978104)
			(xy 309.713207 -302.939033) (xy 309.683183 -302.894996) (xy 309.660057 -302.846975) (xy 309.644347 -302.796045)
			(xy 309.636404 -302.743341) (xy 299.385497 -302.743341) (xy 299.385492 -302.743595) (xy 299.377549 -302.796299)
			(xy 299.361839 -302.847229) (xy 299.338713 -302.89525) (xy 299.308689 -302.939287) (xy 299.272437 -302.978358)
			(xy 299.230766 -303.011589) (xy 299.184608 -303.038238) (xy 299.134994 -303.05771) (xy 299.083032 -303.06957)
			(xy 299.029882 -303.073554) (xy 298.976732 -303.06957) (xy 298.92477 -303.05771) (xy 298.875156 -303.038238)
			(xy 298.828998 -303.011589) (xy 298.787327 -302.978358) (xy 298.751075 -302.939287) (xy 298.721051 -302.89525)
			(xy 298.697925 -302.847229) (xy 298.682215 -302.796299) (xy 298.674272 -302.743595) (xy 295.259986 -302.743595)
			(xy 295.252081 -302.796045) (xy 295.236371 -302.846975) (xy 295.213245 -302.894996) (xy 295.183221 -302.939033)
			(xy 295.146969 -302.978104) (xy 295.105298 -303.011335) (xy 295.05914 -303.037984) (xy 295.009526 -303.057456)
			(xy 294.957564 -303.069316) (xy 294.904414 -303.0733) (xy 294.851264 -303.069316) (xy 294.799302 -303.057456)
			(xy 294.749688 -303.037984) (xy 294.70353 -303.011335) (xy 294.661859 -302.978104) (xy 294.625607 -302.939033)
			(xy 294.595583 -302.894996) (xy 294.572457 -302.846975) (xy 294.556747 -302.796045) (xy 294.548804 -302.743341)
			(xy 284.272492 -302.743341) (xy 284.264549 -302.796045) (xy 284.248839 -302.846975) (xy 284.225713 -302.894996)
			(xy 284.195689 -302.939033) (xy 284.159437 -302.978104) (xy 284.117766 -303.011335) (xy 284.071608 -303.037984)
			(xy 284.021994 -303.057456) (xy 283.970032 -303.069316) (xy 283.916882 -303.0733) (xy 283.863732 -303.069316)
			(xy 283.81177 -303.057456) (xy 283.762156 -303.037984) (xy 283.715998 -303.011335) (xy 283.674327 -302.978104)
			(xy 283.638075 -302.939033) (xy 283.608051 -302.894996) (xy 283.584925 -302.846975) (xy 283.569215 -302.796045)
			(xy 283.561272 -302.743341) (xy 280.172424 -302.743341) (xy 280.164481 -302.796045) (xy 280.148771 -302.846975)
			(xy 280.125645 -302.894996) (xy 280.095621 -302.939033) (xy 280.059369 -302.978104) (xy 280.017698 -303.011335)
			(xy 279.97154 -303.037984) (xy 279.921926 -303.057456) (xy 279.869964 -303.069316) (xy 279.816814 -303.0733)
			(xy 279.763664 -303.069316) (xy 279.711702 -303.057456) (xy 279.662088 -303.037984) (xy 279.61593 -303.011335)
			(xy 279.574259 -302.978104) (xy 279.538007 -302.939033) (xy 279.507983 -302.894996) (xy 279.484857 -302.846975)
			(xy 279.469147 -302.796045) (xy 279.461204 -302.743341) (xy 269.184892 -302.743341) (xy 269.176949 -302.796045)
			(xy 269.161239 -302.846975) (xy 269.138113 -302.894996) (xy 269.108089 -302.939033) (xy 269.071837 -302.978104)
			(xy 269.030166 -303.011335) (xy 268.984008 -303.037984) (xy 268.934394 -303.057456) (xy 268.882432 -303.069316)
			(xy 268.829282 -303.0733) (xy 268.776132 -303.069316) (xy 268.72417 -303.057456) (xy 268.674556 -303.037984)
			(xy 268.628398 -303.011335) (xy 268.586727 -302.978104) (xy 268.550475 -302.939033) (xy 268.520451 -302.894996)
			(xy 268.497325 -302.846975) (xy 268.481615 -302.796045) (xy 268.473672 -302.743341) (xy 265.084824 -302.743341)
			(xy 265.076881 -302.796045) (xy 265.061171 -302.846975) (xy 265.038045 -302.894996) (xy 265.008021 -302.939033)
			(xy 264.971769 -302.978104) (xy 264.930098 -303.011335) (xy 264.88394 -303.037984) (xy 264.834326 -303.057456)
			(xy 264.782364 -303.069316) (xy 264.729214 -303.0733) (xy 264.676064 -303.069316) (xy 264.624102 -303.057456)
			(xy 264.574488 -303.037984) (xy 264.52833 -303.011335) (xy 264.486659 -302.978104) (xy 264.450407 -302.939033)
			(xy 264.420383 -302.894996) (xy 264.397257 -302.846975) (xy 264.381547 -302.796045) (xy 264.373604 -302.743341)
			(xy 254 -302.743341) (xy 254 -303.593225) (xy 264.373604 -303.593225) (xy 264.373604 -303.539927)
			(xy 264.381547 -303.487223) (xy 264.397257 -303.436293) (xy 264.420383 -303.388272) (xy 264.450407 -303.344235)
			(xy 264.486659 -303.305164) (xy 264.52833 -303.271933) (xy 264.574488 -303.245284) (xy 264.624102 -303.225812)
			(xy 264.676064 -303.213952) (xy 264.729214 -303.209969) (xy 264.782364 -303.213952) (xy 264.834326 -303.225812)
			(xy 264.88394 -303.245284) (xy 264.930098 -303.271933) (xy 264.971769 -303.305164) (xy 265.008021 -303.344235)
			(xy 265.038045 -303.388272) (xy 265.061171 -303.436293) (xy 265.076881 -303.487223) (xy 265.084824 -303.539927)
			(xy 265.085322 -303.566576) (xy 265.084824 -303.593225) (xy 279.461204 -303.593225) (xy 279.461204 -303.539927)
			(xy 279.469147 -303.487223) (xy 279.484857 -303.436293) (xy 279.507983 -303.388272) (xy 279.538007 -303.344235)
			(xy 279.574259 -303.305164) (xy 279.61593 -303.271933) (xy 279.662088 -303.245284) (xy 279.711702 -303.225812)
			(xy 279.763664 -303.213952) (xy 279.816814 -303.209969) (xy 279.869964 -303.213952) (xy 279.921926 -303.225812)
			(xy 279.97154 -303.245284) (xy 280.017698 -303.271933) (xy 280.059369 -303.305164) (xy 280.095621 -303.344235)
			(xy 280.125645 -303.388272) (xy 280.148771 -303.436293) (xy 280.164481 -303.487223) (xy 280.172424 -303.539927)
			(xy 280.172922 -303.566576) (xy 280.172424 -303.593225) (xy 294.548804 -303.593225) (xy 294.548804 -303.539927)
			(xy 294.556747 -303.487223) (xy 294.572457 -303.436293) (xy 294.595583 -303.388272) (xy 294.625607 -303.344235)
			(xy 294.661859 -303.305164) (xy 294.70353 -303.271933) (xy 294.749688 -303.245284) (xy 294.799302 -303.225812)
			(xy 294.851264 -303.213952) (xy 294.904414 -303.209969) (xy 294.957564 -303.213952) (xy 295.009526 -303.225812)
			(xy 295.05914 -303.245284) (xy 295.105298 -303.271933) (xy 295.146969 -303.305164) (xy 295.183221 -303.344235)
			(xy 295.213245 -303.388272) (xy 295.236371 -303.436293) (xy 295.252081 -303.487223) (xy 295.260024 -303.539927)
			(xy 295.260522 -303.566576) (xy 295.260024 -303.593225) (xy 309.636404 -303.593225) (xy 309.636404 -303.539927)
			(xy 309.644347 -303.487223) (xy 309.660057 -303.436293) (xy 309.683183 -303.388272) (xy 309.713207 -303.344235)
			(xy 309.749459 -303.305164) (xy 309.79113 -303.271933) (xy 309.837288 -303.245284) (xy 309.886902 -303.225812)
			(xy 309.938864 -303.213952) (xy 309.992014 -303.209969) (xy 310.045164 -303.213952) (xy 310.097126 -303.225812)
			(xy 310.14674 -303.245284) (xy 310.192898 -303.271933) (xy 310.234569 -303.305164) (xy 310.270821 -303.344235)
			(xy 310.300845 -303.388272) (xy 310.323971 -303.436293) (xy 310.339681 -303.487223) (xy 310.347624 -303.539927)
			(xy 310.348122 -303.566576) (xy 310.347624 -303.593225) (xy 310.339681 -303.645929) (xy 310.323971 -303.696859)
			(xy 310.300845 -303.74488) (xy 310.270821 -303.788917) (xy 310.234569 -303.827988) (xy 310.192898 -303.861219)
			(xy 310.14674 -303.887868) (xy 310.097126 -303.90734) (xy 310.045164 -303.9192) (xy 309.992014 -303.923184)
			(xy 309.938864 -303.9192) (xy 309.886902 -303.90734) (xy 309.837288 -303.887868) (xy 309.79113 -303.861219)
			(xy 309.749459 -303.827988) (xy 309.713207 -303.788917) (xy 309.683183 -303.74488) (xy 309.660057 -303.696859)
			(xy 309.644347 -303.645929) (xy 309.636404 -303.593225) (xy 295.260024 -303.593225) (xy 295.252081 -303.645929)
			(xy 295.236371 -303.696859) (xy 295.213245 -303.74488) (xy 295.183221 -303.788917) (xy 295.146969 -303.827988)
			(xy 295.105298 -303.861219) (xy 295.05914 -303.887868) (xy 295.009526 -303.90734) (xy 294.957564 -303.9192)
			(xy 294.904414 -303.923184) (xy 294.851264 -303.9192) (xy 294.799302 -303.90734) (xy 294.749688 -303.887868)
			(xy 294.70353 -303.861219) (xy 294.661859 -303.827988) (xy 294.625607 -303.788917) (xy 294.595583 -303.74488)
			(xy 294.572457 -303.696859) (xy 294.556747 -303.645929) (xy 294.548804 -303.593225) (xy 280.172424 -303.593225)
			(xy 280.164481 -303.645929) (xy 280.148771 -303.696859) (xy 280.125645 -303.74488) (xy 280.095621 -303.788917)
			(xy 280.059369 -303.827988) (xy 280.017698 -303.861219) (xy 279.97154 -303.887868) (xy 279.921926 -303.90734)
			(xy 279.869964 -303.9192) (xy 279.816814 -303.923184) (xy 279.763664 -303.9192) (xy 279.711702 -303.90734)
			(xy 279.662088 -303.887868) (xy 279.61593 -303.861219) (xy 279.574259 -303.827988) (xy 279.538007 -303.788917)
			(xy 279.507983 -303.74488) (xy 279.484857 -303.696859) (xy 279.469147 -303.645929) (xy 279.461204 -303.593225)
			(xy 265.084824 -303.593225) (xy 265.076881 -303.645929) (xy 265.061171 -303.696859) (xy 265.038045 -303.74488)
			(xy 265.008021 -303.788917) (xy 264.971769 -303.827988) (xy 264.930098 -303.861219) (xy 264.88394 -303.887868)
			(xy 264.834326 -303.90734) (xy 264.782364 -303.9192) (xy 264.729214 -303.923184) (xy 264.676064 -303.9192)
			(xy 264.624102 -303.90734) (xy 264.574488 -303.887868) (xy 264.52833 -303.861219) (xy 264.486659 -303.827988)
			(xy 264.450407 -303.788917) (xy 264.420383 -303.74488) (xy 264.397257 -303.696859) (xy 264.381547 -303.645929)
			(xy 264.373604 -303.593225) (xy 254 -303.593225) (xy 254 -304.443363) (xy 268.473672 -304.443363)
			(xy 268.473672 -304.390065) (xy 268.481615 -304.337361) (xy 268.497325 -304.286431) (xy 268.520451 -304.23841)
			(xy 268.550475 -304.194373) (xy 268.586727 -304.155302) (xy 268.628398 -304.122071) (xy 268.674556 -304.095422)
			(xy 268.72417 -304.07595) (xy 268.776132 -304.06409) (xy 268.829282 -304.060107) (xy 268.882432 -304.06409)
			(xy 268.934394 -304.07595) (xy 268.984008 -304.095422) (xy 269.030166 -304.122071) (xy 269.071837 -304.155302)
			(xy 269.108089 -304.194373) (xy 269.138113 -304.23841) (xy 269.161239 -304.286431) (xy 269.176949 -304.337361)
			(xy 269.184892 -304.390065) (xy 269.18539 -304.416714) (xy 269.184892 -304.443363) (xy 283.561272 -304.443363)
			(xy 283.561272 -304.390065) (xy 283.569215 -304.337361) (xy 283.584925 -304.286431) (xy 283.608051 -304.23841)
			(xy 283.638075 -304.194373) (xy 283.674327 -304.155302) (xy 283.715998 -304.122071) (xy 283.762156 -304.095422)
			(xy 283.81177 -304.07595) (xy 283.863732 -304.06409) (xy 283.916882 -304.060107) (xy 283.970032 -304.06409)
			(xy 284.021994 -304.07595) (xy 284.071608 -304.095422) (xy 284.117766 -304.122071) (xy 284.159437 -304.155302)
			(xy 284.195689 -304.194373) (xy 284.225713 -304.23841) (xy 284.248839 -304.286431) (xy 284.264549 -304.337361)
			(xy 284.272492 -304.390065) (xy 284.27299 -304.416714) (xy 284.272492 -304.443363) (xy 298.674272 -304.443363)
			(xy 298.674272 -304.390065) (xy 298.682215 -304.337361) (xy 298.697925 -304.286431) (xy 298.721051 -304.23841)
			(xy 298.751075 -304.194373) (xy 298.787327 -304.155302) (xy 298.828998 -304.122071) (xy 298.875156 -304.095422)
			(xy 298.92477 -304.07595) (xy 298.976732 -304.06409) (xy 299.029882 -304.060107) (xy 299.083032 -304.06409)
			(xy 299.134994 -304.07595) (xy 299.184608 -304.095422) (xy 299.230766 -304.122071) (xy 299.272437 -304.155302)
			(xy 299.308689 -304.194373) (xy 299.338713 -304.23841) (xy 299.361839 -304.286431) (xy 299.377549 -304.337361)
			(xy 299.385492 -304.390065) (xy 299.38599 -304.416714) (xy 299.385492 -304.443363) (xy 299.377549 -304.496067)
			(xy 299.361839 -304.546997) (xy 299.338713 -304.595018) (xy 299.308689 -304.639055) (xy 299.272437 -304.678126)
			(xy 299.230766 -304.711357) (xy 299.184608 -304.738006) (xy 299.134994 -304.757478) (xy 299.083032 -304.769338)
			(xy 299.029882 -304.773322) (xy 298.976732 -304.769338) (xy 298.92477 -304.757478) (xy 298.875156 -304.738006)
			(xy 298.828998 -304.711357) (xy 298.787327 -304.678126) (xy 298.751075 -304.639055) (xy 298.721051 -304.595018)
			(xy 298.697925 -304.546997) (xy 298.682215 -304.496067) (xy 298.674272 -304.443363) (xy 284.272492 -304.443363)
			(xy 284.264549 -304.496067) (xy 284.248839 -304.546997) (xy 284.225713 -304.595018) (xy 284.195689 -304.639055)
			(xy 284.159437 -304.678126) (xy 284.117766 -304.711357) (xy 284.071608 -304.738006) (xy 284.021994 -304.757478)
			(xy 283.970032 -304.769338) (xy 283.916882 -304.773322) (xy 283.863732 -304.769338) (xy 283.81177 -304.757478)
			(xy 283.762156 -304.738006) (xy 283.715998 -304.711357) (xy 283.674327 -304.678126) (xy 283.638075 -304.639055)
			(xy 283.608051 -304.595018) (xy 283.584925 -304.546997) (xy 283.569215 -304.496067) (xy 283.561272 -304.443363)
			(xy 269.184892 -304.443363) (xy 269.176949 -304.496067) (xy 269.161239 -304.546997) (xy 269.138113 -304.595018)
			(xy 269.108089 -304.639055) (xy 269.071837 -304.678126) (xy 269.030166 -304.711357) (xy 268.984008 -304.738006)
			(xy 268.934394 -304.757478) (xy 268.882432 -304.769338) (xy 268.829282 -304.773322) (xy 268.776132 -304.769338)
			(xy 268.72417 -304.757478) (xy 268.674556 -304.738006) (xy 268.628398 -304.711357) (xy 268.586727 -304.678126)
			(xy 268.550475 -304.639055) (xy 268.520451 -304.595018) (xy 268.497325 -304.546997) (xy 268.481615 -304.496067)
			(xy 268.473672 -304.443363) (xy 254 -304.443363) (xy 254 -305.293247) (xy 264.373604 -305.293247)
			(xy 264.373604 -305.239949) (xy 264.381547 -305.187245) (xy 264.397257 -305.136315) (xy 264.420383 -305.088294)
			(xy 264.450407 -305.044257) (xy 264.486659 -305.005186) (xy 264.52833 -304.971955) (xy 264.574488 -304.945306)
			(xy 264.624102 -304.925834) (xy 264.676064 -304.913974) (xy 264.729214 -304.909991) (xy 264.782364 -304.913974)
			(xy 264.834326 -304.925834) (xy 264.88394 -304.945306) (xy 264.930098 -304.971955) (xy 264.971769 -305.005186)
			(xy 265.008021 -305.044257) (xy 265.038045 -305.088294) (xy 265.061171 -305.136315) (xy 265.076881 -305.187245)
			(xy 265.084824 -305.239949) (xy 265.085322 -305.266598) (xy 265.084824 -305.293247) (xy 279.461204 -305.293247)
			(xy 279.461204 -305.239949) (xy 279.469147 -305.187245) (xy 279.484857 -305.136315) (xy 279.507983 -305.088294)
			(xy 279.538007 -305.044257) (xy 279.574259 -305.005186) (xy 279.61593 -304.971955) (xy 279.662088 -304.945306)
			(xy 279.711702 -304.925834) (xy 279.763664 -304.913974) (xy 279.816814 -304.909991) (xy 279.869964 -304.913974)
			(xy 279.921926 -304.925834) (xy 279.97154 -304.945306) (xy 280.017698 -304.971955) (xy 280.059369 -305.005186)
			(xy 280.095621 -305.044257) (xy 280.125645 -305.088294) (xy 280.148771 -305.136315) (xy 280.164481 -305.187245)
			(xy 280.172424 -305.239949) (xy 280.172922 -305.266598) (xy 280.172424 -305.293247) (xy 294.548804 -305.293247)
			(xy 294.548804 -305.239949) (xy 294.556747 -305.187245) (xy 294.572457 -305.136315) (xy 294.595583 -305.088294)
			(xy 294.625607 -305.044257) (xy 294.661859 -305.005186) (xy 294.70353 -304.971955) (xy 294.749688 -304.945306)
			(xy 294.799302 -304.925834) (xy 294.851264 -304.913974) (xy 294.904414 -304.909991) (xy 294.957564 -304.913974)
			(xy 295.009526 -304.925834) (xy 295.05914 -304.945306) (xy 295.105298 -304.971955) (xy 295.146969 -305.005186)
			(xy 295.183221 -305.044257) (xy 295.213245 -305.088294) (xy 295.236371 -305.136315) (xy 295.252081 -305.187245)
			(xy 295.260024 -305.239949) (xy 295.260522 -305.266598) (xy 295.260024 -305.293247) (xy 309.636404 -305.293247)
			(xy 309.636404 -305.239949) (xy 309.644347 -305.187245) (xy 309.660057 -305.136315) (xy 309.683183 -305.088294)
			(xy 309.713207 -305.044257) (xy 309.749459 -305.005186) (xy 309.79113 -304.971955) (xy 309.837288 -304.945306)
			(xy 309.886902 -304.925834) (xy 309.938864 -304.913974) (xy 309.992014 -304.909991) (xy 310.045164 -304.913974)
			(xy 310.097126 -304.925834) (xy 310.14674 -304.945306) (xy 310.192898 -304.971955) (xy 310.234569 -305.005186)
			(xy 310.270821 -305.044257) (xy 310.300845 -305.088294) (xy 310.323971 -305.136315) (xy 310.339681 -305.187245)
			(xy 310.347624 -305.239949) (xy 310.348122 -305.266598) (xy 310.347624 -305.293247) (xy 310.339681 -305.345951)
			(xy 310.323971 -305.396881) (xy 310.300845 -305.444902) (xy 310.270821 -305.488939) (xy 310.234569 -305.52801)
			(xy 310.192898 -305.561241) (xy 310.14674 -305.58789) (xy 310.097126 -305.607362) (xy 310.045164 -305.619222)
			(xy 309.992014 -305.623206) (xy 309.938864 -305.619222) (xy 309.886902 -305.607362) (xy 309.837288 -305.58789)
			(xy 309.79113 -305.561241) (xy 309.749459 -305.52801) (xy 309.713207 -305.488939) (xy 309.683183 -305.444902)
			(xy 309.660057 -305.396881) (xy 309.644347 -305.345951) (xy 309.636404 -305.293247) (xy 295.260024 -305.293247)
			(xy 295.252081 -305.345951) (xy 295.236371 -305.396881) (xy 295.213245 -305.444902) (xy 295.183221 -305.488939)
			(xy 295.146969 -305.52801) (xy 295.105298 -305.561241) (xy 295.05914 -305.58789) (xy 295.009526 -305.607362)
			(xy 294.957564 -305.619222) (xy 294.904414 -305.623206) (xy 294.851264 -305.619222) (xy 294.799302 -305.607362)
			(xy 294.749688 -305.58789) (xy 294.70353 -305.561241) (xy 294.661859 -305.52801) (xy 294.625607 -305.488939)
			(xy 294.595583 -305.444902) (xy 294.572457 -305.396881) (xy 294.556747 -305.345951) (xy 294.548804 -305.293247)
			(xy 280.172424 -305.293247) (xy 280.164481 -305.345951) (xy 280.148771 -305.396881) (xy 280.125645 -305.444902)
			(xy 280.095621 -305.488939) (xy 280.059369 -305.52801) (xy 280.017698 -305.561241) (xy 279.97154 -305.58789)
			(xy 279.921926 -305.607362) (xy 279.869964 -305.619222) (xy 279.816814 -305.623206) (xy 279.763664 -305.619222)
			(xy 279.711702 -305.607362) (xy 279.662088 -305.58789) (xy 279.61593 -305.561241) (xy 279.574259 -305.52801)
			(xy 279.538007 -305.488939) (xy 279.507983 -305.444902) (xy 279.484857 -305.396881) (xy 279.469147 -305.345951)
			(xy 279.461204 -305.293247) (xy 265.084824 -305.293247) (xy 265.076881 -305.345951) (xy 265.061171 -305.396881)
			(xy 265.038045 -305.444902) (xy 265.008021 -305.488939) (xy 264.971769 -305.52801) (xy 264.930098 -305.561241)
			(xy 264.88394 -305.58789) (xy 264.834326 -305.607362) (xy 264.782364 -305.619222) (xy 264.729214 -305.623206)
			(xy 264.676064 -305.619222) (xy 264.624102 -305.607362) (xy 264.574488 -305.58789) (xy 264.52833 -305.561241)
			(xy 264.486659 -305.52801) (xy 264.450407 -305.488939) (xy 264.420383 -305.444902) (xy 264.397257 -305.396881)
			(xy 264.381547 -305.345951) (xy 264.373604 -305.293247) (xy 254 -305.293247) (xy 254 -306.143385)
			(xy 268.473672 -306.143385) (xy 268.473672 -306.090087) (xy 268.481615 -306.037383) (xy 268.497325 -305.986453)
			(xy 268.520451 -305.938432) (xy 268.550475 -305.894395) (xy 268.586727 -305.855324) (xy 268.628398 -305.822093)
			(xy 268.674556 -305.795444) (xy 268.72417 -305.775972) (xy 268.776132 -305.764112) (xy 268.829282 -305.760129)
			(xy 268.882432 -305.764112) (xy 268.934394 -305.775972) (xy 268.984008 -305.795444) (xy 269.030166 -305.822093)
			(xy 269.071837 -305.855324) (xy 269.108089 -305.894395) (xy 269.138113 -305.938432) (xy 269.161239 -305.986453)
			(xy 269.176949 -306.037383) (xy 269.184892 -306.090087) (xy 269.18539 -306.116736) (xy 269.184892 -306.143385)
			(xy 283.561272 -306.143385) (xy 283.561272 -306.090087) (xy 283.569215 -306.037383) (xy 283.584925 -305.986453)
			(xy 283.608051 -305.938432) (xy 283.638075 -305.894395) (xy 283.674327 -305.855324) (xy 283.715998 -305.822093)
			(xy 283.762156 -305.795444) (xy 283.81177 -305.775972) (xy 283.863732 -305.764112) (xy 283.916882 -305.760129)
			(xy 283.970032 -305.764112) (xy 284.021994 -305.775972) (xy 284.071608 -305.795444) (xy 284.117766 -305.822093)
			(xy 284.159437 -305.855324) (xy 284.195689 -305.894395) (xy 284.225713 -305.938432) (xy 284.248839 -305.986453)
			(xy 284.264549 -306.037383) (xy 284.272492 -306.090087) (xy 284.27299 -306.116736) (xy 284.272492 -306.143385)
			(xy 298.674272 -306.143385) (xy 298.674272 -306.090087) (xy 298.682215 -306.037383) (xy 298.697925 -305.986453)
			(xy 298.721051 -305.938432) (xy 298.751075 -305.894395) (xy 298.787327 -305.855324) (xy 298.828998 -305.822093)
			(xy 298.875156 -305.795444) (xy 298.92477 -305.775972) (xy 298.976732 -305.764112) (xy 299.029882 -305.760129)
			(xy 299.083032 -305.764112) (xy 299.134994 -305.775972) (xy 299.184608 -305.795444) (xy 299.230766 -305.822093)
			(xy 299.272437 -305.855324) (xy 299.308689 -305.894395) (xy 299.338713 -305.938432) (xy 299.361839 -305.986453)
			(xy 299.377549 -306.037383) (xy 299.385492 -306.090087) (xy 299.38599 -306.116736) (xy 299.385492 -306.143385)
			(xy 299.377549 -306.196089) (xy 299.361839 -306.247019) (xy 299.338713 -306.29504) (xy 299.308689 -306.339077)
			(xy 299.272437 -306.378148) (xy 299.230766 -306.411379) (xy 299.184608 -306.438028) (xy 299.134994 -306.4575)
			(xy 299.083032 -306.46936) (xy 299.029882 -306.473344) (xy 298.976732 -306.46936) (xy 298.92477 -306.4575)
			(xy 298.875156 -306.438028) (xy 298.828998 -306.411379) (xy 298.787327 -306.378148) (xy 298.751075 -306.339077)
			(xy 298.721051 -306.29504) (xy 298.697925 -306.247019) (xy 298.682215 -306.196089) (xy 298.674272 -306.143385)
			(xy 284.272492 -306.143385) (xy 284.264549 -306.196089) (xy 284.248839 -306.247019) (xy 284.225713 -306.29504)
			(xy 284.195689 -306.339077) (xy 284.159437 -306.378148) (xy 284.117766 -306.411379) (xy 284.071608 -306.438028)
			(xy 284.021994 -306.4575) (xy 283.970032 -306.46936) (xy 283.916882 -306.473344) (xy 283.863732 -306.46936)
			(xy 283.81177 -306.4575) (xy 283.762156 -306.438028) (xy 283.715998 -306.411379) (xy 283.674327 -306.378148)
			(xy 283.638075 -306.339077) (xy 283.608051 -306.29504) (xy 283.584925 -306.247019) (xy 283.569215 -306.196089)
			(xy 283.561272 -306.143385) (xy 269.184892 -306.143385) (xy 269.176949 -306.196089) (xy 269.161239 -306.247019)
			(xy 269.138113 -306.29504) (xy 269.108089 -306.339077) (xy 269.071837 -306.378148) (xy 269.030166 -306.411379)
			(xy 268.984008 -306.438028) (xy 268.934394 -306.4575) (xy 268.882432 -306.46936) (xy 268.829282 -306.473344)
			(xy 268.776132 -306.46936) (xy 268.72417 -306.4575) (xy 268.674556 -306.438028) (xy 268.628398 -306.411379)
			(xy 268.586727 -306.378148) (xy 268.550475 -306.339077) (xy 268.520451 -306.29504) (xy 268.497325 -306.247019)
			(xy 268.481615 -306.196089) (xy 268.473672 -306.143385) (xy 254 -306.143385) (xy 254 -306.993269)
			(xy 264.373604 -306.993269) (xy 264.373604 -306.939971) (xy 264.381547 -306.887267) (xy 264.397257 -306.836337)
			(xy 264.420383 -306.788316) (xy 264.450407 -306.744279) (xy 264.486659 -306.705208) (xy 264.52833 -306.671977)
			(xy 264.574488 -306.645328) (xy 264.624102 -306.625856) (xy 264.676064 -306.613996) (xy 264.729214 -306.610013)
			(xy 264.782364 -306.613996) (xy 264.834326 -306.625856) (xy 264.88394 -306.645328) (xy 264.930098 -306.671977)
			(xy 264.971769 -306.705208) (xy 265.008021 -306.744279) (xy 265.038045 -306.788316) (xy 265.061171 -306.836337)
			(xy 265.076881 -306.887267) (xy 265.084824 -306.939971) (xy 265.085322 -306.96662) (xy 265.084824 -306.993269)
			(xy 279.461204 -306.993269) (xy 279.461204 -306.939971) (xy 279.469147 -306.887267) (xy 279.484857 -306.836337)
			(xy 279.507983 -306.788316) (xy 279.538007 -306.744279) (xy 279.574259 -306.705208) (xy 279.61593 -306.671977)
			(xy 279.662088 -306.645328) (xy 279.711702 -306.625856) (xy 279.763664 -306.613996) (xy 279.816814 -306.610013)
			(xy 279.869964 -306.613996) (xy 279.921926 -306.625856) (xy 279.97154 -306.645328) (xy 280.017698 -306.671977)
			(xy 280.059369 -306.705208) (xy 280.095621 -306.744279) (xy 280.125645 -306.788316) (xy 280.148771 -306.836337)
			(xy 280.164481 -306.887267) (xy 280.172424 -306.939971) (xy 280.172922 -306.96662) (xy 280.172424 -306.993269)
			(xy 294.548804 -306.993269) (xy 294.548804 -306.939971) (xy 294.556747 -306.887267) (xy 294.572457 -306.836337)
			(xy 294.595583 -306.788316) (xy 294.625607 -306.744279) (xy 294.661859 -306.705208) (xy 294.70353 -306.671977)
			(xy 294.749688 -306.645328) (xy 294.799302 -306.625856) (xy 294.851264 -306.613996) (xy 294.904414 -306.610013)
			(xy 294.957564 -306.613996) (xy 295.009526 -306.625856) (xy 295.05914 -306.645328) (xy 295.105298 -306.671977)
			(xy 295.146969 -306.705208) (xy 295.183221 -306.744279) (xy 295.213245 -306.788316) (xy 295.236371 -306.836337)
			(xy 295.252081 -306.887267) (xy 295.260024 -306.939971) (xy 295.260522 -306.96662) (xy 295.260024 -306.993269)
			(xy 309.636404 -306.993269) (xy 309.636404 -306.939971) (xy 309.644347 -306.887267) (xy 309.660057 -306.836337)
			(xy 309.683183 -306.788316) (xy 309.713207 -306.744279) (xy 309.749459 -306.705208) (xy 309.79113 -306.671977)
			(xy 309.837288 -306.645328) (xy 309.886902 -306.625856) (xy 309.938864 -306.613996) (xy 309.992014 -306.610013)
			(xy 310.045164 -306.613996) (xy 310.097126 -306.625856) (xy 310.14674 -306.645328) (xy 310.192898 -306.671977)
			(xy 310.234569 -306.705208) (xy 310.270821 -306.744279) (xy 310.300845 -306.788316) (xy 310.323971 -306.836337)
			(xy 310.339681 -306.887267) (xy 310.347624 -306.939971) (xy 310.348122 -306.96662) (xy 310.347624 -306.993269)
			(xy 310.339681 -307.045973) (xy 310.323971 -307.096903) (xy 310.300845 -307.144924) (xy 310.270821 -307.188961)
			(xy 310.234569 -307.228032) (xy 310.192898 -307.261263) (xy 310.14674 -307.287912) (xy 310.097126 -307.307384)
			(xy 310.045164 -307.319244) (xy 309.992014 -307.323228) (xy 309.938864 -307.319244) (xy 309.886902 -307.307384)
			(xy 309.837288 -307.287912) (xy 309.79113 -307.261263) (xy 309.749459 -307.228032) (xy 309.713207 -307.188961)
			(xy 309.683183 -307.144924) (xy 309.660057 -307.096903) (xy 309.644347 -307.045973) (xy 309.636404 -306.993269)
			(xy 295.260024 -306.993269) (xy 295.252081 -307.045973) (xy 295.236371 -307.096903) (xy 295.213245 -307.144924)
			(xy 295.183221 -307.188961) (xy 295.146969 -307.228032) (xy 295.105298 -307.261263) (xy 295.05914 -307.287912)
			(xy 295.009526 -307.307384) (xy 294.957564 -307.319244) (xy 294.904414 -307.323228) (xy 294.851264 -307.319244)
			(xy 294.799302 -307.307384) (xy 294.749688 -307.287912) (xy 294.70353 -307.261263) (xy 294.661859 -307.228032)
			(xy 294.625607 -307.188961) (xy 294.595583 -307.144924) (xy 294.572457 -307.096903) (xy 294.556747 -307.045973)
			(xy 294.548804 -306.993269) (xy 280.172424 -306.993269) (xy 280.164481 -307.045973) (xy 280.148771 -307.096903)
			(xy 280.125645 -307.144924) (xy 280.095621 -307.188961) (xy 280.059369 -307.228032) (xy 280.017698 -307.261263)
			(xy 279.97154 -307.287912) (xy 279.921926 -307.307384) (xy 279.869964 -307.319244) (xy 279.816814 -307.323228)
			(xy 279.763664 -307.319244) (xy 279.711702 -307.307384) (xy 279.662088 -307.287912) (xy 279.61593 -307.261263)
			(xy 279.574259 -307.228032) (xy 279.538007 -307.188961) (xy 279.507983 -307.144924) (xy 279.484857 -307.096903)
			(xy 279.469147 -307.045973) (xy 279.461204 -306.993269) (xy 265.084824 -306.993269) (xy 265.076881 -307.045973)
			(xy 265.061171 -307.096903) (xy 265.038045 -307.144924) (xy 265.008021 -307.188961) (xy 264.971769 -307.228032)
			(xy 264.930098 -307.261263) (xy 264.88394 -307.287912) (xy 264.834326 -307.307384) (xy 264.782364 -307.319244)
			(xy 264.729214 -307.323228) (xy 264.676064 -307.319244) (xy 264.624102 -307.307384) (xy 264.574488 -307.287912)
			(xy 264.52833 -307.261263) (xy 264.486659 -307.228032) (xy 264.450407 -307.188961) (xy 264.420383 -307.144924)
			(xy 264.397257 -307.096903) (xy 264.381547 -307.045973) (xy 264.373604 -306.993269) (xy 254 -306.993269)
			(xy 254 -307.843407) (xy 268.473672 -307.843407) (xy 268.473672 -307.790109) (xy 268.481615 -307.737405)
			(xy 268.497325 -307.686475) (xy 268.520451 -307.638454) (xy 268.550475 -307.594417) (xy 268.586727 -307.555346)
			(xy 268.628398 -307.522115) (xy 268.674556 -307.495466) (xy 268.72417 -307.475994) (xy 268.776132 -307.464134)
			(xy 268.829282 -307.460151) (xy 268.882432 -307.464134) (xy 268.934394 -307.475994) (xy 268.984008 -307.495466)
			(xy 269.030166 -307.522115) (xy 269.071837 -307.555346) (xy 269.108089 -307.594417) (xy 269.138113 -307.638454)
			(xy 269.161239 -307.686475) (xy 269.176949 -307.737405) (xy 269.184892 -307.790109) (xy 269.18539 -307.816758)
			(xy 269.184892 -307.843407) (xy 283.561272 -307.843407) (xy 283.561272 -307.790109) (xy 283.569215 -307.737405)
			(xy 283.584925 -307.686475) (xy 283.608051 -307.638454) (xy 283.638075 -307.594417) (xy 283.674327 -307.555346)
			(xy 283.715998 -307.522115) (xy 283.762156 -307.495466) (xy 283.81177 -307.475994) (xy 283.863732 -307.464134)
			(xy 283.916882 -307.460151) (xy 283.970032 -307.464134) (xy 284.021994 -307.475994) (xy 284.071608 -307.495466)
			(xy 284.117766 -307.522115) (xy 284.159437 -307.555346) (xy 284.195689 -307.594417) (xy 284.225713 -307.638454)
			(xy 284.248839 -307.686475) (xy 284.264549 -307.737405) (xy 284.272492 -307.790109) (xy 284.27299 -307.816758)
			(xy 284.272492 -307.843407) (xy 298.674272 -307.843407) (xy 298.674272 -307.790109) (xy 298.682215 -307.737405)
			(xy 298.697925 -307.686475) (xy 298.721051 -307.638454) (xy 298.751075 -307.594417) (xy 298.787327 -307.555346)
			(xy 298.828998 -307.522115) (xy 298.875156 -307.495466) (xy 298.92477 -307.475994) (xy 298.976732 -307.464134)
			(xy 299.029882 -307.460151) (xy 299.083032 -307.464134) (xy 299.134994 -307.475994) (xy 299.184608 -307.495466)
			(xy 299.230766 -307.522115) (xy 299.272437 -307.555346) (xy 299.308689 -307.594417) (xy 299.338713 -307.638454)
			(xy 299.361839 -307.686475) (xy 299.377549 -307.737405) (xy 299.385492 -307.790109) (xy 299.38599 -307.816758)
			(xy 299.385492 -307.843407) (xy 299.377549 -307.896111) (xy 299.361839 -307.947041) (xy 299.338713 -307.995062)
			(xy 299.308689 -308.039099) (xy 299.272437 -308.07817) (xy 299.230766 -308.111401) (xy 299.184608 -308.13805)
			(xy 299.134994 -308.157522) (xy 299.083032 -308.169382) (xy 299.029882 -308.173366) (xy 298.976732 -308.169382)
			(xy 298.92477 -308.157522) (xy 298.875156 -308.13805) (xy 298.828998 -308.111401) (xy 298.787327 -308.07817)
			(xy 298.751075 -308.039099) (xy 298.721051 -307.995062) (xy 298.697925 -307.947041) (xy 298.682215 -307.896111)
			(xy 298.674272 -307.843407) (xy 284.272492 -307.843407) (xy 284.264549 -307.896111) (xy 284.248839 -307.947041)
			(xy 284.225713 -307.995062) (xy 284.195689 -308.039099) (xy 284.159437 -308.07817) (xy 284.117766 -308.111401)
			(xy 284.071608 -308.13805) (xy 284.021994 -308.157522) (xy 283.970032 -308.169382) (xy 283.916882 -308.173366)
			(xy 283.863732 -308.169382) (xy 283.81177 -308.157522) (xy 283.762156 -308.13805) (xy 283.715998 -308.111401)
			(xy 283.674327 -308.07817) (xy 283.638075 -308.039099) (xy 283.608051 -307.995062) (xy 283.584925 -307.947041)
			(xy 283.569215 -307.896111) (xy 283.561272 -307.843407) (xy 269.184892 -307.843407) (xy 269.176949 -307.896111)
			(xy 269.161239 -307.947041) (xy 269.138113 -307.995062) (xy 269.108089 -308.039099) (xy 269.071837 -308.07817)
			(xy 269.030166 -308.111401) (xy 268.984008 -308.13805) (xy 268.934394 -308.157522) (xy 268.882432 -308.169382)
			(xy 268.829282 -308.173366) (xy 268.776132 -308.169382) (xy 268.72417 -308.157522) (xy 268.674556 -308.13805)
			(xy 268.628398 -308.111401) (xy 268.586727 -308.07817) (xy 268.550475 -308.039099) (xy 268.520451 -307.995062)
			(xy 268.497325 -307.947041) (xy 268.481615 -307.896111) (xy 268.473672 -307.843407) (xy 254 -307.843407)
			(xy 254 -308.693291) (xy 264.373604 -308.693291) (xy 264.373604 -308.639993) (xy 264.381547 -308.587289)
			(xy 264.397257 -308.536359) (xy 264.420383 -308.488338) (xy 264.450407 -308.444301) (xy 264.486659 -308.40523)
			(xy 264.52833 -308.371999) (xy 264.574488 -308.34535) (xy 264.624102 -308.325878) (xy 264.676064 -308.314018)
			(xy 264.729214 -308.310035) (xy 264.782364 -308.314018) (xy 264.834326 -308.325878) (xy 264.88394 -308.34535)
			(xy 264.930098 -308.371999) (xy 264.971769 -308.40523) (xy 265.008021 -308.444301) (xy 265.038045 -308.488338)
			(xy 265.061171 -308.536359) (xy 265.076881 -308.587289) (xy 265.084824 -308.639993) (xy 265.085322 -308.666642)
			(xy 265.084824 -308.693291) (xy 279.461204 -308.693291) (xy 279.461204 -308.639993) (xy 279.469147 -308.587289)
			(xy 279.484857 -308.536359) (xy 279.507983 -308.488338) (xy 279.538007 -308.444301) (xy 279.574259 -308.40523)
			(xy 279.61593 -308.371999) (xy 279.662088 -308.34535) (xy 279.711702 -308.325878) (xy 279.763664 -308.314018)
			(xy 279.816814 -308.310035) (xy 279.869964 -308.314018) (xy 279.921926 -308.325878) (xy 279.97154 -308.34535)
			(xy 280.017698 -308.371999) (xy 280.059369 -308.40523) (xy 280.095621 -308.444301) (xy 280.125645 -308.488338)
			(xy 280.148771 -308.536359) (xy 280.164481 -308.587289) (xy 280.172424 -308.639993) (xy 280.172922 -308.666642)
			(xy 280.172424 -308.693291) (xy 294.548804 -308.693291) (xy 294.548804 -308.639993) (xy 294.556747 -308.587289)
			(xy 294.572457 -308.536359) (xy 294.595583 -308.488338) (xy 294.625607 -308.444301) (xy 294.661859 -308.40523)
			(xy 294.70353 -308.371999) (xy 294.749688 -308.34535) (xy 294.799302 -308.325878) (xy 294.851264 -308.314018)
			(xy 294.904414 -308.310035) (xy 294.957564 -308.314018) (xy 295.009526 -308.325878) (xy 295.05914 -308.34535)
			(xy 295.105298 -308.371999) (xy 295.146969 -308.40523) (xy 295.183221 -308.444301) (xy 295.213245 -308.488338)
			(xy 295.236371 -308.536359) (xy 295.252081 -308.587289) (xy 295.260024 -308.639993) (xy 295.260522 -308.666642)
			(xy 295.260024 -308.693291) (xy 295.252081 -308.745995) (xy 295.236371 -308.796925) (xy 295.213245 -308.844946)
			(xy 295.183221 -308.888983) (xy 295.146969 -308.928054) (xy 295.105298 -308.961285) (xy 295.05914 -308.987934)
			(xy 295.009526 -309.007406) (xy 294.957564 -309.019266) (xy 294.904414 -309.02325) (xy 294.851264 -309.019266)
			(xy 294.799302 -309.007406) (xy 294.749688 -308.987934) (xy 294.70353 -308.961285) (xy 294.661859 -308.928054)
			(xy 294.625607 -308.888983) (xy 294.595583 -308.844946) (xy 294.572457 -308.796925) (xy 294.556747 -308.745995)
			(xy 294.548804 -308.693291) (xy 280.172424 -308.693291) (xy 280.164481 -308.745995) (xy 280.148771 -308.796925)
			(xy 280.125645 -308.844946) (xy 280.095621 -308.888983) (xy 280.059369 -308.928054) (xy 280.017698 -308.961285)
			(xy 279.97154 -308.987934) (xy 279.921926 -309.007406) (xy 279.869964 -309.019266) (xy 279.816814 -309.02325)
			(xy 279.763664 -309.019266) (xy 279.711702 -309.007406) (xy 279.662088 -308.987934) (xy 279.61593 -308.961285)
			(xy 279.574259 -308.928054) (xy 279.538007 -308.888983) (xy 279.507983 -308.844946) (xy 279.484857 -308.796925)
			(xy 279.469147 -308.745995) (xy 279.461204 -308.693291) (xy 265.084824 -308.693291) (xy 265.076881 -308.745995)
			(xy 265.061171 -308.796925) (xy 265.038045 -308.844946) (xy 265.008021 -308.888983) (xy 264.971769 -308.928054)
			(xy 264.930098 -308.961285) (xy 264.88394 -308.987934) (xy 264.834326 -309.007406) (xy 264.782364 -309.019266)
			(xy 264.729214 -309.02325) (xy 264.676064 -309.019266) (xy 264.624102 -309.007406) (xy 264.574488 -308.987934)
			(xy 264.52833 -308.961285) (xy 264.486659 -308.928054) (xy 264.450407 -308.888983) (xy 264.420383 -308.844946)
			(xy 264.397257 -308.796925) (xy 264.381547 -308.745995) (xy 264.373604 -308.693291) (xy 254 -308.693291)
			(xy 254 -309.543429) (xy 268.473672 -309.543429) (xy 268.473672 -309.490131) (xy 268.481615 -309.437427)
			(xy 268.497325 -309.386497) (xy 268.520451 -309.338476) (xy 268.550475 -309.294439) (xy 268.586727 -309.255368)
			(xy 268.628398 -309.222137) (xy 268.674556 -309.195488) (xy 268.72417 -309.176016) (xy 268.776132 -309.164156)
			(xy 268.829282 -309.160173) (xy 268.882432 -309.164156) (xy 268.934394 -309.176016) (xy 268.984008 -309.195488)
			(xy 269.030166 -309.222137) (xy 269.071837 -309.255368) (xy 269.108089 -309.294439) (xy 269.138113 -309.338476)
			(xy 269.161239 -309.386497) (xy 269.176949 -309.437427) (xy 269.184892 -309.490131) (xy 269.18539 -309.51678)
			(xy 269.184892 -309.543429) (xy 283.561272 -309.543429) (xy 283.561272 -309.490131) (xy 283.569215 -309.437427)
			(xy 283.584925 -309.386497) (xy 283.608051 -309.338476) (xy 283.638075 -309.294439) (xy 283.674327 -309.255368)
			(xy 283.715998 -309.222137) (xy 283.762156 -309.195488) (xy 283.81177 -309.176016) (xy 283.863732 -309.164156)
			(xy 283.916882 -309.160173) (xy 283.970032 -309.164156) (xy 284.021994 -309.176016) (xy 284.071608 -309.195488)
			(xy 284.117766 -309.222137) (xy 284.159437 -309.255368) (xy 284.195689 -309.294439) (xy 284.225713 -309.338476)
			(xy 284.248839 -309.386497) (xy 284.264549 -309.437427) (xy 284.272492 -309.490131) (xy 284.27299 -309.51678)
			(xy 284.272492 -309.543429) (xy 298.674272 -309.543429) (xy 298.674272 -309.490131) (xy 298.682215 -309.437427)
			(xy 298.697925 -309.386497) (xy 298.721051 -309.338476) (xy 298.751075 -309.294439) (xy 298.787327 -309.255368)
			(xy 298.828998 -309.222137) (xy 298.875156 -309.195488) (xy 298.92477 -309.176016) (xy 298.976732 -309.164156)
			(xy 299.029882 -309.160173) (xy 299.083032 -309.164156) (xy 299.134994 -309.176016) (xy 299.184608 -309.195488)
			(xy 299.230766 -309.222137) (xy 299.272437 -309.255368) (xy 299.308689 -309.294439) (xy 299.338713 -309.338476)
			(xy 299.361839 -309.386497) (xy 299.377549 -309.437427) (xy 299.385492 -309.490131) (xy 299.38599 -309.51678)
			(xy 299.385492 -309.543429) (xy 299.377549 -309.596133) (xy 299.361839 -309.647063) (xy 299.338713 -309.695084)
			(xy 299.308689 -309.739121) (xy 299.272437 -309.778192) (xy 299.230766 -309.811423) (xy 299.184608 -309.838072)
			(xy 299.134994 -309.857544) (xy 299.083032 -309.869404) (xy 299.029882 -309.873388) (xy 298.976732 -309.869404)
			(xy 298.92477 -309.857544) (xy 298.875156 -309.838072) (xy 298.828998 -309.811423) (xy 298.787327 -309.778192)
			(xy 298.751075 -309.739121) (xy 298.721051 -309.695084) (xy 298.697925 -309.647063) (xy 298.682215 -309.596133)
			(xy 298.674272 -309.543429) (xy 284.272492 -309.543429) (xy 284.264549 -309.596133) (xy 284.248839 -309.647063)
			(xy 284.225713 -309.695084) (xy 284.195689 -309.739121) (xy 284.159437 -309.778192) (xy 284.117766 -309.811423)
			(xy 284.071608 -309.838072) (xy 284.021994 -309.857544) (xy 283.970032 -309.869404) (xy 283.916882 -309.873388)
			(xy 283.863732 -309.869404) (xy 283.81177 -309.857544) (xy 283.762156 -309.838072) (xy 283.715998 -309.811423)
			(xy 283.674327 -309.778192) (xy 283.638075 -309.739121) (xy 283.608051 -309.695084) (xy 283.584925 -309.647063)
			(xy 283.569215 -309.596133) (xy 283.561272 -309.543429) (xy 269.184892 -309.543429) (xy 269.176949 -309.596133)
			(xy 269.161239 -309.647063) (xy 269.138113 -309.695084) (xy 269.108089 -309.739121) (xy 269.071837 -309.778192)
			(xy 269.030166 -309.811423) (xy 268.984008 -309.838072) (xy 268.934394 -309.857544) (xy 268.882432 -309.869404)
			(xy 268.829282 -309.873388) (xy 268.776132 -309.869404) (xy 268.72417 -309.857544) (xy 268.674556 -309.838072)
			(xy 268.628398 -309.811423) (xy 268.586727 -309.778192) (xy 268.550475 -309.739121) (xy 268.520451 -309.695084)
			(xy 268.497325 -309.647063) (xy 268.481615 -309.596133) (xy 268.473672 -309.543429) (xy 254 -309.543429)
			(xy 254 -310.393313) (xy 264.373604 -310.393313) (xy 264.373604 -310.340015) (xy 264.381547 -310.287311)
			(xy 264.397257 -310.236381) (xy 264.420383 -310.18836) (xy 264.450407 -310.144323) (xy 264.486659 -310.105252)
			(xy 264.52833 -310.072021) (xy 264.574488 -310.045372) (xy 264.624102 -310.0259) (xy 264.676064 -310.01404)
			(xy 264.729214 -310.010057) (xy 264.782364 -310.01404) (xy 264.834326 -310.0259) (xy 264.88394 -310.045372)
			(xy 264.930098 -310.072021) (xy 264.971769 -310.105252) (xy 265.008021 -310.144323) (xy 265.038045 -310.18836)
			(xy 265.061171 -310.236381) (xy 265.076881 -310.287311) (xy 265.084824 -310.340015) (xy 265.085322 -310.366664)
			(xy 265.084824 -310.393313) (xy 279.461204 -310.393313) (xy 279.461204 -310.340015) (xy 279.469147 -310.287311)
			(xy 279.484857 -310.236381) (xy 279.507983 -310.18836) (xy 279.538007 -310.144323) (xy 279.574259 -310.105252)
			(xy 279.61593 -310.072021) (xy 279.662088 -310.045372) (xy 279.711702 -310.0259) (xy 279.763664 -310.01404)
			(xy 279.816814 -310.010057) (xy 279.869964 -310.01404) (xy 279.921926 -310.0259) (xy 279.97154 -310.045372)
			(xy 280.017698 -310.072021) (xy 280.059369 -310.105252) (xy 280.095621 -310.144323) (xy 280.125645 -310.18836)
			(xy 280.148771 -310.236381) (xy 280.164481 -310.287311) (xy 280.172424 -310.340015) (xy 280.172922 -310.366664)
			(xy 280.172424 -310.393313) (xy 294.548804 -310.393313) (xy 294.548804 -310.340015) (xy 294.556747 -310.287311)
			(xy 294.572457 -310.236381) (xy 294.595583 -310.18836) (xy 294.625607 -310.144323) (xy 294.661859 -310.105252)
			(xy 294.70353 -310.072021) (xy 294.749688 -310.045372) (xy 294.799302 -310.0259) (xy 294.851264 -310.01404)
			(xy 294.904414 -310.010057) (xy 294.957564 -310.01404) (xy 295.009526 -310.0259) (xy 295.05914 -310.045372)
			(xy 295.105298 -310.072021) (xy 295.146969 -310.105252) (xy 295.183221 -310.144323) (xy 295.213245 -310.18836)
			(xy 295.236371 -310.236381) (xy 295.252081 -310.287311) (xy 295.260024 -310.340015) (xy 295.260522 -310.366664)
			(xy 295.260024 -310.393313) (xy 295.252081 -310.446017) (xy 295.236371 -310.496947) (xy 295.213245 -310.544968)
			(xy 295.183221 -310.589005) (xy 295.146969 -310.628076) (xy 295.105298 -310.661307) (xy 295.05914 -310.687956)
			(xy 295.009526 -310.707428) (xy 294.957564 -310.719288) (xy 294.904414 -310.723272) (xy 294.851264 -310.719288)
			(xy 294.799302 -310.707428) (xy 294.749688 -310.687956) (xy 294.70353 -310.661307) (xy 294.661859 -310.628076)
			(xy 294.625607 -310.589005) (xy 294.595583 -310.544968) (xy 294.572457 -310.496947) (xy 294.556747 -310.446017)
			(xy 294.548804 -310.393313) (xy 280.172424 -310.393313) (xy 280.164481 -310.446017) (xy 280.148771 -310.496947)
			(xy 280.125645 -310.544968) (xy 280.095621 -310.589005) (xy 280.059369 -310.628076) (xy 280.017698 -310.661307)
			(xy 279.97154 -310.687956) (xy 279.921926 -310.707428) (xy 279.869964 -310.719288) (xy 279.816814 -310.723272)
			(xy 279.763664 -310.719288) (xy 279.711702 -310.707428) (xy 279.662088 -310.687956) (xy 279.61593 -310.661307)
			(xy 279.574259 -310.628076) (xy 279.538007 -310.589005) (xy 279.507983 -310.544968) (xy 279.484857 -310.496947)
			(xy 279.469147 -310.446017) (xy 279.461204 -310.393313) (xy 265.084824 -310.393313) (xy 265.076881 -310.446017)
			(xy 265.061171 -310.496947) (xy 265.038045 -310.544968) (xy 265.008021 -310.589005) (xy 264.971769 -310.628076)
			(xy 264.930098 -310.661307) (xy 264.88394 -310.687956) (xy 264.834326 -310.707428) (xy 264.782364 -310.719288)
			(xy 264.729214 -310.723272) (xy 264.676064 -310.719288) (xy 264.624102 -310.707428) (xy 264.574488 -310.687956)
			(xy 264.52833 -310.661307) (xy 264.486659 -310.628076) (xy 264.450407 -310.589005) (xy 264.420383 -310.544968)
			(xy 264.397257 -310.496947) (xy 264.381547 -310.446017) (xy 264.373604 -310.393313) (xy 254 -310.393313)
			(xy 254 -311.243451) (xy 268.473672 -311.243451) (xy 268.473672 -311.190153) (xy 268.481615 -311.137449)
			(xy 268.497325 -311.086519) (xy 268.520451 -311.038498) (xy 268.550475 -310.994461) (xy 268.586727 -310.95539)
			(xy 268.628398 -310.922159) (xy 268.674556 -310.89551) (xy 268.72417 -310.876038) (xy 268.776132 -310.864178)
			(xy 268.829282 -310.860195) (xy 268.882432 -310.864178) (xy 268.934394 -310.876038) (xy 268.984008 -310.89551)
			(xy 269.030166 -310.922159) (xy 269.071837 -310.95539) (xy 269.108089 -310.994461) (xy 269.138113 -311.038498)
			(xy 269.161239 -311.086519) (xy 269.176949 -311.137449) (xy 269.184892 -311.190153) (xy 269.18539 -311.216802)
			(xy 269.184892 -311.243451) (xy 283.561272 -311.243451) (xy 283.561272 -311.190153) (xy 283.569215 -311.137449)
			(xy 283.584925 -311.086519) (xy 283.608051 -311.038498) (xy 283.638075 -310.994461) (xy 283.674327 -310.95539)
			(xy 283.715998 -310.922159) (xy 283.762156 -310.89551) (xy 283.81177 -310.876038) (xy 283.863732 -310.864178)
			(xy 283.916882 -310.860195) (xy 283.970032 -310.864178) (xy 284.021994 -310.876038) (xy 284.071608 -310.89551)
			(xy 284.117766 -310.922159) (xy 284.159437 -310.95539) (xy 284.195689 -310.994461) (xy 284.225713 -311.038498)
			(xy 284.248839 -311.086519) (xy 284.264549 -311.137449) (xy 284.272492 -311.190153) (xy 284.27299 -311.216802)
			(xy 284.272492 -311.243451) (xy 298.674272 -311.243451) (xy 298.674272 -311.190153) (xy 298.682215 -311.137449)
			(xy 298.697925 -311.086519) (xy 298.721051 -311.038498) (xy 298.751075 -310.994461) (xy 298.787327 -310.95539)
			(xy 298.828998 -310.922159) (xy 298.875156 -310.89551) (xy 298.92477 -310.876038) (xy 298.976732 -310.864178)
			(xy 299.029882 -310.860195) (xy 299.083032 -310.864178) (xy 299.134994 -310.876038) (xy 299.184608 -310.89551)
			(xy 299.230766 -310.922159) (xy 299.272437 -310.95539) (xy 299.308689 -310.994461) (xy 299.338713 -311.038498)
			(xy 299.361839 -311.086519) (xy 299.377549 -311.137449) (xy 299.385492 -311.190153) (xy 299.38599 -311.216802)
			(xy 299.385492 -311.243451) (xy 299.377549 -311.296155) (xy 299.361839 -311.347085) (xy 299.338713 -311.395106)
			(xy 299.308689 -311.439143) (xy 299.272437 -311.478214) (xy 299.230766 -311.511445) (xy 299.184608 -311.538094)
			(xy 299.134994 -311.557566) (xy 299.083032 -311.569426) (xy 299.029882 -311.57341) (xy 298.976732 -311.569426)
			(xy 298.92477 -311.557566) (xy 298.875156 -311.538094) (xy 298.828998 -311.511445) (xy 298.787327 -311.478214)
			(xy 298.751075 -311.439143) (xy 298.721051 -311.395106) (xy 298.697925 -311.347085) (xy 298.682215 -311.296155)
			(xy 298.674272 -311.243451) (xy 284.272492 -311.243451) (xy 284.264549 -311.296155) (xy 284.248839 -311.347085)
			(xy 284.225713 -311.395106) (xy 284.195689 -311.439143) (xy 284.159437 -311.478214) (xy 284.117766 -311.511445)
			(xy 284.071608 -311.538094) (xy 284.021994 -311.557566) (xy 283.970032 -311.569426) (xy 283.916882 -311.57341)
			(xy 283.863732 -311.569426) (xy 283.81177 -311.557566) (xy 283.762156 -311.538094) (xy 283.715998 -311.511445)
			(xy 283.674327 -311.478214) (xy 283.638075 -311.439143) (xy 283.608051 -311.395106) (xy 283.584925 -311.347085)
			(xy 283.569215 -311.296155) (xy 283.561272 -311.243451) (xy 269.184892 -311.243451) (xy 269.176949 -311.296155)
			(xy 269.161239 -311.347085) (xy 269.138113 -311.395106) (xy 269.108089 -311.439143) (xy 269.071837 -311.478214)
			(xy 269.030166 -311.511445) (xy 268.984008 -311.538094) (xy 268.934394 -311.557566) (xy 268.882432 -311.569426)
			(xy 268.829282 -311.57341) (xy 268.776132 -311.569426) (xy 268.72417 -311.557566) (xy 268.674556 -311.538094)
			(xy 268.628398 -311.511445) (xy 268.586727 -311.478214) (xy 268.550475 -311.439143) (xy 268.520451 -311.395106)
			(xy 268.497325 -311.347085) (xy 268.481615 -311.296155) (xy 268.473672 -311.243451) (xy 254 -311.243451)
			(xy 254 -312.093335) (xy 264.373604 -312.093335) (xy 264.373604 -312.040037) (xy 264.381547 -311.987333)
			(xy 264.397257 -311.936403) (xy 264.420383 -311.888382) (xy 264.450407 -311.844345) (xy 264.486659 -311.805274)
			(xy 264.52833 -311.772043) (xy 264.574488 -311.745394) (xy 264.624102 -311.725922) (xy 264.676064 -311.714062)
			(xy 264.729214 -311.710079) (xy 264.782364 -311.714062) (xy 264.834326 -311.725922) (xy 264.88394 -311.745394)
			(xy 264.930098 -311.772043) (xy 264.971769 -311.805274) (xy 265.008021 -311.844345) (xy 265.038045 -311.888382)
			(xy 265.061171 -311.936403) (xy 265.076881 -311.987333) (xy 265.084824 -312.040037) (xy 265.085322 -312.066686)
			(xy 265.084824 -312.093335) (xy 268.473672 -312.093335) (xy 268.473672 -312.040037) (xy 268.481615 -311.987333)
			(xy 268.497325 -311.936403) (xy 268.520451 -311.888382) (xy 268.550475 -311.844345) (xy 268.586727 -311.805274)
			(xy 268.628398 -311.772043) (xy 268.674556 -311.745394) (xy 268.72417 -311.725922) (xy 268.776132 -311.714062)
			(xy 268.829282 -311.710079) (xy 268.882432 -311.714062) (xy 268.934394 -311.725922) (xy 268.984008 -311.745394)
			(xy 269.030166 -311.772043) (xy 269.071837 -311.805274) (xy 269.108089 -311.844345) (xy 269.138113 -311.888382)
			(xy 269.161239 -311.936403) (xy 269.176949 -311.987333) (xy 269.184892 -312.040037) (xy 269.18539 -312.066686)
			(xy 269.184892 -312.093335) (xy 279.461204 -312.093335) (xy 279.461204 -312.040037) (xy 279.469147 -311.987333)
			(xy 279.484857 -311.936403) (xy 279.507983 -311.888382) (xy 279.538007 -311.844345) (xy 279.574259 -311.805274)
			(xy 279.61593 -311.772043) (xy 279.662088 -311.745394) (xy 279.711702 -311.725922) (xy 279.763664 -311.714062)
			(xy 279.816814 -311.710079) (xy 279.869964 -311.714062) (xy 279.921926 -311.725922) (xy 279.97154 -311.745394)
			(xy 280.017698 -311.772043) (xy 280.059369 -311.805274) (xy 280.095621 -311.844345) (xy 280.125645 -311.888382)
			(xy 280.148771 -311.936403) (xy 280.164481 -311.987333) (xy 280.172424 -312.040037) (xy 280.172922 -312.066686)
			(xy 280.172424 -312.093335) (xy 283.561272 -312.093335) (xy 283.561272 -312.040037) (xy 283.569215 -311.987333)
			(xy 283.584925 -311.936403) (xy 283.608051 -311.888382) (xy 283.638075 -311.844345) (xy 283.674327 -311.805274)
			(xy 283.715998 -311.772043) (xy 283.762156 -311.745394) (xy 283.81177 -311.725922) (xy 283.863732 -311.714062)
			(xy 283.916882 -311.710079) (xy 283.970032 -311.714062) (xy 284.021994 -311.725922) (xy 284.071608 -311.745394)
			(xy 284.117766 -311.772043) (xy 284.159437 -311.805274) (xy 284.195689 -311.844345) (xy 284.225713 -311.888382)
			(xy 284.248839 -311.936403) (xy 284.264549 -311.987333) (xy 284.272492 -312.040037) (xy 284.27299 -312.066686)
			(xy 284.272492 -312.093335) (xy 294.548804 -312.093335) (xy 294.548804 -312.040037) (xy 294.556747 -311.987333)
			(xy 294.572457 -311.936403) (xy 294.595583 -311.888382) (xy 294.625607 -311.844345) (xy 294.661859 -311.805274)
			(xy 294.70353 -311.772043) (xy 294.749688 -311.745394) (xy 294.799302 -311.725922) (xy 294.851264 -311.714062)
			(xy 294.904414 -311.710079) (xy 294.957564 -311.714062) (xy 295.009526 -311.725922) (xy 295.05914 -311.745394)
			(xy 295.105298 -311.772043) (xy 295.146969 -311.805274) (xy 295.183221 -311.844345) (xy 295.213245 -311.888382)
			(xy 295.236371 -311.936403) (xy 295.252081 -311.987333) (xy 295.260024 -312.040037) (xy 295.260522 -312.066686)
			(xy 295.260024 -312.093335) (xy 298.674272 -312.093335) (xy 298.674272 -312.040037) (xy 298.682215 -311.987333)
			(xy 298.697925 -311.936403) (xy 298.721051 -311.888382) (xy 298.751075 -311.844345) (xy 298.787327 -311.805274)
			(xy 298.828998 -311.772043) (xy 298.875156 -311.745394) (xy 298.92477 -311.725922) (xy 298.976732 -311.714062)
			(xy 299.029882 -311.710079) (xy 299.083032 -311.714062) (xy 299.134994 -311.725922) (xy 299.184608 -311.745394)
			(xy 299.230766 -311.772043) (xy 299.272437 -311.805274) (xy 299.308689 -311.844345) (xy 299.338713 -311.888382)
			(xy 299.361839 -311.936403) (xy 299.377549 -311.987333) (xy 299.385492 -312.040037) (xy 299.38599 -312.066686)
			(xy 299.385492 -312.093335) (xy 299.377549 -312.146039) (xy 299.361839 -312.196969) (xy 299.338713 -312.24499)
			(xy 299.308689 -312.289027) (xy 299.272437 -312.328098) (xy 299.230766 -312.361329) (xy 299.184608 -312.387978)
			(xy 299.134994 -312.40745) (xy 299.083032 -312.41931) (xy 299.029882 -312.423294) (xy 298.976732 -312.41931)
			(xy 298.92477 -312.40745) (xy 298.875156 -312.387978) (xy 298.828998 -312.361329) (xy 298.787327 -312.328098)
			(xy 298.751075 -312.289027) (xy 298.721051 -312.24499) (xy 298.697925 -312.196969) (xy 298.682215 -312.146039)
			(xy 298.674272 -312.093335) (xy 295.260024 -312.093335) (xy 295.252081 -312.146039) (xy 295.236371 -312.196969)
			(xy 295.213245 -312.24499) (xy 295.183221 -312.289027) (xy 295.146969 -312.328098) (xy 295.105298 -312.361329)
			(xy 295.05914 -312.387978) (xy 295.009526 -312.40745) (xy 294.957564 -312.41931) (xy 294.904414 -312.423294)
			(xy 294.851264 -312.41931) (xy 294.799302 -312.40745) (xy 294.749688 -312.387978) (xy 294.70353 -312.361329)
			(xy 294.661859 -312.328098) (xy 294.625607 -312.289027) (xy 294.595583 -312.24499) (xy 294.572457 -312.196969)
			(xy 294.556747 -312.146039) (xy 294.548804 -312.093335) (xy 284.272492 -312.093335) (xy 284.264549 -312.146039)
			(xy 284.248839 -312.196969) (xy 284.225713 -312.24499) (xy 284.195689 -312.289027) (xy 284.159437 -312.328098)
			(xy 284.117766 -312.361329) (xy 284.071608 -312.387978) (xy 284.021994 -312.40745) (xy 283.970032 -312.41931)
			(xy 283.916882 -312.423294) (xy 283.863732 -312.41931) (xy 283.81177 -312.40745) (xy 283.762156 -312.387978)
			(xy 283.715998 -312.361329) (xy 283.674327 -312.328098) (xy 283.638075 -312.289027) (xy 283.608051 -312.24499)
			(xy 283.584925 -312.196969) (xy 283.569215 -312.146039) (xy 283.561272 -312.093335) (xy 280.172424 -312.093335)
			(xy 280.164481 -312.146039) (xy 280.148771 -312.196969) (xy 280.125645 -312.24499) (xy 280.095621 -312.289027)
			(xy 280.059369 -312.328098) (xy 280.017698 -312.361329) (xy 279.97154 -312.387978) (xy 279.921926 -312.40745)
			(xy 279.869964 -312.41931) (xy 279.816814 -312.423294) (xy 279.763664 -312.41931) (xy 279.711702 -312.40745)
			(xy 279.662088 -312.387978) (xy 279.61593 -312.361329) (xy 279.574259 -312.328098) (xy 279.538007 -312.289027)
			(xy 279.507983 -312.24499) (xy 279.484857 -312.196969) (xy 279.469147 -312.146039) (xy 279.461204 -312.093335)
			(xy 269.184892 -312.093335) (xy 269.176949 -312.146039) (xy 269.161239 -312.196969) (xy 269.138113 -312.24499)
			(xy 269.108089 -312.289027) (xy 269.071837 -312.328098) (xy 269.030166 -312.361329) (xy 268.984008 -312.387978)
			(xy 268.934394 -312.40745) (xy 268.882432 -312.41931) (xy 268.829282 -312.423294) (xy 268.776132 -312.41931)
			(xy 268.72417 -312.40745) (xy 268.674556 -312.387978) (xy 268.628398 -312.361329) (xy 268.586727 -312.328098)
			(xy 268.550475 -312.289027) (xy 268.520451 -312.24499) (xy 268.497325 -312.196969) (xy 268.481615 -312.146039)
			(xy 268.473672 -312.093335) (xy 265.084824 -312.093335) (xy 265.076881 -312.146039) (xy 265.061171 -312.196969)
			(xy 265.038045 -312.24499) (xy 265.008021 -312.289027) (xy 264.971769 -312.328098) (xy 264.930098 -312.361329)
			(xy 264.88394 -312.387978) (xy 264.834326 -312.40745) (xy 264.782364 -312.41931) (xy 264.729214 -312.423294)
			(xy 264.676064 -312.41931) (xy 264.624102 -312.40745) (xy 264.574488 -312.387978) (xy 264.52833 -312.361329)
			(xy 264.486659 -312.328098) (xy 264.450407 -312.289027) (xy 264.420383 -312.24499) (xy 264.397257 -312.196969)
			(xy 264.381547 -312.146039) (xy 264.373604 -312.093335) (xy 254 -312.093335) (xy 254 -312.943219)
			(xy 264.373604 -312.943219) (xy 264.373604 -312.889921) (xy 264.381547 -312.837217) (xy 264.397257 -312.786287)
			(xy 264.420383 -312.738266) (xy 264.450407 -312.694229) (xy 264.486659 -312.655158) (xy 264.52833 -312.621927)
			(xy 264.574488 -312.595278) (xy 264.624102 -312.575806) (xy 264.676064 -312.563946) (xy 264.729214 -312.559963)
			(xy 264.782364 -312.563946) (xy 264.834326 -312.575806) (xy 264.88394 -312.595278) (xy 264.930098 -312.621927)
			(xy 264.971769 -312.655158) (xy 265.008021 -312.694229) (xy 265.038045 -312.738266) (xy 265.061171 -312.786287)
			(xy 265.076881 -312.837217) (xy 265.084824 -312.889921) (xy 265.085322 -312.91657) (xy 265.084824 -312.943219)
			(xy 279.461204 -312.943219) (xy 279.461204 -312.889921) (xy 279.469147 -312.837217) (xy 279.484857 -312.786287)
			(xy 279.507983 -312.738266) (xy 279.538007 -312.694229) (xy 279.574259 -312.655158) (xy 279.61593 -312.621927)
			(xy 279.662088 -312.595278) (xy 279.711702 -312.575806) (xy 279.763664 -312.563946) (xy 279.816814 -312.559963)
			(xy 279.869964 -312.563946) (xy 279.921926 -312.575806) (xy 279.97154 -312.595278) (xy 280.017698 -312.621927)
			(xy 280.059369 -312.655158) (xy 280.095621 -312.694229) (xy 280.125645 -312.738266) (xy 280.148771 -312.786287)
			(xy 280.164481 -312.837217) (xy 280.172424 -312.889921) (xy 280.172922 -312.91657) (xy 280.172424 -312.943219)
			(xy 294.548804 -312.943219) (xy 294.548804 -312.889921) (xy 294.556747 -312.837217) (xy 294.572457 -312.786287)
			(xy 294.595583 -312.738266) (xy 294.625607 -312.694229) (xy 294.661859 -312.655158) (xy 294.70353 -312.621927)
			(xy 294.749688 -312.595278) (xy 294.799302 -312.575806) (xy 294.851264 -312.563946) (xy 294.904414 -312.559963)
			(xy 294.957564 -312.563946) (xy 295.009526 -312.575806) (xy 295.05914 -312.595278) (xy 295.105298 -312.621927)
			(xy 295.146969 -312.655158) (xy 295.183221 -312.694229) (xy 295.213245 -312.738266) (xy 295.236371 -312.786287)
			(xy 295.252081 -312.837217) (xy 295.260024 -312.889921) (xy 295.260522 -312.91657) (xy 295.260024 -312.943219)
			(xy 295.252081 -312.995923) (xy 295.236371 -313.046853) (xy 295.213245 -313.094874) (xy 295.183221 -313.138911)
			(xy 295.146969 -313.177982) (xy 295.105298 -313.211213) (xy 295.05914 -313.237862) (xy 295.009526 -313.257334)
			(xy 294.957564 -313.269194) (xy 294.904414 -313.273178) (xy 294.851264 -313.269194) (xy 294.799302 -313.257334)
			(xy 294.749688 -313.237862) (xy 294.70353 -313.211213) (xy 294.661859 -313.177982) (xy 294.625607 -313.138911)
			(xy 294.595583 -313.094874) (xy 294.572457 -313.046853) (xy 294.556747 -312.995923) (xy 294.548804 -312.943219)
			(xy 280.172424 -312.943219) (xy 280.164481 -312.995923) (xy 280.148771 -313.046853) (xy 280.125645 -313.094874)
			(xy 280.095621 -313.138911) (xy 280.059369 -313.177982) (xy 280.017698 -313.211213) (xy 279.97154 -313.237862)
			(xy 279.921926 -313.257334) (xy 279.869964 -313.269194) (xy 279.816814 -313.273178) (xy 279.763664 -313.269194)
			(xy 279.711702 -313.257334) (xy 279.662088 -313.237862) (xy 279.61593 -313.211213) (xy 279.574259 -313.177982)
			(xy 279.538007 -313.138911) (xy 279.507983 -313.094874) (xy 279.484857 -313.046853) (xy 279.469147 -312.995923)
			(xy 279.461204 -312.943219) (xy 265.084824 -312.943219) (xy 265.076881 -312.995923) (xy 265.061171 -313.046853)
			(xy 265.038045 -313.094874) (xy 265.008021 -313.138911) (xy 264.971769 -313.177982) (xy 264.930098 -313.211213)
			(xy 264.88394 -313.237862) (xy 264.834326 -313.257334) (xy 264.782364 -313.269194) (xy 264.729214 -313.273178)
			(xy 264.676064 -313.269194) (xy 264.624102 -313.257334) (xy 264.574488 -313.237862) (xy 264.52833 -313.211213)
			(xy 264.486659 -313.177982) (xy 264.450407 -313.138911) (xy 264.420383 -313.094874) (xy 264.397257 -313.046853)
			(xy 264.381547 -312.995923) (xy 264.373604 -312.943219) (xy 254 -312.943219) (xy 254 -313.793357)
			(xy 268.473672 -313.793357) (xy 268.473672 -313.740059) (xy 268.481615 -313.687355) (xy 268.497325 -313.636425)
			(xy 268.520451 -313.588404) (xy 268.550475 -313.544367) (xy 268.586727 -313.505296) (xy 268.628398 -313.472065)
			(xy 268.674556 -313.445416) (xy 268.72417 -313.425944) (xy 268.776132 -313.414084) (xy 268.829282 -313.410101)
			(xy 268.882432 -313.414084) (xy 268.934394 -313.425944) (xy 268.984008 -313.445416) (xy 269.030166 -313.472065)
			(xy 269.071837 -313.505296) (xy 269.108089 -313.544367) (xy 269.138113 -313.588404) (xy 269.161239 -313.636425)
			(xy 269.176949 -313.687355) (xy 269.184892 -313.740059) (xy 269.18539 -313.766708) (xy 269.184892 -313.793357)
			(xy 283.561272 -313.793357) (xy 283.561272 -313.740059) (xy 283.569215 -313.687355) (xy 283.584925 -313.636425)
			(xy 283.608051 -313.588404) (xy 283.638075 -313.544367) (xy 283.674327 -313.505296) (xy 283.715998 -313.472065)
			(xy 283.762156 -313.445416) (xy 283.81177 -313.425944) (xy 283.863732 -313.414084) (xy 283.916882 -313.410101)
			(xy 283.970032 -313.414084) (xy 284.021994 -313.425944) (xy 284.071608 -313.445416) (xy 284.117766 -313.472065)
			(xy 284.159437 -313.505296) (xy 284.195689 -313.544367) (xy 284.225713 -313.588404) (xy 284.248839 -313.636425)
			(xy 284.264549 -313.687355) (xy 284.272492 -313.740059) (xy 284.27299 -313.766708) (xy 284.272492 -313.793357)
			(xy 298.674272 -313.793357) (xy 298.674272 -313.740059) (xy 298.682215 -313.687355) (xy 298.697925 -313.636425)
			(xy 298.721051 -313.588404) (xy 298.751075 -313.544367) (xy 298.787327 -313.505296) (xy 298.828998 -313.472065)
			(xy 298.875156 -313.445416) (xy 298.92477 -313.425944) (xy 298.976732 -313.414084) (xy 299.029882 -313.410101)
			(xy 299.083032 -313.414084) (xy 299.134994 -313.425944) (xy 299.184608 -313.445416) (xy 299.230766 -313.472065)
			(xy 299.272437 -313.505296) (xy 299.308689 -313.544367) (xy 299.338713 -313.588404) (xy 299.361839 -313.636425)
			(xy 299.377549 -313.687355) (xy 299.385492 -313.740059) (xy 299.38599 -313.766708) (xy 299.385492 -313.793357)
			(xy 299.377549 -313.846061) (xy 299.361839 -313.896991) (xy 299.338713 -313.945012) (xy 299.308689 -313.989049)
			(xy 299.272437 -314.02812) (xy 299.230766 -314.061351) (xy 299.184608 -314.088) (xy 299.134994 -314.107472)
			(xy 299.083032 -314.119332) (xy 299.029882 -314.123316) (xy 298.976732 -314.119332) (xy 298.92477 -314.107472)
			(xy 298.875156 -314.088) (xy 298.828998 -314.061351) (xy 298.787327 -314.02812) (xy 298.751075 -313.989049)
			(xy 298.721051 -313.945012) (xy 298.697925 -313.896991) (xy 298.682215 -313.846061) (xy 298.674272 -313.793357)
			(xy 284.272492 -313.793357) (xy 284.264549 -313.846061) (xy 284.248839 -313.896991) (xy 284.225713 -313.945012)
			(xy 284.195689 -313.989049) (xy 284.159437 -314.02812) (xy 284.117766 -314.061351) (xy 284.071608 -314.088)
			(xy 284.021994 -314.107472) (xy 283.970032 -314.119332) (xy 283.916882 -314.123316) (xy 283.863732 -314.119332)
			(xy 283.81177 -314.107472) (xy 283.762156 -314.088) (xy 283.715998 -314.061351) (xy 283.674327 -314.02812)
			(xy 283.638075 -313.989049) (xy 283.608051 -313.945012) (xy 283.584925 -313.896991) (xy 283.569215 -313.846061)
			(xy 283.561272 -313.793357) (xy 269.184892 -313.793357) (xy 269.176949 -313.846061) (xy 269.161239 -313.896991)
			(xy 269.138113 -313.945012) (xy 269.108089 -313.989049) (xy 269.071837 -314.02812) (xy 269.030166 -314.061351)
			(xy 268.984008 -314.088) (xy 268.934394 -314.107472) (xy 268.882432 -314.119332) (xy 268.829282 -314.123316)
			(xy 268.776132 -314.119332) (xy 268.72417 -314.107472) (xy 268.674556 -314.088) (xy 268.628398 -314.061351)
			(xy 268.586727 -314.02812) (xy 268.550475 -313.989049) (xy 268.520451 -313.945012) (xy 268.497325 -313.896991)
			(xy 268.481615 -313.846061) (xy 268.473672 -313.793357) (xy 254 -313.793357) (xy 254 -314.643241)
			(xy 264.373604 -314.643241) (xy 264.373604 -314.589943) (xy 264.381547 -314.537239) (xy 264.397257 -314.486309)
			(xy 264.420383 -314.438288) (xy 264.450407 -314.394251) (xy 264.486659 -314.35518) (xy 264.52833 -314.321949)
			(xy 264.574488 -314.2953) (xy 264.624102 -314.275828) (xy 264.676064 -314.263968) (xy 264.729214 -314.259985)
			(xy 264.782364 -314.263968) (xy 264.834326 -314.275828) (xy 264.88394 -314.2953) (xy 264.930098 -314.321949)
			(xy 264.971769 -314.35518) (xy 265.008021 -314.394251) (xy 265.038045 -314.438288) (xy 265.061171 -314.486309)
			(xy 265.076881 -314.537239) (xy 265.084824 -314.589943) (xy 265.085322 -314.616592) (xy 265.084824 -314.643241)
			(xy 279.461204 -314.643241) (xy 279.461204 -314.589943) (xy 279.469147 -314.537239) (xy 279.484857 -314.486309)
			(xy 279.507983 -314.438288) (xy 279.538007 -314.394251) (xy 279.574259 -314.35518) (xy 279.61593 -314.321949)
			(xy 279.662088 -314.2953) (xy 279.711702 -314.275828) (xy 279.763664 -314.263968) (xy 279.816814 -314.259985)
			(xy 279.869964 -314.263968) (xy 279.921926 -314.275828) (xy 279.97154 -314.2953) (xy 280.017698 -314.321949)
			(xy 280.059369 -314.35518) (xy 280.095621 -314.394251) (xy 280.125645 -314.438288) (xy 280.148771 -314.486309)
			(xy 280.164481 -314.537239) (xy 280.172424 -314.589943) (xy 280.172922 -314.616592) (xy 280.172424 -314.643241)
			(xy 294.548804 -314.643241) (xy 294.548804 -314.589943) (xy 294.556747 -314.537239) (xy 294.572457 -314.486309)
			(xy 294.595583 -314.438288) (xy 294.625607 -314.394251) (xy 294.661859 -314.35518) (xy 294.70353 -314.321949)
			(xy 294.749688 -314.2953) (xy 294.799302 -314.275828) (xy 294.851264 -314.263968) (xy 294.904414 -314.259985)
			(xy 294.957564 -314.263968) (xy 295.009526 -314.275828) (xy 295.05914 -314.2953) (xy 295.105298 -314.321949)
			(xy 295.146969 -314.35518) (xy 295.183221 -314.394251) (xy 295.213245 -314.438288) (xy 295.236371 -314.486309)
			(xy 295.252081 -314.537239) (xy 295.260024 -314.589943) (xy 295.260522 -314.616592) (xy 295.260024 -314.643241)
			(xy 295.252081 -314.695945) (xy 295.236371 -314.746875) (xy 295.213245 -314.794896) (xy 295.183221 -314.838933)
			(xy 295.146969 -314.878004) (xy 295.105298 -314.911235) (xy 295.05914 -314.937884) (xy 295.009526 -314.957356)
			(xy 294.957564 -314.969216) (xy 294.904414 -314.9732) (xy 294.851264 -314.969216) (xy 294.799302 -314.957356)
			(xy 294.749688 -314.937884) (xy 294.70353 -314.911235) (xy 294.661859 -314.878004) (xy 294.625607 -314.838933)
			(xy 294.595583 -314.794896) (xy 294.572457 -314.746875) (xy 294.556747 -314.695945) (xy 294.548804 -314.643241)
			(xy 280.172424 -314.643241) (xy 280.164481 -314.695945) (xy 280.148771 -314.746875) (xy 280.125645 -314.794896)
			(xy 280.095621 -314.838933) (xy 280.059369 -314.878004) (xy 280.017698 -314.911235) (xy 279.97154 -314.937884)
			(xy 279.921926 -314.957356) (xy 279.869964 -314.969216) (xy 279.816814 -314.9732) (xy 279.763664 -314.969216)
			(xy 279.711702 -314.957356) (xy 279.662088 -314.937884) (xy 279.61593 -314.911235) (xy 279.574259 -314.878004)
			(xy 279.538007 -314.838933) (xy 279.507983 -314.794896) (xy 279.484857 -314.746875) (xy 279.469147 -314.695945)
			(xy 279.461204 -314.643241) (xy 265.084824 -314.643241) (xy 265.076881 -314.695945) (xy 265.061171 -314.746875)
			(xy 265.038045 -314.794896) (xy 265.008021 -314.838933) (xy 264.971769 -314.878004) (xy 264.930098 -314.911235)
			(xy 264.88394 -314.937884) (xy 264.834326 -314.957356) (xy 264.782364 -314.969216) (xy 264.729214 -314.9732)
			(xy 264.676064 -314.969216) (xy 264.624102 -314.957356) (xy 264.574488 -314.937884) (xy 264.52833 -314.911235)
			(xy 264.486659 -314.878004) (xy 264.450407 -314.838933) (xy 264.420383 -314.794896) (xy 264.397257 -314.746875)
			(xy 264.381547 -314.695945) (xy 264.373604 -314.643241) (xy 254 -314.643241) (xy 254 -315.493379)
			(xy 268.473672 -315.493379) (xy 268.473672 -315.440081) (xy 268.481615 -315.387377) (xy 268.497325 -315.336447)
			(xy 268.520451 -315.288426) (xy 268.550475 -315.244389) (xy 268.586727 -315.205318) (xy 268.628398 -315.172087)
			(xy 268.674556 -315.145438) (xy 268.72417 -315.125966) (xy 268.776132 -315.114106) (xy 268.829282 -315.110123)
			(xy 268.882432 -315.114106) (xy 268.934394 -315.125966) (xy 268.984008 -315.145438) (xy 269.030166 -315.172087)
			(xy 269.071837 -315.205318) (xy 269.108089 -315.244389) (xy 269.138113 -315.288426) (xy 269.161239 -315.336447)
			(xy 269.176949 -315.387377) (xy 269.184892 -315.440081) (xy 269.18539 -315.46673) (xy 269.184892 -315.493379)
			(xy 283.561272 -315.493379) (xy 283.561272 -315.440081) (xy 283.569215 -315.387377) (xy 283.584925 -315.336447)
			(xy 283.608051 -315.288426) (xy 283.638075 -315.244389) (xy 283.674327 -315.205318) (xy 283.715998 -315.172087)
			(xy 283.762156 -315.145438) (xy 283.81177 -315.125966) (xy 283.863732 -315.114106) (xy 283.916882 -315.110123)
			(xy 283.970032 -315.114106) (xy 284.021994 -315.125966) (xy 284.071608 -315.145438) (xy 284.117766 -315.172087)
			(xy 284.159437 -315.205318) (xy 284.195689 -315.244389) (xy 284.225713 -315.288426) (xy 284.248839 -315.336447)
			(xy 284.264549 -315.387377) (xy 284.272492 -315.440081) (xy 284.27299 -315.46673) (xy 284.272492 -315.493379)
			(xy 298.66589 -315.493379) (xy 298.66589 -315.440081) (xy 298.673833 -315.387377) (xy 298.689543 -315.336447)
			(xy 298.712669 -315.288426) (xy 298.742693 -315.244389) (xy 298.778945 -315.205318) (xy 298.820616 -315.172087)
			(xy 298.866774 -315.145438) (xy 298.916388 -315.125966) (xy 298.96835 -315.114106) (xy 299.0215 -315.110123)
			(xy 299.07465 -315.114106) (xy 299.126612 -315.125966) (xy 299.176226 -315.145438) (xy 299.222384 -315.172087)
			(xy 299.264055 -315.205318) (xy 299.300307 -315.244389) (xy 299.330331 -315.288426) (xy 299.353457 -315.336447)
			(xy 299.369167 -315.387377) (xy 299.37711 -315.440081) (xy 299.377608 -315.46673) (xy 299.37711 -315.493379)
			(xy 299.369167 -315.546083) (xy 299.353457 -315.597013) (xy 299.330331 -315.645034) (xy 299.300307 -315.689071)
			(xy 299.264055 -315.728142) (xy 299.222384 -315.761373) (xy 299.176226 -315.788022) (xy 299.126612 -315.807494)
			(xy 299.07465 -315.819354) (xy 299.0215 -315.823338) (xy 298.96835 -315.819354) (xy 298.916388 -315.807494)
			(xy 298.866774 -315.788022) (xy 298.820616 -315.761373) (xy 298.778945 -315.728142) (xy 298.742693 -315.689071)
			(xy 298.712669 -315.645034) (xy 298.689543 -315.597013) (xy 298.673833 -315.546083) (xy 298.66589 -315.493379)
			(xy 284.272492 -315.493379) (xy 284.264549 -315.546083) (xy 284.248839 -315.597013) (xy 284.225713 -315.645034)
			(xy 284.195689 -315.689071) (xy 284.159437 -315.728142) (xy 284.117766 -315.761373) (xy 284.071608 -315.788022)
			(xy 284.021994 -315.807494) (xy 283.970032 -315.819354) (xy 283.916882 -315.823338) (xy 283.863732 -315.819354)
			(xy 283.81177 -315.807494) (xy 283.762156 -315.788022) (xy 283.715998 -315.761373) (xy 283.674327 -315.728142)
			(xy 283.638075 -315.689071) (xy 283.608051 -315.645034) (xy 283.584925 -315.597013) (xy 283.569215 -315.546083)
			(xy 283.561272 -315.493379) (xy 269.184892 -315.493379) (xy 269.176949 -315.546083) (xy 269.161239 -315.597013)
			(xy 269.138113 -315.645034) (xy 269.108089 -315.689071) (xy 269.071837 -315.728142) (xy 269.030166 -315.761373)
			(xy 268.984008 -315.788022) (xy 268.934394 -315.807494) (xy 268.882432 -315.819354) (xy 268.829282 -315.823338)
			(xy 268.776132 -315.819354) (xy 268.72417 -315.807494) (xy 268.674556 -315.788022) (xy 268.628398 -315.761373)
			(xy 268.586727 -315.728142) (xy 268.550475 -315.689071) (xy 268.520451 -315.645034) (xy 268.497325 -315.597013)
			(xy 268.481615 -315.546083) (xy 268.473672 -315.493379) (xy 254 -315.493379) (xy 254 -316.343263)
			(xy 264.373604 -316.343263) (xy 264.373604 -316.289965) (xy 264.381547 -316.237261) (xy 264.397257 -316.186331)
			(xy 264.420383 -316.13831) (xy 264.450407 -316.094273) (xy 264.486659 -316.055202) (xy 264.52833 -316.021971)
			(xy 264.574488 -315.995322) (xy 264.624102 -315.97585) (xy 264.676064 -315.96399) (xy 264.729214 -315.960007)
			(xy 264.782364 -315.96399) (xy 264.834326 -315.97585) (xy 264.88394 -315.995322) (xy 264.930098 -316.021971)
			(xy 264.971769 -316.055202) (xy 265.008021 -316.094273) (xy 265.038045 -316.13831) (xy 265.061171 -316.186331)
			(xy 265.076881 -316.237261) (xy 265.084824 -316.289965) (xy 265.085322 -316.316614) (xy 265.084824 -316.343263)
			(xy 265.076881 -316.395967) (xy 265.061171 -316.446897) (xy 265.038045 -316.494918) (xy 265.008021 -316.538955)
			(xy 264.971769 -316.578026) (xy 264.930098 -316.611257) (xy 264.88394 -316.637906) (xy 264.834326 -316.657378)
			(xy 264.782364 -316.669238) (xy 264.729214 -316.673222) (xy 264.676064 -316.669238) (xy 264.624102 -316.657378)
			(xy 264.574488 -316.637906) (xy 264.52833 -316.611257) (xy 264.486659 -316.578026) (xy 264.450407 -316.538955)
			(xy 264.420383 -316.494918) (xy 264.397257 -316.446897) (xy 264.381547 -316.395967) (xy 264.373604 -316.343263)
			(xy 254 -316.343263) (xy 254 -316.8985) (xy 258.190021 -316.8985) (xy 258.194004 -316.845355) (xy 258.205863 -316.793396)
			(xy 258.225333 -316.743786) (xy 258.251981 -316.697632) (xy 258.285209 -316.655965) (xy 258.324277 -316.619715)
			(xy 258.368311 -316.589694) (xy 258.416327 -316.56657) (xy 258.467254 -316.550861) (xy 258.519953 -316.542918)
			(xy 258.5466 -316.54242) (xy 258.57274 -316.542862) (xy 258.62446 -316.550506) (xy 258.674505 -316.565631)
			(xy 258.721801 -316.58791) (xy 258.765332 -316.616865) (xy 258.804161 -316.651874) (xy 258.837453 -316.692184)
			(xy 258.864494 -316.736929) (xy 258.875022 -316.76086) (xy 258.880956 -316.773972) (xy 258.898981 -316.796396)
			(xy 258.922548 -316.812897) (xy 258.949786 -316.822163) (xy 258.978527 -316.823457) (xy 258.992624 -316.82055)
			(xy 259.013076 -316.815923) (xy 259.054715 -316.81096) (xy 259.075682 -316.810644) (xy 259.10233 -316.811212)
			(xy 259.155032 -316.819153) (xy 259.205962 -316.83486) (xy 259.253982 -316.857983) (xy 259.298018 -316.888005)
			(xy 259.337089 -316.924255) (xy 259.37032 -316.965923) (xy 259.396969 -317.012079) (xy 259.416441 -317.061692)
			(xy 259.428301 -317.113652) (xy 259.432284 -317.1668) (xy 259.43029 -317.193401) (xy 268.473672 -317.193401)
			(xy 268.473672 -317.140103) (xy 268.481615 -317.087399) (xy 268.497325 -317.036469) (xy 268.520451 -316.988448)
			(xy 268.550475 -316.944411) (xy 268.586727 -316.90534) (xy 268.628398 -316.872109) (xy 268.674556 -316.84546)
			(xy 268.72417 -316.825988) (xy 268.776132 -316.814128) (xy 268.829282 -316.810145) (xy 268.882432 -316.814128)
			(xy 268.934394 -316.825988) (xy 268.984008 -316.84546) (xy 269.030166 -316.872109) (xy 269.071837 -316.90534)
			(xy 269.108089 -316.944411) (xy 269.138113 -316.988448) (xy 269.161239 -317.036469) (xy 269.176949 -317.087399)
			(xy 269.184892 -317.140103) (xy 269.18539 -317.166752) (xy 269.18522 -317.175864) (xy 276.016535 -317.175864)
			(xy 276.019275 -317.121765) (xy 276.030175 -317.068704) (xy 276.048984 -317.017906) (xy 276.075269 -316.970542)
			(xy 276.108423 -316.927704) (xy 276.147682 -316.890382) (xy 276.192139 -316.859434) (xy 276.240771 -316.835576)
			(xy 276.292454 -316.819357) (xy 276.345998 -316.811151) (xy 276.373082 -316.810644) (xy 276.392677 -316.810922)
			(xy 276.431628 -316.81525) (xy 276.450806 -316.81928) (xy 276.464098 -316.82181) (xy 276.491117 -316.820501)
			(xy 276.516848 -316.812153) (xy 276.53949 -316.797352) (xy 276.557459 -316.777132) (xy 276.569499 -316.752909)
			(xy 276.574767 -316.726376) (xy 276.57425 -316.712854) (xy 276.573234 -316.6872) (xy 276.573698 -316.66012)
			(xy 276.581899 -316.606586) (xy 276.598111 -316.554911) (xy 276.621962 -316.506286) (xy 276.652901 -316.461834)
			(xy 276.690214 -316.422579) (xy 276.733041 -316.389427) (xy 276.780394 -316.363142) (xy 276.831181 -316.344331)
			(xy 276.884231 -316.333427) (xy 276.93832 -316.330682) (xy 276.992202 -316.336159) (xy 277.019643 -316.343263)
			(xy 279.461204 -316.343263) (xy 279.461204 -316.289965) (xy 279.469147 -316.237261) (xy 279.484857 -316.186331)
			(xy 279.507983 -316.13831) (xy 279.538007 -316.094273) (xy 279.574259 -316.055202) (xy 279.61593 -316.021971)
			(xy 279.662088 -315.995322) (xy 279.711702 -315.97585) (xy 279.763664 -315.96399) (xy 279.816814 -315.960007)
			(xy 279.869964 -315.96399) (xy 279.921926 -315.97585) (xy 279.97154 -315.995322) (xy 280.017698 -316.021971)
			(xy 280.059369 -316.055202) (xy 280.095621 -316.094273) (xy 280.125645 -316.13831) (xy 280.148771 -316.186331)
			(xy 280.164481 -316.237261) (xy 280.172424 -316.289965) (xy 280.172922 -316.316614) (xy 280.172424 -316.343263)
			(xy 294.548804 -316.343263) (xy 294.548804 -316.289965) (xy 294.556747 -316.237261) (xy 294.572457 -316.186331)
			(xy 294.595583 -316.13831) (xy 294.625607 -316.094273) (xy 294.661859 -316.055202) (xy 294.70353 -316.021971)
			(xy 294.749688 -315.995322) (xy 294.799302 -315.97585) (xy 294.851264 -315.96399) (xy 294.904414 -315.960007)
			(xy 294.957564 -315.96399) (xy 295.009526 -315.97585) (xy 295.05914 -315.995322) (xy 295.105298 -316.021971)
			(xy 295.146969 -316.055202) (xy 295.183221 -316.094273) (xy 295.213245 -316.13831) (xy 295.236371 -316.186331)
			(xy 295.252081 -316.237261) (xy 295.260024 -316.289965) (xy 295.260522 -316.316614) (xy 295.260024 -316.343263)
			(xy 295.252081 -316.395967) (xy 295.236371 -316.446897) (xy 295.213245 -316.494918) (xy 295.183221 -316.538955)
			(xy 295.146969 -316.578026) (xy 295.105298 -316.611257) (xy 295.05914 -316.637906) (xy 295.009526 -316.657378)
			(xy 294.957564 -316.669238) (xy 294.904414 -316.673222) (xy 294.851264 -316.669238) (xy 294.799302 -316.657378)
			(xy 294.749688 -316.637906) (xy 294.70353 -316.611257) (xy 294.661859 -316.578026) (xy 294.625607 -316.538955)
			(xy 294.595583 -316.494918) (xy 294.572457 -316.446897) (xy 294.556747 -316.395967) (xy 294.548804 -316.343263)
			(xy 280.172424 -316.343263) (xy 280.164481 -316.395967) (xy 280.148771 -316.446897) (xy 280.125645 -316.494918)
			(xy 280.095621 -316.538955) (xy 280.059369 -316.578026) (xy 280.017698 -316.611257) (xy 279.97154 -316.637906)
			(xy 279.921926 -316.657378) (xy 279.869964 -316.669238) (xy 279.816814 -316.673222) (xy 279.763664 -316.669238)
			(xy 279.711702 -316.657378) (xy 279.662088 -316.637906) (xy 279.61593 -316.611257) (xy 279.574259 -316.578026)
			(xy 279.538007 -316.538955) (xy 279.507983 -316.494918) (xy 279.484857 -316.446897) (xy 279.469147 -316.395967)
			(xy 279.461204 -316.343263) (xy 277.019643 -316.343263) (xy 277.044632 -316.349732) (xy 277.094403 -316.371087)
			(xy 277.140366 -316.399733) (xy 277.181462 -316.435008) (xy 277.216742 -316.4761) (xy 277.245393 -316.52206)
			(xy 277.266755 -316.571828) (xy 277.280334 -316.624257) (xy 277.285817 -316.678138) (xy 277.283078 -316.732227)
			(xy 277.27218 -316.785279) (xy 277.253375 -316.836068) (xy 277.227096 -316.883424) (xy 277.193949 -316.926255)
			(xy 277.154699 -316.963573) (xy 277.11025 -316.994517) (xy 277.061628 -317.018373) (xy 277.009955 -317.034592)
			(xy 276.956421 -317.042799) (xy 276.929342 -317.043308) (xy 276.909747 -317.043027) (xy 276.870796 -317.038701)
			(xy 276.851618 -317.034672) (xy 276.838315 -317.032218) (xy 276.811308 -317.033522) (xy 276.785587 -317.04186)
			(xy 276.762951 -317.056649) (xy 276.744983 -317.076854) (xy 276.732939 -317.101063) (xy 276.727663 -317.127582)
			(xy 276.728174 -317.141098) (xy 276.72919 -317.166752) (xy 276.728754 -317.193836) (xy 276.720558 -317.247381)
			(xy 276.704349 -317.299068) (xy 276.6805 -317.347704) (xy 276.64956 -317.392167) (xy 276.612245 -317.431433)
			(xy 276.569413 -317.464595) (xy 276.522054 -317.490888) (xy 276.47126 -317.509707) (xy 276.418201 -317.520617)
			(xy 276.364102 -317.523366) (xy 276.310211 -317.517892) (xy 276.25777 -317.50432) (xy 276.207989 -317.482963)
			(xy 276.162017 -317.454314) (xy 276.120913 -317.419034) (xy 276.085625 -317.377937) (xy 276.056968 -317.331969)
			(xy 276.035602 -317.282192) (xy 276.02202 -317.229754) (xy 276.016535 -317.175864) (xy 269.18522 -317.175864)
			(xy 269.184892 -317.193401) (xy 269.176949 -317.246105) (xy 269.161239 -317.297035) (xy 269.138113 -317.345056)
			(xy 269.108089 -317.389093) (xy 269.071837 -317.428164) (xy 269.030166 -317.461395) (xy 268.984008 -317.488044)
			(xy 268.934394 -317.507516) (xy 268.882432 -317.519376) (xy 268.829282 -317.52336) (xy 268.776132 -317.519376)
			(xy 268.72417 -317.507516) (xy 268.674556 -317.488044) (xy 268.628398 -317.461395) (xy 268.586727 -317.428164)
			(xy 268.550475 -317.389093) (xy 268.520451 -317.345056) (xy 268.497325 -317.297035) (xy 268.481615 -317.246105)
			(xy 268.473672 -317.193401) (xy 259.43029 -317.193401) (xy 259.428301 -317.219948) (xy 259.416441 -317.271908)
			(xy 259.396969 -317.321521) (xy 259.37032 -317.367677) (xy 259.337089 -317.409345) (xy 259.298018 -317.445595)
			(xy 259.253982 -317.475617) (xy 259.205962 -317.49874) (xy 259.155032 -317.514447) (xy 259.10233 -317.522388)
			(xy 259.075682 -317.52286) (xy 259.04954 -317.522446) (xy 258.99782 -317.514798) (xy 258.947773 -317.49967)
			(xy 258.900476 -317.477387) (xy 258.856945 -317.448428) (xy 258.818117 -317.413415) (xy 258.784826 -317.373101)
			(xy 258.757787 -317.328353) (xy 258.74726 -317.30442) (xy 258.741309 -317.291315) (xy 258.723295 -317.268883)
			(xy 258.699732 -317.252376) (xy 258.672495 -317.243109) (xy 258.643754 -317.241819) (xy 258.629658 -317.24473)
			(xy 258.609207 -317.249362) (xy 258.567567 -317.254322) (xy 258.5466 -317.254636) (xy 258.519953 -317.254082)
			(xy 258.467254 -317.246139) (xy 258.416327 -317.23043) (xy 258.368311 -317.207306) (xy 258.324277 -317.177285)
			(xy 258.285209 -317.141035) (xy 258.251981 -317.099368) (xy 258.225333 -317.053214) (xy 258.205863 -317.003604)
			(xy 258.194004 -316.951645) (xy 258.190021 -316.8985) (xy 254 -316.8985) (xy 254 -317.913237) (xy 254.14477 -317.913237)
			(xy 254.14477 -317.859939) (xy 254.152713 -317.807235) (xy 254.168423 -317.756305) (xy 254.191549 -317.708284)
			(xy 254.221573 -317.664247) (xy 254.257825 -317.625176) (xy 254.299496 -317.591945) (xy 254.345654 -317.565296)
			(xy 254.395268 -317.545824) (xy 254.44723 -317.533964) (xy 254.50038 -317.529981) (xy 254.55353 -317.533964)
			(xy 254.605492 -317.545824) (xy 254.655106 -317.565296) (xy 254.659438 -317.567797) (xy 280.61919 -317.567797)
			(xy 280.61919 -317.514499) (xy 280.627133 -317.461795) (xy 280.642843 -317.410865) (xy 280.665969 -317.362844)
			(xy 280.695993 -317.318807) (xy 280.732245 -317.279736) (xy 280.773916 -317.246505) (xy 280.820074 -317.219856)
			(xy 280.869688 -317.200384) (xy 280.92165 -317.188524) (xy 280.9748 -317.184541) (xy 281.02795 -317.188524)
			(xy 281.049318 -317.193401) (xy 283.561272 -317.193401) (xy 283.561272 -317.140103) (xy 283.569215 -317.087399)
			(xy 283.584925 -317.036469) (xy 283.608051 -316.988448) (xy 283.638075 -316.944411) (xy 283.674327 -316.90534)
			(xy 283.715998 -316.872109) (xy 283.762156 -316.84546) (xy 283.81177 -316.825988) (xy 283.863732 -316.814128)
			(xy 283.916882 -316.810145) (xy 283.970032 -316.814128) (xy 284.021994 -316.825988) (xy 284.071608 -316.84546)
			(xy 284.117766 -316.872109) (xy 284.159437 -316.90534) (xy 284.195689 -316.944411) (xy 284.225713 -316.988448)
			(xy 284.248839 -317.036469) (xy 284.264549 -317.087399) (xy 284.272492 -317.140103) (xy 284.27299 -317.166752)
			(xy 284.272492 -317.193401) (xy 291.105072 -317.193401) (xy 291.105072 -317.140103) (xy 291.113015 -317.087399)
			(xy 291.128725 -317.036469) (xy 291.151851 -316.988448) (xy 291.181875 -316.944411) (xy 291.218127 -316.90534)
			(xy 291.259798 -316.872109) (xy 291.305956 -316.84546) (xy 291.35557 -316.825988) (xy 291.407532 -316.814128)
			(xy 291.460682 -316.810145) (xy 291.513832 -316.814128) (xy 291.565794 -316.825988) (xy 291.615408 -316.84546)
			(xy 291.661566 -316.872109) (xy 291.703237 -316.90534) (xy 291.739489 -316.944411) (xy 291.769513 -316.988448)
			(xy 291.792639 -317.036469) (xy 291.808349 -317.087399) (xy 291.816292 -317.140103) (xy 291.81679 -317.166752)
			(xy 291.816292 -317.193401) (xy 298.63287 -317.193401) (xy 298.63287 -317.140103) (xy 298.640813 -317.087399)
			(xy 298.656523 -317.036469) (xy 298.679649 -316.988448) (xy 298.709673 -316.944411) (xy 298.745925 -316.90534)
			(xy 298.787596 -316.872109) (xy 298.833754 -316.84546) (xy 298.883368 -316.825988) (xy 298.93533 -316.814128)
			(xy 298.98848 -316.810145) (xy 299.04163 -316.814128) (xy 299.093592 -316.825988) (xy 299.143206 -316.84546)
			(xy 299.189364 -316.872109) (xy 299.231035 -316.90534) (xy 299.267287 -316.944411) (xy 299.297311 -316.988448)
			(xy 299.320437 -317.036469) (xy 299.336147 -317.087399) (xy 299.34409 -317.140103) (xy 299.344588 -317.166752)
			(xy 299.34409 -317.193401) (xy 306.192672 -317.193401) (xy 306.192672 -317.140103) (xy 306.200615 -317.087399)
			(xy 306.216325 -317.036469) (xy 306.239451 -316.988448) (xy 306.269475 -316.944411) (xy 306.305727 -316.90534)
			(xy 306.347398 -316.872109) (xy 306.393556 -316.84546) (xy 306.44317 -316.825988) (xy 306.495132 -316.814128)
			(xy 306.548282 -316.810145) (xy 306.601432 -316.814128) (xy 306.653394 -316.825988) (xy 306.703008 -316.84546)
			(xy 306.749166 -316.872109) (xy 306.790837 -316.90534) (xy 306.827089 -316.944411) (xy 306.857113 -316.988448)
			(xy 306.880239 -317.036469) (xy 306.895949 -317.087399) (xy 306.903892 -317.140103) (xy 306.90439 -317.166752)
			(xy 306.903892 -317.193401) (xy 306.895949 -317.246105) (xy 306.880239 -317.297035) (xy 306.857113 -317.345056)
			(xy 306.827089 -317.389093) (xy 306.790837 -317.428164) (xy 306.749166 -317.461395) (xy 306.703008 -317.488044)
			(xy 306.653394 -317.507516) (xy 306.601432 -317.519376) (xy 306.548282 -317.52336) (xy 306.495132 -317.519376)
			(xy 306.44317 -317.507516) (xy 306.393556 -317.488044) (xy 306.347398 -317.461395) (xy 306.305727 -317.428164)
			(xy 306.269475 -317.389093) (xy 306.239451 -317.345056) (xy 306.216325 -317.297035) (xy 306.200615 -317.246105)
			(xy 306.192672 -317.193401) (xy 299.34409 -317.193401) (xy 299.336147 -317.246105) (xy 299.320437 -317.297035)
			(xy 299.297311 -317.345056) (xy 299.267287 -317.389093) (xy 299.231035 -317.428164) (xy 299.189364 -317.461395)
			(xy 299.143206 -317.488044) (xy 299.093592 -317.507516) (xy 299.04163 -317.519376) (xy 298.98848 -317.52336)
			(xy 298.93533 -317.519376) (xy 298.883368 -317.507516) (xy 298.833754 -317.488044) (xy 298.787596 -317.461395)
			(xy 298.745925 -317.428164) (xy 298.709673 -317.389093) (xy 298.679649 -317.345056) (xy 298.656523 -317.297035)
			(xy 298.640813 -317.246105) (xy 298.63287 -317.193401) (xy 291.816292 -317.193401) (xy 291.808349 -317.246105)
			(xy 291.792639 -317.297035) (xy 291.769513 -317.345056) (xy 291.739489 -317.389093) (xy 291.703237 -317.428164)
			(xy 291.661566 -317.461395) (xy 291.615408 -317.488044) (xy 291.565794 -317.507516) (xy 291.513832 -317.519376)
			(xy 291.460682 -317.52336) (xy 291.407532 -317.519376) (xy 291.35557 -317.507516) (xy 291.305956 -317.488044)
			(xy 291.259798 -317.461395) (xy 291.218127 -317.428164) (xy 291.181875 -317.389093) (xy 291.151851 -317.345056)
			(xy 291.128725 -317.297035) (xy 291.113015 -317.246105) (xy 291.105072 -317.193401) (xy 284.272492 -317.193401)
			(xy 284.264549 -317.246105) (xy 284.248839 -317.297035) (xy 284.225713 -317.345056) (xy 284.195689 -317.389093)
			(xy 284.159437 -317.428164) (xy 284.117766 -317.461395) (xy 284.071608 -317.488044) (xy 284.021994 -317.507516)
			(xy 283.970032 -317.519376) (xy 283.916882 -317.52336) (xy 283.863732 -317.519376) (xy 283.81177 -317.507516)
			(xy 283.762156 -317.488044) (xy 283.715998 -317.461395) (xy 283.674327 -317.428164) (xy 283.638075 -317.389093)
			(xy 283.608051 -317.345056) (xy 283.584925 -317.297035) (xy 283.569215 -317.246105) (xy 283.561272 -317.193401)
			(xy 281.049318 -317.193401) (xy 281.079912 -317.200384) (xy 281.129526 -317.219856) (xy 281.175684 -317.246505)
			(xy 281.217355 -317.279736) (xy 281.253607 -317.318807) (xy 281.283631 -317.362844) (xy 281.306757 -317.410865)
			(xy 281.322467 -317.461795) (xy 281.33041 -317.514499) (xy 281.330908 -317.541148) (xy 281.33041 -317.567797)
			(xy 281.322467 -317.620501) (xy 281.306757 -317.671431) (xy 281.283631 -317.719452) (xy 281.253607 -317.763489)
			(xy 281.217355 -317.80256) (xy 281.175684 -317.835791) (xy 281.129526 -317.86244) (xy 281.079912 -317.881912)
			(xy 281.02795 -317.893772) (xy 280.9748 -317.897756) (xy 280.92165 -317.893772) (xy 280.869688 -317.881912)
			(xy 280.820074 -317.86244) (xy 280.773916 -317.835791) (xy 280.732245 -317.80256) (xy 280.695993 -317.763489)
			(xy 280.665969 -317.719452) (xy 280.642843 -317.671431) (xy 280.627133 -317.620501) (xy 280.61919 -317.567797)
			(xy 254.659438 -317.567797) (xy 254.701264 -317.591945) (xy 254.742935 -317.625176) (xy 254.779187 -317.664247)
			(xy 254.809211 -317.708284) (xy 254.832337 -317.756305) (xy 254.848047 -317.807235) (xy 254.85599 -317.859939)
			(xy 254.856488 -317.886588) (xy 254.85599 -317.913237) (xy 254.848047 -317.965941) (xy 254.832337 -318.016871)
			(xy 254.819617 -318.043285) (xy 258.720072 -318.043285) (xy 258.720072 -317.989987) (xy 258.728015 -317.937283)
			(xy 258.743725 -317.886353) (xy 258.766851 -317.838332) (xy 258.796875 -317.794295) (xy 258.833127 -317.755224)
			(xy 258.874798 -317.721993) (xy 258.920956 -317.695344) (xy 258.97057 -317.675872) (xy 259.022532 -317.664012)
			(xy 259.075682 -317.660029) (xy 259.128832 -317.664012) (xy 259.180794 -317.675872) (xy 259.230408 -317.695344)
			(xy 259.276566 -317.721993) (xy 259.318237 -317.755224) (xy 259.354489 -317.794295) (xy 259.384513 -317.838332)
			(xy 259.407639 -317.886353) (xy 259.423349 -317.937283) (xy 259.431292 -317.989987) (xy 259.43179 -318.016636)
			(xy 259.431292 -318.043285) (xy 259.423349 -318.095989) (xy 259.420959 -318.103737) (xy 268.73453 -318.103737)
			(xy 268.73453 -318.050439) (xy 268.742473 -317.997735) (xy 268.758183 -317.946805) (xy 268.781309 -317.898784)
			(xy 268.811333 -317.854747) (xy 268.847585 -317.815676) (xy 268.889256 -317.782445) (xy 268.935414 -317.755796)
			(xy 268.985028 -317.736324) (xy 269.03699 -317.724464) (xy 269.09014 -317.720481) (xy 269.14329 -317.724464)
			(xy 269.195252 -317.736324) (xy 269.244866 -317.755796) (xy 269.291024 -317.782445) (xy 269.332695 -317.815676)
			(xy 269.368947 -317.854747) (xy 269.398971 -317.898784) (xy 269.422097 -317.946805) (xy 269.437807 -317.997735)
			(xy 269.44575 -318.050439) (xy 269.446248 -318.077088) (xy 269.44575 -318.103737) (xy 269.444946 -318.109071)
			(xy 276.062938 -318.109071) (xy 276.062938 -318.055773) (xy 276.070881 -318.003069) (xy 276.086591 -317.952139)
			(xy 276.109717 -317.904118) (xy 276.139741 -317.860081) (xy 276.175993 -317.82101) (xy 276.217664 -317.787779)
			(xy 276.263822 -317.76113) (xy 276.313436 -317.741658) (xy 276.365398 -317.729798) (xy 276.418548 -317.725815)
			(xy 276.471698 -317.729798) (xy 276.52366 -317.741658) (xy 276.573274 -317.76113) (xy 276.619432 -317.787779)
			(xy 276.661103 -317.82101) (xy 276.697355 -317.860081) (xy 276.727379 -317.904118) (xy 276.750505 -317.952139)
			(xy 276.766215 -318.003069) (xy 276.772276 -318.043285) (xy 288.895272 -318.043285) (xy 288.895272 -317.989987)
			(xy 288.903215 -317.937283) (xy 288.918925 -317.886353) (xy 288.942051 -317.838332) (xy 288.972075 -317.794295)
			(xy 289.008327 -317.755224) (xy 289.049998 -317.721993) (xy 289.096156 -317.695344) (xy 289.14577 -317.675872)
			(xy 289.197732 -317.664012) (xy 289.250882 -317.660029) (xy 289.304032 -317.664012) (xy 289.355994 -317.675872)
			(xy 289.405608 -317.695344) (xy 289.451766 -317.721993) (xy 289.493437 -317.755224) (xy 289.529689 -317.794295)
			(xy 289.559713 -317.838332) (xy 289.582839 -317.886353) (xy 289.598549 -317.937283) (xy 289.606492 -317.989987)
			(xy 289.60699 -318.016636) (xy 289.606492 -318.043285) (xy 296.439072 -318.043285) (xy 296.439072 -317.989987)
			(xy 296.447015 -317.937283) (xy 296.462725 -317.886353) (xy 296.485851 -317.838332) (xy 296.515875 -317.794295)
			(xy 296.552127 -317.755224) (xy 296.593798 -317.721993) (xy 296.639956 -317.695344) (xy 296.68957 -317.675872)
			(xy 296.741532 -317.664012) (xy 296.794682 -317.660029) (xy 296.847832 -317.664012) (xy 296.899794 -317.675872)
			(xy 296.949408 -317.695344) (xy 296.995566 -317.721993) (xy 297.037237 -317.755224) (xy 297.073489 -317.794295)
			(xy 297.103513 -317.838332) (xy 297.126639 -317.886353) (xy 297.142349 -317.937283) (xy 297.150292 -317.989987)
			(xy 297.15079 -318.016636) (xy 297.150292 -318.043285) (xy 303.982872 -318.043285) (xy 303.982872 -317.989987)
			(xy 303.990815 -317.937283) (xy 304.006525 -317.886353) (xy 304.029651 -317.838332) (xy 304.059675 -317.794295)
			(xy 304.095927 -317.755224) (xy 304.137598 -317.721993) (xy 304.183756 -317.695344) (xy 304.23337 -317.675872)
			(xy 304.285332 -317.664012) (xy 304.338482 -317.660029) (xy 304.391632 -317.664012) (xy 304.443594 -317.675872)
			(xy 304.493208 -317.695344) (xy 304.539366 -317.721993) (xy 304.581037 -317.755224) (xy 304.617289 -317.794295)
			(xy 304.647313 -317.838332) (xy 304.670439 -317.886353) (xy 304.686149 -317.937283) (xy 304.694092 -317.989987)
			(xy 304.69459 -318.016636) (xy 304.694092 -318.043285) (xy 304.686149 -318.095989) (xy 304.670439 -318.146919)
			(xy 304.647313 -318.19494) (xy 304.617289 -318.238977) (xy 304.581037 -318.278048) (xy 304.539366 -318.311279)
			(xy 304.493208 -318.337928) (xy 304.443594 -318.3574) (xy 304.391632 -318.36926) (xy 304.338482 -318.373244)
			(xy 304.285332 -318.36926) (xy 304.23337 -318.3574) (xy 304.183756 -318.337928) (xy 304.137598 -318.311279)
			(xy 304.095927 -318.278048) (xy 304.059675 -318.238977) (xy 304.029651 -318.19494) (xy 304.006525 -318.146919)
			(xy 303.990815 -318.095989) (xy 303.982872 -318.043285) (xy 297.150292 -318.043285) (xy 297.142349 -318.095989)
			(xy 297.126639 -318.146919) (xy 297.103513 -318.19494) (xy 297.073489 -318.238977) (xy 297.037237 -318.278048)
			(xy 296.995566 -318.311279) (xy 296.949408 -318.337928) (xy 296.899794 -318.3574) (xy 296.847832 -318.36926)
			(xy 296.794682 -318.373244) (xy 296.741532 -318.36926) (xy 296.68957 -318.3574) (xy 296.639956 -318.337928)
			(xy 296.593798 -318.311279) (xy 296.552127 -318.278048) (xy 296.515875 -318.238977) (xy 296.485851 -318.19494)
			(xy 296.462725 -318.146919) (xy 296.447015 -318.095989) (xy 296.439072 -318.043285) (xy 289.606492 -318.043285)
			(xy 289.598549 -318.095989) (xy 289.582839 -318.146919) (xy 289.559713 -318.19494) (xy 289.529689 -318.238977)
			(xy 289.493437 -318.278048) (xy 289.451766 -318.311279) (xy 289.405608 -318.337928) (xy 289.355994 -318.3574)
			(xy 289.304032 -318.36926) (xy 289.250882 -318.373244) (xy 289.197732 -318.36926) (xy 289.14577 -318.3574)
			(xy 289.096156 -318.337928) (xy 289.049998 -318.311279) (xy 289.008327 -318.278048) (xy 288.972075 -318.238977)
			(xy 288.942051 -318.19494) (xy 288.918925 -318.146919) (xy 288.903215 -318.095989) (xy 288.895272 -318.043285)
			(xy 276.772276 -318.043285) (xy 276.774158 -318.055773) (xy 276.774656 -318.082422) (xy 276.774158 -318.109071)
			(xy 276.766215 -318.161775) (xy 276.750505 -318.212705) (xy 276.727379 -318.260726) (xy 276.697355 -318.304763)
			(xy 276.661103 -318.343834) (xy 276.619432 -318.377065) (xy 276.573274 -318.403714) (xy 276.52366 -318.423186)
			(xy 276.471698 -318.435046) (xy 276.418548 -318.43903) (xy 276.365398 -318.435046) (xy 276.313436 -318.423186)
			(xy 276.263822 -318.403714) (xy 276.217664 -318.377065) (xy 276.175993 -318.343834) (xy 276.139741 -318.304763)
			(xy 276.109717 -318.260726) (xy 276.086591 -318.212705) (xy 276.070881 -318.161775) (xy 276.062938 -318.109071)
			(xy 269.444946 -318.109071) (xy 269.437807 -318.156441) (xy 269.422097 -318.207371) (xy 269.398971 -318.255392)
			(xy 269.368947 -318.299429) (xy 269.332695 -318.3385) (xy 269.291024 -318.371731) (xy 269.244866 -318.39838)
			(xy 269.195252 -318.417852) (xy 269.14329 -318.429712) (xy 269.09014 -318.433696) (xy 269.03699 -318.429712)
			(xy 268.985028 -318.417852) (xy 268.935414 -318.39838) (xy 268.889256 -318.371731) (xy 268.847585 -318.3385)
			(xy 268.811333 -318.299429) (xy 268.781309 -318.255392) (xy 268.758183 -318.207371) (xy 268.742473 -318.156441)
			(xy 268.73453 -318.103737) (xy 259.420959 -318.103737) (xy 259.407639 -318.146919) (xy 259.384513 -318.19494)
			(xy 259.354489 -318.238977) (xy 259.318237 -318.278048) (xy 259.276566 -318.311279) (xy 259.230408 -318.337928)
			(xy 259.180794 -318.3574) (xy 259.128832 -318.36926) (xy 259.075682 -318.373244) (xy 259.022532 -318.36926)
			(xy 258.97057 -318.3574) (xy 258.920956 -318.337928) (xy 258.874798 -318.311279) (xy 258.833127 -318.278048)
			(xy 258.796875 -318.238977) (xy 258.766851 -318.19494) (xy 258.743725 -318.146919) (xy 258.728015 -318.095989)
			(xy 258.720072 -318.043285) (xy 254.819617 -318.043285) (xy 254.809211 -318.064892) (xy 254.779187 -318.108929)
			(xy 254.742935 -318.148) (xy 254.701264 -318.181231) (xy 254.655106 -318.20788) (xy 254.605492 -318.227352)
			(xy 254.55353 -318.239212) (xy 254.50038 -318.243196) (xy 254.44723 -318.239212) (xy 254.395268 -318.227352)
			(xy 254.345654 -318.20788) (xy 254.299496 -318.181231) (xy 254.257825 -318.148) (xy 254.221573 -318.108929)
			(xy 254.191549 -318.064892) (xy 254.168423 -318.016871) (xy 254.152713 -317.965941) (xy 254.14477 -317.913237)
			(xy 254 -317.913237) (xy 254 -318.893423) (xy 258.720072 -318.893423) (xy 258.720072 -318.840125)
			(xy 258.728015 -318.787421) (xy 258.743725 -318.736491) (xy 258.766851 -318.68847) (xy 258.796875 -318.644433)
			(xy 258.833127 -318.605362) (xy 258.874798 -318.572131) (xy 258.920956 -318.545482) (xy 258.97057 -318.52601)
			(xy 259.022532 -318.51415) (xy 259.075682 -318.510167) (xy 259.128832 -318.51415) (xy 259.180794 -318.52601)
			(xy 259.230408 -318.545482) (xy 259.276566 -318.572131) (xy 259.318237 -318.605362) (xy 259.354489 -318.644433)
			(xy 259.384513 -318.68847) (xy 259.407639 -318.736491) (xy 259.423349 -318.787421) (xy 259.431292 -318.840125)
			(xy 259.43179 -318.866774) (xy 259.431292 -318.893423) (xy 259.423349 -318.946127) (xy 259.407639 -318.997057)
			(xy 259.384513 -319.045078) (xy 259.373441 -319.061317) (xy 261.33297 -319.061317) (xy 261.33297 -319.008019)
			(xy 261.340913 -318.955315) (xy 261.356623 -318.904385) (xy 261.379749 -318.856364) (xy 261.409773 -318.812327)
			(xy 261.446025 -318.773256) (xy 261.487696 -318.740025) (xy 261.533854 -318.713376) (xy 261.583468 -318.693904)
			(xy 261.63543 -318.682044) (xy 261.68858 -318.678061) (xy 261.74173 -318.682044) (xy 261.793692 -318.693904)
			(xy 261.843306 -318.713376) (xy 261.889464 -318.740025) (xy 261.931135 -318.773256) (xy 261.967387 -318.812327)
			(xy 261.997411 -318.856364) (xy 262.020537 -318.904385) (xy 262.034083 -318.9483) (xy 287.476201 -318.9483)
			(xy 287.480183 -318.895152) (xy 287.492043 -318.84319) (xy 287.511515 -318.793577) (xy 287.538164 -318.74742)
			(xy 287.571394 -318.705751) (xy 287.610464 -318.669499) (xy 287.6545 -318.639476) (xy 287.70252 -318.616351)
			(xy 287.753449 -318.600641) (xy 287.806151 -318.592698) (xy 287.8328 -318.5922) (xy 287.858407 -318.592628)
			(xy 287.909093 -318.599971) (xy 287.958202 -318.614504) (xy 288.00472 -318.635929) (xy 288.047686 -318.663801)
			(xy 288.067242 -318.680338) (xy 288.079257 -318.690081) (xy 288.107527 -318.702588) (xy 288.138245 -318.706056)
			(xy 288.168592 -318.700166) (xy 288.195782 -318.685458) (xy 288.206942 -318.67475) (xy 288.224956 -318.656798)
			(xy 288.264943 -318.625372) (xy 288.30875 -318.599535) (xy 288.3556 -318.579746) (xy 288.404663 -318.566355)
			(xy 288.455071 -318.5596) (xy 288.4805 -318.55918) (xy 288.508768 -318.5597) (xy 288.564687 -318.568031)
			(xy 288.618763 -318.584525) (xy 288.669812 -318.608821) (xy 288.716715 -318.640387) (xy 288.758445 -318.678531)
			(xy 288.776664 -318.70015) (xy 288.785897 -318.710728) (xy 288.808855 -318.726872) (xy 288.835338 -318.736161)
			(xy 288.86335 -318.737896) (xy 288.890777 -318.731945) (xy 288.91555 -318.718757) (xy 288.935802 -318.699328)
			(xy 288.943288 -318.68745) (xy 288.957036 -318.664741) (xy 288.990275 -318.623349) (xy 289.029292 -318.587353)
			(xy 289.073223 -318.557551) (xy 289.121093 -318.534605) (xy 289.17184 -318.519023) (xy 289.224339 -318.511151)
			(xy 289.250882 -318.510666) (xy 289.277532 -318.51119) (xy 289.330237 -318.519131) (xy 289.38117 -318.53484)
			(xy 289.429193 -318.557964) (xy 289.473232 -318.587988) (xy 289.512305 -318.62424) (xy 289.545538 -318.665911)
			(xy 289.572189 -318.71207) (xy 289.591662 -318.761685) (xy 289.603523 -318.813649) (xy 289.607506 -318.8668)
			(xy 289.605511 -318.893423) (xy 296.439072 -318.893423) (xy 296.439072 -318.840125) (xy 296.447015 -318.787421)
			(xy 296.462725 -318.736491) (xy 296.485851 -318.68847) (xy 296.515875 -318.644433) (xy 296.552127 -318.605362)
			(xy 296.593798 -318.572131) (xy 296.639956 -318.545482) (xy 296.68957 -318.52601) (xy 296.741532 -318.51415)
			(xy 296.794682 -318.510167) (xy 296.847832 -318.51415) (xy 296.899794 -318.52601) (xy 296.949408 -318.545482)
			(xy 296.995566 -318.572131) (xy 297.037237 -318.605362) (xy 297.073489 -318.644433) (xy 297.103513 -318.68847)
			(xy 297.126639 -318.736491) (xy 297.142349 -318.787421) (xy 297.150292 -318.840125) (xy 297.15079 -318.866774)
			(xy 297.150292 -318.893423) (xy 297.143172 -318.940667) (xy 298.658778 -318.940667) (xy 298.658778 -318.887369)
			(xy 298.666721 -318.834665) (xy 298.682431 -318.783735) (xy 298.705557 -318.735714) (xy 298.735581 -318.691677)
			(xy 298.771833 -318.652606) (xy 298.813504 -318.619375) (xy 298.859662 -318.592726) (xy 298.909276 -318.573254)
			(xy 298.961238 -318.561394) (xy 299.014388 -318.557411) (xy 299.067538 -318.561394) (xy 299.1195 -318.573254)
			(xy 299.169114 -318.592726) (xy 299.215272 -318.619375) (xy 299.256943 -318.652606) (xy 299.293195 -318.691677)
			(xy 299.323219 -318.735714) (xy 299.346345 -318.783735) (xy 299.362055 -318.834665) (xy 299.369998 -318.887369)
			(xy 299.370496 -318.914018) (xy 299.369998 -318.940667) (xy 299.362055 -318.993371) (xy 299.346345 -319.044301)
			(xy 299.323219 -319.092322) (xy 299.293195 -319.136359) (xy 299.256943 -319.17543) (xy 299.215272 -319.208661)
			(xy 299.169114 -319.23531) (xy 299.1195 -319.254782) (xy 299.067538 -319.266642) (xy 299.014388 -319.270626)
			(xy 298.961238 -319.266642) (xy 298.909276 -319.254782) (xy 298.859662 -319.23531) (xy 298.813504 -319.208661)
			(xy 298.771833 -319.17543) (xy 298.735581 -319.136359) (xy 298.705557 -319.092322) (xy 298.682431 -319.044301)
			(xy 298.666721 -318.993371) (xy 298.658778 -318.940667) (xy 297.143172 -318.940667) (xy 297.142349 -318.946127)
			(xy 297.126639 -318.997057) (xy 297.103513 -319.045078) (xy 297.073489 -319.089115) (xy 297.037237 -319.128186)
			(xy 296.995566 -319.161417) (xy 296.949408 -319.188066) (xy 296.899794 -319.207538) (xy 296.847832 -319.219398)
			(xy 296.794682 -319.223382) (xy 296.741532 -319.219398) (xy 296.68957 -319.207538) (xy 296.639956 -319.188066)
			(xy 296.593798 -319.161417) (xy 296.552127 -319.128186) (xy 296.515875 -319.089115) (xy 296.485851 -319.045078)
			(xy 296.462725 -318.997057) (xy 296.447015 -318.946127) (xy 296.439072 -318.893423) (xy 289.605511 -318.893423)
			(xy 289.603523 -318.919951) (xy 289.591662 -318.971915) (xy 289.572189 -319.02153) (xy 289.545538 -319.067689)
			(xy 289.512305 -319.10936) (xy 289.473232 -319.145612) (xy 289.429193 -319.175636) (xy 289.38117 -319.19876)
			(xy 289.330237 -319.214469) (xy 289.277532 -319.22241) (xy 289.250882 -319.222882) (xy 289.225599 -319.222433)
			(xy 289.17554 -319.215295) (xy 289.126993 -319.201151) (xy 289.080934 -319.180284) (xy 289.038288 -319.153115)
			(xy 288.999912 -319.120189) (xy 288.982912 -319.10147) (xy 288.973287 -319.091278) (xy 288.949741 -319.076087)
			(xy 288.922956 -319.067858) (xy 288.894943 -319.067208) (xy 288.867805 -319.074186) (xy 288.84358 -319.088268)
			(xy 288.824087 -319.108397) (xy 288.81705 -319.12052) (xy 288.802732 -319.146263) (xy 288.7673 -319.193323)
			(xy 288.725058 -319.23438) (xy 288.677008 -319.268457) (xy 288.624292 -319.294745) (xy 288.568163 -319.31262)
			(xy 288.509954 -319.321657) (xy 288.4805 -319.322196) (xy 288.450882 -319.321602) (xy 288.392357 -319.312447)
			(xy 288.33595 -319.294358) (xy 288.283016 -319.267769) (xy 288.234827 -319.233318) (xy 288.213292 -319.212976)
			(xy 288.201843 -319.202609) (xy 288.174331 -319.188612) (xy 288.143898 -319.183452) (xy 288.11331 -319.1876)
			(xy 288.085349 -319.200677) (xy 288.073592 -319.21069) (xy 288.053778 -319.228226) (xy 288.009927 -319.257832)
			(xy 287.962178 -319.280626) (xy 287.911583 -319.296107) (xy 287.859255 -319.303933) (xy 287.8328 -319.304416)
			(xy 287.806151 -319.303902) (xy 287.753449 -319.295959) (xy 287.70252 -319.280249) (xy 287.6545 -319.257124)
			(xy 287.610464 -319.227101) (xy 287.571394 -319.190849) (xy 287.538164 -319.14918) (xy 287.511515 -319.103023)
			(xy 287.492043 -319.05341) (xy 287.480183 -319.001448) (xy 287.476201 -318.9483) (xy 262.034083 -318.9483)
			(xy 262.036247 -318.955315) (xy 262.04419 -319.008019) (xy 262.044688 -319.034668) (xy 262.04419 -319.061317)
			(xy 262.036247 -319.114021) (xy 262.020537 -319.164951) (xy 261.997411 -319.212972) (xy 261.967387 -319.257009)
			(xy 261.931135 -319.29608) (xy 261.889494 -319.329287) (xy 291.379392 -319.329287) (xy 291.379392 -319.275989)
			(xy 291.387335 -319.223285) (xy 291.403045 -319.172355) (xy 291.426171 -319.124334) (xy 291.456195 -319.080297)
			(xy 291.492447 -319.041226) (xy 291.534118 -319.007995) (xy 291.580276 -318.981346) (xy 291.62989 -318.961874)
			(xy 291.681852 -318.950014) (xy 291.735002 -318.946031) (xy 291.788152 -318.950014) (xy 291.840114 -318.961874)
			(xy 291.889728 -318.981346) (xy 291.935886 -319.007995) (xy 291.977557 -319.041226) (xy 292.013809 -319.080297)
			(xy 292.043833 -319.124334) (xy 292.066959 -319.172355) (xy 292.082669 -319.223285) (xy 292.090612 -319.275989)
			(xy 292.09111 -319.302638) (xy 292.090612 -319.329287) (xy 292.082669 -319.381991) (xy 292.066959 -319.432921)
			(xy 292.043833 -319.480942) (xy 292.013809 -319.524979) (xy 291.977557 -319.56405) (xy 291.935886 -319.597281)
			(xy 291.889728 -319.62393) (xy 291.840114 -319.643402) (xy 291.788152 -319.655262) (xy 291.735002 -319.659246)
			(xy 291.681852 -319.655262) (xy 291.62989 -319.643402) (xy 291.580276 -319.62393) (xy 291.534118 -319.597281)
			(xy 291.492447 -319.56405) (xy 291.456195 -319.524979) (xy 291.426171 -319.480942) (xy 291.403045 -319.432921)
			(xy 291.387335 -319.381991) (xy 291.379392 -319.329287) (xy 261.889494 -319.329287) (xy 261.889464 -319.329311)
			(xy 261.843306 -319.35596) (xy 261.793692 -319.375432) (xy 261.74173 -319.387292) (xy 261.68858 -319.391276)
			(xy 261.63543 -319.387292) (xy 261.583468 -319.375432) (xy 261.533854 -319.35596) (xy 261.487696 -319.329311)
			(xy 261.446025 -319.29608) (xy 261.409773 -319.257009) (xy 261.379749 -319.212972) (xy 261.356623 -319.164951)
			(xy 261.340913 -319.114021) (xy 261.33297 -319.061317) (xy 259.373441 -319.061317) (xy 259.354489 -319.089115)
			(xy 259.318237 -319.128186) (xy 259.276566 -319.161417) (xy 259.230408 -319.188066) (xy 259.180794 -319.207538)
			(xy 259.128832 -319.219398) (xy 259.075682 -319.223382) (xy 259.022532 -319.219398) (xy 258.97057 -319.207538)
			(xy 258.920956 -319.188066) (xy 258.874798 -319.161417) (xy 258.833127 -319.128186) (xy 258.796875 -319.089115)
			(xy 258.766851 -319.045078) (xy 258.743725 -318.997057) (xy 258.728015 -318.946127) (xy 258.720072 -318.893423)
			(xy 254 -318.893423) (xy 254 -319.263268) (xy 254.169672 -319.263268) (xy 254.17017 -319.236619)
			(xy 254.178113 -319.183915) (xy 254.193823 -319.132985) (xy 254.216949 -319.084964) (xy 254.246973 -319.040927)
			(xy 254.283225 -319.001856) (xy 254.324896 -318.968625) (xy 254.371054 -318.941976) (xy 254.420668 -318.922504)
			(xy 254.47263 -318.910644) (xy 254.52578 -318.906661) (xy 254.57893 -318.910644) (xy 254.630892 -318.922504)
			(xy 254.680506 -318.941976) (xy 254.726664 -318.968625) (xy 254.768335 -319.001856) (xy 254.804587 -319.040927)
			(xy 254.834611 -319.084964) (xy 254.857737 -319.132985) (xy 254.873447 -319.183915) (xy 254.88139 -319.236619)
			(xy 254.881888 -319.263268) (xy 254.881704 -319.279812) (xy 254.878651 -319.312758) (xy 254.875792 -319.329054)
			(xy 254.873559 -319.343757) (xy 254.876688 -319.373316) (xy 254.888197 -319.400722) (xy 254.907109 -319.423653)
			(xy 254.931824 -319.440166) (xy 254.960247 -319.448864) (xy 254.975106 -319.44945) (xy 255.002981 -319.450222)
			(xy 255.058007 -319.459222) (xy 255.110958 -319.47669) (xy 255.160539 -319.502197) (xy 255.205539 -319.535121)
			(xy 255.244857 -319.574656) (xy 255.277532 -319.619836) (xy 255.302765 -319.669558) (xy 255.319941 -319.722604)
			(xy 255.32321 -319.743307) (xy 262.163804 -319.743307) (xy 262.163804 -319.690009) (xy 262.171747 -319.637305)
			(xy 262.187457 -319.586375) (xy 262.210583 -319.538354) (xy 262.240607 -319.494317) (xy 262.276859 -319.455246)
			(xy 262.31853 -319.422015) (xy 262.364688 -319.395366) (xy 262.414302 -319.375894) (xy 262.466264 -319.364034)
			(xy 262.519414 -319.360051) (xy 262.572564 -319.364034) (xy 262.624526 -319.375894) (xy 262.67414 -319.395366)
			(xy 262.720298 -319.422015) (xy 262.761969 -319.455246) (xy 262.798221 -319.494317) (xy 262.828245 -319.538354)
			(xy 262.851371 -319.586375) (xy 262.867081 -319.637305) (xy 262.875024 -319.690009) (xy 262.875522 -319.716658)
			(xy 262.875024 -319.743307) (xy 262.867081 -319.796011) (xy 262.852772 -319.8424) (xy 265.583856 -319.8424)
			(xy 265.58784 -319.789241) (xy 265.599703 -319.73727) (xy 265.61918 -319.687648) (xy 265.645835 -319.641483)
			(xy 265.679074 -319.599806) (xy 265.718154 -319.56355) (xy 265.762201 -319.533524) (xy 265.810232 -319.510398)
			(xy 265.861173 -319.49469) (xy 265.913886 -319.48675) (xy 265.94054 -319.48628) (xy 265.970434 -319.486922)
			(xy 266.029384 -319.496903) (xy 266.085843 -319.516578) (xy 266.138228 -319.545396) (xy 266.162028 -319.563496)
			(xy 266.17374 -319.57209) (xy 266.20061 -319.583077) (xy 266.229486 -319.586052) (xy 266.258032 -319.580775)
			(xy 266.283936 -319.567673) (xy 266.305102 -319.547806) (xy 266.312904 -319.535556) (xy 266.326713 -319.513054)
			(xy 266.359973 -319.472055) (xy 266.398924 -319.436418) (xy 266.442711 -319.406925) (xy 266.490375 -319.384222)
			(xy 266.540868 -319.368809) (xy 266.593085 -319.361024) (xy 266.619482 -319.36055) (xy 266.646131 -319.361106)
			(xy 266.698834 -319.369047) (xy 266.749764 -319.384755) (xy 266.797785 -319.407878) (xy 266.841822 -319.4379)
			(xy 266.880893 -319.474151) (xy 266.914125 -319.51582) (xy 266.940774 -319.561977) (xy 266.960247 -319.61159)
			(xy 266.972107 -319.663551) (xy 266.97609 -319.7167) (xy 266.974096 -319.743307) (xy 269.707604 -319.743307)
			(xy 269.707604 -319.690009) (xy 269.715547 -319.637305) (xy 269.731257 -319.586375) (xy 269.754383 -319.538354)
			(xy 269.784407 -319.494317) (xy 269.820659 -319.455246) (xy 269.86233 -319.422015) (xy 269.908488 -319.395366)
			(xy 269.958102 -319.375894) (xy 270.010064 -319.364034) (xy 270.063214 -319.360051) (xy 270.116364 -319.364034)
			(xy 270.168326 -319.375894) (xy 270.21794 -319.395366) (xy 270.264098 -319.422015) (xy 270.305769 -319.455246)
			(xy 270.342021 -319.494317) (xy 270.372045 -319.538354) (xy 270.395171 -319.586375) (xy 270.410881 -319.637305)
			(xy 270.418824 -319.690009) (xy 270.419322 -319.716658) (xy 270.418824 -319.743307) (xy 270.410881 -319.796011)
			(xy 270.408324 -319.8043) (xy 273.07948 -319.8043) (xy 273.083463 -319.751151) (xy 273.095323 -319.699188)
			(xy 273.114794 -319.649574) (xy 273.141443 -319.603415) (xy 273.174673 -319.561744) (xy 273.213742 -319.525491)
			(xy 273.257779 -319.495465) (xy 273.305798 -319.472338) (xy 273.356728 -319.456626) (xy 273.409431 -319.448679)
			(xy 273.43608 -319.44818) (xy 273.464857 -319.448735) (xy 273.521662 -319.457981) (xy 273.576238 -319.476252)
			(xy 273.627161 -319.503072) (xy 273.673101 -319.537739) (xy 273.693382 -319.558162) (xy 273.703036 -319.56762)
			(xy 273.726146 -319.581609) (xy 273.752118 -319.589035) (xy 273.77913 -319.589376) (xy 273.805282 -319.582608)
			(xy 273.828737 -319.569208) (xy 273.847848 -319.550116) (xy 273.854926 -319.538604) (xy 273.868632 -319.515743)
			(xy 273.901858 -319.474066) (xy 273.940927 -319.437809) (xy 273.984966 -319.407783) (xy 274.03299 -319.384658)
			(xy 274.083924 -319.368953) (xy 274.136631 -319.361017) (xy 274.163282 -319.36055) (xy 274.189931 -319.361106)
			(xy 274.242634 -319.369047) (xy 274.293564 -319.384755) (xy 274.341585 -319.407878) (xy 274.385622 -319.4379)
			(xy 274.424693 -319.474151) (xy 274.457925 -319.51582) (xy 274.484574 -319.561977) (xy 274.504047 -319.61159)
			(xy 274.515907 -319.663551) (xy 274.51989 -319.7167) (xy 274.517896 -319.743307) (xy 277.251404 -319.743307)
			(xy 277.251404 -319.690009) (xy 277.259347 -319.637305) (xy 277.275057 -319.586375) (xy 277.298183 -319.538354)
			(xy 277.328207 -319.494317) (xy 277.364459 -319.455246) (xy 277.40613 -319.422015) (xy 277.452288 -319.395366)
			(xy 277.501902 -319.375894) (xy 277.553864 -319.364034) (xy 277.607014 -319.360051) (xy 277.660164 -319.364034)
			(xy 277.712126 -319.375894) (xy 277.76174 -319.395366) (xy 277.807898 -319.422015) (xy 277.849569 -319.455246)
			(xy 277.885821 -319.494317) (xy 277.915845 -319.538354) (xy 277.938971 -319.586375) (xy 277.954681 -319.637305)
			(xy 277.962624 -319.690009) (xy 277.963122 -319.716658) (xy 277.962624 -319.743307) (xy 284.795204 -319.743307)
			(xy 284.795204 -319.690009) (xy 284.803147 -319.637305) (xy 284.818857 -319.586375) (xy 284.841983 -319.538354)
			(xy 284.872007 -319.494317) (xy 284.908259 -319.455246) (xy 284.94993 -319.422015) (xy 284.996088 -319.395366)
			(xy 285.045702 -319.375894) (xy 285.097664 -319.364034) (xy 285.150814 -319.360051) (xy 285.203964 -319.364034)
			(xy 285.255926 -319.375894) (xy 285.30554 -319.395366) (xy 285.351698 -319.422015) (xy 285.393369 -319.455246)
			(xy 285.429621 -319.494317) (xy 285.459645 -319.538354) (xy 285.482771 -319.586375) (xy 285.498481 -319.637305)
			(xy 285.506424 -319.690009) (xy 285.506922 -319.716658) (xy 285.506424 -319.743307) (xy 288.895272 -319.743307)
			(xy 288.895272 -319.690009) (xy 288.903215 -319.637305) (xy 288.918925 -319.586375) (xy 288.942051 -319.538354)
			(xy 288.972075 -319.494317) (xy 289.008327 -319.455246) (xy 289.049998 -319.422015) (xy 289.096156 -319.395366)
			(xy 289.14577 -319.375894) (xy 289.197732 -319.364034) (xy 289.250882 -319.360051) (xy 289.304032 -319.364034)
			(xy 289.355994 -319.375894) (xy 289.405608 -319.395366) (xy 289.451766 -319.422015) (xy 289.493437 -319.455246)
			(xy 289.529689 -319.494317) (xy 289.559713 -319.538354) (xy 289.582839 -319.586375) (xy 289.598549 -319.637305)
			(xy 289.606492 -319.690009) (xy 289.60699 -319.716658) (xy 289.606492 -319.743307) (xy 292.339004 -319.743307)
			(xy 292.339004 -319.690009) (xy 292.346947 -319.637305) (xy 292.362657 -319.586375) (xy 292.385783 -319.538354)
			(xy 292.415807 -319.494317) (xy 292.452059 -319.455246) (xy 292.49373 -319.422015) (xy 292.539888 -319.395366)
			(xy 292.589502 -319.375894) (xy 292.641464 -319.364034) (xy 292.694614 -319.360051) (xy 292.747764 -319.364034)
			(xy 292.799726 -319.375894) (xy 292.84934 -319.395366) (xy 292.895498 -319.422015) (xy 292.937169 -319.455246)
			(xy 292.973421 -319.494317) (xy 293.003445 -319.538354) (xy 293.026571 -319.586375) (xy 293.042281 -319.637305)
			(xy 293.050224 -319.690009) (xy 293.050722 -319.716658) (xy 293.050224 -319.743307) (xy 296.439072 -319.743307)
			(xy 296.439072 -319.690009) (xy 296.447015 -319.637305) (xy 296.462725 -319.586375) (xy 296.485851 -319.538354)
			(xy 296.515875 -319.494317) (xy 296.552127 -319.455246) (xy 296.593798 -319.422015) (xy 296.639956 -319.395366)
			(xy 296.68957 -319.375894) (xy 296.741532 -319.364034) (xy 296.794682 -319.360051) (xy 296.847832 -319.364034)
			(xy 296.899794 -319.375894) (xy 296.949408 -319.395366) (xy 296.995566 -319.422015) (xy 297.037237 -319.455246)
			(xy 297.073489 -319.494317) (xy 297.103513 -319.538354) (xy 297.126639 -319.586375) (xy 297.142349 -319.637305)
			(xy 297.150292 -319.690009) (xy 297.15079 -319.716658) (xy 297.150292 -319.743307) (xy 297.142349 -319.796011)
			(xy 297.126639 -319.846941) (xy 297.103513 -319.894962) (xy 297.073489 -319.938999) (xy 297.037237 -319.97807)
			(xy 296.995566 -320.011301) (xy 296.949408 -320.03795) (xy 296.899794 -320.057422) (xy 296.847832 -320.069282)
			(xy 296.794682 -320.073266) (xy 296.741532 -320.069282) (xy 296.68957 -320.057422) (xy 296.639956 -320.03795)
			(xy 296.593798 -320.011301) (xy 296.552127 -319.97807) (xy 296.515875 -319.938999) (xy 296.485851 -319.894962)
			(xy 296.462725 -319.846941) (xy 296.447015 -319.796011) (xy 296.439072 -319.743307) (xy 293.050224 -319.743307)
			(xy 293.042281 -319.796011) (xy 293.026571 -319.846941) (xy 293.003445 -319.894962) (xy 292.973421 -319.938999)
			(xy 292.937169 -319.97807) (xy 292.895498 -320.011301) (xy 292.84934 -320.03795) (xy 292.799726 -320.057422)
			(xy 292.747764 -320.069282) (xy 292.694614 -320.073266) (xy 292.641464 -320.069282) (xy 292.589502 -320.057422)
			(xy 292.539888 -320.03795) (xy 292.49373 -320.011301) (xy 292.452059 -319.97807) (xy 292.415807 -319.938999)
			(xy 292.385783 -319.894962) (xy 292.362657 -319.846941) (xy 292.346947 -319.796011) (xy 292.339004 -319.743307)
			(xy 289.606492 -319.743307) (xy 289.598549 -319.796011) (xy 289.582839 -319.846941) (xy 289.559713 -319.894962)
			(xy 289.529689 -319.938999) (xy 289.493437 -319.97807) (xy 289.451766 -320.011301) (xy 289.405608 -320.03795)
			(xy 289.355994 -320.057422) (xy 289.304032 -320.069282) (xy 289.250882 -320.073266) (xy 289.197732 -320.069282)
			(xy 289.14577 -320.057422) (xy 289.096156 -320.03795) (xy 289.049998 -320.011301) (xy 289.008327 -319.97807)
			(xy 288.972075 -319.938999) (xy 288.942051 -319.894962) (xy 288.918925 -319.846941) (xy 288.903215 -319.796011)
			(xy 288.895272 -319.743307) (xy 285.506424 -319.743307) (xy 285.498481 -319.796011) (xy 285.482771 -319.846941)
			(xy 285.459645 -319.894962) (xy 285.429621 -319.938999) (xy 285.393369 -319.97807) (xy 285.351698 -320.011301)
			(xy 285.30554 -320.03795) (xy 285.255926 -320.057422) (xy 285.203964 -320.069282) (xy 285.150814 -320.073266)
			(xy 285.097664 -320.069282) (xy 285.045702 -320.057422) (xy 284.996088 -320.03795) (xy 284.94993 -320.011301)
			(xy 284.908259 -319.97807) (xy 284.872007 -319.938999) (xy 284.841983 -319.894962) (xy 284.818857 -319.846941)
			(xy 284.803147 -319.796011) (xy 284.795204 -319.743307) (xy 277.962624 -319.743307) (xy 277.954681 -319.796011)
			(xy 277.938971 -319.846941) (xy 277.915845 -319.894962) (xy 277.885821 -319.938999) (xy 277.849569 -319.97807)
			(xy 277.807898 -320.011301) (xy 277.76174 -320.03795) (xy 277.712126 -320.057422) (xy 277.660164 -320.069282)
			(xy 277.607014 -320.073266) (xy 277.553864 -320.069282) (xy 277.501902 -320.057422) (xy 277.452288 -320.03795)
			(xy 277.40613 -320.011301) (xy 277.364459 -319.97807) (xy 277.328207 -319.938999) (xy 277.298183 -319.894962)
			(xy 277.275057 -319.846941) (xy 277.259347 -319.796011) (xy 277.251404 -319.743307) (xy 274.517896 -319.743307)
			(xy 274.515907 -319.769849) (xy 274.504047 -319.82181) (xy 274.484574 -319.871423) (xy 274.457925 -319.91758)
			(xy 274.424693 -319.959249) (xy 274.385622 -319.9955) (xy 274.341585 -320.025522) (xy 274.293564 -320.048645)
			(xy 274.242634 -320.064353) (xy 274.189931 -320.072294) (xy 274.163282 -320.072766) (xy 274.134503 -320.072252)
			(xy 274.077695 -320.062998) (xy 274.023118 -320.044718) (xy 273.972196 -320.017889) (xy 273.926259 -319.983212)
			(xy 273.90598 -319.962784) (xy 273.896355 -319.953296) (xy 273.873237 -319.939318) (xy 273.847258 -319.931901)
			(xy 273.820244 -319.931567) (xy 273.79409 -319.938338) (xy 273.770633 -319.95174) (xy 273.751517 -319.970831)
			(xy 273.744436 -319.982342) (xy 273.730704 -320.005186) (xy 273.69748 -320.04686) (xy 273.658414 -320.083117)
			(xy 273.61438 -320.113144) (xy 273.609661 -320.115417) (xy 299.83429 -320.115417) (xy 299.83429 -320.062119)
			(xy 299.842233 -320.009415) (xy 299.857943 -319.958485) (xy 299.881069 -319.910464) (xy 299.911093 -319.866427)
			(xy 299.947345 -319.827356) (xy 299.989016 -319.794125) (xy 300.035174 -319.767476) (xy 300.084788 -319.748004)
			(xy 300.13675 -319.736144) (xy 300.1899 -319.732161) (xy 300.24305 -319.736144) (xy 300.295012 -319.748004)
			(xy 300.344626 -319.767476) (xy 300.390784 -319.794125) (xy 300.432455 -319.827356) (xy 300.468707 -319.866427)
			(xy 300.498731 -319.910464) (xy 300.521857 -319.958485) (xy 300.537567 -320.009415) (xy 300.54551 -320.062119)
			(xy 300.546008 -320.088768) (xy 300.54551 -320.115417) (xy 300.537567 -320.168121) (xy 300.521857 -320.219051)
			(xy 300.498731 -320.267072) (xy 300.468707 -320.311109) (xy 300.432455 -320.35018) (xy 300.390784 -320.383411)
			(xy 300.344626 -320.41006) (xy 300.295012 -320.429532) (xy 300.24305 -320.441392) (xy 300.1899 -320.445376)
			(xy 300.13675 -320.441392) (xy 300.084788 -320.429532) (xy 300.035174 -320.41006) (xy 299.989016 -320.383411)
			(xy 299.947345 -320.35018) (xy 299.911093 -320.311109) (xy 299.881069 -320.267072) (xy 299.857943 -320.219051)
			(xy 299.842233 -320.168121) (xy 299.83429 -320.115417) (xy 273.609661 -320.115417) (xy 273.566361 -320.136271)
			(xy 273.515432 -320.151982) (xy 273.462729 -320.159924) (xy 273.43608 -320.160396) (xy 273.409431 -320.159921)
			(xy 273.356728 -320.151974) (xy 273.305798 -320.136262) (xy 273.257779 -320.113135) (xy 273.213742 -320.083109)
			(xy 273.174673 -320.046856) (xy 273.141443 -320.005185) (xy 273.114794 -319.959026) (xy 273.095323 -319.909412)
			(xy 273.083463 -319.857449) (xy 273.07948 -319.8043) (xy 270.408324 -319.8043) (xy 270.395171 -319.846941)
			(xy 270.372045 -319.894962) (xy 270.342021 -319.938999) (xy 270.305769 -319.97807) (xy 270.264098 -320.011301)
			(xy 270.21794 -320.03795) (xy 270.168326 -320.057422) (xy 270.116364 -320.069282) (xy 270.063214 -320.073266)
			(xy 270.010064 -320.069282) (xy 269.958102 -320.057422) (xy 269.908488 -320.03795) (xy 269.86233 -320.011301)
			(xy 269.820659 -319.97807) (xy 269.784407 -319.938999) (xy 269.754383 -319.894962) (xy 269.731257 -319.846941)
			(xy 269.715547 -319.796011) (xy 269.707604 -319.743307) (xy 266.974096 -319.743307) (xy 266.972107 -319.769849)
			(xy 266.960247 -319.82181) (xy 266.940774 -319.871423) (xy 266.914125 -319.91758) (xy 266.880893 -319.959249)
			(xy 266.841822 -319.9955) (xy 266.797785 -320.025522) (xy 266.749764 -320.048645) (xy 266.698834 -320.064353)
			(xy 266.646131 -320.072294) (xy 266.619482 -320.072766) (xy 266.589586 -320.072156) (xy 266.530636 -320.062164)
			(xy 266.474177 -320.042479) (xy 266.421793 -320.013653) (xy 266.397994 -319.99555) (xy 266.386351 -319.986854)
			(xy 266.359458 -319.97587) (xy 266.33056 -319.972906) (xy 266.301997 -319.978202) (xy 266.276083 -319.99133)
			(xy 266.254916 -320.011225) (xy 266.247118 -320.02349) (xy 266.233311 -320.045992) (xy 266.200049 -320.086989)
			(xy 266.161097 -320.122625) (xy 266.117309 -320.152117) (xy 266.069646 -320.174819) (xy 266.019153 -320.190233)
			(xy 265.966937 -320.198021) (xy 265.94054 -320.198496) (xy 265.913886 -320.19805) (xy 265.861173 -320.19011)
			(xy 265.810232 -320.174402) (xy 265.762201 -320.151276) (xy 265.718154 -320.12125) (xy 265.679074 -320.084994)
			(xy 265.645835 -320.043317) (xy 265.61918 -319.997152) (xy 265.599703 -319.94753) (xy 265.58784 -319.895559)
			(xy 265.583856 -319.8424) (xy 262.852772 -319.8424) (xy 262.851371 -319.846941) (xy 262.828245 -319.894962)
			(xy 262.798221 -319.938999) (xy 262.761969 -319.97807) (xy 262.720298 -320.011301) (xy 262.67414 -320.03795)
			(xy 262.624526 -320.057422) (xy 262.572564 -320.069282) (xy 262.519414 -320.073266) (xy 262.466264 -320.069282)
			(xy 262.414302 -320.057422) (xy 262.364688 -320.03795) (xy 262.31853 -320.011301) (xy 262.276859 -319.97807)
			(xy 262.240607 -319.938999) (xy 262.210583 -319.894962) (xy 262.187457 -319.846941) (xy 262.171747 -319.796011)
			(xy 262.163804 -319.743307) (xy 255.32321 -319.743307) (xy 255.328638 -319.777679) (xy 255.329182 -319.805558)
			(xy 255.328751 -319.830452) (xy 255.321821 -319.879756) (xy 255.30809 -319.927613) (xy 255.287826 -319.973091)
			(xy 255.261423 -320.015303) (xy 255.229398 -320.053424) (xy 255.192374 -320.086713) (xy 255.171956 -320.10096)
			(xy 255.160359 -320.109349) (xy 255.141923 -320.131224) (xy 255.130284 -320.157356) (xy 255.126355 -320.185692)
			(xy 255.130446 -320.214005) (xy 255.142234 -320.24007) (xy 255.160795 -320.261838) (xy 255.172464 -320.270124)
			(xy 255.19313 -320.284312) (xy 255.230606 -320.317604) (xy 255.263041 -320.355825) (xy 255.289795 -320.398217)
			(xy 255.310337 -320.443944) (xy 255.324262 -320.492099) (xy 255.331294 -320.541732) (xy 255.331722 -320.566796)
			(xy 255.331224 -320.593445) (xy 258.720072 -320.593445) (xy 258.720072 -320.540147) (xy 258.728015 -320.487443)
			(xy 258.743725 -320.436513) (xy 258.766851 -320.388492) (xy 258.796875 -320.344455) (xy 258.833127 -320.305384)
			(xy 258.874798 -320.272153) (xy 258.920956 -320.245504) (xy 258.97057 -320.226032) (xy 259.022532 -320.214172)
			(xy 259.075682 -320.210189) (xy 259.128832 -320.214172) (xy 259.180794 -320.226032) (xy 259.230408 -320.245504)
			(xy 259.276566 -320.272153) (xy 259.318237 -320.305384) (xy 259.354489 -320.344455) (xy 259.384513 -320.388492)
			(xy 259.388782 -320.397357) (xy 261.47521 -320.397357) (xy 261.47521 -320.344059) (xy 261.483153 -320.291355)
			(xy 261.498863 -320.240425) (xy 261.521989 -320.192404) (xy 261.552013 -320.148367) (xy 261.588265 -320.109296)
			(xy 261.629936 -320.076065) (xy 261.676094 -320.049416) (xy 261.725708 -320.029944) (xy 261.77767 -320.018084)
			(xy 261.83082 -320.014101) (xy 261.88397 -320.018084) (xy 261.935932 -320.029944) (xy 261.985546 -320.049416)
			(xy 262.031704 -320.076065) (xy 262.073375 -320.109296) (xy 262.109627 -320.148367) (xy 262.139651 -320.192404)
			(xy 262.162777 -320.240425) (xy 262.178487 -320.291355) (xy 262.18643 -320.344059) (xy 262.186928 -320.370708)
			(xy 262.18643 -320.397357) (xy 262.178487 -320.450061) (xy 262.162777 -320.500991) (xy 262.139651 -320.549012)
			(xy 262.109627 -320.593049) (xy 262.073375 -320.63212) (xy 262.031704 -320.665351) (xy 261.985546 -320.692)
			(xy 261.935932 -320.711472) (xy 261.88397 -320.723332) (xy 261.83082 -320.727316) (xy 261.77767 -320.723332)
			(xy 261.725708 -320.711472) (xy 261.676094 -320.692) (xy 261.629936 -320.665351) (xy 261.588265 -320.63212)
			(xy 261.552013 -320.593049) (xy 261.521989 -320.549012) (xy 261.498863 -320.500991) (xy 261.483153 -320.450061)
			(xy 261.47521 -320.397357) (xy 259.388782 -320.397357) (xy 259.407639 -320.436513) (xy 259.423349 -320.487443)
			(xy 259.431292 -320.540147) (xy 259.43179 -320.566796) (xy 259.431292 -320.593445) (xy 259.423349 -320.646149)
			(xy 259.407639 -320.697079) (xy 259.384513 -320.7451) (xy 259.354489 -320.789137) (xy 259.318237 -320.828208)
			(xy 259.276566 -320.861439) (xy 259.230408 -320.888088) (xy 259.180794 -320.90756) (xy 259.128832 -320.91942)
			(xy 259.075682 -320.923404) (xy 259.022532 -320.91942) (xy 258.97057 -320.90756) (xy 258.920956 -320.888088)
			(xy 258.874798 -320.861439) (xy 258.833127 -320.828208) (xy 258.796875 -320.789137) (xy 258.766851 -320.7451)
			(xy 258.743725 -320.697079) (xy 258.728015 -320.646149) (xy 258.720072 -320.593445) (xy 255.331224 -320.593445)
			(xy 255.323281 -320.646149) (xy 255.307571 -320.697079) (xy 255.284445 -320.7451) (xy 255.254421 -320.789137)
			(xy 255.218169 -320.828208) (xy 255.176498 -320.861439) (xy 255.13034 -320.888088) (xy 255.080726 -320.90756)
			(xy 255.028764 -320.91942) (xy 254.975614 -320.923404) (xy 254.922464 -320.91942) (xy 254.870502 -320.90756)
			(xy 254.820888 -320.888088) (xy 254.77473 -320.861439) (xy 254.733059 -320.828208) (xy 254.696807 -320.789137)
			(xy 254.666783 -320.7451) (xy 254.643657 -320.697079) (xy 254.627947 -320.646149) (xy 254.620004 -320.593445)
			(xy 254.619506 -320.566796) (xy 254.619907 -320.541901) (xy 254.626843 -320.492596) (xy 254.64058 -320.444738)
			(xy 254.660849 -320.39926) (xy 254.687256 -320.35705) (xy 254.719285 -320.318929) (xy 254.756312 -320.285641)
			(xy 254.776732 -320.271394) (xy 254.788365 -320.263057) (xy 254.806786 -320.241165) (xy 254.818413 -320.215024)
			(xy 254.822332 -320.186683) (xy 254.818237 -320.158367) (xy 254.806448 -320.132298) (xy 254.787891 -320.110521)
			(xy 254.776224 -320.10223) (xy 254.75558 -320.088011) (xy 254.718104 -320.054723) (xy 254.685668 -320.016508)
			(xy 254.658912 -319.974121) (xy 254.638366 -319.9284) (xy 254.624436 -319.880249) (xy 254.617398 -319.830621)
			(xy 254.616966 -319.805558) (xy 254.617155 -319.789014) (xy 254.620205 -319.756068) (xy 254.623062 -319.739772)
			(xy 254.625313 -319.725069) (xy 254.62219 -319.695504) (xy 254.610681 -319.668093) (xy 254.591764 -319.645158)
			(xy 254.567042 -319.628646) (xy 254.53861 -319.619956) (xy 254.523748 -319.619376) (xy 254.495868 -319.61872)
			(xy 254.440833 -319.60971) (xy 254.387875 -319.592232) (xy 254.338289 -319.566712) (xy 254.293286 -319.533775)
			(xy 254.253968 -319.494227) (xy 254.221295 -319.449032) (xy 254.196067 -319.399298) (xy 254.178898 -319.346239)
			(xy 254.170211 -319.291152) (xy 254.169672 -319.263268) (xy 254 -319.263268) (xy 254 -320.953617)
			(xy 265.05661 -320.953617) (xy 265.05661 -320.900319) (xy 265.064553 -320.847615) (xy 265.080263 -320.796685)
			(xy 265.103389 -320.748664) (xy 265.133413 -320.704627) (xy 265.169665 -320.665556) (xy 265.211336 -320.632325)
			(xy 265.257494 -320.605676) (xy 265.307108 -320.586204) (xy 265.35907 -320.574344) (xy 265.41222 -320.570361)
			(xy 265.46537 -320.574344) (xy 265.517332 -320.586204) (xy 265.535782 -320.593445) (xy 266.263872 -320.593445)
			(xy 266.263872 -320.540147) (xy 266.271815 -320.487443) (xy 266.287525 -320.436513) (xy 266.310651 -320.388492)
			(xy 266.340675 -320.344455) (xy 266.376927 -320.305384) (xy 266.418598 -320.272153) (xy 266.464756 -320.245504)
			(xy 266.51437 -320.226032) (xy 266.566332 -320.214172) (xy 266.619482 -320.210189) (xy 266.672632 -320.214172)
			(xy 266.724594 -320.226032) (xy 266.774208 -320.245504) (xy 266.820366 -320.272153) (xy 266.862037 -320.305384)
			(xy 266.898289 -320.344455) (xy 266.928313 -320.388492) (xy 266.951439 -320.436513) (xy 266.967149 -320.487443)
			(xy 266.975092 -320.540147) (xy 266.97559 -320.566796) (xy 266.975092 -320.593445) (xy 269.22221 -320.593445)
			(xy 269.22221 -320.540147) (xy 269.230153 -320.487443) (xy 269.245863 -320.436513) (xy 269.268989 -320.388492)
			(xy 269.299013 -320.344455) (xy 269.335265 -320.305384) (xy 269.376936 -320.272153) (xy 269.423094 -320.245504)
			(xy 269.472708 -320.226032) (xy 269.52467 -320.214172) (xy 269.57782 -320.210189) (xy 269.63097 -320.214172)
			(xy 269.682932 -320.226032) (xy 269.732546 -320.245504) (xy 269.778704 -320.272153) (xy 269.820375 -320.305384)
			(xy 269.856627 -320.344455) (xy 269.886651 -320.388492) (xy 269.909777 -320.436513) (xy 269.925487 -320.487443)
			(xy 269.93343 -320.540147) (xy 269.933928 -320.566796) (xy 269.93343 -320.593445) (xy 273.807672 -320.593445)
			(xy 273.807672 -320.540147) (xy 273.815615 -320.487443) (xy 273.831325 -320.436513) (xy 273.854451 -320.388492)
			(xy 273.884475 -320.344455) (xy 273.920727 -320.305384) (xy 273.962398 -320.272153) (xy 274.008556 -320.245504)
			(xy 274.05817 -320.226032) (xy 274.110132 -320.214172) (xy 274.163282 -320.210189) (xy 274.216432 -320.214172)
			(xy 274.268394 -320.226032) (xy 274.318008 -320.245504) (xy 274.364166 -320.272153) (xy 274.405837 -320.305384)
			(xy 274.442089 -320.344455) (xy 274.472113 -320.388492) (xy 274.495239 -320.436513) (xy 274.510949 -320.487443)
			(xy 274.518892 -320.540147) (xy 274.51939 -320.566796) (xy 274.518892 -320.593445) (xy 276.75839 -320.593445)
			(xy 276.75839 -320.540147) (xy 276.766333 -320.487443) (xy 276.782043 -320.436513) (xy 276.805169 -320.388492)
			(xy 276.835193 -320.344455) (xy 276.871445 -320.305384) (xy 276.913116 -320.272153) (xy 276.959274 -320.245504)
			(xy 277.008888 -320.226032) (xy 277.06085 -320.214172) (xy 277.114 -320.210189) (xy 277.16715 -320.214172)
			(xy 277.219112 -320.226032) (xy 277.268726 -320.245504) (xy 277.314884 -320.272153) (xy 277.356555 -320.305384)
			(xy 277.392807 -320.344455) (xy 277.422831 -320.388492) (xy 277.445957 -320.436513) (xy 277.461667 -320.487443)
			(xy 277.46961 -320.540147) (xy 277.470108 -320.566796) (xy 277.46961 -320.593445) (xy 277.461667 -320.646149)
			(xy 277.445957 -320.697079) (xy 277.422831 -320.7451) (xy 277.392807 -320.789137) (xy 277.356555 -320.828208)
			(xy 277.314884 -320.861439) (xy 277.268726 -320.888088) (xy 277.219112 -320.90756) (xy 277.16715 -320.91942)
			(xy 277.114 -320.923404) (xy 277.06085 -320.91942) (xy 277.008888 -320.90756) (xy 276.959274 -320.888088)
			(xy 276.913116 -320.861439) (xy 276.871445 -320.828208) (xy 276.835193 -320.789137) (xy 276.805169 -320.7451)
			(xy 276.782043 -320.697079) (xy 276.766333 -320.646149) (xy 276.75839 -320.593445) (xy 274.518892 -320.593445)
			(xy 274.510949 -320.646149) (xy 274.495239 -320.697079) (xy 274.472113 -320.7451) (xy 274.442089 -320.789137)
			(xy 274.405837 -320.828208) (xy 274.364166 -320.861439) (xy 274.318008 -320.888088) (xy 274.268394 -320.90756)
			(xy 274.216432 -320.91942) (xy 274.163282 -320.923404) (xy 274.110132 -320.91942) (xy 274.05817 -320.90756)
			(xy 274.008556 -320.888088) (xy 273.962398 -320.861439) (xy 273.920727 -320.828208) (xy 273.884475 -320.789137)
			(xy 273.854451 -320.7451) (xy 273.831325 -320.697079) (xy 273.815615 -320.646149) (xy 273.807672 -320.593445)
			(xy 269.93343 -320.593445) (xy 269.925487 -320.646149) (xy 269.909777 -320.697079) (xy 269.886651 -320.7451)
			(xy 269.856627 -320.789137) (xy 269.820375 -320.828208) (xy 269.778704 -320.861439) (xy 269.732546 -320.888088)
			(xy 269.682932 -320.90756) (xy 269.63097 -320.91942) (xy 269.57782 -320.923404) (xy 269.52467 -320.91942)
			(xy 269.472708 -320.90756) (xy 269.423094 -320.888088) (xy 269.376936 -320.861439) (xy 269.335265 -320.828208)
			(xy 269.299013 -320.789137) (xy 269.268989 -320.7451) (xy 269.245863 -320.697079) (xy 269.230153 -320.646149)
			(xy 269.22221 -320.593445) (xy 266.975092 -320.593445) (xy 266.967149 -320.646149) (xy 266.951439 -320.697079)
			(xy 266.928313 -320.7451) (xy 266.898289 -320.789137) (xy 266.862037 -320.828208) (xy 266.820366 -320.861439)
			(xy 266.774208 -320.888088) (xy 266.724594 -320.90756) (xy 266.672632 -320.91942) (xy 266.619482 -320.923404)
			(xy 266.566332 -320.91942) (xy 266.51437 -320.90756) (xy 266.464756 -320.888088) (xy 266.418598 -320.861439)
			(xy 266.376927 -320.828208) (xy 266.340675 -320.789137) (xy 266.310651 -320.7451) (xy 266.287525 -320.697079)
			(xy 266.271815 -320.646149) (xy 266.263872 -320.593445) (xy 265.535782 -320.593445) (xy 265.566946 -320.605676)
			(xy 265.613104 -320.632325) (xy 265.654775 -320.665556) (xy 265.691027 -320.704627) (xy 265.721051 -320.748664)
			(xy 265.744177 -320.796685) (xy 265.759887 -320.847615) (xy 265.76783 -320.900319) (xy 265.768328 -320.926968)
			(xy 265.76783 -320.953617) (xy 265.759887 -321.006321) (xy 265.756557 -321.017117) (xy 272.56231 -321.017117)
			(xy 272.56231 -320.963819) (xy 272.570253 -320.911115) (xy 272.585963 -320.860185) (xy 272.609089 -320.812164)
			(xy 272.639113 -320.768127) (xy 272.675365 -320.729056) (xy 272.717036 -320.695825) (xy 272.763194 -320.669176)
			(xy 272.812808 -320.649704) (xy 272.86477 -320.637844) (xy 272.91792 -320.633861) (xy 272.97107 -320.637844)
			(xy 273.023032 -320.649704) (xy 273.072646 -320.669176) (xy 273.118804 -320.695825) (xy 273.160475 -320.729056)
			(xy 273.196727 -320.768127) (xy 273.226751 -320.812164) (xy 273.249877 -320.860185) (xy 273.265587 -320.911115)
			(xy 273.27353 -320.963819) (xy 273.273861 -320.981557) (xy 279.94101 -320.981557) (xy 279.94101 -320.928259)
			(xy 279.948953 -320.875555) (xy 279.964663 -320.824625) (xy 279.987789 -320.776604) (xy 280.017813 -320.732567)
			(xy 280.054065 -320.693496) (xy 280.095736 -320.660265) (xy 280.141894 -320.633616) (xy 280.191508 -320.614144)
			(xy 280.24347 -320.602284) (xy 280.29662 -320.598301) (xy 280.34977 -320.602284) (xy 280.401732 -320.614144)
			(xy 280.451346 -320.633616) (xy 280.497504 -320.660265) (xy 280.539175 -320.693496) (xy 280.575427 -320.732567)
			(xy 280.605451 -320.776604) (xy 280.614256 -320.794888) (xy 281.342592 -320.794888) (xy 281.34309 -320.768239)
			(xy 281.351033 -320.715535) (xy 281.366743 -320.664605) (xy 281.389869 -320.616584) (xy 281.419893 -320.572547)
			(xy 281.456145 -320.533476) (xy 281.497816 -320.500245) (xy 281.543974 -320.473596) (xy 281.593588 -320.454124)
			(xy 281.64555 -320.442264) (xy 281.6987 -320.438281) (xy 281.75185 -320.442264) (xy 281.803812 -320.454124)
			(xy 281.853426 -320.473596) (xy 281.899584 -320.500245) (xy 281.941255 -320.533476) (xy 281.963793 -320.557767)
			(xy 284.326682 -320.557767) (xy 284.332162 -320.503885) (xy 284.345737 -320.451453) (xy 284.367095 -320.401682)
			(xy 284.395743 -320.355719) (xy 284.431022 -320.314625) (xy 284.472116 -320.279346) (xy 284.518079 -320.250697)
			(xy 284.567849 -320.229338) (xy 284.620281 -320.215762) (xy 284.674163 -320.210283) (xy 284.728254 -320.213025)
			(xy 284.781305 -320.223927) (xy 284.832094 -320.242737) (xy 284.879449 -320.269021) (xy 284.922278 -320.302172)
			(xy 284.959593 -320.341427) (xy 284.990534 -320.385879) (xy 285.014386 -320.434504) (xy 285.0306 -320.48618)
			(xy 285.038802 -320.539716) (xy 285.039308 -320.566796) (xy 285.038872 -320.592492) (xy 285.03149 -320.64335)
			(xy 285.016892 -320.692625) (xy 285.006542 -320.716148) (xy 285.000606 -320.73027) (xy 284.996587 -320.760625)
			(xy 285.001747 -320.790806) (xy 285.015621 -320.818102) (xy 285.036963 -320.840058) (xy 285.063853 -320.854702)
			(xy 285.093876 -320.860717) (xy 285.109158 -320.859658) (xy 285.14548 -320.85788) (xy 285.172562 -320.858376)
			(xy 285.226102 -320.866575) (xy 285.277784 -320.882788) (xy 285.326414 -320.906639) (xy 285.370871 -320.937579)
			(xy 285.410131 -320.974895) (xy 285.443287 -321.017726) (xy 285.469575 -321.065083) (xy 285.486155 -321.109848)
			(xy 288.690812 -321.109848) (xy 288.691276 -321.083011) (xy 288.699318 -321.029943) (xy 288.715243 -320.978686)
			(xy 288.738687 -320.930403) (xy 288.76912 -320.88619) (xy 288.80585 -320.847052) (xy 288.848044 -320.813877)
			(xy 288.871152 -320.800222) (xy 288.883314 -320.792712) (xy 288.903247 -320.772242) (xy 288.916742 -320.747059)
			(xy 288.922747 -320.719126) (xy 288.920794 -320.690622) (xy 288.916364 -320.677032) (xy 288.906279 -320.647501)
			(xy 288.895422 -320.586056) (xy 288.894774 -320.554858) (xy 288.895272 -320.528209) (xy 288.903215 -320.475505)
			(xy 288.918925 -320.424575) (xy 288.942051 -320.376554) (xy 288.972075 -320.332517) (xy 289.008327 -320.293446)
			(xy 289.049998 -320.260215) (xy 289.096156 -320.233566) (xy 289.14577 -320.214094) (xy 289.197732 -320.202234)
			(xy 289.250882 -320.198251) (xy 289.304032 -320.202234) (xy 289.355994 -320.214094) (xy 289.405608 -320.233566)
			(xy 289.451766 -320.260215) (xy 289.493437 -320.293446) (xy 289.529689 -320.332517) (xy 289.559713 -320.376554)
			(xy 289.582839 -320.424575) (xy 289.598549 -320.475505) (xy 289.606492 -320.528209) (xy 289.60699 -320.554858)
			(xy 289.60653 -320.581695) (xy 289.604749 -320.593445) (xy 291.84599 -320.593445) (xy 291.84599 -320.540147)
			(xy 291.853933 -320.487443) (xy 291.869643 -320.436513) (xy 291.892769 -320.388492) (xy 291.922793 -320.344455)
			(xy 291.959045 -320.305384) (xy 292.000716 -320.272153) (xy 292.046874 -320.245504) (xy 292.096488 -320.226032)
			(xy 292.14845 -320.214172) (xy 292.2016 -320.210189) (xy 292.25475 -320.214172) (xy 292.306712 -320.226032)
			(xy 292.356326 -320.245504) (xy 292.402484 -320.272153) (xy 292.444155 -320.305384) (xy 292.480407 -320.344455)
			(xy 292.510431 -320.388492) (xy 292.533557 -320.436513) (xy 292.549267 -320.487443) (xy 292.55721 -320.540147)
			(xy 292.557708 -320.566796) (xy 292.55721 -320.593445) (xy 296.439072 -320.593445) (xy 296.439072 -320.540147)
			(xy 296.447015 -320.487443) (xy 296.462725 -320.436513) (xy 296.485851 -320.388492) (xy 296.515875 -320.344455)
			(xy 296.552127 -320.305384) (xy 296.593798 -320.272153) (xy 296.639956 -320.245504) (xy 296.68957 -320.226032)
			(xy 296.741532 -320.214172) (xy 296.794682 -320.210189) (xy 296.847832 -320.214172) (xy 296.899794 -320.226032)
			(xy 296.949408 -320.245504) (xy 296.995566 -320.272153) (xy 297.037237 -320.305384) (xy 297.073489 -320.344455)
			(xy 297.103513 -320.388492) (xy 297.126639 -320.436513) (xy 297.142349 -320.487443) (xy 297.150292 -320.540147)
			(xy 297.15079 -320.566796) (xy 297.150292 -320.593445) (xy 297.142349 -320.646149) (xy 297.126639 -320.697079)
			(xy 297.103513 -320.7451) (xy 297.073489 -320.789137) (xy 297.037237 -320.828208) (xy 296.995566 -320.861439)
			(xy 296.949408 -320.888088) (xy 296.899794 -320.90756) (xy 296.847832 -320.91942) (xy 296.794682 -320.923404)
			(xy 296.741532 -320.91942) (xy 296.68957 -320.90756) (xy 296.639956 -320.888088) (xy 296.593798 -320.861439)
			(xy 296.552127 -320.828208) (xy 296.515875 -320.789137) (xy 296.485851 -320.7451) (xy 296.462725 -320.697079)
			(xy 296.447015 -320.646149) (xy 296.439072 -320.593445) (xy 292.55721 -320.593445) (xy 292.549267 -320.646149)
			(xy 292.533557 -320.697079) (xy 292.510431 -320.7451) (xy 292.480407 -320.789137) (xy 292.444155 -320.828208)
			(xy 292.402484 -320.861439) (xy 292.356326 -320.888088) (xy 292.306712 -320.90756) (xy 292.25475 -320.91942)
			(xy 292.2016 -320.923404) (xy 292.14845 -320.91942) (xy 292.096488 -320.90756) (xy 292.046874 -320.888088)
			(xy 292.000716 -320.861439) (xy 291.959045 -320.828208) (xy 291.922793 -320.789137) (xy 291.892769 -320.7451)
			(xy 291.869643 -320.697079) (xy 291.853933 -320.646149) (xy 291.84599 -320.593445) (xy 289.604749 -320.593445)
			(xy 289.598487 -320.634763) (xy 289.582562 -320.686021) (xy 289.559116 -320.734304) (xy 289.528683 -320.778516)
			(xy 289.491952 -320.817654) (xy 289.449759 -320.850829) (xy 289.42665 -320.864484) (xy 289.414484 -320.871989)
			(xy 289.394551 -320.89246) (xy 289.381057 -320.917644) (xy 289.375053 -320.945579) (xy 289.377007 -320.974084)
			(xy 289.381438 -320.987674) (xy 289.391524 -321.017204) (xy 289.402381 -321.07865) (xy 289.403028 -321.109848)
			(xy 289.40253 -321.136497) (xy 289.394587 -321.189201) (xy 289.378877 -321.240131) (xy 289.355751 -321.288152)
			(xy 289.325727 -321.332189) (xy 289.289475 -321.37126) (xy 289.247804 -321.404491) (xy 289.201646 -321.43114)
			(xy 289.170589 -321.443329) (xy 292.339004 -321.443329) (xy 292.339004 -321.390031) (xy 292.346947 -321.337327)
			(xy 292.362657 -321.286397) (xy 292.385783 -321.238376) (xy 292.415807 -321.194339) (xy 292.452059 -321.155268)
			(xy 292.49373 -321.122037) (xy 292.539888 -321.095388) (xy 292.589502 -321.075916) (xy 292.641464 -321.064056)
			(xy 292.694614 -321.060073) (xy 292.747764 -321.064056) (xy 292.799726 -321.075916) (xy 292.84934 -321.095388)
			(xy 292.895498 -321.122037) (xy 292.937169 -321.155268) (xy 292.973421 -321.194339) (xy 293.003445 -321.238376)
			(xy 293.026571 -321.286397) (xy 293.042281 -321.337327) (xy 293.050224 -321.390031) (xy 293.050722 -321.41668)
			(xy 293.050224 -321.443329) (xy 296.439072 -321.443329) (xy 296.439072 -321.390031) (xy 296.447015 -321.337327)
			(xy 296.462725 -321.286397) (xy 296.485851 -321.238376) (xy 296.515875 -321.194339) (xy 296.552127 -321.155268)
			(xy 296.593798 -321.122037) (xy 296.639956 -321.095388) (xy 296.68957 -321.075916) (xy 296.741532 -321.064056)
			(xy 296.794682 -321.060073) (xy 296.847832 -321.064056) (xy 296.899794 -321.075916) (xy 296.949408 -321.095388)
			(xy 296.995566 -321.122037) (xy 297.037237 -321.155268) (xy 297.073489 -321.194339) (xy 297.103513 -321.238376)
			(xy 297.126639 -321.286397) (xy 297.142349 -321.337327) (xy 297.150292 -321.390031) (xy 297.15079 -321.41668)
			(xy 297.150292 -321.443329) (xy 297.142349 -321.496033) (xy 297.131409 -321.5315) (xy 299.155056 -321.5315)
			(xy 299.15904 -321.478343) (xy 299.170902 -321.426374) (xy 299.190377 -321.376753) (xy 299.217031 -321.330589)
			(xy 299.250268 -321.288913) (xy 299.289345 -321.252657) (xy 299.33339 -321.222631) (xy 299.381418 -321.199504)
			(xy 299.432356 -321.183794) (xy 299.485067 -321.175852) (xy 299.51172 -321.17538) (xy 299.539399 -321.175919)
			(xy 299.594091 -321.184481) (xy 299.646801 -321.201397) (xy 299.696263 -321.226259) (xy 299.741285 -321.258469)
			(xy 299.761402 -321.277488) (xy 299.771387 -321.286697) (xy 299.795056 -321.299997) (xy 299.821397 -321.306576)
			(xy 299.84854 -321.305967) (xy 299.874559 -321.298211) (xy 299.897607 -321.283861) (xy 299.916047 -321.263934)
			(xy 299.922692 -321.252088) (xy 299.936 -321.227737) (xy 299.968957 -321.183096) (xy 300.008442 -321.14411)
			(xy 300.053499 -321.111724) (xy 300.103036 -321.086722) (xy 300.155853 -321.069711) (xy 300.21067 -321.061102)
			(xy 300.238414 -321.060572) (xy 300.265061 -321.061111) (xy 300.31776 -321.069056) (xy 300.368686 -321.084766)
			(xy 300.416702 -321.107891) (xy 300.460735 -321.137914) (xy 300.499801 -321.174164) (xy 300.533029 -321.215832)
			(xy 300.559676 -321.261986) (xy 300.579146 -321.311597) (xy 300.591004 -321.363555) (xy 300.594987 -321.4167)
			(xy 300.591004 -321.469845) (xy 300.579146 -321.521803) (xy 300.559676 -321.571414) (xy 300.533029 -321.617568)
			(xy 300.499801 -321.659236) (xy 300.460735 -321.695486) (xy 300.416702 -321.725509) (xy 300.368686 -321.748634)
			(xy 300.31776 -321.764344) (xy 300.265061 -321.772289) (xy 300.238414 -321.772788) (xy 300.210733 -321.772299)
			(xy 300.156038 -321.763726) (xy 300.103327 -321.746799) (xy 300.053867 -321.721926) (xy 300.008847 -321.689704)
			(xy 299.988732 -321.67068) (xy 299.978825 -321.661378) (xy 299.955136 -321.64807) (xy 299.928774 -321.641493)
			(xy 299.901611 -321.642114) (xy 299.875576 -321.649888) (xy 299.852521 -321.664264) (xy 299.834082 -321.68422)
			(xy 299.827442 -321.69608) (xy 299.814169 -321.720451) (xy 299.781208 -321.765095) (xy 299.741718 -321.804082)
			(xy 299.696655 -321.836467) (xy 299.647112 -321.861465) (xy 299.594289 -321.87847) (xy 299.539467 -321.887071)
			(xy 299.51172 -321.887596) (xy 299.485067 -321.887148) (xy 299.432356 -321.879206) (xy 299.381418 -321.863496)
			(xy 299.33339 -321.840369) (xy 299.289345 -321.810343) (xy 299.250268 -321.774087) (xy 299.217031 -321.732411)
			(xy 299.190377 -321.686247) (xy 299.170902 -321.636626) (xy 299.15904 -321.584657) (xy 299.155056 -321.5315)
			(xy 297.131409 -321.5315) (xy 297.126639 -321.546963) (xy 297.103513 -321.594984) (xy 297.073489 -321.639021)
			(xy 297.037237 -321.678092) (xy 296.995566 -321.711323) (xy 296.949408 -321.737972) (xy 296.899794 -321.757444)
			(xy 296.847832 -321.769304) (xy 296.794682 -321.773288) (xy 296.741532 -321.769304) (xy 296.68957 -321.757444)
			(xy 296.639956 -321.737972) (xy 296.593798 -321.711323) (xy 296.552127 -321.678092) (xy 296.515875 -321.639021)
			(xy 296.485851 -321.594984) (xy 296.462725 -321.546963) (xy 296.447015 -321.496033) (xy 296.439072 -321.443329)
			(xy 293.050224 -321.443329) (xy 293.042281 -321.496033) (xy 293.026571 -321.546963) (xy 293.003445 -321.594984)
			(xy 292.973421 -321.639021) (xy 292.937169 -321.678092) (xy 292.895498 -321.711323) (xy 292.84934 -321.737972)
			(xy 292.799726 -321.757444) (xy 292.747764 -321.769304) (xy 292.694614 -321.773288) (xy 292.641464 -321.769304)
			(xy 292.589502 -321.757444) (xy 292.539888 -321.737972) (xy 292.49373 -321.711323) (xy 292.452059 -321.678092)
			(xy 292.415807 -321.639021) (xy 292.385783 -321.594984) (xy 292.362657 -321.546963) (xy 292.346947 -321.496033)
			(xy 292.339004 -321.443329) (xy 289.170589 -321.443329) (xy 289.152032 -321.450612) (xy 289.10007 -321.462472)
			(xy 289.04692 -321.466456) (xy 288.99377 -321.462472) (xy 288.941808 -321.450612) (xy 288.892194 -321.43114)
			(xy 288.846036 -321.404491) (xy 288.804365 -321.37126) (xy 288.768113 -321.332189) (xy 288.738089 -321.288152)
			(xy 288.714963 -321.240131) (xy 288.699253 -321.189201) (xy 288.69131 -321.136497) (xy 288.690812 -321.109848)
			(xy 285.486155 -321.109848) (xy 285.488388 -321.115876) (xy 285.499293 -321.168931) (xy 285.502038 -321.223026)
			(xy 285.496559 -321.276912) (xy 285.482984 -321.329348) (xy 285.461625 -321.379123) (xy 285.432975 -321.42509)
			(xy 285.397694 -321.466188) (xy 285.356597 -321.50147) (xy 285.31063 -321.530121) (xy 285.260856 -321.551481)
			(xy 285.20842 -321.565058) (xy 285.154534 -321.570538) (xy 285.100439 -321.567794) (xy 285.047383 -321.55689)
			(xy 284.996591 -321.538078) (xy 284.949233 -321.511791) (xy 284.906401 -321.478636) (xy 284.869084 -321.439378)
			(xy 284.838143 -321.394921) (xy 284.814291 -321.346291) (xy 284.798077 -321.29461) (xy 284.789877 -321.24107)
			(xy 284.789372 -321.213988) (xy 284.789804 -321.188292) (xy 284.797188 -321.137434) (xy 284.811788 -321.088159)
			(xy 284.822138 -321.064636) (xy 284.828113 -321.050528) (xy 284.83213 -321.020166) (xy 284.826967 -320.989978)
			(xy 284.813086 -320.962678) (xy 284.791737 -320.940719) (xy 284.764838 -320.926076) (xy 284.734807 -320.920064)
			(xy 284.719522 -320.921126) (xy 284.6832 -320.922904) (xy 284.65612 -320.922402) (xy 284.602584 -320.914201)
			(xy 284.550908 -320.897987) (xy 284.502282 -320.874136) (xy 284.45783 -320.843196) (xy 284.418575 -320.805881)
			(xy 284.385423 -320.763053) (xy 284.359139 -320.715698) (xy 284.340328 -320.664909) (xy 284.329426 -320.611858)
			(xy 284.326682 -320.557767) (xy 281.963793 -320.557767) (xy 281.977507 -320.572547) (xy 282.007531 -320.616584)
			(xy 282.030657 -320.664605) (xy 282.046367 -320.715535) (xy 282.05431 -320.768239) (xy 282.054808 -320.794888)
			(xy 282.054343 -320.821001) (xy 282.046717 -320.872667) (xy 282.031626 -320.922665) (xy 282.009394 -320.969922)
			(xy 281.980498 -321.013426) (xy 281.963368 -321.03314) (xy 281.953556 -321.044803) (xy 281.940685 -321.072414)
			(xy 281.936525 -321.102593) (xy 281.941447 -321.132656) (xy 281.955012 -321.159933) (xy 281.965146 -321.171316)
			(xy 281.983425 -321.191307) (xy 282.014382 -321.235754) (xy 282.038249 -321.284379) (xy 282.054474 -321.336057)
			(xy 282.062682 -321.389597) (xy 282.06319 -321.41668) (xy 282.062692 -321.443329) (xy 282.054749 -321.496033)
			(xy 282.039039 -321.546963) (xy 282.015913 -321.594984) (xy 281.985889 -321.639021) (xy 281.949637 -321.678092)
			(xy 281.907966 -321.711323) (xy 281.861808 -321.737972) (xy 281.812194 -321.757444) (xy 281.760232 -321.769304)
			(xy 281.707082 -321.773288) (xy 281.653932 -321.769304) (xy 281.60197 -321.757444) (xy 281.552356 -321.737972)
			(xy 281.506198 -321.711323) (xy 281.464527 -321.678092) (xy 281.428275 -321.639021) (xy 281.398251 -321.594984)
			(xy 281.375125 -321.546963) (xy 281.359415 -321.496033) (xy 281.351472 -321.443329) (xy 281.350974 -321.41668)
			(xy 281.351424 -321.390567) (xy 281.359055 -321.3389) (xy 281.37415 -321.288902) (xy 281.396385 -321.241645)
			(xy 281.425283 -321.198142) (xy 281.442414 -321.178428) (xy 281.452259 -321.16679) (xy 281.465129 -321.13917)
			(xy 281.469284 -321.108983) (xy 281.464353 -321.078914) (xy 281.450776 -321.051635) (xy 281.440636 -321.040252)
			(xy 281.422339 -321.020277) (xy 281.391385 -320.975825) (xy 281.367522 -320.927197) (xy 281.351301 -320.875515)
			(xy 281.343097 -320.821972) (xy 281.342592 -320.794888) (xy 280.614256 -320.794888) (xy 280.628577 -320.824625)
			(xy 280.644287 -320.875555) (xy 280.65223 -320.928259) (xy 280.652728 -320.954908) (xy 280.65223 -320.981557)
			(xy 280.644287 -321.034261) (xy 280.628577 -321.085191) (xy 280.605451 -321.133212) (xy 280.575427 -321.177249)
			(xy 280.539175 -321.21632) (xy 280.497504 -321.249551) (xy 280.451346 -321.2762) (xy 280.401732 -321.295672)
			(xy 280.34977 -321.307532) (xy 280.29662 -321.311516) (xy 280.24347 -321.307532) (xy 280.191508 -321.295672)
			(xy 280.141894 -321.2762) (xy 280.095736 -321.249551) (xy 280.054065 -321.21632) (xy 280.017813 -321.177249)
			(xy 279.987789 -321.133212) (xy 279.964663 -321.085191) (xy 279.948953 -321.034261) (xy 279.94101 -320.981557)
			(xy 273.273861 -320.981557) (xy 273.274028 -320.990468) (xy 273.27353 -321.017117) (xy 273.265587 -321.069821)
			(xy 273.249877 -321.120751) (xy 273.226751 -321.168772) (xy 273.196727 -321.212809) (xy 273.160475 -321.25188)
			(xy 273.118804 -321.285111) (xy 273.072646 -321.31176) (xy 273.023032 -321.331232) (xy 272.97107 -321.343092)
			(xy 272.91792 -321.347076) (xy 272.86477 -321.343092) (xy 272.812808 -321.331232) (xy 272.763194 -321.31176)
			(xy 272.717036 -321.285111) (xy 272.675365 -321.25188) (xy 272.639113 -321.212809) (xy 272.609089 -321.168772)
			(xy 272.585963 -321.120751) (xy 272.570253 -321.069821) (xy 272.56231 -321.017117) (xy 265.756557 -321.017117)
			(xy 265.744177 -321.057251) (xy 265.721051 -321.105272) (xy 265.691027 -321.149309) (xy 265.654775 -321.18838)
			(xy 265.613104 -321.221611) (xy 265.566946 -321.24826) (xy 265.517332 -321.267732) (xy 265.46537 -321.279592)
			(xy 265.41222 -321.283576) (xy 265.35907 -321.279592) (xy 265.307108 -321.267732) (xy 265.257494 -321.24826)
			(xy 265.211336 -321.221611) (xy 265.169665 -321.18838) (xy 265.133413 -321.149309) (xy 265.103389 -321.105272)
			(xy 265.080263 -321.057251) (xy 265.064553 -321.006321) (xy 265.05661 -320.953617) (xy 254 -320.953617)
			(xy 254 -321.443329) (xy 254.620004 -321.443329) (xy 254.620004 -321.390031) (xy 254.627947 -321.337327)
			(xy 254.643657 -321.286397) (xy 254.666783 -321.238376) (xy 254.696807 -321.194339) (xy 254.733059 -321.155268)
			(xy 254.77473 -321.122037) (xy 254.820888 -321.095388) (xy 254.870502 -321.075916) (xy 254.922464 -321.064056)
			(xy 254.975614 -321.060073) (xy 255.028764 -321.064056) (xy 255.080726 -321.075916) (xy 255.13034 -321.095388)
			(xy 255.176498 -321.122037) (xy 255.218169 -321.155268) (xy 255.254421 -321.194339) (xy 255.284445 -321.238376)
			(xy 255.307571 -321.286397) (xy 255.323281 -321.337327) (xy 255.331224 -321.390031) (xy 255.331722 -321.41668)
			(xy 255.331224 -321.443329) (xy 258.720072 -321.443329) (xy 258.720072 -321.390031) (xy 258.728015 -321.337327)
			(xy 258.743725 -321.286397) (xy 258.766851 -321.238376) (xy 258.796875 -321.194339) (xy 258.833127 -321.155268)
			(xy 258.874798 -321.122037) (xy 258.920956 -321.095388) (xy 258.97057 -321.075916) (xy 259.022532 -321.064056)
			(xy 259.075682 -321.060073) (xy 259.128832 -321.064056) (xy 259.180794 -321.075916) (xy 259.230408 -321.095388)
			(xy 259.276566 -321.122037) (xy 259.318237 -321.155268) (xy 259.354489 -321.194339) (xy 259.384513 -321.238376)
			(xy 259.407639 -321.286397) (xy 259.423349 -321.337327) (xy 259.431292 -321.390031) (xy 259.43179 -321.41668)
			(xy 259.431292 -321.443329) (xy 259.423349 -321.496033) (xy 259.407639 -321.546963) (xy 259.384513 -321.594984)
			(xy 259.354489 -321.639021) (xy 259.318237 -321.678092) (xy 259.291893 -321.6991) (xy 261.461496 -321.6991)
			(xy 261.465479 -321.645949) (xy 261.47734 -321.593985) (xy 261.496813 -321.54437) (xy 261.523464 -321.498212)
			(xy 261.556697 -321.456541) (xy 261.59577 -321.420289) (xy 261.63981 -321.390265) (xy 261.687832 -321.367141)
			(xy 261.738765 -321.351433) (xy 261.79147 -321.343492) (xy 261.81812 -321.34302) (xy 261.844355 -321.343479)
			(xy 261.896263 -321.351139) (xy 261.946479 -321.366348) (xy 261.993914 -321.388776) (xy 262.015986 -321.402964)
			(xy 262.027996 -321.410429) (xy 262.05491 -321.419073) (xy 262.083162 -321.420013) (xy 262.11059 -321.413176)
			(xy 262.135096 -321.399086) (xy 262.154803 -321.378821) (xy 262.168204 -321.353932) (xy 262.171688 -321.340226)
			(xy 262.177956 -321.314158) (xy 262.197167 -321.264107) (xy 262.223667 -321.217504) (xy 262.256856 -321.175402)
			(xy 262.295985 -321.138753) (xy 262.340167 -321.108388) (xy 262.388404 -321.084992) (xy 262.439604 -321.069095)
			(xy 262.492608 -321.061057) (xy 262.519414 -321.060572) (xy 262.546061 -321.061111) (xy 262.59876 -321.069056)
			(xy 262.649686 -321.084766) (xy 262.697702 -321.107891) (xy 262.741735 -321.137914) (xy 262.780801 -321.174164)
			(xy 262.814029 -321.215832) (xy 262.840676 -321.261986) (xy 262.860146 -321.311597) (xy 262.872004 -321.363555)
			(xy 262.875987 -321.4167) (xy 262.873991 -321.443329) (xy 266.263872 -321.443329) (xy 266.263872 -321.390031)
			(xy 266.271815 -321.337327) (xy 266.287525 -321.286397) (xy 266.310651 -321.238376) (xy 266.340675 -321.194339)
			(xy 266.376927 -321.155268) (xy 266.418598 -321.122037) (xy 266.464756 -321.095388) (xy 266.51437 -321.075916)
			(xy 266.566332 -321.064056) (xy 266.619482 -321.060073) (xy 266.672632 -321.064056) (xy 266.724594 -321.075916)
			(xy 266.774208 -321.095388) (xy 266.820366 -321.122037) (xy 266.862037 -321.155268) (xy 266.898289 -321.194339)
			(xy 266.928313 -321.238376) (xy 266.951439 -321.286397) (xy 266.967149 -321.337327) (xy 266.975092 -321.390031)
			(xy 266.97559 -321.41668) (xy 266.975092 -321.443329) (xy 269.707604 -321.443329) (xy 269.707604 -321.390031)
			(xy 269.715547 -321.337327) (xy 269.731257 -321.286397) (xy 269.754383 -321.238376) (xy 269.784407 -321.194339)
			(xy 269.820659 -321.155268) (xy 269.86233 -321.122037) (xy 269.908488 -321.095388) (xy 269.958102 -321.075916)
			(xy 270.010064 -321.064056) (xy 270.063214 -321.060073) (xy 270.116364 -321.064056) (xy 270.168326 -321.075916)
			(xy 270.21794 -321.095388) (xy 270.264098 -321.122037) (xy 270.305769 -321.155268) (xy 270.342021 -321.194339)
			(xy 270.372045 -321.238376) (xy 270.395171 -321.286397) (xy 270.410881 -321.337327) (xy 270.418824 -321.390031)
			(xy 270.419322 -321.41668) (xy 270.418824 -321.443329) (xy 273.807672 -321.443329) (xy 273.807672 -321.390031)
			(xy 273.815615 -321.337327) (xy 273.831325 -321.286397) (xy 273.854451 -321.238376) (xy 273.884475 -321.194339)
			(xy 273.920727 -321.155268) (xy 273.962398 -321.122037) (xy 274.008556 -321.095388) (xy 274.05817 -321.075916)
			(xy 274.110132 -321.064056) (xy 274.163282 -321.060073) (xy 274.216432 -321.064056) (xy 274.268394 -321.075916)
			(xy 274.318008 -321.095388) (xy 274.364166 -321.122037) (xy 274.405837 -321.155268) (xy 274.442089 -321.194339)
			(xy 274.472113 -321.238376) (xy 274.495239 -321.286397) (xy 274.510949 -321.337327) (xy 274.518892 -321.390031)
			(xy 274.51939 -321.41668) (xy 274.518892 -321.443329) (xy 277.251404 -321.443329) (xy 277.251404 -321.390031)
			(xy 277.259347 -321.337327) (xy 277.275057 -321.286397) (xy 277.298183 -321.238376) (xy 277.328207 -321.194339)
			(xy 277.364459 -321.155268) (xy 277.40613 -321.122037) (xy 277.452288 -321.095388) (xy 277.501902 -321.075916)
			(xy 277.553864 -321.064056) (xy 277.607014 -321.060073) (xy 277.660164 -321.064056) (xy 277.712126 -321.075916)
			(xy 277.76174 -321.095388) (xy 277.807898 -321.122037) (xy 277.849569 -321.155268) (xy 277.885821 -321.194339)
			(xy 277.915845 -321.238376) (xy 277.938971 -321.286397) (xy 277.954681 -321.337327) (xy 277.962624 -321.390031)
			(xy 277.963122 -321.41668) (xy 277.962624 -321.443329) (xy 277.954681 -321.496033) (xy 277.938971 -321.546963)
			(xy 277.915845 -321.594984) (xy 277.885821 -321.639021) (xy 277.849569 -321.678092) (xy 277.807898 -321.711323)
			(xy 277.76174 -321.737972) (xy 277.712126 -321.757444) (xy 277.660164 -321.769304) (xy 277.607014 -321.773288)
			(xy 277.553864 -321.769304) (xy 277.501902 -321.757444) (xy 277.452288 -321.737972) (xy 277.40613 -321.711323)
			(xy 277.364459 -321.678092) (xy 277.328207 -321.639021) (xy 277.298183 -321.594984) (xy 277.275057 -321.546963)
			(xy 277.259347 -321.496033) (xy 277.251404 -321.443329) (xy 274.518892 -321.443329) (xy 274.510949 -321.496033)
			(xy 274.495239 -321.546963) (xy 274.472113 -321.594984) (xy 274.442089 -321.639021) (xy 274.405837 -321.678092)
			(xy 274.364166 -321.711323) (xy 274.318008 -321.737972) (xy 274.268394 -321.757444) (xy 274.216432 -321.769304)
			(xy 274.163282 -321.773288) (xy 274.110132 -321.769304) (xy 274.05817 -321.757444) (xy 274.008556 -321.737972)
			(xy 273.962398 -321.711323) (xy 273.920727 -321.678092) (xy 273.884475 -321.639021) (xy 273.854451 -321.594984)
			(xy 273.831325 -321.546963) (xy 273.815615 -321.496033) (xy 273.807672 -321.443329) (xy 270.418824 -321.443329)
			(xy 270.410881 -321.496033) (xy 270.395171 -321.546963) (xy 270.372045 -321.594984) (xy 270.342021 -321.639021)
			(xy 270.305769 -321.678092) (xy 270.264098 -321.711323) (xy 270.21794 -321.737972) (xy 270.168326 -321.757444)
			(xy 270.116364 -321.769304) (xy 270.063214 -321.773288) (xy 270.010064 -321.769304) (xy 269.958102 -321.757444)
			(xy 269.908488 -321.737972) (xy 269.86233 -321.711323) (xy 269.820659 -321.678092) (xy 269.784407 -321.639021)
			(xy 269.754383 -321.594984) (xy 269.731257 -321.546963) (xy 269.715547 -321.496033) (xy 269.707604 -321.443329)
			(xy 266.975092 -321.443329) (xy 266.967149 -321.496033) (xy 266.951439 -321.546963) (xy 266.928313 -321.594984)
			(xy 266.898289 -321.639021) (xy 266.862037 -321.678092) (xy 266.820366 -321.711323) (xy 266.774208 -321.737972)
			(xy 266.724594 -321.757444) (xy 266.672632 -321.769304) (xy 266.619482 -321.773288) (xy 266.566332 -321.769304)
			(xy 266.51437 -321.757444) (xy 266.464756 -321.737972) (xy 266.418598 -321.711323) (xy 266.376927 -321.678092)
			(xy 266.340675 -321.639021) (xy 266.310651 -321.594984) (xy 266.287525 -321.546963) (xy 266.271815 -321.496033)
			(xy 266.263872 -321.443329) (xy 262.873991 -321.443329) (xy 262.872004 -321.469845) (xy 262.860146 -321.521803)
			(xy 262.840676 -321.571414) (xy 262.814029 -321.617568) (xy 262.780801 -321.659236) (xy 262.741735 -321.695486)
			(xy 262.697702 -321.725509) (xy 262.649686 -321.748634) (xy 262.59876 -321.764344) (xy 262.546061 -321.772289)
			(xy 262.519414 -321.772788) (xy 262.493178 -321.77236) (xy 262.441269 -321.764691) (xy 262.391052 -321.749473)
			(xy 262.343619 -321.727037) (xy 262.321548 -321.712844) (xy 262.309516 -321.705416) (xy 262.28261 -321.696766)
			(xy 262.254363 -321.69582) (xy 262.226938 -321.70265) (xy 262.202434 -321.716735) (xy 262.182729 -321.736995)
			(xy 262.169329 -321.761879) (xy 262.165846 -321.775582) (xy 262.159644 -321.801668) (xy 262.140428 -321.851723)
			(xy 262.113921 -321.898329) (xy 262.080723 -321.940433) (xy 262.041586 -321.977081) (xy 261.997395 -322.007444)
			(xy 261.949149 -322.030835) (xy 261.897941 -322.046726) (xy 261.844929 -322.054756) (xy 261.81812 -322.055236)
			(xy 261.79147 -322.054708) (xy 261.738765 -322.046767) (xy 261.687832 -322.031059) (xy 261.63981 -322.007935)
			(xy 261.59577 -321.977911) (xy 261.556697 -321.941659) (xy 261.523464 -321.899988) (xy 261.496813 -321.85383)
			(xy 261.47734 -321.804215) (xy 261.465479 -321.752251) (xy 261.461496 -321.6991) (xy 259.291893 -321.6991)
			(xy 259.276566 -321.711323) (xy 259.230408 -321.737972) (xy 259.180794 -321.757444) (xy 259.128832 -321.769304)
			(xy 259.075682 -321.773288) (xy 259.022532 -321.769304) (xy 258.97057 -321.757444) (xy 258.920956 -321.737972)
			(xy 258.874798 -321.711323) (xy 258.833127 -321.678092) (xy 258.796875 -321.639021) (xy 258.766851 -321.594984)
			(xy 258.743725 -321.546963) (xy 258.728015 -321.496033) (xy 258.720072 -321.443329) (xy 255.331224 -321.443329)
			(xy 255.323281 -321.496033) (xy 255.307571 -321.546963) (xy 255.284445 -321.594984) (xy 255.254421 -321.639021)
			(xy 255.218169 -321.678092) (xy 255.176498 -321.711323) (xy 255.13034 -321.737972) (xy 255.080726 -321.757444)
			(xy 255.028764 -321.769304) (xy 254.975614 -321.773288) (xy 254.922464 -321.769304) (xy 254.870502 -321.757444)
			(xy 254.820888 -321.737972) (xy 254.77473 -321.711323) (xy 254.733059 -321.678092) (xy 254.696807 -321.639021)
			(xy 254.666783 -321.594984) (xy 254.643657 -321.546963) (xy 254.627947 -321.496033) (xy 254.620004 -321.443329)
			(xy 254 -321.443329) (xy 254 -322.073757) (xy 280.75635 -322.073757) (xy 280.75635 -322.020459) (xy 280.764293 -321.967755)
			(xy 280.780003 -321.916825) (xy 280.803129 -321.868804) (xy 280.833153 -321.824767) (xy 280.869405 -321.785696)
			(xy 280.911076 -321.752465) (xy 280.957234 -321.725816) (xy 281.006848 -321.706344) (xy 281.05881 -321.694484)
			(xy 281.11196 -321.690501) (xy 281.16511 -321.694484) (xy 281.217072 -321.706344) (xy 281.266686 -321.725816)
			(xy 281.312844 -321.752465) (xy 281.354515 -321.785696) (xy 281.390767 -321.824767) (xy 281.420791 -321.868804)
			(xy 281.443917 -321.916825) (xy 281.459627 -321.967755) (xy 281.46757 -322.020459) (xy 281.468068 -322.047108)
			(xy 281.46757 -322.073757) (xy 281.459627 -322.126461) (xy 281.443917 -322.177391) (xy 281.420791 -322.225412)
			(xy 281.390767 -322.269449) (xy 281.354515 -322.30852) (xy 281.312844 -322.341751) (xy 281.266686 -322.3684)
			(xy 281.217072 -322.387872) (xy 281.16511 -322.399732) (xy 281.11196 -322.403716) (xy 281.05881 -322.399732)
			(xy 281.006848 -322.387872) (xy 280.957234 -322.3684) (xy 280.911076 -322.341751) (xy 280.869405 -322.30852)
			(xy 280.833153 -322.269449) (xy 280.803129 -322.225412) (xy 280.780003 -322.177391) (xy 280.764293 -322.126461)
			(xy 280.75635 -322.073757) (xy 254 -322.073757) (xy 254 -326.786748) (xy 254.038608 -326.825356)
			(xy 267.169898 -326.825356) (xy 267.173969 -326.769734) (xy 267.186095 -326.715297) (xy 267.206018 -326.663206)
			(xy 267.233314 -326.614571) (xy 267.2674 -326.570428) (xy 267.307549 -326.531719) (xy 267.352907 -326.499268)
			(xy 267.402507 -326.473767) (xy 267.455291 -326.45576) (xy 267.510134 -326.44563) (xy 267.565868 -326.443593)
			(xy 267.621305 -326.449693) (xy 267.675262 -326.463799) (xy 267.726591 -326.485611) (xy 267.774197 -326.514665)
			(xy 267.817065 -326.55034) (xy 267.854282 -326.591877) (xy 267.885055 -326.63839) (xy 267.908727 -326.688887)
			(xy 267.924795 -326.742294) (xy 267.932915 -326.79747) (xy 267.933424 -326.825356) (xy 268.439898 -326.825356)
			(xy 268.443969 -326.769734) (xy 268.456095 -326.715297) (xy 268.476018 -326.663206) (xy 268.503314 -326.614571)
			(xy 268.5374 -326.570428) (xy 268.577549 -326.531719) (xy 268.622907 -326.499268) (xy 268.672507 -326.473767)
			(xy 268.725291 -326.45576) (xy 268.780134 -326.44563) (xy 268.835868 -326.443593) (xy 268.891305 -326.449693)
			(xy 268.945262 -326.463799) (xy 268.996591 -326.485611) (xy 269.044197 -326.514665) (xy 269.087065 -326.55034)
			(xy 269.124282 -326.591877) (xy 269.155055 -326.63839) (xy 269.178727 -326.688887) (xy 269.194795 -326.742294)
			(xy 269.202915 -326.79747) (xy 269.203424 -326.825356) (xy 269.709898 -326.825356) (xy 269.713969 -326.769734)
			(xy 269.726095 -326.715297) (xy 269.746018 -326.663206) (xy 269.773314 -326.614571) (xy 269.8074 -326.570428)
			(xy 269.847549 -326.531719) (xy 269.892907 -326.499268) (xy 269.942507 -326.473767) (xy 269.995291 -326.45576)
			(xy 270.050134 -326.44563) (xy 270.105868 -326.443593) (xy 270.161305 -326.449693) (xy 270.215262 -326.463799)
			(xy 270.266591 -326.485611) (xy 270.314197 -326.514665) (xy 270.357065 -326.55034) (xy 270.394282 -326.591877)
			(xy 270.425055 -326.63839) (xy 270.448727 -326.688887) (xy 270.464795 -326.742294) (xy 270.472915 -326.79747)
			(xy 270.473424 -326.825356) (xy 270.472915 -326.853242) (xy 270.464795 -326.908418) (xy 270.448727 -326.961825)
			(xy 270.425055 -327.012322) (xy 270.394282 -327.058835) (xy 270.357065 -327.100372) (xy 270.314197 -327.136047)
			(xy 270.266591 -327.165101) (xy 270.215262 -327.186913) (xy 270.161305 -327.201019) (xy 270.105868 -327.207119)
			(xy 270.050134 -327.205082) (xy 269.995291 -327.194952) (xy 269.942507 -327.176945) (xy 269.892907 -327.151444)
			(xy 269.847549 -327.118993) (xy 269.8074 -327.080284) (xy 269.773314 -327.036141) (xy 269.746018 -326.987506)
			(xy 269.726095 -326.935415) (xy 269.713969 -326.880978) (xy 269.709898 -326.825356) (xy 269.203424 -326.825356)
			(xy 269.202915 -326.853242) (xy 269.194795 -326.908418) (xy 269.178727 -326.961825) (xy 269.155055 -327.012322)
			(xy 269.124282 -327.058835) (xy 269.087065 -327.100372) (xy 269.044197 -327.136047) (xy 268.996591 -327.165101)
			(xy 268.945262 -327.186913) (xy 268.891305 -327.201019) (xy 268.835868 -327.207119) (xy 268.780134 -327.205082)
			(xy 268.725291 -327.194952) (xy 268.672507 -327.176945) (xy 268.622907 -327.151444) (xy 268.577549 -327.118993)
			(xy 268.5374 -327.080284) (xy 268.503314 -327.036141) (xy 268.476018 -326.987506) (xy 268.456095 -326.935415)
			(xy 268.443969 -326.880978) (xy 268.439898 -326.825356) (xy 267.933424 -326.825356) (xy 267.932915 -326.853242)
			(xy 267.924795 -326.908418) (xy 267.908727 -326.961825) (xy 267.885055 -327.012322) (xy 267.854282 -327.058835)
			(xy 267.817065 -327.100372) (xy 267.774197 -327.136047) (xy 267.726591 -327.165101) (xy 267.675262 -327.186913)
			(xy 267.621305 -327.201019) (xy 267.565868 -327.207119) (xy 267.510134 -327.205082) (xy 267.455291 -327.194952)
			(xy 267.402507 -327.176945) (xy 267.352907 -327.151444) (xy 267.307549 -327.118993) (xy 267.2674 -327.080284)
			(xy 267.233314 -327.036141) (xy 267.206018 -326.987506) (xy 267.186095 -326.935415) (xy 267.173969 -326.880978)
			(xy 267.169898 -326.825356) (xy 254.038608 -326.825356) (xy 255.016 -327.802748)
		)
		(stroke
			(width 0)
			(type solid)
		)
		(fill yes)
		(layer "In13.Cu")
		(net "GND")
	)
	(gr_poly
		(pts
			(xy 193.254376 -328.329798) (xy 193.265976 -328.305995) (xy 193.29478 -328.261565) (xy 193.329459 -328.221552)
			(xy 193.349118 -328.203814) (xy 193.359106 -328.194539) (xy 193.374193 -328.171852) (xy 193.382752 -328.145985)
			(xy 193.384172 -328.118776) (xy 193.378354 -328.092159) (xy 193.36571 -328.068024) (xy 193.356738 -328.057764)
			(xy 193.337567 -328.036476) (xy 193.305175 -327.989227) (xy 193.280215 -327.937665) (xy 193.263247 -327.882949)
			(xy 193.254654 -327.826311) (xy 193.254122 -327.797668) (xy 193.254658 -327.768753) (xy 193.26339 -327.711585)
			(xy 193.280648 -327.656389) (xy 193.306038 -327.60443) (xy 193.338977 -327.556897) (xy 193.378713 -327.514878)
			(xy 193.401188 -327.496678) (xy 193.412988 -327.486781) (xy 193.430496 -327.46146) (xy 193.439664 -327.432073)
			(xy 193.439658 -327.401288) (xy 193.430479 -327.371904) (xy 193.412961 -327.346591) (xy 193.401188 -327.336658)
			(xy 193.380406 -327.319905) (xy 193.343278 -327.281554) (xy 193.311858 -327.238401) (xy 193.286761 -327.191289)
			(xy 193.268477 -327.141139) (xy 193.257363 -327.088929) (xy 193.253636 -327.03568) (xy 193.257369 -326.982432)
			(xy 193.268488 -326.930223) (xy 193.286777 -326.880075) (xy 193.311879 -326.832966) (xy 193.343303 -326.789816)
			(xy 193.380435 -326.751468) (xy 193.401188 -326.734678) (xy 193.412988 -326.724781) (xy 193.430496 -326.69946)
			(xy 193.439664 -326.670073) (xy 193.439658 -326.639288) (xy 193.430479 -326.609904) (xy 193.412961 -326.584591)
			(xy 193.401188 -326.574658) (xy 193.378703 -326.556468) (xy 193.338964 -326.51445) (xy 193.306023 -326.466916)
			(xy 193.280634 -326.414954) (xy 193.26338 -326.359755) (xy 193.254655 -326.302584) (xy 193.254122 -326.273668)
			(xy 193.25461 -326.246419) (xy 193.262371 -326.192476) (xy 193.277729 -326.140187) (xy 193.300372 -326.090616)
			(xy 193.32984 -326.044772) (xy 193.365532 -326.003588) (xy 193.406722 -325.967903) (xy 193.452571 -325.938443)
			(xy 193.502145 -325.915807) (xy 193.554437 -325.900458) (xy 193.608381 -325.892706) (xy 193.63563 -325.89216)
			(xy 193.664545 -325.892696) (xy 193.721712 -325.901428) (xy 193.776907 -325.918687) (xy 193.828865 -325.944079)
			(xy 193.876396 -325.97702) (xy 193.918411 -326.016758) (xy 193.93662 -326.039226) (xy 193.946517 -326.051031)
			(xy 193.971841 -326.06855) (xy 194.001234 -326.077726) (xy 194.032026 -326.077726) (xy 194.061419 -326.06855)
			(xy 194.086743 -326.051031) (xy 194.09664 -326.039226) (xy 194.114829 -326.016739) (xy 194.156845 -325.976996)
			(xy 194.204378 -325.944052) (xy 194.256341 -325.91866) (xy 194.31154 -325.901403) (xy 194.368713 -325.892677)
			(xy 194.39763 -325.89216) (xy 194.427149 -325.892716) (xy 194.485479 -325.901821) (xy 194.541709 -325.919809)
			(xy 194.594494 -325.946251) (xy 194.642572 -325.980513) (xy 194.684793 -326.021777) (xy 194.702938 -326.045068)
			(xy 194.712578 -326.057022) (xy 194.737465 -326.07499) (xy 194.766558 -326.084777) (xy 194.797244 -326.085504)
			(xy 194.826769 -326.077106) (xy 194.852478 -326.060337) (xy 194.862704 -326.048878) (xy 194.880905 -326.027538)
			(xy 194.922502 -325.989916) (xy 194.969164 -325.958798) (xy 195.019883 -325.934854) (xy 195.073564 -325.918603)
			(xy 195.129047 -325.910396) (xy 195.15709 -325.90994) (xy 195.184342 -325.910403) (xy 195.238292 -325.918159)
			(xy 195.290588 -325.933514) (xy 195.340166 -325.956157) (xy 195.386017 -325.985625) (xy 195.427207 -326.02132)
			(xy 195.462897 -326.062513) (xy 195.492361 -326.108367) (xy 195.514999 -326.157948) (xy 195.530349 -326.210246)
			(xy 195.5381 -326.264196) (xy 195.538598 -326.291448) (xy 195.53806 -326.320363) (xy 195.529327 -326.37753)
			(xy 195.512068 -326.432725) (xy 195.486678 -326.484683) (xy 195.453738 -326.532216) (xy 195.414004 -326.574234)
			(xy 195.391532 -326.592438) (xy 195.379732 -326.602334) (xy 195.362225 -326.627653) (xy 195.35306 -326.657038)
			(xy 195.353069 -326.68782) (xy 195.362251 -326.717201) (xy 195.379773 -326.742509) (xy 195.391532 -326.752458)
			(xy 195.412312 -326.769211) (xy 195.449436 -326.807563) (xy 195.480852 -326.850716) (xy 195.505945 -326.897826)
			(xy 195.524227 -326.947975) (xy 195.535338 -327.000183) (xy 195.539064 -327.05343) (xy 195.53533 -327.106676)
			(xy 195.52421 -327.158882) (xy 195.505921 -327.209027) (xy 195.480821 -327.256134) (xy 195.449398 -327.299282)
			(xy 195.412268 -327.337628) (xy 195.391532 -327.354438) (xy 195.379732 -327.364334) (xy 195.362225 -327.389653)
			(xy 195.35306 -327.419038) (xy 195.353069 -327.44982) (xy 195.362251 -327.479201) (xy 195.379773 -327.504509)
			(xy 195.391532 -327.514458) (xy 195.414015 -327.532649) (xy 195.45375 -327.574668) (xy 195.486688 -327.622203)
			(xy 195.512073 -327.674164) (xy 195.529324 -327.729363) (xy 195.538046 -327.786532) (xy 195.538598 -327.815448)
			(xy 195.538117 -327.842569) (xy 195.530425 -327.896264) (xy 195.515204 -327.948327) (xy 195.492759 -327.997708)
			(xy 195.463544 -328.043412) (xy 195.428149 -328.084515) (xy 195.408042 -328.102722) (xy 195.398054 -328.111994)
			(xy 195.382966 -328.134677) (xy 195.374411 -328.160542) (xy 195.372997 -328.187748) (xy 195.378824 -328.214361)
			(xy 195.391479 -328.238486) (xy 195.400422 -328.248772) (xy 195.417559 -328.267724) (xy 195.447129 -328.309392)
			(xy 195.45935 -328.33183) (xy 195.473828 -328.359008) (xy 197.44055 -328.359008) (xy 197.45071 -328.354182)
			(xy 197.476252 -328.342695) (xy 197.529863 -328.326502) (xy 197.585268 -328.318337) (xy 197.61327 -328.31786)
			(xy 197.64127 -328.318354) (xy 197.69667 -328.326533) (xy 197.750285 -328.342706) (xy 197.77583 -328.354182)
			(xy 197.78599 -328.359008) (xy 200.78446 -328.359008) (xy 200.798176 -328.329798) (xy 200.809776 -328.305995)
			(xy 200.83858 -328.261565) (xy 200.873259 -328.221552) (xy 200.892918 -328.203814) (xy 200.902906 -328.194539)
			(xy 200.917993 -328.171852) (xy 200.926552 -328.145985) (xy 200.927972 -328.118776) (xy 200.922154 -328.092159)
			(xy 200.90951 -328.068024) (xy 200.900538 -328.057764) (xy 200.881367 -328.036476) (xy 200.848975 -327.989227)
			(xy 200.824015 -327.937665) (xy 200.807047 -327.882949) (xy 200.798454 -327.826311) (xy 200.797922 -327.797668)
			(xy 200.798458 -327.768753) (xy 200.80719 -327.711585) (xy 200.824448 -327.656389) (xy 200.849838 -327.60443)
			(xy 200.882777 -327.556897) (xy 200.922513 -327.514878) (xy 200.944988 -327.496678) (xy 200.956788 -327.486781)
			(xy 200.974296 -327.46146) (xy 200.983464 -327.432073) (xy 200.983458 -327.401288) (xy 200.974279 -327.371904)
			(xy 200.956761 -327.346591) (xy 200.944988 -327.336658) (xy 200.924206 -327.319905) (xy 200.887078 -327.281554)
			(xy 200.855658 -327.238401) (xy 200.830561 -327.191289) (xy 200.812277 -327.141139) (xy 200.801163 -327.088929)
			(xy 200.797436 -327.03568) (xy 200.801169 -326.982432) (xy 200.812288 -326.930223) (xy 200.830577 -326.880075)
			(xy 200.855679 -326.832966) (xy 200.887103 -326.789816) (xy 200.924235 -326.751468) (xy 200.944988 -326.734678)
			(xy 200.956788 -326.724781) (xy 200.974296 -326.69946) (xy 200.983464 -326.670073) (xy 200.983458 -326.639288)
			(xy 200.974279 -326.609904) (xy 200.956761 -326.584591) (xy 200.944988 -326.574658) (xy 200.922503 -326.556468)
			(xy 200.882764 -326.51445) (xy 200.849823 -326.466916) (xy 200.824434 -326.414954) (xy 200.80718 -326.359755)
			(xy 200.798455 -326.302584) (xy 200.797922 -326.273668) (xy 200.79841 -326.246419) (xy 200.806171 -326.192476)
			(xy 200.821529 -326.140187) (xy 200.844172 -326.090616) (xy 200.87364 -326.044772) (xy 200.909332 -326.003588)
			(xy 200.950522 -325.967903) (xy 200.996371 -325.938443) (xy 201.045945 -325.915807) (xy 201.098237 -325.900458)
			(xy 201.152181 -325.892706) (xy 201.17943 -325.89216) (xy 201.208345 -325.892696) (xy 201.265512 -325.901428)
			(xy 201.320707 -325.918687) (xy 201.372665 -325.944079) (xy 201.420196 -325.97702) (xy 201.462211 -326.016758)
			(xy 201.48042 -326.039226) (xy 201.490317 -326.051031) (xy 201.515641 -326.06855) (xy 201.545034 -326.077726)
			(xy 201.575826 -326.077726) (xy 201.605219 -326.06855) (xy 201.630543 -326.051031) (xy 201.64044 -326.039226)
			(xy 201.658629 -326.016739) (xy 201.700645 -325.976996) (xy 201.748178 -325.944052) (xy 201.800141 -325.91866)
			(xy 201.85534 -325.901403) (xy 201.912513 -325.892677) (xy 201.94143 -325.89216) (xy 201.970949 -325.892716)
			(xy 202.029279 -325.901821) (xy 202.085509 -325.919809) (xy 202.138294 -325.946251) (xy 202.186372 -325.980513)
			(xy 202.228593 -326.021777) (xy 202.246738 -326.045068) (xy 202.256378 -326.057022) (xy 202.281265 -326.07499)
			(xy 202.310358 -326.084777) (xy 202.341044 -326.085504) (xy 202.370569 -326.077106) (xy 202.396278 -326.060337)
			(xy 202.406504 -326.048878) (xy 202.424705 -326.027538) (xy 202.466302 -325.989916) (xy 202.512964 -325.958798)
			(xy 202.563683 -325.934854) (xy 202.617364 -325.918603) (xy 202.672847 -325.910396) (xy 202.70089 -325.90994)
			(xy 202.728142 -325.910403) (xy 202.782092 -325.918159) (xy 202.834388 -325.933514) (xy 202.883966 -325.956157)
			(xy 202.929817 -325.985625) (xy 202.971007 -326.02132) (xy 203.006697 -326.062513) (xy 203.036161 -326.108367)
			(xy 203.058799 -326.157948) (xy 203.074149 -326.210246) (xy 203.0819 -326.264196) (xy 203.082398 -326.291448)
			(xy 203.08186 -326.320363) (xy 203.073127 -326.37753) (xy 203.055868 -326.432725) (xy 203.030478 -326.484683)
			(xy 202.997538 -326.532216) (xy 202.957804 -326.574234) (xy 202.935332 -326.592438) (xy 202.923532 -326.602334)
			(xy 202.906025 -326.627653) (xy 202.89686 -326.657038) (xy 202.896869 -326.68782) (xy 202.906051 -326.717201)
			(xy 202.923573 -326.742509) (xy 202.935332 -326.752458) (xy 202.956112 -326.769211) (xy 202.993236 -326.807563)
			(xy 203.024652 -326.850716) (xy 203.049745 -326.897826) (xy 203.068027 -326.947975) (xy 203.079138 -327.000183)
			(xy 203.082864 -327.05343) (xy 203.07913 -327.106676) (xy 203.06801 -327.158882) (xy 203.049721 -327.209027)
			(xy 203.024621 -327.256134) (xy 202.993198 -327.299282) (xy 202.956068 -327.337628) (xy 202.935332 -327.354438)
			(xy 202.923532 -327.364334) (xy 202.906025 -327.389653) (xy 202.89686 -327.419038) (xy 202.896869 -327.44982)
			(xy 202.906051 -327.479201) (xy 202.923573 -327.504509) (xy 202.935332 -327.514458) (xy 202.957815 -327.532649)
			(xy 202.99755 -327.574668) (xy 203.030488 -327.622203) (xy 203.055873 -327.674164) (xy 203.073124 -327.729363)
			(xy 203.081846 -327.786532) (xy 203.082398 -327.815448) (xy 203.081917 -327.842569) (xy 203.074225 -327.896264)
			(xy 203.059004 -327.948327) (xy 203.036559 -327.997708) (xy 203.007344 -328.043412) (xy 202.971949 -328.084515)
			(xy 202.951842 -328.102722) (xy 202.941854 -328.111994) (xy 202.926766 -328.134677) (xy 202.918211 -328.160542)
			(xy 202.916797 -328.187748) (xy 202.922624 -328.214361) (xy 202.935279 -328.238486) (xy 202.944222 -328.248772)
			(xy 202.961359 -328.267724) (xy 202.990929 -328.309392) (xy 203.00315 -328.33183) (xy 203.017628 -328.359008)
			(xy 216.16162 -328.359008) (xy 217.64498 -326.875648) (xy 217.64498 -196.814948) (xy 216.789 -195.958968)
			(xy 214.243412 -195.958968) (xy 214.229104 -195.959452) (xy 214.201613 -195.967393) (xy 214.177407 -195.982654)
			(xy 214.15839 -196.004035) (xy 214.146056 -196.029856) (xy 214.141375 -196.058085) (xy 214.144715 -196.086505)
			(xy 214.155814 -196.11288) (xy 214.164418 -196.124322) (xy 214.180308 -196.144744) (xy 214.207015 -196.189065)
			(xy 214.227483 -196.23659) (xy 214.241336 -196.286446) (xy 214.248321 -196.337717) (xy 214.248746 -196.36359)
			(xy 214.24826 -196.390841) (xy 214.240504 -196.444789) (xy 214.225149 -196.497084) (xy 214.202507 -196.546661)
			(xy 214.173041 -196.592511) (xy 214.13735 -196.633702) (xy 214.096159 -196.669393) (xy 214.050309 -196.698859)
			(xy 214.000732 -196.721501) (xy 213.948437 -196.736856) (xy 213.894489 -196.744612) (xy 213.839987 -196.744612)
			(xy 213.786039 -196.736856) (xy 213.733744 -196.721501) (xy 213.684167 -196.698859) (xy 213.638317 -196.669393)
			(xy 213.597126 -196.633702) (xy 213.561435 -196.592511) (xy 213.531969 -196.546661) (xy 213.509327 -196.497084)
			(xy 213.493972 -196.444789) (xy 213.486216 -196.390841) (xy 213.48573 -196.36359) (xy 213.486162 -196.337718)
			(xy 213.493154 -196.286449) (xy 213.507008 -196.236594) (xy 213.527471 -196.189069) (xy 213.554168 -196.144743)
			(xy 213.570058 -196.124322) (xy 213.578653 -196.112887) (xy 213.589717 -196.086522) (xy 213.593033 -196.058122)
			(xy 213.588342 -196.029917) (xy 213.576011 -196.00412) (xy 213.557009 -195.982755) (xy 213.532826 -195.9675)
			(xy 213.50536 -195.959552) (xy 213.491064 -195.958968) (xy 213.4235 -195.958968) (xy 212.100414 -194.636136)
			(xy 210.946238 -194.636136) (xy 210.93239 -194.636599) (xy 210.905715 -194.644043) (xy 210.882027 -194.658392)
			(xy 210.863076 -194.678588) (xy 210.85026 -194.703139) (xy 210.844525 -194.730234) (xy 210.844892 -194.744086)
			(xy 210.845654 -194.766692) (xy 210.845156 -194.793341) (xy 210.837213 -194.846045) (xy 210.821503 -194.896975)
			(xy 210.798377 -194.944996) (xy 210.768353 -194.989033) (xy 210.732101 -195.028104) (xy 210.69043 -195.061335)
			(xy 210.644272 -195.087984) (xy 210.594658 -195.107456) (xy 210.542696 -195.119316) (xy 210.489546 -195.1233)
			(xy 210.436396 -195.119316) (xy 210.384434 -195.107456) (xy 210.33482 -195.087984) (xy 210.288662 -195.061335)
			(xy 210.246991 -195.028104) (xy 210.210739 -194.989033) (xy 210.180715 -194.944996) (xy 210.157589 -194.896975)
			(xy 210.141879 -194.846045) (xy 210.133936 -194.793341) (xy 210.133438 -194.766692) (xy 210.133589 -194.752019)
			(xy 210.136007 -194.722772) (xy 210.138264 -194.708272) (xy 210.140194 -194.693674) (xy 210.136548 -194.664468)
			(xy 210.124731 -194.637512) (xy 210.105723 -194.61504) (xy 210.0811 -194.598917) (xy 210.052903 -194.590478)
			(xy 210.038188 -194.589908) (xy 202.948286 -194.589908) (xy 202.933347 -194.590477) (xy 202.904769 -194.599202)
			(xy 202.879933 -194.615815) (xy 202.860958 -194.638898) (xy 202.849466 -194.666481) (xy 202.846437 -194.696207)
			(xy 202.852129 -194.725541) (xy 202.858624 -194.739006) (xy 202.871655 -194.764827) (xy 202.8901 -194.81964)
			(xy 202.899452 -194.876713) (xy 202.900026 -194.90563) (xy 202.899528 -194.932279) (xy 202.891585 -194.984983)
			(xy 202.875875 -195.035913) (xy 202.852749 -195.083934) (xy 202.822725 -195.127971) (xy 202.786473 -195.167042)
			(xy 202.744802 -195.200273) (xy 202.698644 -195.226922) (xy 202.64903 -195.246394) (xy 202.597068 -195.258254)
			(xy 202.543918 -195.262238) (xy 202.490768 -195.258254) (xy 202.438806 -195.246394) (xy 202.389192 -195.226922)
			(xy 202.343034 -195.200273) (xy 202.301363 -195.167042) (xy 202.265111 -195.127971) (xy 202.235087 -195.083934)
			(xy 202.211961 -195.035913) (xy 202.196251 -194.984983) (xy 202.188308 -194.932279) (xy 202.18781 -194.90563)
			(xy 202.188372 -194.876712) (xy 202.197719 -194.819636) (xy 202.216173 -194.764823) (xy 202.229212 -194.739006)
			(xy 202.235738 -194.725545) (xy 202.241468 -194.696198) (xy 202.238458 -194.666449) (xy 202.226964 -194.638846)
			(xy 202.207972 -194.615751) (xy 202.183107 -194.599144) (xy 202.1545 -194.590446) (xy 202.13955 -194.589908)
			(xy 199.239124 -194.589908) (xy 199.224927 -194.590414) (xy 199.197647 -194.598301) (xy 199.17359 -194.613389)
			(xy 199.154612 -194.634513) (xy 199.142178 -194.660043) (xy 199.137248 -194.688009) (xy 199.138286 -194.702176)
			(xy 199.139259 -194.71218) (xy 199.140274 -194.732257) (xy 199.140318 -194.742308) (xy 199.139832 -194.769559)
			(xy 199.132076 -194.823507) (xy 199.116721 -194.875802) (xy 199.094079 -194.925379) (xy 199.064613 -194.971229)
			(xy 199.028922 -195.01242) (xy 198.987731 -195.048111) (xy 198.941881 -195.077577) (xy 198.892304 -195.100219)
			(xy 198.840009 -195.115574) (xy 198.786061 -195.12333) (xy 198.731559 -195.12333) (xy 198.677611 -195.115574)
			(xy 198.625316 -195.100219) (xy 198.575739 -195.077577) (xy 198.529889 -195.048111) (xy 198.488698 -195.01242)
			(xy 198.453007 -194.971229) (xy 198.423541 -194.925379) (xy 198.400899 -194.875802) (xy 198.385544 -194.823507)
			(xy 198.377788 -194.769559) (xy 198.377302 -194.742308) (xy 198.377349 -194.732257) (xy 198.378367 -194.712181)
			(xy 198.379334 -194.702176) (xy 198.380359 -194.688005) (xy 198.375449 -194.660031) (xy 198.363025 -194.634491)
			(xy 198.344047 -194.613361) (xy 198.319983 -194.598276) (xy 198.292696 -194.590401) (xy 198.278496 -194.589908)
			(xy 195.878704 -194.589908) (xy 195.863971 -194.59039) (xy 195.835726 -194.598787) (xy 195.811062 -194.61491)
			(xy 195.792039 -194.637412) (xy 195.780244 -194.664414) (xy 195.776663 -194.693662) (xy 195.778628 -194.708272)
			(xy 195.780886 -194.722771) (xy 195.783299 -194.752019) (xy 195.783454 -194.766692) (xy 195.782956 -194.793341)
			(xy 195.775013 -194.846045) (xy 195.759303 -194.896975) (xy 195.736177 -194.944996) (xy 195.706153 -194.989033)
			(xy 195.669901 -195.028104) (xy 195.62823 -195.061335) (xy 195.582072 -195.087984) (xy 195.532458 -195.107456)
			(xy 195.480496 -195.119316) (xy 195.427346 -195.1233) (xy 195.374196 -195.119316) (xy 195.322234 -195.107456)
			(xy 195.27262 -195.087984) (xy 195.226462 -195.061335) (xy 195.184791 -195.028104) (xy 195.148539 -194.989033)
			(xy 195.118515 -194.944996) (xy 195.095389 -194.896975) (xy 195.079679 -194.846045) (xy 195.071736 -194.793341)
			(xy 195.071238 -194.766692) (xy 195.071389 -194.752019) (xy 195.073807 -194.722772) (xy 195.076064 -194.708272)
			(xy 195.077994 -194.693674) (xy 195.074348 -194.664468) (xy 195.062531 -194.637512) (xy 195.043523 -194.61504)
			(xy 195.0189 -194.598917) (xy 194.990703 -194.590478) (xy 194.975988 -194.589908) (xy 188.334904 -194.589908)
			(xy 188.320171 -194.59039) (xy 188.291926 -194.598787) (xy 188.267262 -194.61491) (xy 188.248239 -194.637412)
			(xy 188.236444 -194.664414) (xy 188.232863 -194.693662) (xy 188.234828 -194.708272) (xy 188.237086 -194.722771)
			(xy 188.239499 -194.752019) (xy 188.239654 -194.766692) (xy 188.239156 -194.793341) (xy 188.231213 -194.846045)
			(xy 188.215503 -194.896975) (xy 188.192377 -194.944996) (xy 188.162353 -194.989033) (xy 188.126101 -195.028104)
			(xy 188.08443 -195.061335) (xy 188.038272 -195.087984) (xy 187.988658 -195.107456) (xy 187.936696 -195.119316)
			(xy 187.883546 -195.1233) (xy 187.830396 -195.119316) (xy 187.778434 -195.107456) (xy 187.72882 -195.087984)
			(xy 187.682662 -195.061335) (xy 187.640991 -195.028104) (xy 187.604739 -194.989033) (xy 187.574715 -194.944996)
			(xy 187.551589 -194.896975) (xy 187.535879 -194.846045) (xy 187.527936 -194.793341) (xy 187.527438 -194.766692)
			(xy 187.527589 -194.752019) (xy 187.530007 -194.722772) (xy 187.532264 -194.708272) (xy 187.534194 -194.693674)
			(xy 187.530548 -194.664468) (xy 187.518731 -194.637512) (xy 187.499723 -194.61504) (xy 187.4751 -194.598917)
			(xy 187.446903 -194.590478) (xy 187.432188 -194.589908) (xy 183.435752 -194.589908) (xy 183.425592 -194.6275)
			(xy 183.417936 -194.654195) (xy 183.395963 -194.705198) (xy 183.366827 -194.752475) (xy 183.331145 -194.795029)
			(xy 183.28967 -194.83196) (xy 183.243279 -194.862487) (xy 183.192952 -194.885965) (xy 183.139752 -194.901899)
			(xy 183.084805 -194.909951) (xy 183.029271 -194.909951) (xy 182.974324 -194.901899) (xy 182.921124 -194.885965)
			(xy 182.870797 -194.862487) (xy 182.824406 -194.83196) (xy 182.782931 -194.795029) (xy 182.747249 -194.752475)
			(xy 182.718113 -194.705198) (xy 182.69614 -194.654195) (xy 182.688484 -194.6275) (xy 182.678324 -194.589908)
			(xy 180.765704 -194.589908) (xy 180.750971 -194.59039) (xy 180.722726 -194.598787) (xy 180.698062 -194.61491)
			(xy 180.679039 -194.637412) (xy 180.667244 -194.664414) (xy 180.663663 -194.693662) (xy 180.665628 -194.708272)
			(xy 180.667886 -194.722771) (xy 180.670299 -194.752019) (xy 180.670454 -194.766692) (xy 180.669956 -194.793341)
			(xy 180.662013 -194.846045) (xy 180.646303 -194.896975) (xy 180.623177 -194.944996) (xy 180.593153 -194.989033)
			(xy 180.556901 -195.028104) (xy 180.51523 -195.061335) (xy 180.469072 -195.087984) (xy 180.419458 -195.107456)
			(xy 180.367496 -195.119316) (xy 180.314346 -195.1233) (xy 180.261196 -195.119316) (xy 180.209234 -195.107456)
			(xy 180.15962 -195.087984) (xy 180.113462 -195.061335) (xy 180.071791 -195.028104) (xy 180.035539 -194.989033)
			(xy 180.005515 -194.944996) (xy 179.982389 -194.896975) (xy 179.966679 -194.846045) (xy 179.958736 -194.793341)
			(xy 179.958238 -194.766692) (xy 179.958389 -194.752019) (xy 179.960807 -194.722772) (xy 179.963064 -194.708272)
			(xy 179.964994 -194.693674) (xy 179.961348 -194.664468) (xy 179.949531 -194.637512) (xy 179.930523 -194.61504)
			(xy 179.9059 -194.598917) (xy 179.877703 -194.590478) (xy 179.862988 -194.589908) (xy 173.247304 -194.589908)
			(xy 173.232571 -194.59039) (xy 173.204326 -194.598787) (xy 173.179662 -194.61491) (xy 173.160639 -194.637412)
			(xy 173.148844 -194.664414) (xy 173.145263 -194.693662) (xy 173.147228 -194.708272) (xy 173.149486 -194.722771)
			(xy 173.151899 -194.752019) (xy 173.152054 -194.766692) (xy 173.151556 -194.793341) (xy 173.143613 -194.846045)
			(xy 173.127903 -194.896975) (xy 173.104777 -194.944996) (xy 173.074753 -194.989033) (xy 173.038501 -195.028104)
			(xy 172.99683 -195.061335) (xy 172.950672 -195.087984) (xy 172.901058 -195.107456) (xy 172.849096 -195.119316)
			(xy 172.795946 -195.1233) (xy 172.742796 -195.119316) (xy 172.690834 -195.107456) (xy 172.64122 -195.087984)
			(xy 172.595062 -195.061335) (xy 172.553391 -195.028104) (xy 172.517139 -194.989033) (xy 172.487115 -194.944996)
			(xy 172.463989 -194.896975) (xy 172.448279 -194.846045) (xy 172.440336 -194.793341) (xy 172.439838 -194.766692)
			(xy 172.439989 -194.752019) (xy 172.442407 -194.722772) (xy 172.444664 -194.708272) (xy 172.446594 -194.693674)
			(xy 172.442948 -194.664468) (xy 172.431131 -194.637512) (xy 172.412123 -194.61504) (xy 172.3875 -194.598917)
			(xy 172.359303 -194.590478) (xy 172.344588 -194.589908) (xy 165.703504 -194.589908) (xy 165.688771 -194.59039)
			(xy 165.660526 -194.598787) (xy 165.635862 -194.61491) (xy 165.616839 -194.637412) (xy 165.605044 -194.664414)
			(xy 165.601463 -194.693662) (xy 165.603428 -194.708272) (xy 165.605686 -194.722771) (xy 165.608099 -194.752019)
			(xy 165.608254 -194.766692) (xy 165.607756 -194.793341) (xy 165.599813 -194.846045) (xy 165.584103 -194.896975)
			(xy 165.560977 -194.944996) (xy 165.530953 -194.989033) (xy 165.494701 -195.028104) (xy 165.45303 -195.061335)
			(xy 165.406872 -195.087984) (xy 165.357258 -195.107456) (xy 165.305296 -195.119316) (xy 165.252146 -195.1233)
			(xy 165.198996 -195.119316) (xy 165.147034 -195.107456) (xy 165.09742 -195.087984) (xy 165.051262 -195.061335)
			(xy 165.009591 -195.028104) (xy 164.973339 -194.989033) (xy 164.943315 -194.944996) (xy 164.920189 -194.896975)
			(xy 164.904479 -194.846045) (xy 164.896536 -194.793341) (xy 164.896038 -194.766692) (xy 164.896189 -194.752019)
			(xy 164.898607 -194.722772) (xy 164.900864 -194.708272) (xy 164.902794 -194.693674) (xy 164.899148 -194.664468)
			(xy 164.887331 -194.637512) (xy 164.868323 -194.61504) (xy 164.8437 -194.598917) (xy 164.815503 -194.590478)
			(xy 164.800788 -194.589908) (xy 160.39084 -194.589908) (xy 160.377624 -194.590324) (xy 160.352075 -194.597104)
			(xy 160.329126 -194.610219) (xy 160.310316 -194.628789) (xy 160.296908 -194.651569) (xy 160.289801 -194.677028)
			(xy 160.28924 -194.690238) (xy 160.288333 -194.71797) (xy 160.278983 -194.772661) (xy 160.261263 -194.82524)
			(xy 160.235601 -194.874434) (xy 160.20262 -194.919052) (xy 160.163117 -194.958014) (xy 160.118049 -194.990377)
			(xy 160.068507 -195.015358) (xy 160.015689 -195.032352) (xy 159.960874 -195.040948) (xy 159.933132 -195.04152)
			(xy 159.905436 -195.040988) (xy 159.850715 -195.032399) (xy 159.797984 -195.015438) (xy 159.748516 -194.990515)
			(xy 159.703505 -194.958232) (xy 159.664037 -194.919367) (xy 159.631064 -194.874858) (xy 159.605383 -194.82578)
			(xy 159.587612 -194.773316) (xy 159.582358 -194.746118) (xy 159.579518 -194.732511) (xy 159.567566 -194.70743)
			(xy 159.549296 -194.686498) (xy 159.526062 -194.671265) (xy 159.499581 -194.662857) (xy 159.471814 -194.661896)
			(xy 159.444816 -194.668455) (xy 159.420584 -194.682047) (xy 159.4104 -194.691508) (xy 158.88716 -195.214748)
			(xy 158.88716 -195.643225) (xy 176.540404 -195.643225) (xy 176.540404 -195.589927) (xy 176.548347 -195.537223)
			(xy 176.564057 -195.486293) (xy 176.587183 -195.438272) (xy 176.617207 -195.394235) (xy 176.653459 -195.355164)
			(xy 176.69513 -195.321933) (xy 176.741288 -195.295284) (xy 176.790902 -195.275812) (xy 176.842864 -195.263952)
			(xy 176.896014 -195.259969) (xy 176.949164 -195.263952) (xy 177.001126 -195.275812) (xy 177.05074 -195.295284)
			(xy 177.096898 -195.321933) (xy 177.138569 -195.355164) (xy 177.174821 -195.394235) (xy 177.204845 -195.438272)
			(xy 177.227971 -195.486293) (xy 177.243681 -195.537223) (xy 177.251624 -195.589927) (xy 177.252122 -195.616576)
			(xy 177.251624 -195.643225) (xy 191.628004 -195.643225) (xy 191.628004 -195.589927) (xy 191.635947 -195.537223)
			(xy 191.651657 -195.486293) (xy 191.674783 -195.438272) (xy 191.704807 -195.394235) (xy 191.741059 -195.355164)
			(xy 191.78273 -195.321933) (xy 191.828888 -195.295284) (xy 191.878502 -195.275812) (xy 191.930464 -195.263952)
			(xy 191.983614 -195.259969) (xy 192.036764 -195.263952) (xy 192.088726 -195.275812) (xy 192.13834 -195.295284)
			(xy 192.184498 -195.321933) (xy 192.226169 -195.355164) (xy 192.262421 -195.394235) (xy 192.292445 -195.438272)
			(xy 192.315571 -195.486293) (xy 192.331281 -195.537223) (xy 192.339224 -195.589927) (xy 192.339722 -195.616576)
			(xy 192.339224 -195.643225) (xy 192.33834 -195.649088) (xy 205.573882 -195.649088) (xy 205.577953 -195.593466)
			(xy 205.590079 -195.539029) (xy 205.610002 -195.486938) (xy 205.637298 -195.438303) (xy 205.671384 -195.39416)
			(xy 205.711533 -195.355451) (xy 205.756891 -195.323) (xy 205.806491 -195.297499) (xy 205.859275 -195.279492)
			(xy 205.914118 -195.269362) (xy 205.969852 -195.267325) (xy 206.025289 -195.273425) (xy 206.079246 -195.287531)
			(xy 206.130575 -195.309343) (xy 206.178181 -195.338397) (xy 206.221049 -195.374072) (xy 206.258266 -195.415609)
			(xy 206.289039 -195.462122) (xy 206.312711 -195.512619) (xy 206.328779 -195.566026) (xy 206.336899 -195.621202)
			(xy 206.337301 -195.643225) (xy 206.715604 -195.643225) (xy 206.715604 -195.589927) (xy 206.723547 -195.537223)
			(xy 206.739257 -195.486293) (xy 206.762383 -195.438272) (xy 206.792407 -195.394235) (xy 206.828659 -195.355164)
			(xy 206.87033 -195.321933) (xy 206.916488 -195.295284) (xy 206.966102 -195.275812) (xy 207.018064 -195.263952)
			(xy 207.071214 -195.259969) (xy 207.124364 -195.263952) (xy 207.176326 -195.275812) (xy 207.22594 -195.295284)
			(xy 207.272098 -195.321933) (xy 207.313769 -195.355164) (xy 207.350021 -195.394235) (xy 207.380045 -195.438272)
			(xy 207.403171 -195.486293) (xy 207.418881 -195.537223) (xy 207.426824 -195.589927) (xy 207.427322 -195.616576)
			(xy 207.426824 -195.643225) (xy 207.418881 -195.695929) (xy 207.403171 -195.746859) (xy 207.380045 -195.79488)
			(xy 207.350021 -195.838917) (xy 207.313769 -195.877988) (xy 207.272098 -195.911219) (xy 207.22594 -195.937868)
			(xy 207.176326 -195.95734) (xy 207.124364 -195.9692) (xy 207.071214 -195.973184) (xy 207.018064 -195.9692)
			(xy 206.966102 -195.95734) (xy 206.916488 -195.937868) (xy 206.87033 -195.911219) (xy 206.828659 -195.877988)
			(xy 206.792407 -195.838917) (xy 206.762383 -195.79488) (xy 206.739257 -195.746859) (xy 206.723547 -195.695929)
			(xy 206.715604 -195.643225) (xy 206.337301 -195.643225) (xy 206.337408 -195.649088) (xy 206.336899 -195.676974)
			(xy 206.328779 -195.73215) (xy 206.312711 -195.785557) (xy 206.289039 -195.836054) (xy 206.258266 -195.882567)
			(xy 206.221049 -195.924104) (xy 206.178181 -195.959779) (xy 206.130575 -195.988833) (xy 206.079246 -196.010645)
			(xy 206.025289 -196.024751) (xy 205.969852 -196.030851) (xy 205.914118 -196.028814) (xy 205.859275 -196.018684)
			(xy 205.806491 -196.000677) (xy 205.756891 -195.975176) (xy 205.711533 -195.942725) (xy 205.671384 -195.904016)
			(xy 205.637298 -195.859873) (xy 205.610002 -195.811238) (xy 205.590079 -195.759147) (xy 205.577953 -195.70471)
			(xy 205.573882 -195.649088) (xy 192.33834 -195.649088) (xy 192.331281 -195.695929) (xy 192.315571 -195.746859)
			(xy 192.292445 -195.79488) (xy 192.262421 -195.838917) (xy 192.226169 -195.877988) (xy 192.184498 -195.911219)
			(xy 192.13834 -195.937868) (xy 192.088726 -195.95734) (xy 192.036764 -195.9692) (xy 191.983614 -195.973184)
			(xy 191.930464 -195.9692) (xy 191.878502 -195.95734) (xy 191.828888 -195.937868) (xy 191.78273 -195.911219)
			(xy 191.741059 -195.877988) (xy 191.704807 -195.838917) (xy 191.674783 -195.79488) (xy 191.651657 -195.746859)
			(xy 191.635947 -195.695929) (xy 191.628004 -195.643225) (xy 177.251624 -195.643225) (xy 177.243681 -195.695929)
			(xy 177.227971 -195.746859) (xy 177.204845 -195.79488) (xy 177.174821 -195.838917) (xy 177.138569 -195.877988)
			(xy 177.096898 -195.911219) (xy 177.05074 -195.937868) (xy 177.001126 -195.95734) (xy 176.949164 -195.9692)
			(xy 176.896014 -195.973184) (xy 176.842864 -195.9692) (xy 176.790902 -195.95734) (xy 176.741288 -195.937868)
			(xy 176.69513 -195.911219) (xy 176.653459 -195.877988) (xy 176.617207 -195.838917) (xy 176.587183 -195.79488)
			(xy 176.564057 -195.746859) (xy 176.548347 -195.695929) (xy 176.540404 -195.643225) (xy 158.88716 -195.643225)
			(xy 158.88716 -196.493363) (xy 172.440336 -196.493363) (xy 172.440336 -196.440065) (xy 172.448279 -196.387361)
			(xy 172.463989 -196.336431) (xy 172.487115 -196.28841) (xy 172.517139 -196.244373) (xy 172.553391 -196.205302)
			(xy 172.595062 -196.172071) (xy 172.64122 -196.145422) (xy 172.690834 -196.12595) (xy 172.742796 -196.11409)
			(xy 172.795946 -196.110107) (xy 172.849096 -196.11409) (xy 172.901058 -196.12595) (xy 172.950672 -196.145422)
			(xy 172.99683 -196.172071) (xy 173.038501 -196.205302) (xy 173.074753 -196.244373) (xy 173.104777 -196.28841)
			(xy 173.127903 -196.336431) (xy 173.143613 -196.387361) (xy 173.151556 -196.440065) (xy 173.152054 -196.466714)
			(xy 173.151556 -196.493363) (xy 187.527936 -196.493363) (xy 187.527936 -196.440065) (xy 187.535879 -196.387361)
			(xy 187.551589 -196.336431) (xy 187.574715 -196.28841) (xy 187.604739 -196.244373) (xy 187.640991 -196.205302)
			(xy 187.682662 -196.172071) (xy 187.72882 -196.145422) (xy 187.778434 -196.12595) (xy 187.830396 -196.11409)
			(xy 187.883546 -196.110107) (xy 187.936696 -196.11409) (xy 187.988658 -196.12595) (xy 188.038272 -196.145422)
			(xy 188.08443 -196.172071) (xy 188.126101 -196.205302) (xy 188.162353 -196.244373) (xy 188.192377 -196.28841)
			(xy 188.215503 -196.336431) (xy 188.231213 -196.387361) (xy 188.239156 -196.440065) (xy 188.239654 -196.466714)
			(xy 188.239156 -196.493363) (xy 202.615536 -196.493363) (xy 202.615536 -196.440065) (xy 202.623479 -196.387361)
			(xy 202.639189 -196.336431) (xy 202.662315 -196.28841) (xy 202.692339 -196.244373) (xy 202.728591 -196.205302)
			(xy 202.770262 -196.172071) (xy 202.81642 -196.145422) (xy 202.866034 -196.12595) (xy 202.917996 -196.11409)
			(xy 202.971146 -196.110107) (xy 203.024296 -196.11409) (xy 203.076258 -196.12595) (xy 203.125872 -196.145422)
			(xy 203.17203 -196.172071) (xy 203.213701 -196.205302) (xy 203.249953 -196.244373) (xy 203.279977 -196.28841)
			(xy 203.303103 -196.336431) (xy 203.318813 -196.387361) (xy 203.326756 -196.440065) (xy 203.327254 -196.466714)
			(xy 203.326756 -196.493363) (xy 203.318813 -196.546067) (xy 203.303103 -196.596997) (xy 203.279977 -196.645018)
			(xy 203.249953 -196.689055) (xy 203.213701 -196.728126) (xy 203.17203 -196.761357) (xy 203.125872 -196.788006)
			(xy 203.076258 -196.807478) (xy 203.024296 -196.819338) (xy 202.971146 -196.823322) (xy 202.917996 -196.819338)
			(xy 202.866034 -196.807478) (xy 202.81642 -196.788006) (xy 202.770262 -196.761357) (xy 202.728591 -196.728126)
			(xy 202.692339 -196.689055) (xy 202.662315 -196.645018) (xy 202.639189 -196.596997) (xy 202.623479 -196.546067)
			(xy 202.615536 -196.493363) (xy 188.239156 -196.493363) (xy 188.231213 -196.546067) (xy 188.215503 -196.596997)
			(xy 188.192377 -196.645018) (xy 188.162353 -196.689055) (xy 188.126101 -196.728126) (xy 188.08443 -196.761357)
			(xy 188.038272 -196.788006) (xy 187.988658 -196.807478) (xy 187.936696 -196.819338) (xy 187.883546 -196.823322)
			(xy 187.830396 -196.819338) (xy 187.778434 -196.807478) (xy 187.72882 -196.788006) (xy 187.682662 -196.761357)
			(xy 187.640991 -196.728126) (xy 187.604739 -196.689055) (xy 187.574715 -196.645018) (xy 187.551589 -196.596997)
			(xy 187.535879 -196.546067) (xy 187.527936 -196.493363) (xy 173.151556 -196.493363) (xy 173.143613 -196.546067)
			(xy 173.127903 -196.596997) (xy 173.104777 -196.645018) (xy 173.074753 -196.689055) (xy 173.038501 -196.728126)
			(xy 172.99683 -196.761357) (xy 172.950672 -196.788006) (xy 172.901058 -196.807478) (xy 172.849096 -196.819338)
			(xy 172.795946 -196.823322) (xy 172.742796 -196.819338) (xy 172.690834 -196.807478) (xy 172.64122 -196.788006)
			(xy 172.595062 -196.761357) (xy 172.553391 -196.728126) (xy 172.517139 -196.689055) (xy 172.487115 -196.645018)
			(xy 172.463989 -196.596997) (xy 172.448279 -196.546067) (xy 172.440336 -196.493363) (xy 158.88716 -196.493363)
			(xy 158.88716 -197.343247) (xy 176.540404 -197.343247) (xy 176.540404 -197.289949) (xy 176.548347 -197.237245)
			(xy 176.564057 -197.186315) (xy 176.587183 -197.138294) (xy 176.617207 -197.094257) (xy 176.653459 -197.055186)
			(xy 176.69513 -197.021955) (xy 176.741288 -196.995306) (xy 176.790902 -196.975834) (xy 176.842864 -196.963974)
			(xy 176.896014 -196.959991) (xy 176.949164 -196.963974) (xy 177.001126 -196.975834) (xy 177.05074 -196.995306)
			(xy 177.096898 -197.021955) (xy 177.138569 -197.055186) (xy 177.174821 -197.094257) (xy 177.204845 -197.138294)
			(xy 177.227971 -197.186315) (xy 177.243681 -197.237245) (xy 177.251624 -197.289949) (xy 177.252122 -197.316598)
			(xy 177.251624 -197.343247) (xy 191.628004 -197.343247) (xy 191.628004 -197.289949) (xy 191.635947 -197.237245)
			(xy 191.651657 -197.186315) (xy 191.674783 -197.138294) (xy 191.704807 -197.094257) (xy 191.741059 -197.055186)
			(xy 191.78273 -197.021955) (xy 191.828888 -196.995306) (xy 191.878502 -196.975834) (xy 191.930464 -196.963974)
			(xy 191.983614 -196.959991) (xy 192.036764 -196.963974) (xy 192.088726 -196.975834) (xy 192.13834 -196.995306)
			(xy 192.184498 -197.021955) (xy 192.226169 -197.055186) (xy 192.262421 -197.094257) (xy 192.292445 -197.138294)
			(xy 192.315571 -197.186315) (xy 192.331281 -197.237245) (xy 192.339224 -197.289949) (xy 192.339722 -197.316598)
			(xy 192.339224 -197.343247) (xy 206.715604 -197.343247) (xy 206.715604 -197.289949) (xy 206.723547 -197.237245)
			(xy 206.739257 -197.186315) (xy 206.762383 -197.138294) (xy 206.792407 -197.094257) (xy 206.828659 -197.055186)
			(xy 206.87033 -197.021955) (xy 206.916488 -196.995306) (xy 206.966102 -196.975834) (xy 207.018064 -196.963974)
			(xy 207.071214 -196.959991) (xy 207.124364 -196.963974) (xy 207.176326 -196.975834) (xy 207.22594 -196.995306)
			(xy 207.272098 -197.021955) (xy 207.313769 -197.055186) (xy 207.350021 -197.094257) (xy 207.380045 -197.138294)
			(xy 207.403171 -197.186315) (xy 207.418881 -197.237245) (xy 207.426824 -197.289949) (xy 207.427322 -197.316598)
			(xy 207.426824 -197.343247) (xy 207.418881 -197.395951) (xy 207.403171 -197.446881) (xy 207.380045 -197.494902)
			(xy 207.350021 -197.538939) (xy 207.313769 -197.57801) (xy 207.272098 -197.611241) (xy 207.22594 -197.63789)
			(xy 207.176326 -197.657362) (xy 207.124364 -197.669222) (xy 207.071214 -197.673206) (xy 207.018064 -197.669222)
			(xy 206.966102 -197.657362) (xy 206.916488 -197.63789) (xy 206.87033 -197.611241) (xy 206.828659 -197.57801)
			(xy 206.792407 -197.538939) (xy 206.762383 -197.494902) (xy 206.739257 -197.446881) (xy 206.723547 -197.395951)
			(xy 206.715604 -197.343247) (xy 192.339224 -197.343247) (xy 192.331281 -197.395951) (xy 192.315571 -197.446881)
			(xy 192.292445 -197.494902) (xy 192.262421 -197.538939) (xy 192.226169 -197.57801) (xy 192.184498 -197.611241)
			(xy 192.13834 -197.63789) (xy 192.088726 -197.657362) (xy 192.036764 -197.669222) (xy 191.983614 -197.673206)
			(xy 191.930464 -197.669222) (xy 191.878502 -197.657362) (xy 191.828888 -197.63789) (xy 191.78273 -197.611241)
			(xy 191.741059 -197.57801) (xy 191.704807 -197.538939) (xy 191.674783 -197.494902) (xy 191.651657 -197.446881)
			(xy 191.635947 -197.395951) (xy 191.628004 -197.343247) (xy 177.251624 -197.343247) (xy 177.243681 -197.395951)
			(xy 177.227971 -197.446881) (xy 177.204845 -197.494902) (xy 177.174821 -197.538939) (xy 177.138569 -197.57801)
			(xy 177.096898 -197.611241) (xy 177.05074 -197.63789) (xy 177.001126 -197.657362) (xy 176.949164 -197.669222)
			(xy 176.896014 -197.673206) (xy 176.842864 -197.669222) (xy 176.790902 -197.657362) (xy 176.741288 -197.63789)
			(xy 176.69513 -197.611241) (xy 176.653459 -197.57801) (xy 176.617207 -197.538939) (xy 176.587183 -197.494902)
			(xy 176.564057 -197.446881) (xy 176.548347 -197.395951) (xy 176.540404 -197.343247) (xy 158.88716 -197.343247)
			(xy 158.88716 -198.193385) (xy 172.440336 -198.193385) (xy 172.440336 -198.140087) (xy 172.448279 -198.087383)
			(xy 172.463989 -198.036453) (xy 172.487115 -197.988432) (xy 172.517139 -197.944395) (xy 172.553391 -197.905324)
			(xy 172.595062 -197.872093) (xy 172.64122 -197.845444) (xy 172.690834 -197.825972) (xy 172.742796 -197.814112)
			(xy 172.795946 -197.810129) (xy 172.849096 -197.814112) (xy 172.901058 -197.825972) (xy 172.950672 -197.845444)
			(xy 172.99683 -197.872093) (xy 173.038501 -197.905324) (xy 173.074753 -197.944395) (xy 173.104777 -197.988432)
			(xy 173.127903 -198.036453) (xy 173.143613 -198.087383) (xy 173.151556 -198.140087) (xy 173.152054 -198.166736)
			(xy 173.151556 -198.193385) (xy 187.527936 -198.193385) (xy 187.527936 -198.140087) (xy 187.535879 -198.087383)
			(xy 187.551589 -198.036453) (xy 187.574715 -197.988432) (xy 187.604739 -197.944395) (xy 187.640991 -197.905324)
			(xy 187.682662 -197.872093) (xy 187.72882 -197.845444) (xy 187.778434 -197.825972) (xy 187.830396 -197.814112)
			(xy 187.883546 -197.810129) (xy 187.936696 -197.814112) (xy 187.988658 -197.825972) (xy 188.038272 -197.845444)
			(xy 188.08443 -197.872093) (xy 188.126101 -197.905324) (xy 188.162353 -197.944395) (xy 188.192377 -197.988432)
			(xy 188.215503 -198.036453) (xy 188.231213 -198.087383) (xy 188.239156 -198.140087) (xy 188.239654 -198.166736)
			(xy 188.239156 -198.193385) (xy 202.615536 -198.193385) (xy 202.615536 -198.140087) (xy 202.623479 -198.087383)
			(xy 202.639189 -198.036453) (xy 202.662315 -197.988432) (xy 202.692339 -197.944395) (xy 202.728591 -197.905324)
			(xy 202.770262 -197.872093) (xy 202.81642 -197.845444) (xy 202.866034 -197.825972) (xy 202.917996 -197.814112)
			(xy 202.971146 -197.810129) (xy 203.024296 -197.814112) (xy 203.076258 -197.825972) (xy 203.125872 -197.845444)
			(xy 203.17203 -197.872093) (xy 203.213701 -197.905324) (xy 203.249953 -197.944395) (xy 203.279977 -197.988432)
			(xy 203.303103 -198.036453) (xy 203.318813 -198.087383) (xy 203.326756 -198.140087) (xy 203.327254 -198.166736)
			(xy 203.326756 -198.193385) (xy 203.318813 -198.246089) (xy 203.303103 -198.297019) (xy 203.279977 -198.34504)
			(xy 203.249953 -198.389077) (xy 203.213701 -198.428148) (xy 203.17203 -198.461379) (xy 203.125872 -198.488028)
			(xy 203.076258 -198.5075) (xy 203.024296 -198.51936) (xy 202.971146 -198.523344) (xy 202.917996 -198.51936)
			(xy 202.866034 -198.5075) (xy 202.81642 -198.488028) (xy 202.770262 -198.461379) (xy 202.728591 -198.428148)
			(xy 202.692339 -198.389077) (xy 202.662315 -198.34504) (xy 202.639189 -198.297019) (xy 202.623479 -198.246089)
			(xy 202.615536 -198.193385) (xy 188.239156 -198.193385) (xy 188.231213 -198.246089) (xy 188.215503 -198.297019)
			(xy 188.192377 -198.34504) (xy 188.162353 -198.389077) (xy 188.126101 -198.428148) (xy 188.08443 -198.461379)
			(xy 188.038272 -198.488028) (xy 187.988658 -198.5075) (xy 187.936696 -198.51936) (xy 187.883546 -198.523344)
			(xy 187.830396 -198.51936) (xy 187.778434 -198.5075) (xy 187.72882 -198.488028) (xy 187.682662 -198.461379)
			(xy 187.640991 -198.428148) (xy 187.604739 -198.389077) (xy 187.574715 -198.34504) (xy 187.551589 -198.297019)
			(xy 187.535879 -198.246089) (xy 187.527936 -198.193385) (xy 173.151556 -198.193385) (xy 173.143613 -198.246089)
			(xy 173.127903 -198.297019) (xy 173.104777 -198.34504) (xy 173.074753 -198.389077) (xy 173.038501 -198.428148)
			(xy 172.99683 -198.461379) (xy 172.950672 -198.488028) (xy 172.901058 -198.5075) (xy 172.849096 -198.51936)
			(xy 172.795946 -198.523344) (xy 172.742796 -198.51936) (xy 172.690834 -198.5075) (xy 172.64122 -198.488028)
			(xy 172.595062 -198.461379) (xy 172.553391 -198.428148) (xy 172.517139 -198.389077) (xy 172.487115 -198.34504)
			(xy 172.463989 -198.297019) (xy 172.448279 -198.246089) (xy 172.440336 -198.193385) (xy 158.88716 -198.193385)
			(xy 158.88716 -199.043269) (xy 176.540404 -199.043269) (xy 176.540404 -198.989971) (xy 176.548347 -198.937267)
			(xy 176.564057 -198.886337) (xy 176.587183 -198.838316) (xy 176.617207 -198.794279) (xy 176.653459 -198.755208)
			(xy 176.69513 -198.721977) (xy 176.741288 -198.695328) (xy 176.790902 -198.675856) (xy 176.842864 -198.663996)
			(xy 176.896014 -198.660013) (xy 176.949164 -198.663996) (xy 177.001126 -198.675856) (xy 177.05074 -198.695328)
			(xy 177.096898 -198.721977) (xy 177.138569 -198.755208) (xy 177.174821 -198.794279) (xy 177.204845 -198.838316)
			(xy 177.227971 -198.886337) (xy 177.243681 -198.937267) (xy 177.251624 -198.989971) (xy 177.252122 -199.01662)
			(xy 177.251624 -199.043269) (xy 191.628004 -199.043269) (xy 191.628004 -198.989971) (xy 191.635947 -198.937267)
			(xy 191.651657 -198.886337) (xy 191.674783 -198.838316) (xy 191.704807 -198.794279) (xy 191.741059 -198.755208)
			(xy 191.78273 -198.721977) (xy 191.828888 -198.695328) (xy 191.878502 -198.675856) (xy 191.930464 -198.663996)
			(xy 191.983614 -198.660013) (xy 192.036764 -198.663996) (xy 192.088726 -198.675856) (xy 192.13834 -198.695328)
			(xy 192.184498 -198.721977) (xy 192.226169 -198.755208) (xy 192.262421 -198.794279) (xy 192.292445 -198.838316)
			(xy 192.315571 -198.886337) (xy 192.331281 -198.937267) (xy 192.339224 -198.989971) (xy 192.339722 -199.01662)
			(xy 192.339224 -199.043269) (xy 206.715604 -199.043269) (xy 206.715604 -198.989971) (xy 206.723547 -198.937267)
			(xy 206.739257 -198.886337) (xy 206.762383 -198.838316) (xy 206.792407 -198.794279) (xy 206.828659 -198.755208)
			(xy 206.87033 -198.721977) (xy 206.916488 -198.695328) (xy 206.966102 -198.675856) (xy 207.018064 -198.663996)
			(xy 207.071214 -198.660013) (xy 207.124364 -198.663996) (xy 207.176326 -198.675856) (xy 207.22594 -198.695328)
			(xy 207.272098 -198.721977) (xy 207.313769 -198.755208) (xy 207.350021 -198.794279) (xy 207.380045 -198.838316)
			(xy 207.403171 -198.886337) (xy 207.418881 -198.937267) (xy 207.426824 -198.989971) (xy 207.427322 -199.01662)
			(xy 207.426824 -199.043269) (xy 207.418881 -199.095973) (xy 207.403171 -199.146903) (xy 207.380045 -199.194924)
			(xy 207.350021 -199.238961) (xy 207.313769 -199.278032) (xy 207.272098 -199.311263) (xy 207.22594 -199.337912)
			(xy 207.176326 -199.357384) (xy 207.124364 -199.369244) (xy 207.071214 -199.373228) (xy 207.018064 -199.369244)
			(xy 206.966102 -199.357384) (xy 206.916488 -199.337912) (xy 206.87033 -199.311263) (xy 206.828659 -199.278032)
			(xy 206.792407 -199.238961) (xy 206.762383 -199.194924) (xy 206.739257 -199.146903) (xy 206.723547 -199.095973)
			(xy 206.715604 -199.043269) (xy 192.339224 -199.043269) (xy 192.331281 -199.095973) (xy 192.315571 -199.146903)
			(xy 192.292445 -199.194924) (xy 192.262421 -199.238961) (xy 192.226169 -199.278032) (xy 192.184498 -199.311263)
			(xy 192.13834 -199.337912) (xy 192.088726 -199.357384) (xy 192.036764 -199.369244) (xy 191.983614 -199.373228)
			(xy 191.930464 -199.369244) (xy 191.878502 -199.357384) (xy 191.828888 -199.337912) (xy 191.78273 -199.311263)
			(xy 191.741059 -199.278032) (xy 191.704807 -199.238961) (xy 191.674783 -199.194924) (xy 191.651657 -199.146903)
			(xy 191.635947 -199.095973) (xy 191.628004 -199.043269) (xy 177.251624 -199.043269) (xy 177.243681 -199.095973)
			(xy 177.227971 -199.146903) (xy 177.204845 -199.194924) (xy 177.174821 -199.238961) (xy 177.138569 -199.278032)
			(xy 177.096898 -199.311263) (xy 177.05074 -199.337912) (xy 177.001126 -199.357384) (xy 176.949164 -199.369244)
			(xy 176.896014 -199.373228) (xy 176.842864 -199.369244) (xy 176.790902 -199.357384) (xy 176.741288 -199.337912)
			(xy 176.69513 -199.311263) (xy 176.653459 -199.278032) (xy 176.617207 -199.238961) (xy 176.587183 -199.194924)
			(xy 176.564057 -199.146903) (xy 176.548347 -199.095973) (xy 176.540404 -199.043269) (xy 158.88716 -199.043269)
			(xy 158.88716 -199.893407) (xy 172.440336 -199.893407) (xy 172.440336 -199.840109) (xy 172.448279 -199.787405)
			(xy 172.463989 -199.736475) (xy 172.487115 -199.688454) (xy 172.517139 -199.644417) (xy 172.553391 -199.605346)
			(xy 172.595062 -199.572115) (xy 172.64122 -199.545466) (xy 172.690834 -199.525994) (xy 172.742796 -199.514134)
			(xy 172.795946 -199.510151) (xy 172.849096 -199.514134) (xy 172.901058 -199.525994) (xy 172.950672 -199.545466)
			(xy 172.99683 -199.572115) (xy 173.038501 -199.605346) (xy 173.074753 -199.644417) (xy 173.104777 -199.688454)
			(xy 173.127903 -199.736475) (xy 173.143613 -199.787405) (xy 173.151556 -199.840109) (xy 173.152054 -199.866758)
			(xy 173.151556 -199.893407) (xy 176.540404 -199.893407) (xy 176.540404 -199.840109) (xy 176.548347 -199.787405)
			(xy 176.564057 -199.736475) (xy 176.587183 -199.688454) (xy 176.617207 -199.644417) (xy 176.653459 -199.605346)
			(xy 176.69513 -199.572115) (xy 176.741288 -199.545466) (xy 176.790902 -199.525994) (xy 176.842864 -199.514134)
			(xy 176.896014 -199.510151) (xy 176.949164 -199.514134) (xy 177.001126 -199.525994) (xy 177.05074 -199.545466)
			(xy 177.096898 -199.572115) (xy 177.138569 -199.605346) (xy 177.174821 -199.644417) (xy 177.204845 -199.688454)
			(xy 177.227971 -199.736475) (xy 177.243681 -199.787405) (xy 177.251624 -199.840109) (xy 177.252122 -199.866758)
			(xy 177.251624 -199.893407) (xy 187.527936 -199.893407) (xy 187.527936 -199.840109) (xy 187.535879 -199.787405)
			(xy 187.551589 -199.736475) (xy 187.574715 -199.688454) (xy 187.604739 -199.644417) (xy 187.640991 -199.605346)
			(xy 187.682662 -199.572115) (xy 187.72882 -199.545466) (xy 187.778434 -199.525994) (xy 187.830396 -199.514134)
			(xy 187.883546 -199.510151) (xy 187.936696 -199.514134) (xy 187.988658 -199.525994) (xy 188.038272 -199.545466)
			(xy 188.08443 -199.572115) (xy 188.126101 -199.605346) (xy 188.162353 -199.644417) (xy 188.192377 -199.688454)
			(xy 188.215503 -199.736475) (xy 188.231213 -199.787405) (xy 188.239156 -199.840109) (xy 188.239654 -199.866758)
			(xy 188.239156 -199.893407) (xy 191.628004 -199.893407) (xy 191.628004 -199.840109) (xy 191.635947 -199.787405)
			(xy 191.651657 -199.736475) (xy 191.674783 -199.688454) (xy 191.704807 -199.644417) (xy 191.741059 -199.605346)
			(xy 191.78273 -199.572115) (xy 191.828888 -199.545466) (xy 191.878502 -199.525994) (xy 191.930464 -199.514134)
			(xy 191.983614 -199.510151) (xy 192.036764 -199.514134) (xy 192.088726 -199.525994) (xy 192.13834 -199.545466)
			(xy 192.184498 -199.572115) (xy 192.226169 -199.605346) (xy 192.262421 -199.644417) (xy 192.292445 -199.688454)
			(xy 192.315571 -199.736475) (xy 192.331281 -199.787405) (xy 192.339224 -199.840109) (xy 192.339722 -199.866758)
			(xy 192.339224 -199.893407) (xy 202.615536 -199.893407) (xy 202.615536 -199.840109) (xy 202.623479 -199.787405)
			(xy 202.639189 -199.736475) (xy 202.662315 -199.688454) (xy 202.692339 -199.644417) (xy 202.728591 -199.605346)
			(xy 202.770262 -199.572115) (xy 202.81642 -199.545466) (xy 202.866034 -199.525994) (xy 202.917996 -199.514134)
			(xy 202.971146 -199.510151) (xy 203.024296 -199.514134) (xy 203.076258 -199.525994) (xy 203.125872 -199.545466)
			(xy 203.17203 -199.572115) (xy 203.213701 -199.605346) (xy 203.249953 -199.644417) (xy 203.279977 -199.688454)
			(xy 203.303103 -199.736475) (xy 203.318813 -199.787405) (xy 203.326756 -199.840109) (xy 203.327254 -199.866758)
			(xy 203.326756 -199.893407) (xy 206.715604 -199.893407) (xy 206.715604 -199.840109) (xy 206.723547 -199.787405)
			(xy 206.739257 -199.736475) (xy 206.762383 -199.688454) (xy 206.792407 -199.644417) (xy 206.828659 -199.605346)
			(xy 206.87033 -199.572115) (xy 206.916488 -199.545466) (xy 206.966102 -199.525994) (xy 207.018064 -199.514134)
			(xy 207.071214 -199.510151) (xy 207.124364 -199.514134) (xy 207.176326 -199.525994) (xy 207.22594 -199.545466)
			(xy 207.272098 -199.572115) (xy 207.313769 -199.605346) (xy 207.350021 -199.644417) (xy 207.380045 -199.688454)
			(xy 207.403171 -199.736475) (xy 207.418881 -199.787405) (xy 207.426824 -199.840109) (xy 207.427322 -199.866758)
			(xy 207.426824 -199.893407) (xy 207.418881 -199.946111) (xy 207.403171 -199.997041) (xy 207.380045 -200.045062)
			(xy 207.350021 -200.089099) (xy 207.313769 -200.12817) (xy 207.272098 -200.161401) (xy 207.22594 -200.18805)
			(xy 207.176326 -200.207522) (xy 207.124364 -200.219382) (xy 207.071214 -200.223366) (xy 207.018064 -200.219382)
			(xy 206.966102 -200.207522) (xy 206.916488 -200.18805) (xy 206.87033 -200.161401) (xy 206.828659 -200.12817)
			(xy 206.792407 -200.089099) (xy 206.762383 -200.045062) (xy 206.739257 -199.997041) (xy 206.723547 -199.946111)
			(xy 206.715604 -199.893407) (xy 203.326756 -199.893407) (xy 203.318813 -199.946111) (xy 203.303103 -199.997041)
			(xy 203.279977 -200.045062) (xy 203.249953 -200.089099) (xy 203.213701 -200.12817) (xy 203.17203 -200.161401)
			(xy 203.125872 -200.18805) (xy 203.076258 -200.207522) (xy 203.024296 -200.219382) (xy 202.971146 -200.223366)
			(xy 202.917996 -200.219382) (xy 202.866034 -200.207522) (xy 202.81642 -200.18805) (xy 202.770262 -200.161401)
			(xy 202.728591 -200.12817) (xy 202.692339 -200.089099) (xy 202.662315 -200.045062) (xy 202.639189 -199.997041)
			(xy 202.623479 -199.946111) (xy 202.615536 -199.893407) (xy 192.339224 -199.893407) (xy 192.331281 -199.946111)
			(xy 192.315571 -199.997041) (xy 192.292445 -200.045062) (xy 192.262421 -200.089099) (xy 192.226169 -200.12817)
			(xy 192.184498 -200.161401) (xy 192.13834 -200.18805) (xy 192.088726 -200.207522) (xy 192.036764 -200.219382)
			(xy 191.983614 -200.223366) (xy 191.930464 -200.219382) (xy 191.878502 -200.207522) (xy 191.828888 -200.18805)
			(xy 191.78273 -200.161401) (xy 191.741059 -200.12817) (xy 191.704807 -200.089099) (xy 191.674783 -200.045062)
			(xy 191.651657 -199.997041) (xy 191.635947 -199.946111) (xy 191.628004 -199.893407) (xy 188.239156 -199.893407)
			(xy 188.231213 -199.946111) (xy 188.215503 -199.997041) (xy 188.192377 -200.045062) (xy 188.162353 -200.089099)
			(xy 188.126101 -200.12817) (xy 188.08443 -200.161401) (xy 188.038272 -200.18805) (xy 187.988658 -200.207522)
			(xy 187.936696 -200.219382) (xy 187.883546 -200.223366) (xy 187.830396 -200.219382) (xy 187.778434 -200.207522)
			(xy 187.72882 -200.18805) (xy 187.682662 -200.161401) (xy 187.640991 -200.12817) (xy 187.604739 -200.089099)
			(xy 187.574715 -200.045062) (xy 187.551589 -199.997041) (xy 187.535879 -199.946111) (xy 187.527936 -199.893407)
			(xy 177.251624 -199.893407) (xy 177.243681 -199.946111) (xy 177.227971 -199.997041) (xy 177.204845 -200.045062)
			(xy 177.174821 -200.089099) (xy 177.138569 -200.12817) (xy 177.096898 -200.161401) (xy 177.05074 -200.18805)
			(xy 177.001126 -200.207522) (xy 176.949164 -200.219382) (xy 176.896014 -200.223366) (xy 176.842864 -200.219382)
			(xy 176.790902 -200.207522) (xy 176.741288 -200.18805) (xy 176.69513 -200.161401) (xy 176.653459 -200.12817)
			(xy 176.617207 -200.089099) (xy 176.587183 -200.045062) (xy 176.564057 -199.997041) (xy 176.548347 -199.946111)
			(xy 176.540404 -199.893407) (xy 173.151556 -199.893407) (xy 173.143613 -199.946111) (xy 173.127903 -199.997041)
			(xy 173.104777 -200.045062) (xy 173.074753 -200.089099) (xy 173.038501 -200.12817) (xy 172.99683 -200.161401)
			(xy 172.950672 -200.18805) (xy 172.901058 -200.207522) (xy 172.849096 -200.219382) (xy 172.795946 -200.223366)
			(xy 172.742796 -200.219382) (xy 172.690834 -200.207522) (xy 172.64122 -200.18805) (xy 172.595062 -200.161401)
			(xy 172.553391 -200.12817) (xy 172.517139 -200.089099) (xy 172.487115 -200.045062) (xy 172.463989 -199.997041)
			(xy 172.448279 -199.946111) (xy 172.440336 -199.893407) (xy 158.88716 -199.893407) (xy 158.88716 -200.743291)
			(xy 172.440336 -200.743291) (xy 172.440336 -200.689993) (xy 172.448279 -200.637289) (xy 172.463989 -200.586359)
			(xy 172.487115 -200.538338) (xy 172.517139 -200.494301) (xy 172.553391 -200.45523) (xy 172.595062 -200.421999)
			(xy 172.64122 -200.39535) (xy 172.690834 -200.375878) (xy 172.742796 -200.364018) (xy 172.795946 -200.360035)
			(xy 172.849096 -200.364018) (xy 172.901058 -200.375878) (xy 172.950672 -200.39535) (xy 172.99683 -200.421999)
			(xy 173.038501 -200.45523) (xy 173.074753 -200.494301) (xy 173.104777 -200.538338) (xy 173.127903 -200.586359)
			(xy 173.143613 -200.637289) (xy 173.151556 -200.689993) (xy 173.152054 -200.716642) (xy 173.151556 -200.743291)
			(xy 187.527936 -200.743291) (xy 187.527936 -200.689993) (xy 187.535879 -200.637289) (xy 187.551589 -200.586359)
			(xy 187.574715 -200.538338) (xy 187.604739 -200.494301) (xy 187.640991 -200.45523) (xy 187.682662 -200.421999)
			(xy 187.72882 -200.39535) (xy 187.778434 -200.375878) (xy 187.830396 -200.364018) (xy 187.883546 -200.360035)
			(xy 187.936696 -200.364018) (xy 187.988658 -200.375878) (xy 188.038272 -200.39535) (xy 188.08443 -200.421999)
			(xy 188.126101 -200.45523) (xy 188.162353 -200.494301) (xy 188.192377 -200.538338) (xy 188.215503 -200.586359)
			(xy 188.231213 -200.637289) (xy 188.239156 -200.689993) (xy 188.239654 -200.716642) (xy 188.239156 -200.743291)
			(xy 202.615536 -200.743291) (xy 202.615536 -200.689993) (xy 202.623479 -200.637289) (xy 202.639189 -200.586359)
			(xy 202.662315 -200.538338) (xy 202.692339 -200.494301) (xy 202.728591 -200.45523) (xy 202.770262 -200.421999)
			(xy 202.81642 -200.39535) (xy 202.866034 -200.375878) (xy 202.917996 -200.364018) (xy 202.971146 -200.360035)
			(xy 203.024296 -200.364018) (xy 203.076258 -200.375878) (xy 203.125872 -200.39535) (xy 203.17203 -200.421999)
			(xy 203.213701 -200.45523) (xy 203.249953 -200.494301) (xy 203.279977 -200.538338) (xy 203.303103 -200.586359)
			(xy 203.318813 -200.637289) (xy 203.326756 -200.689993) (xy 203.327254 -200.716642) (xy 203.326756 -200.743291)
			(xy 203.318813 -200.795995) (xy 203.303103 -200.846925) (xy 203.279977 -200.894946) (xy 203.249953 -200.938983)
			(xy 203.213701 -200.978054) (xy 203.17203 -201.011285) (xy 203.125872 -201.037934) (xy 203.076258 -201.057406)
			(xy 203.024296 -201.069266) (xy 202.971146 -201.07325) (xy 202.917996 -201.069266) (xy 202.866034 -201.057406)
			(xy 202.81642 -201.037934) (xy 202.770262 -201.011285) (xy 202.728591 -200.978054) (xy 202.692339 -200.938983)
			(xy 202.662315 -200.894946) (xy 202.639189 -200.846925) (xy 202.623479 -200.795995) (xy 202.615536 -200.743291)
			(xy 188.239156 -200.743291) (xy 188.231213 -200.795995) (xy 188.215503 -200.846925) (xy 188.192377 -200.894946)
			(xy 188.162353 -200.938983) (xy 188.126101 -200.978054) (xy 188.08443 -201.011285) (xy 188.038272 -201.037934)
			(xy 187.988658 -201.057406) (xy 187.936696 -201.069266) (xy 187.883546 -201.07325) (xy 187.830396 -201.069266)
			(xy 187.778434 -201.057406) (xy 187.72882 -201.037934) (xy 187.682662 -201.011285) (xy 187.640991 -200.978054)
			(xy 187.604739 -200.938983) (xy 187.574715 -200.894946) (xy 187.551589 -200.846925) (xy 187.535879 -200.795995)
			(xy 187.527936 -200.743291) (xy 173.151556 -200.743291) (xy 173.143613 -200.795995) (xy 173.127903 -200.846925)
			(xy 173.104777 -200.894946) (xy 173.074753 -200.938983) (xy 173.038501 -200.978054) (xy 172.99683 -201.011285)
			(xy 172.950672 -201.037934) (xy 172.901058 -201.057406) (xy 172.849096 -201.069266) (xy 172.795946 -201.07325)
			(xy 172.742796 -201.069266) (xy 172.690834 -201.057406) (xy 172.64122 -201.037934) (xy 172.595062 -201.011285)
			(xy 172.553391 -200.978054) (xy 172.517139 -200.938983) (xy 172.487115 -200.894946) (xy 172.463989 -200.846925)
			(xy 172.448279 -200.795995) (xy 172.440336 -200.743291) (xy 158.88716 -200.743291) (xy 158.88716 -201.593429)
			(xy 176.540404 -201.593429) (xy 176.540404 -201.540131) (xy 176.548347 -201.487427) (xy 176.564057 -201.436497)
			(xy 176.587183 -201.388476) (xy 176.617207 -201.344439) (xy 176.653459 -201.305368) (xy 176.69513 -201.272137)
			(xy 176.741288 -201.245488) (xy 176.790902 -201.226016) (xy 176.842864 -201.214156) (xy 176.896014 -201.210173)
			(xy 176.949164 -201.214156) (xy 177.001126 -201.226016) (xy 177.05074 -201.245488) (xy 177.096898 -201.272137)
			(xy 177.138569 -201.305368) (xy 177.174821 -201.344439) (xy 177.204845 -201.388476) (xy 177.227971 -201.436497)
			(xy 177.243681 -201.487427) (xy 177.251624 -201.540131) (xy 177.252122 -201.56678) (xy 177.251624 -201.593429)
			(xy 191.628004 -201.593429) (xy 191.628004 -201.540131) (xy 191.635947 -201.487427) (xy 191.651657 -201.436497)
			(xy 191.674783 -201.388476) (xy 191.704807 -201.344439) (xy 191.741059 -201.305368) (xy 191.78273 -201.272137)
			(xy 191.828888 -201.245488) (xy 191.878502 -201.226016) (xy 191.930464 -201.214156) (xy 191.983614 -201.210173)
			(xy 192.036764 -201.214156) (xy 192.088726 -201.226016) (xy 192.13834 -201.245488) (xy 192.184498 -201.272137)
			(xy 192.226169 -201.305368) (xy 192.262421 -201.344439) (xy 192.292445 -201.388476) (xy 192.315571 -201.436497)
			(xy 192.331281 -201.487427) (xy 192.339224 -201.540131) (xy 192.339722 -201.56678) (xy 192.339224 -201.593429)
			(xy 206.715604 -201.593429) (xy 206.715604 -201.540131) (xy 206.723547 -201.487427) (xy 206.739257 -201.436497)
			(xy 206.762383 -201.388476) (xy 206.792407 -201.344439) (xy 206.828659 -201.305368) (xy 206.87033 -201.272137)
			(xy 206.916488 -201.245488) (xy 206.966102 -201.226016) (xy 207.018064 -201.214156) (xy 207.071214 -201.210173)
			(xy 207.124364 -201.214156) (xy 207.176326 -201.226016) (xy 207.22594 -201.245488) (xy 207.272098 -201.272137)
			(xy 207.313769 -201.305368) (xy 207.350021 -201.344439) (xy 207.380045 -201.388476) (xy 207.403171 -201.436497)
			(xy 207.418881 -201.487427) (xy 207.426824 -201.540131) (xy 207.427322 -201.56678) (xy 207.426824 -201.593429)
			(xy 207.418881 -201.646133) (xy 207.403171 -201.697063) (xy 207.380045 -201.745084) (xy 207.350021 -201.789121)
			(xy 207.313769 -201.828192) (xy 207.272098 -201.861423) (xy 207.22594 -201.888072) (xy 207.176326 -201.907544)
			(xy 207.124364 -201.919404) (xy 207.071214 -201.923388) (xy 207.018064 -201.919404) (xy 206.966102 -201.907544)
			(xy 206.916488 -201.888072) (xy 206.87033 -201.861423) (xy 206.828659 -201.828192) (xy 206.792407 -201.789121)
			(xy 206.762383 -201.745084) (xy 206.739257 -201.697063) (xy 206.723547 -201.646133) (xy 206.715604 -201.593429)
			(xy 192.339224 -201.593429) (xy 192.331281 -201.646133) (xy 192.315571 -201.697063) (xy 192.292445 -201.745084)
			(xy 192.262421 -201.789121) (xy 192.226169 -201.828192) (xy 192.184498 -201.861423) (xy 192.13834 -201.888072)
			(xy 192.088726 -201.907544) (xy 192.036764 -201.919404) (xy 191.983614 -201.923388) (xy 191.930464 -201.919404)
			(xy 191.878502 -201.907544) (xy 191.828888 -201.888072) (xy 191.78273 -201.861423) (xy 191.741059 -201.828192)
			(xy 191.704807 -201.789121) (xy 191.674783 -201.745084) (xy 191.651657 -201.697063) (xy 191.635947 -201.646133)
			(xy 191.628004 -201.593429) (xy 177.251624 -201.593429) (xy 177.243681 -201.646133) (xy 177.227971 -201.697063)
			(xy 177.204845 -201.745084) (xy 177.174821 -201.789121) (xy 177.138569 -201.828192) (xy 177.096898 -201.861423)
			(xy 177.05074 -201.888072) (xy 177.001126 -201.907544) (xy 176.949164 -201.919404) (xy 176.896014 -201.923388)
			(xy 176.842864 -201.919404) (xy 176.790902 -201.907544) (xy 176.741288 -201.888072) (xy 176.69513 -201.861423)
			(xy 176.653459 -201.828192) (xy 176.617207 -201.789121) (xy 176.587183 -201.745084) (xy 176.564057 -201.697063)
			(xy 176.548347 -201.646133) (xy 176.540404 -201.593429) (xy 158.88716 -201.593429) (xy 158.88716 -202.443313)
			(xy 172.440336 -202.443313) (xy 172.440336 -202.390015) (xy 172.448279 -202.337311) (xy 172.463989 -202.286381)
			(xy 172.487115 -202.23836) (xy 172.517139 -202.194323) (xy 172.553391 -202.155252) (xy 172.595062 -202.122021)
			(xy 172.64122 -202.095372) (xy 172.690834 -202.0759) (xy 172.742796 -202.06404) (xy 172.795946 -202.060057)
			(xy 172.849096 -202.06404) (xy 172.901058 -202.0759) (xy 172.950672 -202.095372) (xy 172.99683 -202.122021)
			(xy 173.038501 -202.155252) (xy 173.074753 -202.194323) (xy 173.104777 -202.23836) (xy 173.127903 -202.286381)
			(xy 173.143613 -202.337311) (xy 173.151556 -202.390015) (xy 173.152054 -202.416664) (xy 173.151556 -202.443313)
			(xy 187.527936 -202.443313) (xy 187.527936 -202.390015) (xy 187.535879 -202.337311) (xy 187.551589 -202.286381)
			(xy 187.574715 -202.23836) (xy 187.604739 -202.194323) (xy 187.640991 -202.155252) (xy 187.682662 -202.122021)
			(xy 187.72882 -202.095372) (xy 187.778434 -202.0759) (xy 187.830396 -202.06404) (xy 187.883546 -202.060057)
			(xy 187.936696 -202.06404) (xy 187.988658 -202.0759) (xy 188.038272 -202.095372) (xy 188.08443 -202.122021)
			(xy 188.126101 -202.155252) (xy 188.162353 -202.194323) (xy 188.192377 -202.23836) (xy 188.215503 -202.286381)
			(xy 188.231213 -202.337311) (xy 188.239156 -202.390015) (xy 188.239654 -202.416664) (xy 188.239156 -202.443313)
			(xy 202.615536 -202.443313) (xy 202.615536 -202.390015) (xy 202.623479 -202.337311) (xy 202.639189 -202.286381)
			(xy 202.662315 -202.23836) (xy 202.692339 -202.194323) (xy 202.728591 -202.155252) (xy 202.770262 -202.122021)
			(xy 202.81642 -202.095372) (xy 202.866034 -202.0759) (xy 202.917996 -202.06404) (xy 202.971146 -202.060057)
			(xy 203.024296 -202.06404) (xy 203.076258 -202.0759) (xy 203.125872 -202.095372) (xy 203.17203 -202.122021)
			(xy 203.213701 -202.155252) (xy 203.249953 -202.194323) (xy 203.279977 -202.23836) (xy 203.303103 -202.286381)
			(xy 203.318813 -202.337311) (xy 203.326756 -202.390015) (xy 203.327254 -202.416664) (xy 203.326756 -202.443313)
			(xy 203.318813 -202.496017) (xy 203.303103 -202.546947) (xy 203.279977 -202.594968) (xy 203.249953 -202.639005)
			(xy 203.213701 -202.678076) (xy 203.17203 -202.711307) (xy 203.125872 -202.737956) (xy 203.076258 -202.757428)
			(xy 203.024296 -202.769288) (xy 202.971146 -202.773272) (xy 202.917996 -202.769288) (xy 202.866034 -202.757428)
			(xy 202.81642 -202.737956) (xy 202.770262 -202.711307) (xy 202.728591 -202.678076) (xy 202.692339 -202.639005)
			(xy 202.662315 -202.594968) (xy 202.639189 -202.546947) (xy 202.623479 -202.496017) (xy 202.615536 -202.443313)
			(xy 188.239156 -202.443313) (xy 188.231213 -202.496017) (xy 188.215503 -202.546947) (xy 188.192377 -202.594968)
			(xy 188.162353 -202.639005) (xy 188.126101 -202.678076) (xy 188.08443 -202.711307) (xy 188.038272 -202.737956)
			(xy 187.988658 -202.757428) (xy 187.936696 -202.769288) (xy 187.883546 -202.773272) (xy 187.830396 -202.769288)
			(xy 187.778434 -202.757428) (xy 187.72882 -202.737956) (xy 187.682662 -202.711307) (xy 187.640991 -202.678076)
			(xy 187.604739 -202.639005) (xy 187.574715 -202.594968) (xy 187.551589 -202.546947) (xy 187.535879 -202.496017)
			(xy 187.527936 -202.443313) (xy 173.151556 -202.443313) (xy 173.143613 -202.496017) (xy 173.127903 -202.546947)
			(xy 173.104777 -202.594968) (xy 173.074753 -202.639005) (xy 173.038501 -202.678076) (xy 172.99683 -202.711307)
			(xy 172.950672 -202.737956) (xy 172.901058 -202.757428) (xy 172.849096 -202.769288) (xy 172.795946 -202.773272)
			(xy 172.742796 -202.769288) (xy 172.690834 -202.757428) (xy 172.64122 -202.737956) (xy 172.595062 -202.711307)
			(xy 172.553391 -202.678076) (xy 172.517139 -202.639005) (xy 172.487115 -202.594968) (xy 172.463989 -202.546947)
			(xy 172.448279 -202.496017) (xy 172.440336 -202.443313) (xy 158.88716 -202.443313) (xy 158.88716 -203.293451)
			(xy 176.540404 -203.293451) (xy 176.540404 -203.240153) (xy 176.548347 -203.187449) (xy 176.564057 -203.136519)
			(xy 176.587183 -203.088498) (xy 176.617207 -203.044461) (xy 176.653459 -203.00539) (xy 176.69513 -202.972159)
			(xy 176.741288 -202.94551) (xy 176.790902 -202.926038) (xy 176.842864 -202.914178) (xy 176.896014 -202.910195)
			(xy 176.949164 -202.914178) (xy 177.001126 -202.926038) (xy 177.05074 -202.94551) (xy 177.096898 -202.972159)
			(xy 177.138569 -203.00539) (xy 177.174821 -203.044461) (xy 177.204845 -203.088498) (xy 177.227971 -203.136519)
			(xy 177.243681 -203.187449) (xy 177.251624 -203.240153) (xy 177.252122 -203.266802) (xy 177.251624 -203.293451)
			(xy 191.628004 -203.293451) (xy 191.628004 -203.240153) (xy 191.635947 -203.187449) (xy 191.651657 -203.136519)
			(xy 191.674783 -203.088498) (xy 191.704807 -203.044461) (xy 191.741059 -203.00539) (xy 191.78273 -202.972159)
			(xy 191.828888 -202.94551) (xy 191.878502 -202.926038) (xy 191.930464 -202.914178) (xy 191.983614 -202.910195)
			(xy 192.036764 -202.914178) (xy 192.088726 -202.926038) (xy 192.13834 -202.94551) (xy 192.184498 -202.972159)
			(xy 192.226169 -203.00539) (xy 192.262421 -203.044461) (xy 192.292445 -203.088498) (xy 192.315571 -203.136519)
			(xy 192.331281 -203.187449) (xy 192.339224 -203.240153) (xy 192.339722 -203.266802) (xy 192.339224 -203.293451)
			(xy 206.715604 -203.293451) (xy 206.715604 -203.240153) (xy 206.723547 -203.187449) (xy 206.739257 -203.136519)
			(xy 206.762383 -203.088498) (xy 206.792407 -203.044461) (xy 206.828659 -203.00539) (xy 206.87033 -202.972159)
			(xy 206.916488 -202.94551) (xy 206.966102 -202.926038) (xy 207.018064 -202.914178) (xy 207.071214 -202.910195)
			(xy 207.124364 -202.914178) (xy 207.176326 -202.926038) (xy 207.22594 -202.94551) (xy 207.272098 -202.972159)
			(xy 207.313769 -203.00539) (xy 207.350021 -203.044461) (xy 207.380045 -203.088498) (xy 207.403171 -203.136519)
			(xy 207.418881 -203.187449) (xy 207.426824 -203.240153) (xy 207.427322 -203.266802) (xy 207.426824 -203.293451)
			(xy 207.418881 -203.346155) (xy 207.403171 -203.397085) (xy 207.380045 -203.445106) (xy 207.350021 -203.489143)
			(xy 207.313769 -203.528214) (xy 207.272098 -203.561445) (xy 207.22594 -203.588094) (xy 207.176326 -203.607566)
			(xy 207.124364 -203.619426) (xy 207.071214 -203.62341) (xy 207.018064 -203.619426) (xy 206.966102 -203.607566)
			(xy 206.916488 -203.588094) (xy 206.87033 -203.561445) (xy 206.828659 -203.528214) (xy 206.792407 -203.489143)
			(xy 206.762383 -203.445106) (xy 206.739257 -203.397085) (xy 206.723547 -203.346155) (xy 206.715604 -203.293451)
			(xy 192.339224 -203.293451) (xy 192.331281 -203.346155) (xy 192.315571 -203.397085) (xy 192.292445 -203.445106)
			(xy 192.262421 -203.489143) (xy 192.226169 -203.528214) (xy 192.184498 -203.561445) (xy 192.13834 -203.588094)
			(xy 192.088726 -203.607566) (xy 192.036764 -203.619426) (xy 191.983614 -203.62341) (xy 191.930464 -203.619426)
			(xy 191.878502 -203.607566) (xy 191.828888 -203.588094) (xy 191.78273 -203.561445) (xy 191.741059 -203.528214)
			(xy 191.704807 -203.489143) (xy 191.674783 -203.445106) (xy 191.651657 -203.397085) (xy 191.635947 -203.346155)
			(xy 191.628004 -203.293451) (xy 177.251624 -203.293451) (xy 177.243681 -203.346155) (xy 177.227971 -203.397085)
			(xy 177.204845 -203.445106) (xy 177.174821 -203.489143) (xy 177.138569 -203.528214) (xy 177.096898 -203.561445)
			(xy 177.05074 -203.588094) (xy 177.001126 -203.607566) (xy 176.949164 -203.619426) (xy 176.896014 -203.62341)
			(xy 176.842864 -203.619426) (xy 176.790902 -203.607566) (xy 176.741288 -203.588094) (xy 176.69513 -203.561445)
			(xy 176.653459 -203.528214) (xy 176.617207 -203.489143) (xy 176.587183 -203.445106) (xy 176.564057 -203.397085)
			(xy 176.548347 -203.346155) (xy 176.540404 -203.293451) (xy 158.88716 -203.293451) (xy 158.88716 -204.143335)
			(xy 172.440336 -204.143335) (xy 172.440336 -204.090037) (xy 172.448279 -204.037333) (xy 172.463989 -203.986403)
			(xy 172.487115 -203.938382) (xy 172.517139 -203.894345) (xy 172.553391 -203.855274) (xy 172.595062 -203.822043)
			(xy 172.64122 -203.795394) (xy 172.690834 -203.775922) (xy 172.742796 -203.764062) (xy 172.795946 -203.760079)
			(xy 172.849096 -203.764062) (xy 172.901058 -203.775922) (xy 172.950672 -203.795394) (xy 172.99683 -203.822043)
			(xy 173.038501 -203.855274) (xy 173.074753 -203.894345) (xy 173.104777 -203.938382) (xy 173.127903 -203.986403)
			(xy 173.143613 -204.037333) (xy 173.151556 -204.090037) (xy 173.152054 -204.116686) (xy 173.151556 -204.143335)
			(xy 187.527936 -204.143335) (xy 187.527936 -204.090037) (xy 187.535879 -204.037333) (xy 187.551589 -203.986403)
			(xy 187.574715 -203.938382) (xy 187.604739 -203.894345) (xy 187.640991 -203.855274) (xy 187.682662 -203.822043)
			(xy 187.72882 -203.795394) (xy 187.778434 -203.775922) (xy 187.830396 -203.764062) (xy 187.883546 -203.760079)
			(xy 187.936696 -203.764062) (xy 187.988658 -203.775922) (xy 188.038272 -203.795394) (xy 188.08443 -203.822043)
			(xy 188.126101 -203.855274) (xy 188.162353 -203.894345) (xy 188.192377 -203.938382) (xy 188.215503 -203.986403)
			(xy 188.231213 -204.037333) (xy 188.239156 -204.090037) (xy 188.239654 -204.116686) (xy 188.239156 -204.143335)
			(xy 202.615536 -204.143335) (xy 202.615536 -204.090037) (xy 202.623479 -204.037333) (xy 202.639189 -203.986403)
			(xy 202.662315 -203.938382) (xy 202.692339 -203.894345) (xy 202.728591 -203.855274) (xy 202.770262 -203.822043)
			(xy 202.81642 -203.795394) (xy 202.866034 -203.775922) (xy 202.917996 -203.764062) (xy 202.971146 -203.760079)
			(xy 203.024296 -203.764062) (xy 203.076258 -203.775922) (xy 203.125872 -203.795394) (xy 203.17203 -203.822043)
			(xy 203.213701 -203.855274) (xy 203.249953 -203.894345) (xy 203.279977 -203.938382) (xy 203.303103 -203.986403)
			(xy 203.318813 -204.037333) (xy 203.326756 -204.090037) (xy 203.327254 -204.116686) (xy 203.326756 -204.143335)
			(xy 203.318813 -204.196039) (xy 203.303103 -204.246969) (xy 203.279977 -204.29499) (xy 203.249953 -204.339027)
			(xy 203.213701 -204.378098) (xy 203.17203 -204.411329) (xy 203.125872 -204.437978) (xy 203.076258 -204.45745)
			(xy 203.024296 -204.46931) (xy 202.971146 -204.473294) (xy 202.917996 -204.46931) (xy 202.866034 -204.45745)
			(xy 202.81642 -204.437978) (xy 202.770262 -204.411329) (xy 202.728591 -204.378098) (xy 202.692339 -204.339027)
			(xy 202.662315 -204.29499) (xy 202.639189 -204.246969) (xy 202.623479 -204.196039) (xy 202.615536 -204.143335)
			(xy 188.239156 -204.143335) (xy 188.231213 -204.196039) (xy 188.215503 -204.246969) (xy 188.192377 -204.29499)
			(xy 188.162353 -204.339027) (xy 188.126101 -204.378098) (xy 188.08443 -204.411329) (xy 188.038272 -204.437978)
			(xy 187.988658 -204.45745) (xy 187.936696 -204.46931) (xy 187.883546 -204.473294) (xy 187.830396 -204.46931)
			(xy 187.778434 -204.45745) (xy 187.72882 -204.437978) (xy 187.682662 -204.411329) (xy 187.640991 -204.378098)
			(xy 187.604739 -204.339027) (xy 187.574715 -204.29499) (xy 187.551589 -204.246969) (xy 187.535879 -204.196039)
			(xy 187.527936 -204.143335) (xy 173.151556 -204.143335) (xy 173.143613 -204.196039) (xy 173.127903 -204.246969)
			(xy 173.104777 -204.29499) (xy 173.074753 -204.339027) (xy 173.038501 -204.378098) (xy 172.99683 -204.411329)
			(xy 172.950672 -204.437978) (xy 172.901058 -204.45745) (xy 172.849096 -204.46931) (xy 172.795946 -204.473294)
			(xy 172.742796 -204.46931) (xy 172.690834 -204.45745) (xy 172.64122 -204.437978) (xy 172.595062 -204.411329)
			(xy 172.553391 -204.378098) (xy 172.517139 -204.339027) (xy 172.487115 -204.29499) (xy 172.463989 -204.246969)
			(xy 172.448279 -204.196039) (xy 172.440336 -204.143335) (xy 158.88716 -204.143335) (xy 158.88716 -204.993219)
			(xy 176.540404 -204.993219) (xy 176.540404 -204.939921) (xy 176.548347 -204.887217) (xy 176.564057 -204.836287)
			(xy 176.587183 -204.788266) (xy 176.617207 -204.744229) (xy 176.653459 -204.705158) (xy 176.69513 -204.671927)
			(xy 176.741288 -204.645278) (xy 176.790902 -204.625806) (xy 176.842864 -204.613946) (xy 176.896014 -204.609963)
			(xy 176.949164 -204.613946) (xy 177.001126 -204.625806) (xy 177.05074 -204.645278) (xy 177.096898 -204.671927)
			(xy 177.138569 -204.705158) (xy 177.174821 -204.744229) (xy 177.204845 -204.788266) (xy 177.227971 -204.836287)
			(xy 177.243681 -204.887217) (xy 177.251624 -204.939921) (xy 177.252122 -204.96657) (xy 177.251624 -204.993219)
			(xy 191.628004 -204.993219) (xy 191.628004 -204.939921) (xy 191.635947 -204.887217) (xy 191.651657 -204.836287)
			(xy 191.674783 -204.788266) (xy 191.704807 -204.744229) (xy 191.741059 -204.705158) (xy 191.78273 -204.671927)
			(xy 191.828888 -204.645278) (xy 191.878502 -204.625806) (xy 191.930464 -204.613946) (xy 191.983614 -204.609963)
			(xy 192.036764 -204.613946) (xy 192.088726 -204.625806) (xy 192.13834 -204.645278) (xy 192.184498 -204.671927)
			(xy 192.226169 -204.705158) (xy 192.262421 -204.744229) (xy 192.292445 -204.788266) (xy 192.315571 -204.836287)
			(xy 192.331281 -204.887217) (xy 192.339224 -204.939921) (xy 192.339722 -204.96657) (xy 192.339224 -204.993219)
			(xy 206.715604 -204.993219) (xy 206.715604 -204.939921) (xy 206.723547 -204.887217) (xy 206.739257 -204.836287)
			(xy 206.762383 -204.788266) (xy 206.792407 -204.744229) (xy 206.828659 -204.705158) (xy 206.87033 -204.671927)
			(xy 206.916488 -204.645278) (xy 206.966102 -204.625806) (xy 207.018064 -204.613946) (xy 207.071214 -204.609963)
			(xy 207.124364 -204.613946) (xy 207.176326 -204.625806) (xy 207.22594 -204.645278) (xy 207.272098 -204.671927)
			(xy 207.313769 -204.705158) (xy 207.350021 -204.744229) (xy 207.380045 -204.788266) (xy 207.403171 -204.836287)
			(xy 207.418881 -204.887217) (xy 207.426824 -204.939921) (xy 207.427322 -204.96657) (xy 207.426824 -204.993219)
			(xy 207.418881 -205.045923) (xy 207.403171 -205.096853) (xy 207.380045 -205.144874) (xy 207.350021 -205.188911)
			(xy 207.313769 -205.227982) (xy 207.272098 -205.261213) (xy 207.22594 -205.287862) (xy 207.176326 -205.307334)
			(xy 207.124364 -205.319194) (xy 207.071214 -205.323178) (xy 207.018064 -205.319194) (xy 206.966102 -205.307334)
			(xy 206.916488 -205.287862) (xy 206.87033 -205.261213) (xy 206.828659 -205.227982) (xy 206.792407 -205.188911)
			(xy 206.762383 -205.144874) (xy 206.739257 -205.096853) (xy 206.723547 -205.045923) (xy 206.715604 -204.993219)
			(xy 192.339224 -204.993219) (xy 192.331281 -205.045923) (xy 192.315571 -205.096853) (xy 192.292445 -205.144874)
			(xy 192.262421 -205.188911) (xy 192.226169 -205.227982) (xy 192.184498 -205.261213) (xy 192.13834 -205.287862)
			(xy 192.088726 -205.307334) (xy 192.036764 -205.319194) (xy 191.983614 -205.323178) (xy 191.930464 -205.319194)
			(xy 191.878502 -205.307334) (xy 191.828888 -205.287862) (xy 191.78273 -205.261213) (xy 191.741059 -205.227982)
			(xy 191.704807 -205.188911) (xy 191.674783 -205.144874) (xy 191.651657 -205.096853) (xy 191.635947 -205.045923)
			(xy 191.628004 -204.993219) (xy 177.251624 -204.993219) (xy 177.243681 -205.045923) (xy 177.227971 -205.096853)
			(xy 177.204845 -205.144874) (xy 177.174821 -205.188911) (xy 177.138569 -205.227982) (xy 177.096898 -205.261213)
			(xy 177.05074 -205.287862) (xy 177.001126 -205.307334) (xy 176.949164 -205.319194) (xy 176.896014 -205.323178)
			(xy 176.842864 -205.319194) (xy 176.790902 -205.307334) (xy 176.741288 -205.287862) (xy 176.69513 -205.261213)
			(xy 176.653459 -205.227982) (xy 176.617207 -205.188911) (xy 176.587183 -205.144874) (xy 176.564057 -205.096853)
			(xy 176.548347 -205.045923) (xy 176.540404 -204.993219) (xy 158.88716 -204.993219) (xy 158.88716 -205.843357)
			(xy 172.440336 -205.843357) (xy 172.440336 -205.790059) (xy 172.448279 -205.737355) (xy 172.463989 -205.686425)
			(xy 172.487115 -205.638404) (xy 172.517139 -205.594367) (xy 172.553391 -205.555296) (xy 172.595062 -205.522065)
			(xy 172.64122 -205.495416) (xy 172.690834 -205.475944) (xy 172.742796 -205.464084) (xy 172.795946 -205.460101)
			(xy 172.849096 -205.464084) (xy 172.901058 -205.475944) (xy 172.950672 -205.495416) (xy 172.99683 -205.522065)
			(xy 173.038501 -205.555296) (xy 173.074753 -205.594367) (xy 173.104777 -205.638404) (xy 173.127903 -205.686425)
			(xy 173.143613 -205.737355) (xy 173.151556 -205.790059) (xy 173.152054 -205.816708) (xy 173.151556 -205.843357)
			(xy 187.527936 -205.843357) (xy 187.527936 -205.790059) (xy 187.535879 -205.737355) (xy 187.551589 -205.686425)
			(xy 187.574715 -205.638404) (xy 187.604739 -205.594367) (xy 187.640991 -205.555296) (xy 187.682662 -205.522065)
			(xy 187.72882 -205.495416) (xy 187.778434 -205.475944) (xy 187.830396 -205.464084) (xy 187.883546 -205.460101)
			(xy 187.936696 -205.464084) (xy 187.988658 -205.475944) (xy 188.038272 -205.495416) (xy 188.08443 -205.522065)
			(xy 188.126101 -205.555296) (xy 188.162353 -205.594367) (xy 188.192377 -205.638404) (xy 188.215503 -205.686425)
			(xy 188.231213 -205.737355) (xy 188.239156 -205.790059) (xy 188.239654 -205.816708) (xy 188.239156 -205.843357)
			(xy 202.615536 -205.843357) (xy 202.615536 -205.790059) (xy 202.623479 -205.737355) (xy 202.639189 -205.686425)
			(xy 202.662315 -205.638404) (xy 202.692339 -205.594367) (xy 202.728591 -205.555296) (xy 202.770262 -205.522065)
			(xy 202.81642 -205.495416) (xy 202.866034 -205.475944) (xy 202.917996 -205.464084) (xy 202.971146 -205.460101)
			(xy 203.024296 -205.464084) (xy 203.076258 -205.475944) (xy 203.125872 -205.495416) (xy 203.17203 -205.522065)
			(xy 203.213701 -205.555296) (xy 203.249953 -205.594367) (xy 203.279977 -205.638404) (xy 203.303103 -205.686425)
			(xy 203.318813 -205.737355) (xy 203.326756 -205.790059) (xy 203.327254 -205.816708) (xy 203.326756 -205.843357)
			(xy 203.318813 -205.896061) (xy 203.303103 -205.946991) (xy 203.279977 -205.995012) (xy 203.249953 -206.039049)
			(xy 203.213701 -206.07812) (xy 203.17203 -206.111351) (xy 203.125872 -206.138) (xy 203.076258 -206.157472)
			(xy 203.024296 -206.169332) (xy 202.971146 -206.173316) (xy 202.917996 -206.169332) (xy 202.866034 -206.157472)
			(xy 202.81642 -206.138) (xy 202.770262 -206.111351) (xy 202.728591 -206.07812) (xy 202.692339 -206.039049)
			(xy 202.662315 -205.995012) (xy 202.639189 -205.946991) (xy 202.623479 -205.896061) (xy 202.615536 -205.843357)
			(xy 188.239156 -205.843357) (xy 188.231213 -205.896061) (xy 188.215503 -205.946991) (xy 188.192377 -205.995012)
			(xy 188.162353 -206.039049) (xy 188.126101 -206.07812) (xy 188.08443 -206.111351) (xy 188.038272 -206.138)
			(xy 187.988658 -206.157472) (xy 187.936696 -206.169332) (xy 187.883546 -206.173316) (xy 187.830396 -206.169332)
			(xy 187.778434 -206.157472) (xy 187.72882 -206.138) (xy 187.682662 -206.111351) (xy 187.640991 -206.07812)
			(xy 187.604739 -206.039049) (xy 187.574715 -205.995012) (xy 187.551589 -205.946991) (xy 187.535879 -205.896061)
			(xy 187.527936 -205.843357) (xy 173.151556 -205.843357) (xy 173.143613 -205.896061) (xy 173.127903 -205.946991)
			(xy 173.104777 -205.995012) (xy 173.074753 -206.039049) (xy 173.038501 -206.07812) (xy 172.99683 -206.111351)
			(xy 172.950672 -206.138) (xy 172.901058 -206.157472) (xy 172.849096 -206.169332) (xy 172.795946 -206.173316)
			(xy 172.742796 -206.169332) (xy 172.690834 -206.157472) (xy 172.64122 -206.138) (xy 172.595062 -206.111351)
			(xy 172.553391 -206.07812) (xy 172.517139 -206.039049) (xy 172.487115 -205.995012) (xy 172.463989 -205.946991)
			(xy 172.448279 -205.896061) (xy 172.440336 -205.843357) (xy 158.88716 -205.843357) (xy 158.88716 -206.693241)
			(xy 176.540404 -206.693241) (xy 176.540404 -206.639943) (xy 176.548347 -206.587239) (xy 176.564057 -206.536309)
			(xy 176.587183 -206.488288) (xy 176.617207 -206.444251) (xy 176.653459 -206.40518) (xy 176.69513 -206.371949)
			(xy 176.741288 -206.3453) (xy 176.790902 -206.325828) (xy 176.842864 -206.313968) (xy 176.896014 -206.309985)
			(xy 176.949164 -206.313968) (xy 177.001126 -206.325828) (xy 177.05074 -206.3453) (xy 177.096898 -206.371949)
			(xy 177.138569 -206.40518) (xy 177.174821 -206.444251) (xy 177.204845 -206.488288) (xy 177.227971 -206.536309)
			(xy 177.243681 -206.587239) (xy 177.251624 -206.639943) (xy 177.252122 -206.666592) (xy 177.251624 -206.693241)
			(xy 191.628004 -206.693241) (xy 191.628004 -206.639943) (xy 191.635947 -206.587239) (xy 191.651657 -206.536309)
			(xy 191.674783 -206.488288) (xy 191.704807 -206.444251) (xy 191.741059 -206.40518) (xy 191.78273 -206.371949)
			(xy 191.828888 -206.3453) (xy 191.878502 -206.325828) (xy 191.930464 -206.313968) (xy 191.983614 -206.309985)
			(xy 192.036764 -206.313968) (xy 192.088726 -206.325828) (xy 192.13834 -206.3453) (xy 192.184498 -206.371949)
			(xy 192.226169 -206.40518) (xy 192.262421 -206.444251) (xy 192.292445 -206.488288) (xy 192.315571 -206.536309)
			(xy 192.331281 -206.587239) (xy 192.339224 -206.639943) (xy 192.339722 -206.666592) (xy 192.339224 -206.693241)
			(xy 206.715604 -206.693241) (xy 206.715604 -206.639943) (xy 206.723547 -206.587239) (xy 206.739257 -206.536309)
			(xy 206.762383 -206.488288) (xy 206.792407 -206.444251) (xy 206.828659 -206.40518) (xy 206.87033 -206.371949)
			(xy 206.916488 -206.3453) (xy 206.966102 -206.325828) (xy 207.018064 -206.313968) (xy 207.071214 -206.309985)
			(xy 207.124364 -206.313968) (xy 207.176326 -206.325828) (xy 207.22594 -206.3453) (xy 207.272098 -206.371949)
			(xy 207.313769 -206.40518) (xy 207.350021 -206.444251) (xy 207.380045 -206.488288) (xy 207.403171 -206.536309)
			(xy 207.418881 -206.587239) (xy 207.426824 -206.639943) (xy 207.427322 -206.666592) (xy 207.426824 -206.693241)
			(xy 207.418881 -206.745945) (xy 207.403171 -206.796875) (xy 207.380045 -206.844896) (xy 207.350021 -206.888933)
			(xy 207.313769 -206.928004) (xy 207.272098 -206.961235) (xy 207.22594 -206.987884) (xy 207.176326 -207.007356)
			(xy 207.124364 -207.019216) (xy 207.071214 -207.0232) (xy 207.018064 -207.019216) (xy 206.966102 -207.007356)
			(xy 206.916488 -206.987884) (xy 206.87033 -206.961235) (xy 206.828659 -206.928004) (xy 206.792407 -206.888933)
			(xy 206.762383 -206.844896) (xy 206.739257 -206.796875) (xy 206.723547 -206.745945) (xy 206.715604 -206.693241)
			(xy 192.339224 -206.693241) (xy 192.331281 -206.745945) (xy 192.315571 -206.796875) (xy 192.292445 -206.844896)
			(xy 192.262421 -206.888933) (xy 192.226169 -206.928004) (xy 192.184498 -206.961235) (xy 192.13834 -206.987884)
			(xy 192.088726 -207.007356) (xy 192.036764 -207.019216) (xy 191.983614 -207.0232) (xy 191.930464 -207.019216)
			(xy 191.878502 -207.007356) (xy 191.828888 -206.987884) (xy 191.78273 -206.961235) (xy 191.741059 -206.928004)
			(xy 191.704807 -206.888933) (xy 191.674783 -206.844896) (xy 191.651657 -206.796875) (xy 191.635947 -206.745945)
			(xy 191.628004 -206.693241) (xy 177.251624 -206.693241) (xy 177.243681 -206.745945) (xy 177.227971 -206.796875)
			(xy 177.204845 -206.844896) (xy 177.174821 -206.888933) (xy 177.138569 -206.928004) (xy 177.096898 -206.961235)
			(xy 177.05074 -206.987884) (xy 177.001126 -207.007356) (xy 176.949164 -207.019216) (xy 176.896014 -207.0232)
			(xy 176.842864 -207.019216) (xy 176.790902 -207.007356) (xy 176.741288 -206.987884) (xy 176.69513 -206.961235)
			(xy 176.653459 -206.928004) (xy 176.617207 -206.888933) (xy 176.587183 -206.844896) (xy 176.564057 -206.796875)
			(xy 176.548347 -206.745945) (xy 176.540404 -206.693241) (xy 158.88716 -206.693241) (xy 158.88716 -207.543379)
			(xy 172.440336 -207.543379) (xy 172.440336 -207.490081) (xy 172.448279 -207.437377) (xy 172.463989 -207.386447)
			(xy 172.487115 -207.338426) (xy 172.517139 -207.294389) (xy 172.553391 -207.255318) (xy 172.595062 -207.222087)
			(xy 172.64122 -207.195438) (xy 172.690834 -207.175966) (xy 172.742796 -207.164106) (xy 172.795946 -207.160123)
			(xy 172.849096 -207.164106) (xy 172.901058 -207.175966) (xy 172.950672 -207.195438) (xy 172.99683 -207.222087)
			(xy 173.038501 -207.255318) (xy 173.074753 -207.294389) (xy 173.104777 -207.338426) (xy 173.127903 -207.386447)
			(xy 173.143613 -207.437377) (xy 173.151556 -207.490081) (xy 173.152054 -207.51673) (xy 173.151556 -207.543379)
			(xy 187.527936 -207.543379) (xy 187.527936 -207.490081) (xy 187.535879 -207.437377) (xy 187.551589 -207.386447)
			(xy 187.574715 -207.338426) (xy 187.604739 -207.294389) (xy 187.640991 -207.255318) (xy 187.682662 -207.222087)
			(xy 187.72882 -207.195438) (xy 187.778434 -207.175966) (xy 187.830396 -207.164106) (xy 187.883546 -207.160123)
			(xy 187.936696 -207.164106) (xy 187.988658 -207.175966) (xy 188.038272 -207.195438) (xy 188.08443 -207.222087)
			(xy 188.126101 -207.255318) (xy 188.162353 -207.294389) (xy 188.192377 -207.338426) (xy 188.215503 -207.386447)
			(xy 188.231213 -207.437377) (xy 188.239156 -207.490081) (xy 188.239654 -207.51673) (xy 188.239156 -207.543379)
			(xy 202.615536 -207.543379) (xy 202.615536 -207.490081) (xy 202.623479 -207.437377) (xy 202.639189 -207.386447)
			(xy 202.662315 -207.338426) (xy 202.692339 -207.294389) (xy 202.728591 -207.255318) (xy 202.770262 -207.222087)
			(xy 202.81642 -207.195438) (xy 202.866034 -207.175966) (xy 202.917996 -207.164106) (xy 202.971146 -207.160123)
			(xy 203.024296 -207.164106) (xy 203.076258 -207.175966) (xy 203.125872 -207.195438) (xy 203.17203 -207.222087)
			(xy 203.213701 -207.255318) (xy 203.249953 -207.294389) (xy 203.279977 -207.338426) (xy 203.303103 -207.386447)
			(xy 203.318813 -207.437377) (xy 203.326756 -207.490081) (xy 203.327254 -207.51673) (xy 203.326756 -207.543379)
			(xy 203.318813 -207.596083) (xy 203.303103 -207.647013) (xy 203.279977 -207.695034) (xy 203.249953 -207.739071)
			(xy 203.213701 -207.778142) (xy 203.17203 -207.811373) (xy 203.125872 -207.838022) (xy 203.076258 -207.857494)
			(xy 203.024296 -207.869354) (xy 202.971146 -207.873338) (xy 202.917996 -207.869354) (xy 202.866034 -207.857494)
			(xy 202.81642 -207.838022) (xy 202.770262 -207.811373) (xy 202.728591 -207.778142) (xy 202.692339 -207.739071)
			(xy 202.662315 -207.695034) (xy 202.639189 -207.647013) (xy 202.623479 -207.596083) (xy 202.615536 -207.543379)
			(xy 188.239156 -207.543379) (xy 188.231213 -207.596083) (xy 188.215503 -207.647013) (xy 188.192377 -207.695034)
			(xy 188.162353 -207.739071) (xy 188.126101 -207.778142) (xy 188.08443 -207.811373) (xy 188.038272 -207.838022)
			(xy 187.988658 -207.857494) (xy 187.936696 -207.869354) (xy 187.883546 -207.873338) (xy 187.830396 -207.869354)
			(xy 187.778434 -207.857494) (xy 187.72882 -207.838022) (xy 187.682662 -207.811373) (xy 187.640991 -207.778142)
			(xy 187.604739 -207.739071) (xy 187.574715 -207.695034) (xy 187.551589 -207.647013) (xy 187.535879 -207.596083)
			(xy 187.527936 -207.543379) (xy 173.151556 -207.543379) (xy 173.143613 -207.596083) (xy 173.127903 -207.647013)
			(xy 173.104777 -207.695034) (xy 173.074753 -207.739071) (xy 173.038501 -207.778142) (xy 172.99683 -207.811373)
			(xy 172.950672 -207.838022) (xy 172.901058 -207.857494) (xy 172.849096 -207.869354) (xy 172.795946 -207.873338)
			(xy 172.742796 -207.869354) (xy 172.690834 -207.857494) (xy 172.64122 -207.838022) (xy 172.595062 -207.811373)
			(xy 172.553391 -207.778142) (xy 172.517139 -207.739071) (xy 172.487115 -207.695034) (xy 172.463989 -207.647013)
			(xy 172.448279 -207.596083) (xy 172.440336 -207.543379) (xy 158.88716 -207.543379) (xy 158.88716 -208.393263)
			(xy 176.540404 -208.393263) (xy 176.540404 -208.339965) (xy 176.548347 -208.287261) (xy 176.564057 -208.236331)
			(xy 176.587183 -208.18831) (xy 176.617207 -208.144273) (xy 176.653459 -208.105202) (xy 176.69513 -208.071971)
			(xy 176.741288 -208.045322) (xy 176.790902 -208.02585) (xy 176.842864 -208.01399) (xy 176.896014 -208.010007)
			(xy 176.949164 -208.01399) (xy 177.001126 -208.02585) (xy 177.05074 -208.045322) (xy 177.096898 -208.071971)
			(xy 177.138569 -208.105202) (xy 177.174821 -208.144273) (xy 177.204845 -208.18831) (xy 177.227971 -208.236331)
			(xy 177.243681 -208.287261) (xy 177.251624 -208.339965) (xy 177.252122 -208.366614) (xy 177.251624 -208.393263)
			(xy 191.628004 -208.393263) (xy 191.628004 -208.339965) (xy 191.635947 -208.287261) (xy 191.651657 -208.236331)
			(xy 191.674783 -208.18831) (xy 191.704807 -208.144273) (xy 191.741059 -208.105202) (xy 191.78273 -208.071971)
			(xy 191.828888 -208.045322) (xy 191.878502 -208.02585) (xy 191.930464 -208.01399) (xy 191.983614 -208.010007)
			(xy 192.036764 -208.01399) (xy 192.088726 -208.02585) (xy 192.13834 -208.045322) (xy 192.184498 -208.071971)
			(xy 192.226169 -208.105202) (xy 192.262421 -208.144273) (xy 192.292445 -208.18831) (xy 192.315571 -208.236331)
			(xy 192.331281 -208.287261) (xy 192.339224 -208.339965) (xy 192.339722 -208.366614) (xy 192.339224 -208.393263)
			(xy 206.715604 -208.393263) (xy 206.715604 -208.339965) (xy 206.723547 -208.287261) (xy 206.739257 -208.236331)
			(xy 206.762383 -208.18831) (xy 206.792407 -208.144273) (xy 206.828659 -208.105202) (xy 206.87033 -208.071971)
			(xy 206.916488 -208.045322) (xy 206.966102 -208.02585) (xy 207.018064 -208.01399) (xy 207.071214 -208.010007)
			(xy 207.124364 -208.01399) (xy 207.176326 -208.02585) (xy 207.22594 -208.045322) (xy 207.272098 -208.071971)
			(xy 207.313769 -208.105202) (xy 207.350021 -208.144273) (xy 207.380045 -208.18831) (xy 207.403171 -208.236331)
			(xy 207.418881 -208.287261) (xy 207.426824 -208.339965) (xy 207.427322 -208.366614) (xy 207.426824 -208.393263)
			(xy 207.418881 -208.445967) (xy 207.403171 -208.496897) (xy 207.380045 -208.544918) (xy 207.350021 -208.588955)
			(xy 207.313769 -208.628026) (xy 207.272098 -208.661257) (xy 207.22594 -208.687906) (xy 207.176326 -208.707378)
			(xy 207.124364 -208.719238) (xy 207.071214 -208.723222) (xy 207.018064 -208.719238) (xy 206.966102 -208.707378)
			(xy 206.916488 -208.687906) (xy 206.87033 -208.661257) (xy 206.828659 -208.628026) (xy 206.792407 -208.588955)
			(xy 206.762383 -208.544918) (xy 206.739257 -208.496897) (xy 206.723547 -208.445967) (xy 206.715604 -208.393263)
			(xy 192.339224 -208.393263) (xy 192.331281 -208.445967) (xy 192.315571 -208.496897) (xy 192.292445 -208.544918)
			(xy 192.262421 -208.588955) (xy 192.226169 -208.628026) (xy 192.184498 -208.661257) (xy 192.13834 -208.687906)
			(xy 192.088726 -208.707378) (xy 192.036764 -208.719238) (xy 191.983614 -208.723222) (xy 191.930464 -208.719238)
			(xy 191.878502 -208.707378) (xy 191.828888 -208.687906) (xy 191.78273 -208.661257) (xy 191.741059 -208.628026)
			(xy 191.704807 -208.588955) (xy 191.674783 -208.544918) (xy 191.651657 -208.496897) (xy 191.635947 -208.445967)
			(xy 191.628004 -208.393263) (xy 177.251624 -208.393263) (xy 177.243681 -208.445967) (xy 177.227971 -208.496897)
			(xy 177.204845 -208.544918) (xy 177.174821 -208.588955) (xy 177.138569 -208.628026) (xy 177.096898 -208.661257)
			(xy 177.05074 -208.687906) (xy 177.001126 -208.707378) (xy 176.949164 -208.719238) (xy 176.896014 -208.723222)
			(xy 176.842864 -208.719238) (xy 176.790902 -208.707378) (xy 176.741288 -208.687906) (xy 176.69513 -208.661257)
			(xy 176.653459 -208.628026) (xy 176.617207 -208.588955) (xy 176.587183 -208.544918) (xy 176.564057 -208.496897)
			(xy 176.548347 -208.445967) (xy 176.540404 -208.393263) (xy 158.88716 -208.393263) (xy 158.88716 -209.243401)
			(xy 172.440336 -209.243401) (xy 172.440336 -209.190103) (xy 172.448279 -209.137399) (xy 172.463989 -209.086469)
			(xy 172.487115 -209.038448) (xy 172.517139 -208.994411) (xy 172.553391 -208.95534) (xy 172.595062 -208.922109)
			(xy 172.64122 -208.89546) (xy 172.690834 -208.875988) (xy 172.742796 -208.864128) (xy 172.795946 -208.860145)
			(xy 172.849096 -208.864128) (xy 172.901058 -208.875988) (xy 172.950672 -208.89546) (xy 172.99683 -208.922109)
			(xy 173.038501 -208.95534) (xy 173.074753 -208.994411) (xy 173.104777 -209.038448) (xy 173.127903 -209.086469)
			(xy 173.143613 -209.137399) (xy 173.151556 -209.190103) (xy 173.152054 -209.216752) (xy 173.151556 -209.243401)
			(xy 176.540404 -209.243401) (xy 176.540404 -209.190103) (xy 176.548347 -209.137399) (xy 176.564057 -209.086469)
			(xy 176.587183 -209.038448) (xy 176.617207 -208.994411) (xy 176.653459 -208.95534) (xy 176.69513 -208.922109)
			(xy 176.741288 -208.89546) (xy 176.790902 -208.875988) (xy 176.842864 -208.864128) (xy 176.896014 -208.860145)
			(xy 176.949164 -208.864128) (xy 177.001126 -208.875988) (xy 177.05074 -208.89546) (xy 177.096898 -208.922109)
			(xy 177.138569 -208.95534) (xy 177.174821 -208.994411) (xy 177.204845 -209.038448) (xy 177.227971 -209.086469)
			(xy 177.243681 -209.137399) (xy 177.251624 -209.190103) (xy 177.252122 -209.216752) (xy 177.251624 -209.243401)
			(xy 187.527936 -209.243401) (xy 187.527936 -209.190103) (xy 187.535879 -209.137399) (xy 187.551589 -209.086469)
			(xy 187.574715 -209.038448) (xy 187.604739 -208.994411) (xy 187.640991 -208.95534) (xy 187.682662 -208.922109)
			(xy 187.72882 -208.89546) (xy 187.778434 -208.875988) (xy 187.830396 -208.864128) (xy 187.883546 -208.860145)
			(xy 187.936696 -208.864128) (xy 187.988658 -208.875988) (xy 188.038272 -208.89546) (xy 188.08443 -208.922109)
			(xy 188.126101 -208.95534) (xy 188.162353 -208.994411) (xy 188.192377 -209.038448) (xy 188.215503 -209.086469)
			(xy 188.231213 -209.137399) (xy 188.239156 -209.190103) (xy 188.239654 -209.216752) (xy 188.239156 -209.243401)
			(xy 191.628004 -209.243401) (xy 191.628004 -209.190103) (xy 191.635947 -209.137399) (xy 191.651657 -209.086469)
			(xy 191.674783 -209.038448) (xy 191.704807 -208.994411) (xy 191.741059 -208.95534) (xy 191.78273 -208.922109)
			(xy 191.828888 -208.89546) (xy 191.878502 -208.875988) (xy 191.930464 -208.864128) (xy 191.983614 -208.860145)
			(xy 192.036764 -208.864128) (xy 192.088726 -208.875988) (xy 192.13834 -208.89546) (xy 192.184498 -208.922109)
			(xy 192.226169 -208.95534) (xy 192.262421 -208.994411) (xy 192.292445 -209.038448) (xy 192.315571 -209.086469)
			(xy 192.331281 -209.137399) (xy 192.339224 -209.190103) (xy 192.339722 -209.216752) (xy 192.339224 -209.243401)
			(xy 202.615536 -209.243401) (xy 202.615536 -209.190103) (xy 202.623479 -209.137399) (xy 202.639189 -209.086469)
			(xy 202.662315 -209.038448) (xy 202.692339 -208.994411) (xy 202.728591 -208.95534) (xy 202.770262 -208.922109)
			(xy 202.81642 -208.89546) (xy 202.866034 -208.875988) (xy 202.917996 -208.864128) (xy 202.971146 -208.860145)
			(xy 203.024296 -208.864128) (xy 203.076258 -208.875988) (xy 203.125872 -208.89546) (xy 203.17203 -208.922109)
			(xy 203.213701 -208.95534) (xy 203.249953 -208.994411) (xy 203.279977 -209.038448) (xy 203.303103 -209.086469)
			(xy 203.318813 -209.137399) (xy 203.326756 -209.190103) (xy 203.327254 -209.216752) (xy 203.326756 -209.243401)
			(xy 206.715604 -209.243401) (xy 206.715604 -209.190103) (xy 206.723547 -209.137399) (xy 206.739257 -209.086469)
			(xy 206.762383 -209.038448) (xy 206.792407 -208.994411) (xy 206.828659 -208.95534) (xy 206.87033 -208.922109)
			(xy 206.916488 -208.89546) (xy 206.966102 -208.875988) (xy 207.018064 -208.864128) (xy 207.071214 -208.860145)
			(xy 207.124364 -208.864128) (xy 207.176326 -208.875988) (xy 207.22594 -208.89546) (xy 207.272098 -208.922109)
			(xy 207.313769 -208.95534) (xy 207.350021 -208.994411) (xy 207.380045 -209.038448) (xy 207.403171 -209.086469)
			(xy 207.418881 -209.137399) (xy 207.426824 -209.190103) (xy 207.427322 -209.216752) (xy 207.426824 -209.243401)
			(xy 207.418881 -209.296105) (xy 207.403171 -209.347035) (xy 207.380045 -209.395056) (xy 207.350021 -209.439093)
			(xy 207.313769 -209.478164) (xy 207.272098 -209.511395) (xy 207.22594 -209.538044) (xy 207.176326 -209.557516)
			(xy 207.124364 -209.569376) (xy 207.071214 -209.57336) (xy 207.018064 -209.569376) (xy 206.966102 -209.557516)
			(xy 206.916488 -209.538044) (xy 206.87033 -209.511395) (xy 206.828659 -209.478164) (xy 206.792407 -209.439093)
			(xy 206.762383 -209.395056) (xy 206.739257 -209.347035) (xy 206.723547 -209.296105) (xy 206.715604 -209.243401)
			(xy 203.326756 -209.243401) (xy 203.318813 -209.296105) (xy 203.303103 -209.347035) (xy 203.279977 -209.395056)
			(xy 203.249953 -209.439093) (xy 203.213701 -209.478164) (xy 203.17203 -209.511395) (xy 203.125872 -209.538044)
			(xy 203.076258 -209.557516) (xy 203.024296 -209.569376) (xy 202.971146 -209.57336) (xy 202.917996 -209.569376)
			(xy 202.866034 -209.557516) (xy 202.81642 -209.538044) (xy 202.770262 -209.511395) (xy 202.728591 -209.478164)
			(xy 202.692339 -209.439093) (xy 202.662315 -209.395056) (xy 202.639189 -209.347035) (xy 202.623479 -209.296105)
			(xy 202.615536 -209.243401) (xy 192.339224 -209.243401) (xy 192.331281 -209.296105) (xy 192.315571 -209.347035)
			(xy 192.292445 -209.395056) (xy 192.262421 -209.439093) (xy 192.226169 -209.478164) (xy 192.184498 -209.511395)
			(xy 192.13834 -209.538044) (xy 192.088726 -209.557516) (xy 192.036764 -209.569376) (xy 191.983614 -209.57336)
			(xy 191.930464 -209.569376) (xy 191.878502 -209.557516) (xy 191.828888 -209.538044) (xy 191.78273 -209.511395)
			(xy 191.741059 -209.478164) (xy 191.704807 -209.439093) (xy 191.674783 -209.395056) (xy 191.651657 -209.347035)
			(xy 191.635947 -209.296105) (xy 191.628004 -209.243401) (xy 188.239156 -209.243401) (xy 188.231213 -209.296105)
			(xy 188.215503 -209.347035) (xy 188.192377 -209.395056) (xy 188.162353 -209.439093) (xy 188.126101 -209.478164)
			(xy 188.08443 -209.511395) (xy 188.038272 -209.538044) (xy 187.988658 -209.557516) (xy 187.936696 -209.569376)
			(xy 187.883546 -209.57336) (xy 187.830396 -209.569376) (xy 187.778434 -209.557516) (xy 187.72882 -209.538044)
			(xy 187.682662 -209.511395) (xy 187.640991 -209.478164) (xy 187.604739 -209.439093) (xy 187.574715 -209.395056)
			(xy 187.551589 -209.347035) (xy 187.535879 -209.296105) (xy 187.527936 -209.243401) (xy 177.251624 -209.243401)
			(xy 177.243681 -209.296105) (xy 177.227971 -209.347035) (xy 177.204845 -209.395056) (xy 177.174821 -209.439093)
			(xy 177.138569 -209.478164) (xy 177.096898 -209.511395) (xy 177.05074 -209.538044) (xy 177.001126 -209.557516)
			(xy 176.949164 -209.569376) (xy 176.896014 -209.57336) (xy 176.842864 -209.569376) (xy 176.790902 -209.557516)
			(xy 176.741288 -209.538044) (xy 176.69513 -209.511395) (xy 176.653459 -209.478164) (xy 176.617207 -209.439093)
			(xy 176.587183 -209.395056) (xy 176.564057 -209.347035) (xy 176.548347 -209.296105) (xy 176.540404 -209.243401)
			(xy 173.151556 -209.243401) (xy 173.143613 -209.296105) (xy 173.127903 -209.347035) (xy 173.104777 -209.395056)
			(xy 173.074753 -209.439093) (xy 173.038501 -209.478164) (xy 172.99683 -209.511395) (xy 172.950672 -209.538044)
			(xy 172.901058 -209.557516) (xy 172.849096 -209.569376) (xy 172.795946 -209.57336) (xy 172.742796 -209.569376)
			(xy 172.690834 -209.557516) (xy 172.64122 -209.538044) (xy 172.595062 -209.511395) (xy 172.553391 -209.478164)
			(xy 172.517139 -209.439093) (xy 172.487115 -209.395056) (xy 172.463989 -209.347035) (xy 172.448279 -209.296105)
			(xy 172.440336 -209.243401) (xy 158.88716 -209.243401) (xy 158.88716 -210.093285) (xy 172.440336 -210.093285)
			(xy 172.440336 -210.039987) (xy 172.448279 -209.987283) (xy 172.463989 -209.936353) (xy 172.487115 -209.888332)
			(xy 172.517139 -209.844295) (xy 172.553391 -209.805224) (xy 172.595062 -209.771993) (xy 172.64122 -209.745344)
			(xy 172.690834 -209.725872) (xy 172.742796 -209.714012) (xy 172.795946 -209.710029) (xy 172.849096 -209.714012)
			(xy 172.901058 -209.725872) (xy 172.950672 -209.745344) (xy 172.99683 -209.771993) (xy 173.038501 -209.805224)
			(xy 173.074753 -209.844295) (xy 173.104777 -209.888332) (xy 173.127903 -209.936353) (xy 173.143613 -209.987283)
			(xy 173.151556 -210.039987) (xy 173.152054 -210.066636) (xy 173.151556 -210.093285) (xy 187.527936 -210.093285)
			(xy 187.527936 -210.039987) (xy 187.535879 -209.987283) (xy 187.551589 -209.936353) (xy 187.574715 -209.888332)
			(xy 187.604739 -209.844295) (xy 187.640991 -209.805224) (xy 187.682662 -209.771993) (xy 187.72882 -209.745344)
			(xy 187.778434 -209.725872) (xy 187.830396 -209.714012) (xy 187.883546 -209.710029) (xy 187.936696 -209.714012)
			(xy 187.988658 -209.725872) (xy 188.038272 -209.745344) (xy 188.08443 -209.771993) (xy 188.126101 -209.805224)
			(xy 188.162353 -209.844295) (xy 188.192377 -209.888332) (xy 188.215503 -209.936353) (xy 188.231213 -209.987283)
			(xy 188.239156 -210.039987) (xy 188.239654 -210.066636) (xy 188.239156 -210.093285) (xy 202.615536 -210.093285)
			(xy 202.615536 -210.039987) (xy 202.623479 -209.987283) (xy 202.639189 -209.936353) (xy 202.662315 -209.888332)
			(xy 202.692339 -209.844295) (xy 202.728591 -209.805224) (xy 202.770262 -209.771993) (xy 202.81642 -209.745344)
			(xy 202.866034 -209.725872) (xy 202.917996 -209.714012) (xy 202.971146 -209.710029) (xy 203.024296 -209.714012)
			(xy 203.076258 -209.725872) (xy 203.125872 -209.745344) (xy 203.17203 -209.771993) (xy 203.213701 -209.805224)
			(xy 203.249953 -209.844295) (xy 203.279977 -209.888332) (xy 203.303103 -209.936353) (xy 203.318813 -209.987283)
			(xy 203.326756 -210.039987) (xy 203.327254 -210.066636) (xy 203.326756 -210.093285) (xy 203.318813 -210.145989)
			(xy 203.303103 -210.196919) (xy 203.279977 -210.24494) (xy 203.249953 -210.288977) (xy 203.213701 -210.328048)
			(xy 203.17203 -210.361279) (xy 203.125872 -210.387928) (xy 203.076258 -210.4074) (xy 203.024296 -210.41926)
			(xy 202.971146 -210.423244) (xy 202.917996 -210.41926) (xy 202.866034 -210.4074) (xy 202.81642 -210.387928)
			(xy 202.770262 -210.361279) (xy 202.728591 -210.328048) (xy 202.692339 -210.288977) (xy 202.662315 -210.24494)
			(xy 202.639189 -210.196919) (xy 202.623479 -210.145989) (xy 202.615536 -210.093285) (xy 188.239156 -210.093285)
			(xy 188.231213 -210.145989) (xy 188.215503 -210.196919) (xy 188.192377 -210.24494) (xy 188.162353 -210.288977)
			(xy 188.126101 -210.328048) (xy 188.08443 -210.361279) (xy 188.038272 -210.387928) (xy 187.988658 -210.4074)
			(xy 187.936696 -210.41926) (xy 187.883546 -210.423244) (xy 187.830396 -210.41926) (xy 187.778434 -210.4074)
			(xy 187.72882 -210.387928) (xy 187.682662 -210.361279) (xy 187.640991 -210.328048) (xy 187.604739 -210.288977)
			(xy 187.574715 -210.24494) (xy 187.551589 -210.196919) (xy 187.535879 -210.145989) (xy 187.527936 -210.093285)
			(xy 173.151556 -210.093285) (xy 173.143613 -210.145989) (xy 173.127903 -210.196919) (xy 173.104777 -210.24494)
			(xy 173.074753 -210.288977) (xy 173.038501 -210.328048) (xy 172.99683 -210.361279) (xy 172.950672 -210.387928)
			(xy 172.901058 -210.4074) (xy 172.849096 -210.41926) (xy 172.795946 -210.423244) (xy 172.742796 -210.41926)
			(xy 172.690834 -210.4074) (xy 172.64122 -210.387928) (xy 172.595062 -210.361279) (xy 172.553391 -210.328048)
			(xy 172.517139 -210.288977) (xy 172.487115 -210.24494) (xy 172.463989 -210.196919) (xy 172.448279 -210.145989)
			(xy 172.440336 -210.093285) (xy 158.88716 -210.093285) (xy 158.88716 -210.943423) (xy 176.540404 -210.943423)
			(xy 176.540404 -210.890125) (xy 176.548347 -210.837421) (xy 176.564057 -210.786491) (xy 176.587183 -210.73847)
			(xy 176.617207 -210.694433) (xy 176.653459 -210.655362) (xy 176.69513 -210.622131) (xy 176.741288 -210.595482)
			(xy 176.790902 -210.57601) (xy 176.842864 -210.56415) (xy 176.896014 -210.560167) (xy 176.949164 -210.56415)
			(xy 177.001126 -210.57601) (xy 177.05074 -210.595482) (xy 177.096898 -210.622131) (xy 177.138569 -210.655362)
			(xy 177.174821 -210.694433) (xy 177.204845 -210.73847) (xy 177.227971 -210.786491) (xy 177.243681 -210.837421)
			(xy 177.251624 -210.890125) (xy 177.252122 -210.916774) (xy 177.251624 -210.943423) (xy 191.628004 -210.943423)
			(xy 191.628004 -210.890125) (xy 191.635947 -210.837421) (xy 191.651657 -210.786491) (xy 191.674783 -210.73847)
			(xy 191.704807 -210.694433) (xy 191.741059 -210.655362) (xy 191.78273 -210.622131) (xy 191.828888 -210.595482)
			(xy 191.878502 -210.57601) (xy 191.930464 -210.56415) (xy 191.983614 -210.560167) (xy 192.036764 -210.56415)
			(xy 192.088726 -210.57601) (xy 192.13834 -210.595482) (xy 192.184498 -210.622131) (xy 192.226169 -210.655362)
			(xy 192.262421 -210.694433) (xy 192.292445 -210.73847) (xy 192.315571 -210.786491) (xy 192.331281 -210.837421)
			(xy 192.339224 -210.890125) (xy 192.339722 -210.916774) (xy 192.339224 -210.943423) (xy 206.715604 -210.943423)
			(xy 206.715604 -210.890125) (xy 206.723547 -210.837421) (xy 206.739257 -210.786491) (xy 206.762383 -210.73847)
			(xy 206.792407 -210.694433) (xy 206.828659 -210.655362) (xy 206.87033 -210.622131) (xy 206.916488 -210.595482)
			(xy 206.966102 -210.57601) (xy 207.018064 -210.56415) (xy 207.071214 -210.560167) (xy 207.124364 -210.56415)
			(xy 207.176326 -210.57601) (xy 207.22594 -210.595482) (xy 207.272098 -210.622131) (xy 207.313769 -210.655362)
			(xy 207.350021 -210.694433) (xy 207.380045 -210.73847) (xy 207.403171 -210.786491) (xy 207.418881 -210.837421)
			(xy 207.426824 -210.890125) (xy 207.427322 -210.916774) (xy 207.426824 -210.943423) (xy 207.418881 -210.996127)
			(xy 207.403171 -211.047057) (xy 207.380045 -211.095078) (xy 207.350021 -211.139115) (xy 207.313769 -211.178186)
			(xy 207.272098 -211.211417) (xy 207.22594 -211.238066) (xy 207.176326 -211.257538) (xy 207.124364 -211.269398)
			(xy 207.071214 -211.273382) (xy 207.018064 -211.269398) (xy 206.966102 -211.257538) (xy 206.916488 -211.238066)
			(xy 206.87033 -211.211417) (xy 206.828659 -211.178186) (xy 206.792407 -211.139115) (xy 206.762383 -211.095078)
			(xy 206.739257 -211.047057) (xy 206.723547 -210.996127) (xy 206.715604 -210.943423) (xy 192.339224 -210.943423)
			(xy 192.331281 -210.996127) (xy 192.315571 -211.047057) (xy 192.292445 -211.095078) (xy 192.262421 -211.139115)
			(xy 192.226169 -211.178186) (xy 192.184498 -211.211417) (xy 192.13834 -211.238066) (xy 192.088726 -211.257538)
			(xy 192.036764 -211.269398) (xy 191.983614 -211.273382) (xy 191.930464 -211.269398) (xy 191.878502 -211.257538)
			(xy 191.828888 -211.238066) (xy 191.78273 -211.211417) (xy 191.741059 -211.178186) (xy 191.704807 -211.139115)
			(xy 191.674783 -211.095078) (xy 191.651657 -211.047057) (xy 191.635947 -210.996127) (xy 191.628004 -210.943423)
			(xy 177.251624 -210.943423) (xy 177.243681 -210.996127) (xy 177.227971 -211.047057) (xy 177.204845 -211.095078)
			(xy 177.174821 -211.139115) (xy 177.138569 -211.178186) (xy 177.096898 -211.211417) (xy 177.05074 -211.238066)
			(xy 177.001126 -211.257538) (xy 176.949164 -211.269398) (xy 176.896014 -211.273382) (xy 176.842864 -211.269398)
			(xy 176.790902 -211.257538) (xy 176.741288 -211.238066) (xy 176.69513 -211.211417) (xy 176.653459 -211.178186)
			(xy 176.617207 -211.139115) (xy 176.587183 -211.095078) (xy 176.564057 -211.047057) (xy 176.548347 -210.996127)
			(xy 176.540404 -210.943423) (xy 158.88716 -210.943423) (xy 158.88716 -211.793307) (xy 172.440336 -211.793307)
			(xy 172.440336 -211.740009) (xy 172.448279 -211.687305) (xy 172.463989 -211.636375) (xy 172.487115 -211.588354)
			(xy 172.517139 -211.544317) (xy 172.553391 -211.505246) (xy 172.595062 -211.472015) (xy 172.64122 -211.445366)
			(xy 172.690834 -211.425894) (xy 172.742796 -211.414034) (xy 172.795946 -211.410051) (xy 172.849096 -211.414034)
			(xy 172.901058 -211.425894) (xy 172.950672 -211.445366) (xy 172.99683 -211.472015) (xy 173.038501 -211.505246)
			(xy 173.074753 -211.544317) (xy 173.104777 -211.588354) (xy 173.127903 -211.636375) (xy 173.143613 -211.687305)
			(xy 173.151556 -211.740009) (xy 173.152054 -211.766658) (xy 173.151556 -211.793307) (xy 187.527936 -211.793307)
			(xy 187.527936 -211.740009) (xy 187.535879 -211.687305) (xy 187.551589 -211.636375) (xy 187.574715 -211.588354)
			(xy 187.604739 -211.544317) (xy 187.640991 -211.505246) (xy 187.682662 -211.472015) (xy 187.72882 -211.445366)
			(xy 187.778434 -211.425894) (xy 187.830396 -211.414034) (xy 187.883546 -211.410051) (xy 187.936696 -211.414034)
			(xy 187.988658 -211.425894) (xy 188.038272 -211.445366) (xy 188.08443 -211.472015) (xy 188.126101 -211.505246)
			(xy 188.162353 -211.544317) (xy 188.192377 -211.588354) (xy 188.215503 -211.636375) (xy 188.231213 -211.687305)
			(xy 188.239156 -211.740009) (xy 188.239654 -211.766658) (xy 188.239156 -211.793307) (xy 202.615536 -211.793307)
			(xy 202.615536 -211.740009) (xy 202.623479 -211.687305) (xy 202.639189 -211.636375) (xy 202.662315 -211.588354)
			(xy 202.692339 -211.544317) (xy 202.728591 -211.505246) (xy 202.770262 -211.472015) (xy 202.81642 -211.445366)
			(xy 202.866034 -211.425894) (xy 202.917996 -211.414034) (xy 202.971146 -211.410051) (xy 203.024296 -211.414034)
			(xy 203.076258 -211.425894) (xy 203.125872 -211.445366) (xy 203.17203 -211.472015) (xy 203.213701 -211.505246)
			(xy 203.249953 -211.544317) (xy 203.279977 -211.588354) (xy 203.303103 -211.636375) (xy 203.318813 -211.687305)
			(xy 203.326756 -211.740009) (xy 203.327254 -211.766658) (xy 203.326756 -211.793307) (xy 203.318813 -211.846011)
			(xy 203.303103 -211.896941) (xy 203.279977 -211.944962) (xy 203.249953 -211.988999) (xy 203.213701 -212.02807)
			(xy 203.17203 -212.061301) (xy 203.125872 -212.08795) (xy 203.076258 -212.107422) (xy 203.024296 -212.119282)
			(xy 202.971146 -212.123266) (xy 202.917996 -212.119282) (xy 202.866034 -212.107422) (xy 202.81642 -212.08795)
			(xy 202.770262 -212.061301) (xy 202.728591 -212.02807) (xy 202.692339 -211.988999) (xy 202.662315 -211.944962)
			(xy 202.639189 -211.896941) (xy 202.623479 -211.846011) (xy 202.615536 -211.793307) (xy 188.239156 -211.793307)
			(xy 188.231213 -211.846011) (xy 188.215503 -211.896941) (xy 188.192377 -211.944962) (xy 188.162353 -211.988999)
			(xy 188.126101 -212.02807) (xy 188.08443 -212.061301) (xy 188.038272 -212.08795) (xy 187.988658 -212.107422)
			(xy 187.936696 -212.119282) (xy 187.883546 -212.123266) (xy 187.830396 -212.119282) (xy 187.778434 -212.107422)
			(xy 187.72882 -212.08795) (xy 187.682662 -212.061301) (xy 187.640991 -212.02807) (xy 187.604739 -211.988999)
			(xy 187.574715 -211.944962) (xy 187.551589 -211.896941) (xy 187.535879 -211.846011) (xy 187.527936 -211.793307)
			(xy 173.151556 -211.793307) (xy 173.143613 -211.846011) (xy 173.127903 -211.896941) (xy 173.104777 -211.944962)
			(xy 173.074753 -211.988999) (xy 173.038501 -212.02807) (xy 172.99683 -212.061301) (xy 172.950672 -212.08795)
			(xy 172.901058 -212.107422) (xy 172.849096 -212.119282) (xy 172.795946 -212.123266) (xy 172.742796 -212.119282)
			(xy 172.690834 -212.107422) (xy 172.64122 -212.08795) (xy 172.595062 -212.061301) (xy 172.553391 -212.02807)
			(xy 172.517139 -211.988999) (xy 172.487115 -211.944962) (xy 172.463989 -211.896941) (xy 172.448279 -211.846011)
			(xy 172.440336 -211.793307) (xy 158.88716 -211.793307) (xy 158.88716 -212.643445) (xy 176.540404 -212.643445)
			(xy 176.540404 -212.590147) (xy 176.548347 -212.537443) (xy 176.564057 -212.486513) (xy 176.587183 -212.438492)
			(xy 176.617207 -212.394455) (xy 176.653459 -212.355384) (xy 176.69513 -212.322153) (xy 176.741288 -212.295504)
			(xy 176.790902 -212.276032) (xy 176.842864 -212.264172) (xy 176.896014 -212.260189) (xy 176.949164 -212.264172)
			(xy 177.001126 -212.276032) (xy 177.05074 -212.295504) (xy 177.096898 -212.322153) (xy 177.138569 -212.355384)
			(xy 177.174821 -212.394455) (xy 177.204845 -212.438492) (xy 177.227971 -212.486513) (xy 177.243681 -212.537443)
			(xy 177.251624 -212.590147) (xy 177.252122 -212.616796) (xy 177.251624 -212.643445) (xy 191.628004 -212.643445)
			(xy 191.628004 -212.590147) (xy 191.635947 -212.537443) (xy 191.651657 -212.486513) (xy 191.674783 -212.438492)
			(xy 191.704807 -212.394455) (xy 191.741059 -212.355384) (xy 191.78273 -212.322153) (xy 191.828888 -212.295504)
			(xy 191.878502 -212.276032) (xy 191.930464 -212.264172) (xy 191.983614 -212.260189) (xy 192.036764 -212.264172)
			(xy 192.088726 -212.276032) (xy 192.13834 -212.295504) (xy 192.184498 -212.322153) (xy 192.226169 -212.355384)
			(xy 192.262421 -212.394455) (xy 192.292445 -212.438492) (xy 192.315571 -212.486513) (xy 192.331281 -212.537443)
			(xy 192.339224 -212.590147) (xy 192.339722 -212.616796) (xy 192.339224 -212.643445) (xy 206.715604 -212.643445)
			(xy 206.715604 -212.590147) (xy 206.723547 -212.537443) (xy 206.739257 -212.486513) (xy 206.762383 -212.438492)
			(xy 206.792407 -212.394455) (xy 206.828659 -212.355384) (xy 206.87033 -212.322153) (xy 206.916488 -212.295504)
			(xy 206.966102 -212.276032) (xy 207.018064 -212.264172) (xy 207.071214 -212.260189) (xy 207.124364 -212.264172)
			(xy 207.176326 -212.276032) (xy 207.22594 -212.295504) (xy 207.272098 -212.322153) (xy 207.313769 -212.355384)
			(xy 207.350021 -212.394455) (xy 207.380045 -212.438492) (xy 207.403171 -212.486513) (xy 207.418881 -212.537443)
			(xy 207.426824 -212.590147) (xy 207.427322 -212.616796) (xy 207.426824 -212.643445) (xy 207.418881 -212.696149)
			(xy 207.403171 -212.747079) (xy 207.380045 -212.7951) (xy 207.350021 -212.839137) (xy 207.313769 -212.878208)
			(xy 207.272098 -212.911439) (xy 207.22594 -212.938088) (xy 207.176326 -212.95756) (xy 207.124364 -212.96942)
			(xy 207.071214 -212.973404) (xy 207.018064 -212.96942) (xy 206.966102 -212.95756) (xy 206.916488 -212.938088)
			(xy 206.87033 -212.911439) (xy 206.828659 -212.878208) (xy 206.792407 -212.839137) (xy 206.762383 -212.7951)
			(xy 206.739257 -212.747079) (xy 206.723547 -212.696149) (xy 206.715604 -212.643445) (xy 192.339224 -212.643445)
			(xy 192.331281 -212.696149) (xy 192.315571 -212.747079) (xy 192.292445 -212.7951) (xy 192.262421 -212.839137)
			(xy 192.226169 -212.878208) (xy 192.184498 -212.911439) (xy 192.13834 -212.938088) (xy 192.088726 -212.95756)
			(xy 192.036764 -212.96942) (xy 191.983614 -212.973404) (xy 191.930464 -212.96942) (xy 191.878502 -212.95756)
			(xy 191.828888 -212.938088) (xy 191.78273 -212.911439) (xy 191.741059 -212.878208) (xy 191.704807 -212.839137)
			(xy 191.674783 -212.7951) (xy 191.651657 -212.747079) (xy 191.635947 -212.696149) (xy 191.628004 -212.643445)
			(xy 177.251624 -212.643445) (xy 177.243681 -212.696149) (xy 177.227971 -212.747079) (xy 177.204845 -212.7951)
			(xy 177.174821 -212.839137) (xy 177.138569 -212.878208) (xy 177.096898 -212.911439) (xy 177.05074 -212.938088)
			(xy 177.001126 -212.95756) (xy 176.949164 -212.96942) (xy 176.896014 -212.973404) (xy 176.842864 -212.96942)
			(xy 176.790902 -212.95756) (xy 176.741288 -212.938088) (xy 176.69513 -212.911439) (xy 176.653459 -212.878208)
			(xy 176.617207 -212.839137) (xy 176.587183 -212.7951) (xy 176.564057 -212.747079) (xy 176.548347 -212.696149)
			(xy 176.540404 -212.643445) (xy 158.88716 -212.643445) (xy 158.88716 -213.493329) (xy 172.440336 -213.493329)
			(xy 172.440336 -213.440031) (xy 172.448279 -213.387327) (xy 172.463989 -213.336397) (xy 172.487115 -213.288376)
			(xy 172.517139 -213.244339) (xy 172.553391 -213.205268) (xy 172.595062 -213.172037) (xy 172.64122 -213.145388)
			(xy 172.690834 -213.125916) (xy 172.742796 -213.114056) (xy 172.795946 -213.110073) (xy 172.849096 -213.114056)
			(xy 172.901058 -213.125916) (xy 172.950672 -213.145388) (xy 172.99683 -213.172037) (xy 173.038501 -213.205268)
			(xy 173.074753 -213.244339) (xy 173.104777 -213.288376) (xy 173.127903 -213.336397) (xy 173.143613 -213.387327)
			(xy 173.151556 -213.440031) (xy 173.152054 -213.46668) (xy 173.151556 -213.493329) (xy 187.527936 -213.493329)
			(xy 187.527936 -213.440031) (xy 187.535879 -213.387327) (xy 187.551589 -213.336397) (xy 187.574715 -213.288376)
			(xy 187.604739 -213.244339) (xy 187.640991 -213.205268) (xy 187.682662 -213.172037) (xy 187.72882 -213.145388)
			(xy 187.778434 -213.125916) (xy 187.830396 -213.114056) (xy 187.883546 -213.110073) (xy 187.936696 -213.114056)
			(xy 187.988658 -213.125916) (xy 188.038272 -213.145388) (xy 188.08443 -213.172037) (xy 188.126101 -213.205268)
			(xy 188.162353 -213.244339) (xy 188.192377 -213.288376) (xy 188.215503 -213.336397) (xy 188.231213 -213.387327)
			(xy 188.239156 -213.440031) (xy 188.239654 -213.46668) (xy 188.239156 -213.493329) (xy 202.615536 -213.493329)
			(xy 202.615536 -213.440031) (xy 202.623479 -213.387327) (xy 202.639189 -213.336397) (xy 202.662315 -213.288376)
			(xy 202.692339 -213.244339) (xy 202.728591 -213.205268) (xy 202.770262 -213.172037) (xy 202.81642 -213.145388)
			(xy 202.866034 -213.125916) (xy 202.917996 -213.114056) (xy 202.971146 -213.110073) (xy 203.024296 -213.114056)
			(xy 203.076258 -213.125916) (xy 203.125872 -213.145388) (xy 203.17203 -213.172037) (xy 203.213701 -213.205268)
			(xy 203.249953 -213.244339) (xy 203.279977 -213.288376) (xy 203.303103 -213.336397) (xy 203.318813 -213.387327)
			(xy 203.326756 -213.440031) (xy 203.327254 -213.46668) (xy 203.326756 -213.493329) (xy 203.318813 -213.546033)
			(xy 203.303103 -213.596963) (xy 203.279977 -213.644984) (xy 203.249953 -213.689021) (xy 203.213701 -213.728092)
			(xy 203.17203 -213.761323) (xy 203.125872 -213.787972) (xy 203.076258 -213.807444) (xy 203.024296 -213.819304)
			(xy 202.971146 -213.823288) (xy 202.917996 -213.819304) (xy 202.866034 -213.807444) (xy 202.81642 -213.787972)
			(xy 202.770262 -213.761323) (xy 202.728591 -213.728092) (xy 202.692339 -213.689021) (xy 202.662315 -213.644984)
			(xy 202.639189 -213.596963) (xy 202.623479 -213.546033) (xy 202.615536 -213.493329) (xy 188.239156 -213.493329)
			(xy 188.231213 -213.546033) (xy 188.215503 -213.596963) (xy 188.192377 -213.644984) (xy 188.162353 -213.689021)
			(xy 188.126101 -213.728092) (xy 188.08443 -213.761323) (xy 188.038272 -213.787972) (xy 187.988658 -213.807444)
			(xy 187.936696 -213.819304) (xy 187.883546 -213.823288) (xy 187.830396 -213.819304) (xy 187.778434 -213.807444)
			(xy 187.72882 -213.787972) (xy 187.682662 -213.761323) (xy 187.640991 -213.728092) (xy 187.604739 -213.689021)
			(xy 187.574715 -213.644984) (xy 187.551589 -213.596963) (xy 187.535879 -213.546033) (xy 187.527936 -213.493329)
			(xy 173.151556 -213.493329) (xy 173.143613 -213.546033) (xy 173.127903 -213.596963) (xy 173.104777 -213.644984)
			(xy 173.074753 -213.689021) (xy 173.038501 -213.728092) (xy 172.99683 -213.761323) (xy 172.950672 -213.787972)
			(xy 172.901058 -213.807444) (xy 172.849096 -213.819304) (xy 172.795946 -213.823288) (xy 172.742796 -213.819304)
			(xy 172.690834 -213.807444) (xy 172.64122 -213.787972) (xy 172.595062 -213.761323) (xy 172.553391 -213.728092)
			(xy 172.517139 -213.689021) (xy 172.487115 -213.644984) (xy 172.463989 -213.596963) (xy 172.448279 -213.546033)
			(xy 172.440336 -213.493329) (xy 158.88716 -213.493329) (xy 158.88716 -214.343213) (xy 176.540404 -214.343213)
			(xy 176.540404 -214.289915) (xy 176.548347 -214.237211) (xy 176.564057 -214.186281) (xy 176.587183 -214.13826)
			(xy 176.617207 -214.094223) (xy 176.653459 -214.055152) (xy 176.69513 -214.021921) (xy 176.741288 -213.995272)
			(xy 176.790902 -213.9758) (xy 176.842864 -213.96394) (xy 176.896014 -213.959957) (xy 176.949164 -213.96394)
			(xy 177.001126 -213.9758) (xy 177.05074 -213.995272) (xy 177.096898 -214.021921) (xy 177.138569 -214.055152)
			(xy 177.174821 -214.094223) (xy 177.204845 -214.13826) (xy 177.227971 -214.186281) (xy 177.243681 -214.237211)
			(xy 177.251624 -214.289915) (xy 177.252122 -214.316564) (xy 177.251624 -214.343213) (xy 191.628004 -214.343213)
			(xy 191.628004 -214.289915) (xy 191.635947 -214.237211) (xy 191.651657 -214.186281) (xy 191.674783 -214.13826)
			(xy 191.704807 -214.094223) (xy 191.741059 -214.055152) (xy 191.78273 -214.021921) (xy 191.828888 -213.995272)
			(xy 191.878502 -213.9758) (xy 191.930464 -213.96394) (xy 191.983614 -213.959957) (xy 192.036764 -213.96394)
			(xy 192.088726 -213.9758) (xy 192.13834 -213.995272) (xy 192.184498 -214.021921) (xy 192.226169 -214.055152)
			(xy 192.262421 -214.094223) (xy 192.292445 -214.13826) (xy 192.315571 -214.186281) (xy 192.331281 -214.237211)
			(xy 192.339224 -214.289915) (xy 192.339722 -214.316564) (xy 192.339224 -214.343213) (xy 206.715604 -214.343213)
			(xy 206.715604 -214.289915) (xy 206.723547 -214.237211) (xy 206.739257 -214.186281) (xy 206.762383 -214.13826)
			(xy 206.792407 -214.094223) (xy 206.828659 -214.055152) (xy 206.87033 -214.021921) (xy 206.916488 -213.995272)
			(xy 206.966102 -213.9758) (xy 207.018064 -213.96394) (xy 207.071214 -213.959957) (xy 207.124364 -213.96394)
			(xy 207.176326 -213.9758) (xy 207.22594 -213.995272) (xy 207.272098 -214.021921) (xy 207.313769 -214.055152)
			(xy 207.350021 -214.094223) (xy 207.380045 -214.13826) (xy 207.403171 -214.186281) (xy 207.418881 -214.237211)
			(xy 207.426824 -214.289915) (xy 207.427322 -214.316564) (xy 207.426824 -214.343213) (xy 207.418881 -214.395917)
			(xy 207.403171 -214.446847) (xy 207.380045 -214.494868) (xy 207.350021 -214.538905) (xy 207.313769 -214.577976)
			(xy 207.272098 -214.611207) (xy 207.22594 -214.637856) (xy 207.176326 -214.657328) (xy 207.124364 -214.669188)
			(xy 207.071214 -214.673172) (xy 207.018064 -214.669188) (xy 206.966102 -214.657328) (xy 206.916488 -214.637856)
			(xy 206.87033 -214.611207) (xy 206.828659 -214.577976) (xy 206.792407 -214.538905) (xy 206.762383 -214.494868)
			(xy 206.739257 -214.446847) (xy 206.723547 -214.395917) (xy 206.715604 -214.343213) (xy 192.339224 -214.343213)
			(xy 192.331281 -214.395917) (xy 192.315571 -214.446847) (xy 192.292445 -214.494868) (xy 192.262421 -214.538905)
			(xy 192.226169 -214.577976) (xy 192.184498 -214.611207) (xy 192.13834 -214.637856) (xy 192.088726 -214.657328)
			(xy 192.036764 -214.669188) (xy 191.983614 -214.673172) (xy 191.930464 -214.669188) (xy 191.878502 -214.657328)
			(xy 191.828888 -214.637856) (xy 191.78273 -214.611207) (xy 191.741059 -214.577976) (xy 191.704807 -214.538905)
			(xy 191.674783 -214.494868) (xy 191.651657 -214.446847) (xy 191.635947 -214.395917) (xy 191.628004 -214.343213)
			(xy 177.251624 -214.343213) (xy 177.243681 -214.395917) (xy 177.227971 -214.446847) (xy 177.204845 -214.494868)
			(xy 177.174821 -214.538905) (xy 177.138569 -214.577976) (xy 177.096898 -214.611207) (xy 177.05074 -214.637856)
			(xy 177.001126 -214.657328) (xy 176.949164 -214.669188) (xy 176.896014 -214.673172) (xy 176.842864 -214.669188)
			(xy 176.790902 -214.657328) (xy 176.741288 -214.637856) (xy 176.69513 -214.611207) (xy 176.653459 -214.577976)
			(xy 176.617207 -214.538905) (xy 176.587183 -214.494868) (xy 176.564057 -214.446847) (xy 176.548347 -214.395917)
			(xy 176.540404 -214.343213) (xy 158.88716 -214.343213) (xy 158.88716 -215.193351) (xy 172.440336 -215.193351)
			(xy 172.440336 -215.140053) (xy 172.448279 -215.087349) (xy 172.463989 -215.036419) (xy 172.487115 -214.988398)
			(xy 172.517139 -214.944361) (xy 172.553391 -214.90529) (xy 172.595062 -214.872059) (xy 172.64122 -214.84541)
			(xy 172.690834 -214.825938) (xy 172.742796 -214.814078) (xy 172.795946 -214.810095) (xy 172.849096 -214.814078)
			(xy 172.901058 -214.825938) (xy 172.950672 -214.84541) (xy 172.99683 -214.872059) (xy 173.038501 -214.90529)
			(xy 173.074753 -214.944361) (xy 173.104777 -214.988398) (xy 173.127903 -215.036419) (xy 173.143613 -215.087349)
			(xy 173.151556 -215.140053) (xy 173.152054 -215.166702) (xy 173.151556 -215.193351) (xy 187.527936 -215.193351)
			(xy 187.527936 -215.140053) (xy 187.535879 -215.087349) (xy 187.551589 -215.036419) (xy 187.574715 -214.988398)
			(xy 187.604739 -214.944361) (xy 187.640991 -214.90529) (xy 187.682662 -214.872059) (xy 187.72882 -214.84541)
			(xy 187.778434 -214.825938) (xy 187.830396 -214.814078) (xy 187.883546 -214.810095) (xy 187.936696 -214.814078)
			(xy 187.988658 -214.825938) (xy 188.038272 -214.84541) (xy 188.08443 -214.872059) (xy 188.126101 -214.90529)
			(xy 188.162353 -214.944361) (xy 188.192377 -214.988398) (xy 188.215503 -215.036419) (xy 188.231213 -215.087349)
			(xy 188.239156 -215.140053) (xy 188.239654 -215.166702) (xy 188.239156 -215.193351) (xy 202.615536 -215.193351)
			(xy 202.615536 -215.140053) (xy 202.623479 -215.087349) (xy 202.639189 -215.036419) (xy 202.662315 -214.988398)
			(xy 202.692339 -214.944361) (xy 202.728591 -214.90529) (xy 202.770262 -214.872059) (xy 202.81642 -214.84541)
			(xy 202.866034 -214.825938) (xy 202.917996 -214.814078) (xy 202.971146 -214.810095) (xy 203.024296 -214.814078)
			(xy 203.076258 -214.825938) (xy 203.125872 -214.84541) (xy 203.17203 -214.872059) (xy 203.213701 -214.90529)
			(xy 203.249953 -214.944361) (xy 203.279977 -214.988398) (xy 203.303103 -215.036419) (xy 203.318813 -215.087349)
			(xy 203.326756 -215.140053) (xy 203.327254 -215.166702) (xy 203.326756 -215.193351) (xy 203.318813 -215.246055)
			(xy 203.303103 -215.296985) (xy 203.279977 -215.345006) (xy 203.249953 -215.389043) (xy 203.213701 -215.428114)
			(xy 203.17203 -215.461345) (xy 203.125872 -215.487994) (xy 203.076258 -215.507466) (xy 203.024296 -215.519326)
			(xy 202.971146 -215.52331) (xy 202.917996 -215.519326) (xy 202.866034 -215.507466) (xy 202.81642 -215.487994)
			(xy 202.770262 -215.461345) (xy 202.728591 -215.428114) (xy 202.692339 -215.389043) (xy 202.662315 -215.345006)
			(xy 202.639189 -215.296985) (xy 202.623479 -215.246055) (xy 202.615536 -215.193351) (xy 188.239156 -215.193351)
			(xy 188.231213 -215.246055) (xy 188.215503 -215.296985) (xy 188.192377 -215.345006) (xy 188.162353 -215.389043)
			(xy 188.126101 -215.428114) (xy 188.08443 -215.461345) (xy 188.038272 -215.487994) (xy 187.988658 -215.507466)
			(xy 187.936696 -215.519326) (xy 187.883546 -215.52331) (xy 187.830396 -215.519326) (xy 187.778434 -215.507466)
			(xy 187.72882 -215.487994) (xy 187.682662 -215.461345) (xy 187.640991 -215.428114) (xy 187.604739 -215.389043)
			(xy 187.574715 -215.345006) (xy 187.551589 -215.296985) (xy 187.535879 -215.246055) (xy 187.527936 -215.193351)
			(xy 173.151556 -215.193351) (xy 173.143613 -215.246055) (xy 173.127903 -215.296985) (xy 173.104777 -215.345006)
			(xy 173.074753 -215.389043) (xy 173.038501 -215.428114) (xy 172.99683 -215.461345) (xy 172.950672 -215.487994)
			(xy 172.901058 -215.507466) (xy 172.849096 -215.519326) (xy 172.795946 -215.52331) (xy 172.742796 -215.519326)
			(xy 172.690834 -215.507466) (xy 172.64122 -215.487994) (xy 172.595062 -215.461345) (xy 172.553391 -215.428114)
			(xy 172.517139 -215.389043) (xy 172.487115 -215.345006) (xy 172.463989 -215.296985) (xy 172.448279 -215.246055)
			(xy 172.440336 -215.193351) (xy 158.88716 -215.193351) (xy 158.88716 -216.043235) (xy 176.540404 -216.043235)
			(xy 176.540404 -215.989937) (xy 176.548347 -215.937233) (xy 176.564057 -215.886303) (xy 176.587183 -215.838282)
			(xy 176.617207 -215.794245) (xy 176.653459 -215.755174) (xy 176.69513 -215.721943) (xy 176.741288 -215.695294)
			(xy 176.790902 -215.675822) (xy 176.842864 -215.663962) (xy 176.896014 -215.659979) (xy 176.949164 -215.663962)
			(xy 177.001126 -215.675822) (xy 177.05074 -215.695294) (xy 177.096898 -215.721943) (xy 177.138569 -215.755174)
			(xy 177.174821 -215.794245) (xy 177.204845 -215.838282) (xy 177.227971 -215.886303) (xy 177.243681 -215.937233)
			(xy 177.251624 -215.989937) (xy 177.252122 -216.016586) (xy 177.251624 -216.043235) (xy 191.628004 -216.043235)
			(xy 191.628004 -215.989937) (xy 191.635947 -215.937233) (xy 191.651657 -215.886303) (xy 191.674783 -215.838282)
			(xy 191.704807 -215.794245) (xy 191.741059 -215.755174) (xy 191.78273 -215.721943) (xy 191.828888 -215.695294)
			(xy 191.878502 -215.675822) (xy 191.930464 -215.663962) (xy 191.983614 -215.659979) (xy 192.036764 -215.663962)
			(xy 192.088726 -215.675822) (xy 192.13834 -215.695294) (xy 192.184498 -215.721943) (xy 192.226169 -215.755174)
			(xy 192.262421 -215.794245) (xy 192.292445 -215.838282) (xy 192.315571 -215.886303) (xy 192.331281 -215.937233)
			(xy 192.339224 -215.989937) (xy 192.339722 -216.016586) (xy 192.339224 -216.043235) (xy 206.715604 -216.043235)
			(xy 206.715604 -215.989937) (xy 206.723547 -215.937233) (xy 206.739257 -215.886303) (xy 206.762383 -215.838282)
			(xy 206.792407 -215.794245) (xy 206.828659 -215.755174) (xy 206.87033 -215.721943) (xy 206.916488 -215.695294)
			(xy 206.966102 -215.675822) (xy 207.018064 -215.663962) (xy 207.071214 -215.659979) (xy 207.124364 -215.663962)
			(xy 207.176326 -215.675822) (xy 207.22594 -215.695294) (xy 207.272098 -215.721943) (xy 207.313769 -215.755174)
			(xy 207.350021 -215.794245) (xy 207.380045 -215.838282) (xy 207.403171 -215.886303) (xy 207.418881 -215.937233)
			(xy 207.426824 -215.989937) (xy 207.427322 -216.016586) (xy 207.426824 -216.043235) (xy 207.418881 -216.095939)
			(xy 207.403171 -216.146869) (xy 207.380045 -216.19489) (xy 207.350021 -216.238927) (xy 207.313769 -216.277998)
			(xy 207.272098 -216.311229) (xy 207.22594 -216.337878) (xy 207.176326 -216.35735) (xy 207.124364 -216.36921)
			(xy 207.071214 -216.373194) (xy 207.018064 -216.36921) (xy 206.966102 -216.35735) (xy 206.916488 -216.337878)
			(xy 206.87033 -216.311229) (xy 206.828659 -216.277998) (xy 206.792407 -216.238927) (xy 206.762383 -216.19489)
			(xy 206.739257 -216.146869) (xy 206.723547 -216.095939) (xy 206.715604 -216.043235) (xy 192.339224 -216.043235)
			(xy 192.331281 -216.095939) (xy 192.315571 -216.146869) (xy 192.292445 -216.19489) (xy 192.262421 -216.238927)
			(xy 192.226169 -216.277998) (xy 192.184498 -216.311229) (xy 192.13834 -216.337878) (xy 192.088726 -216.35735)
			(xy 192.036764 -216.36921) (xy 191.983614 -216.373194) (xy 191.930464 -216.36921) (xy 191.878502 -216.35735)
			(xy 191.828888 -216.337878) (xy 191.78273 -216.311229) (xy 191.741059 -216.277998) (xy 191.704807 -216.238927)
			(xy 191.674783 -216.19489) (xy 191.651657 -216.146869) (xy 191.635947 -216.095939) (xy 191.628004 -216.043235)
			(xy 177.251624 -216.043235) (xy 177.243681 -216.095939) (xy 177.227971 -216.146869) (xy 177.204845 -216.19489)
			(xy 177.174821 -216.238927) (xy 177.138569 -216.277998) (xy 177.096898 -216.311229) (xy 177.05074 -216.337878)
			(xy 177.001126 -216.35735) (xy 176.949164 -216.36921) (xy 176.896014 -216.373194) (xy 176.842864 -216.36921)
			(xy 176.790902 -216.35735) (xy 176.741288 -216.337878) (xy 176.69513 -216.311229) (xy 176.653459 -216.277998)
			(xy 176.617207 -216.238927) (xy 176.587183 -216.19489) (xy 176.564057 -216.146869) (xy 176.548347 -216.095939)
			(xy 176.540404 -216.043235) (xy 158.88716 -216.043235) (xy 158.88716 -216.893373) (xy 172.440336 -216.893373)
			(xy 172.440336 -216.840075) (xy 172.448279 -216.787371) (xy 172.463989 -216.736441) (xy 172.487115 -216.68842)
			(xy 172.517139 -216.644383) (xy 172.553391 -216.605312) (xy 172.595062 -216.572081) (xy 172.64122 -216.545432)
			(xy 172.690834 -216.52596) (xy 172.742796 -216.5141) (xy 172.795946 -216.510117) (xy 172.849096 -216.5141)
			(xy 172.901058 -216.52596) (xy 172.950672 -216.545432) (xy 172.99683 -216.572081) (xy 173.038501 -216.605312)
			(xy 173.074753 -216.644383) (xy 173.104777 -216.68842) (xy 173.127903 -216.736441) (xy 173.143613 -216.787371)
			(xy 173.151556 -216.840075) (xy 173.152054 -216.866724) (xy 173.151556 -216.893373) (xy 187.527936 -216.893373)
			(xy 187.527936 -216.840075) (xy 187.535879 -216.787371) (xy 187.551589 -216.736441) (xy 187.574715 -216.68842)
			(xy 187.604739 -216.644383) (xy 187.640991 -216.605312) (xy 187.682662 -216.572081) (xy 187.72882 -216.545432)
			(xy 187.778434 -216.52596) (xy 187.830396 -216.5141) (xy 187.883546 -216.510117) (xy 187.936696 -216.5141)
			(xy 187.988658 -216.52596) (xy 188.038272 -216.545432) (xy 188.08443 -216.572081) (xy 188.126101 -216.605312)
			(xy 188.162353 -216.644383) (xy 188.192377 -216.68842) (xy 188.215503 -216.736441) (xy 188.231213 -216.787371)
			(xy 188.239156 -216.840075) (xy 188.239654 -216.866724) (xy 188.239156 -216.893373) (xy 202.615536 -216.893373)
			(xy 202.615536 -216.840075) (xy 202.623479 -216.787371) (xy 202.639189 -216.736441) (xy 202.662315 -216.68842)
			(xy 202.692339 -216.644383) (xy 202.728591 -216.605312) (xy 202.770262 -216.572081) (xy 202.81642 -216.545432)
			(xy 202.866034 -216.52596) (xy 202.917996 -216.5141) (xy 202.971146 -216.510117) (xy 203.024296 -216.5141)
			(xy 203.076258 -216.52596) (xy 203.125872 -216.545432) (xy 203.17203 -216.572081) (xy 203.213701 -216.605312)
			(xy 203.249953 -216.644383) (xy 203.279977 -216.68842) (xy 203.303103 -216.736441) (xy 203.318813 -216.787371)
			(xy 203.326756 -216.840075) (xy 203.327254 -216.866724) (xy 203.326756 -216.893373) (xy 203.318813 -216.946077)
			(xy 203.303103 -216.997007) (xy 203.279977 -217.045028) (xy 203.249953 -217.089065) (xy 203.213701 -217.128136)
			(xy 203.17203 -217.161367) (xy 203.125872 -217.188016) (xy 203.076258 -217.207488) (xy 203.024296 -217.219348)
			(xy 202.971146 -217.223332) (xy 202.917996 -217.219348) (xy 202.866034 -217.207488) (xy 202.81642 -217.188016)
			(xy 202.770262 -217.161367) (xy 202.728591 -217.128136) (xy 202.692339 -217.089065) (xy 202.662315 -217.045028)
			(xy 202.639189 -216.997007) (xy 202.623479 -216.946077) (xy 202.615536 -216.893373) (xy 188.239156 -216.893373)
			(xy 188.231213 -216.946077) (xy 188.215503 -216.997007) (xy 188.192377 -217.045028) (xy 188.162353 -217.089065)
			(xy 188.126101 -217.128136) (xy 188.08443 -217.161367) (xy 188.038272 -217.188016) (xy 187.988658 -217.207488)
			(xy 187.936696 -217.219348) (xy 187.883546 -217.223332) (xy 187.830396 -217.219348) (xy 187.778434 -217.207488)
			(xy 187.72882 -217.188016) (xy 187.682662 -217.161367) (xy 187.640991 -217.128136) (xy 187.604739 -217.089065)
			(xy 187.574715 -217.045028) (xy 187.551589 -216.997007) (xy 187.535879 -216.946077) (xy 187.527936 -216.893373)
			(xy 173.151556 -216.893373) (xy 173.143613 -216.946077) (xy 173.127903 -216.997007) (xy 173.104777 -217.045028)
			(xy 173.074753 -217.089065) (xy 173.038501 -217.128136) (xy 172.99683 -217.161367) (xy 172.950672 -217.188016)
			(xy 172.901058 -217.207488) (xy 172.849096 -217.219348) (xy 172.795946 -217.223332) (xy 172.742796 -217.219348)
			(xy 172.690834 -217.207488) (xy 172.64122 -217.188016) (xy 172.595062 -217.161367) (xy 172.553391 -217.128136)
			(xy 172.517139 -217.089065) (xy 172.487115 -217.045028) (xy 172.463989 -216.997007) (xy 172.448279 -216.946077)
			(xy 172.440336 -216.893373) (xy 158.88716 -216.893373) (xy 158.88716 -217.743257) (xy 176.540404 -217.743257)
			(xy 176.540404 -217.689959) (xy 176.548347 -217.637255) (xy 176.564057 -217.586325) (xy 176.587183 -217.538304)
			(xy 176.617207 -217.494267) (xy 176.653459 -217.455196) (xy 176.69513 -217.421965) (xy 176.741288 -217.395316)
			(xy 176.790902 -217.375844) (xy 176.842864 -217.363984) (xy 176.896014 -217.360001) (xy 176.949164 -217.363984)
			(xy 177.001126 -217.375844) (xy 177.05074 -217.395316) (xy 177.096898 -217.421965) (xy 177.138569 -217.455196)
			(xy 177.174821 -217.494267) (xy 177.204845 -217.538304) (xy 177.227971 -217.586325) (xy 177.243681 -217.637255)
			(xy 177.251624 -217.689959) (xy 177.252122 -217.716608) (xy 177.251624 -217.743257) (xy 191.628004 -217.743257)
			(xy 191.628004 -217.689959) (xy 191.635947 -217.637255) (xy 191.651657 -217.586325) (xy 191.674783 -217.538304)
			(xy 191.704807 -217.494267) (xy 191.741059 -217.455196) (xy 191.78273 -217.421965) (xy 191.828888 -217.395316)
			(xy 191.878502 -217.375844) (xy 191.930464 -217.363984) (xy 191.983614 -217.360001) (xy 192.036764 -217.363984)
			(xy 192.088726 -217.375844) (xy 192.13834 -217.395316) (xy 192.184498 -217.421965) (xy 192.226169 -217.455196)
			(xy 192.262421 -217.494267) (xy 192.292445 -217.538304) (xy 192.315571 -217.586325) (xy 192.331281 -217.637255)
			(xy 192.339224 -217.689959) (xy 192.339722 -217.716608) (xy 192.339224 -217.743257) (xy 206.715604 -217.743257)
			(xy 206.715604 -217.689959) (xy 206.723547 -217.637255) (xy 206.739257 -217.586325) (xy 206.762383 -217.538304)
			(xy 206.792407 -217.494267) (xy 206.828659 -217.455196) (xy 206.87033 -217.421965) (xy 206.916488 -217.395316)
			(xy 206.966102 -217.375844) (xy 207.018064 -217.363984) (xy 207.071214 -217.360001) (xy 207.124364 -217.363984)
			(xy 207.176326 -217.375844) (xy 207.22594 -217.395316) (xy 207.272098 -217.421965) (xy 207.313769 -217.455196)
			(xy 207.350021 -217.494267) (xy 207.380045 -217.538304) (xy 207.403171 -217.586325) (xy 207.418881 -217.637255)
			(xy 207.426824 -217.689959) (xy 207.427322 -217.716608) (xy 207.426824 -217.743257) (xy 207.418881 -217.795961)
			(xy 207.403171 -217.846891) (xy 207.380045 -217.894912) (xy 207.350021 -217.938949) (xy 207.313769 -217.97802)
			(xy 207.272098 -218.011251) (xy 207.22594 -218.0379) (xy 207.176326 -218.057372) (xy 207.124364 -218.069232)
			(xy 207.071214 -218.073216) (xy 207.018064 -218.069232) (xy 206.966102 -218.057372) (xy 206.916488 -218.0379)
			(xy 206.87033 -218.011251) (xy 206.828659 -217.97802) (xy 206.792407 -217.938949) (xy 206.762383 -217.894912)
			(xy 206.739257 -217.846891) (xy 206.723547 -217.795961) (xy 206.715604 -217.743257) (xy 192.339224 -217.743257)
			(xy 192.331281 -217.795961) (xy 192.315571 -217.846891) (xy 192.292445 -217.894912) (xy 192.262421 -217.938949)
			(xy 192.226169 -217.97802) (xy 192.184498 -218.011251) (xy 192.13834 -218.0379) (xy 192.088726 -218.057372)
			(xy 192.036764 -218.069232) (xy 191.983614 -218.073216) (xy 191.930464 -218.069232) (xy 191.878502 -218.057372)
			(xy 191.828888 -218.0379) (xy 191.78273 -218.011251) (xy 191.741059 -217.97802) (xy 191.704807 -217.938949)
			(xy 191.674783 -217.894912) (xy 191.651657 -217.846891) (xy 191.635947 -217.795961) (xy 191.628004 -217.743257)
			(xy 177.251624 -217.743257) (xy 177.243681 -217.795961) (xy 177.227971 -217.846891) (xy 177.204845 -217.894912)
			(xy 177.174821 -217.938949) (xy 177.138569 -217.97802) (xy 177.096898 -218.011251) (xy 177.05074 -218.0379)
			(xy 177.001126 -218.057372) (xy 176.949164 -218.069232) (xy 176.896014 -218.073216) (xy 176.842864 -218.069232)
			(xy 176.790902 -218.057372) (xy 176.741288 -218.0379) (xy 176.69513 -218.011251) (xy 176.653459 -217.97802)
			(xy 176.617207 -217.938949) (xy 176.587183 -217.894912) (xy 176.564057 -217.846891) (xy 176.548347 -217.795961)
			(xy 176.540404 -217.743257) (xy 158.88716 -217.743257) (xy 158.88716 -218.593395) (xy 172.440336 -218.593395)
			(xy 172.440336 -218.540097) (xy 172.448279 -218.487393) (xy 172.463989 -218.436463) (xy 172.487115 -218.388442)
			(xy 172.517139 -218.344405) (xy 172.553391 -218.305334) (xy 172.595062 -218.272103) (xy 172.64122 -218.245454)
			(xy 172.690834 -218.225982) (xy 172.742796 -218.214122) (xy 172.795946 -218.210139) (xy 172.849096 -218.214122)
			(xy 172.901058 -218.225982) (xy 172.950672 -218.245454) (xy 172.99683 -218.272103) (xy 173.038501 -218.305334)
			(xy 173.074753 -218.344405) (xy 173.104777 -218.388442) (xy 173.127903 -218.436463) (xy 173.143613 -218.487393)
			(xy 173.151556 -218.540097) (xy 173.152054 -218.566746) (xy 173.151556 -218.593395) (xy 176.540404 -218.593395)
			(xy 176.540404 -218.540097) (xy 176.548347 -218.487393) (xy 176.564057 -218.436463) (xy 176.587183 -218.388442)
			(xy 176.617207 -218.344405) (xy 176.653459 -218.305334) (xy 176.69513 -218.272103) (xy 176.741288 -218.245454)
			(xy 176.790902 -218.225982) (xy 176.842864 -218.214122) (xy 176.896014 -218.210139) (xy 176.949164 -218.214122)
			(xy 177.001126 -218.225982) (xy 177.05074 -218.245454) (xy 177.096898 -218.272103) (xy 177.138569 -218.305334)
			(xy 177.174821 -218.344405) (xy 177.204845 -218.388442) (xy 177.227971 -218.436463) (xy 177.243681 -218.487393)
			(xy 177.251624 -218.540097) (xy 177.252122 -218.566746) (xy 177.251624 -218.593395) (xy 187.527936 -218.593395)
			(xy 187.527936 -218.540097) (xy 187.535879 -218.487393) (xy 187.551589 -218.436463) (xy 187.574715 -218.388442)
			(xy 187.604739 -218.344405) (xy 187.640991 -218.305334) (xy 187.682662 -218.272103) (xy 187.72882 -218.245454)
			(xy 187.778434 -218.225982) (xy 187.830396 -218.214122) (xy 187.883546 -218.210139) (xy 187.936696 -218.214122)
			(xy 187.988658 -218.225982) (xy 188.038272 -218.245454) (xy 188.08443 -218.272103) (xy 188.126101 -218.305334)
			(xy 188.162353 -218.344405) (xy 188.192377 -218.388442) (xy 188.215503 -218.436463) (xy 188.231213 -218.487393)
			(xy 188.239156 -218.540097) (xy 188.239654 -218.566746) (xy 188.239156 -218.593395) (xy 191.628004 -218.593395)
			(xy 191.628004 -218.540097) (xy 191.635947 -218.487393) (xy 191.651657 -218.436463) (xy 191.674783 -218.388442)
			(xy 191.704807 -218.344405) (xy 191.741059 -218.305334) (xy 191.78273 -218.272103) (xy 191.828888 -218.245454)
			(xy 191.878502 -218.225982) (xy 191.930464 -218.214122) (xy 191.983614 -218.210139) (xy 192.036764 -218.214122)
			(xy 192.088726 -218.225982) (xy 192.13834 -218.245454) (xy 192.184498 -218.272103) (xy 192.226169 -218.305334)
			(xy 192.262421 -218.344405) (xy 192.292445 -218.388442) (xy 192.315571 -218.436463) (xy 192.331281 -218.487393)
			(xy 192.339224 -218.540097) (xy 192.339722 -218.566746) (xy 192.339224 -218.593395) (xy 202.615536 -218.593395)
			(xy 202.615536 -218.540097) (xy 202.623479 -218.487393) (xy 202.639189 -218.436463) (xy 202.662315 -218.388442)
			(xy 202.692339 -218.344405) (xy 202.728591 -218.305334) (xy 202.770262 -218.272103) (xy 202.81642 -218.245454)
			(xy 202.866034 -218.225982) (xy 202.917996 -218.214122) (xy 202.971146 -218.210139) (xy 203.024296 -218.214122)
			(xy 203.076258 -218.225982) (xy 203.125872 -218.245454) (xy 203.17203 -218.272103) (xy 203.213701 -218.305334)
			(xy 203.249953 -218.344405) (xy 203.279977 -218.388442) (xy 203.303103 -218.436463) (xy 203.318813 -218.487393)
			(xy 203.326756 -218.540097) (xy 203.327254 -218.566746) (xy 203.326756 -218.593395) (xy 206.715604 -218.593395)
			(xy 206.715604 -218.540097) (xy 206.723547 -218.487393) (xy 206.739257 -218.436463) (xy 206.762383 -218.388442)
			(xy 206.792407 -218.344405) (xy 206.828659 -218.305334) (xy 206.87033 -218.272103) (xy 206.916488 -218.245454)
			(xy 206.966102 -218.225982) (xy 207.018064 -218.214122) (xy 207.071214 -218.210139) (xy 207.124364 -218.214122)
			(xy 207.176326 -218.225982) (xy 207.22594 -218.245454) (xy 207.272098 -218.272103) (xy 207.313769 -218.305334)
			(xy 207.350021 -218.344405) (xy 207.380045 -218.388442) (xy 207.403171 -218.436463) (xy 207.418881 -218.487393)
			(xy 207.426824 -218.540097) (xy 207.427322 -218.566746) (xy 207.426824 -218.593395) (xy 207.418881 -218.646099)
			(xy 207.403171 -218.697029) (xy 207.380045 -218.74505) (xy 207.350021 -218.789087) (xy 207.313769 -218.828158)
			(xy 207.272098 -218.861389) (xy 207.22594 -218.888038) (xy 207.176326 -218.90751) (xy 207.124364 -218.91937)
			(xy 207.071214 -218.923354) (xy 207.018064 -218.91937) (xy 206.966102 -218.90751) (xy 206.916488 -218.888038)
			(xy 206.87033 -218.861389) (xy 206.828659 -218.828158) (xy 206.792407 -218.789087) (xy 206.762383 -218.74505)
			(xy 206.739257 -218.697029) (xy 206.723547 -218.646099) (xy 206.715604 -218.593395) (xy 203.326756 -218.593395)
			(xy 203.318813 -218.646099) (xy 203.303103 -218.697029) (xy 203.279977 -218.74505) (xy 203.249953 -218.789087)
			(xy 203.213701 -218.828158) (xy 203.17203 -218.861389) (xy 203.125872 -218.888038) (xy 203.076258 -218.90751)
			(xy 203.024296 -218.91937) (xy 202.971146 -218.923354) (xy 202.917996 -218.91937) (xy 202.866034 -218.90751)
			(xy 202.81642 -218.888038) (xy 202.770262 -218.861389) (xy 202.728591 -218.828158) (xy 202.692339 -218.789087)
			(xy 202.662315 -218.74505) (xy 202.639189 -218.697029) (xy 202.623479 -218.646099) (xy 202.615536 -218.593395)
			(xy 192.339224 -218.593395) (xy 192.331281 -218.646099) (xy 192.315571 -218.697029) (xy 192.292445 -218.74505)
			(xy 192.262421 -218.789087) (xy 192.226169 -218.828158) (xy 192.184498 -218.861389) (xy 192.13834 -218.888038)
			(xy 192.088726 -218.90751) (xy 192.036764 -218.91937) (xy 191.983614 -218.923354) (xy 191.930464 -218.91937)
			(xy 191.878502 -218.90751) (xy 191.828888 -218.888038) (xy 191.78273 -218.861389) (xy 191.741059 -218.828158)
			(xy 191.704807 -218.789087) (xy 191.674783 -218.74505) (xy 191.651657 -218.697029) (xy 191.635947 -218.646099)
			(xy 191.628004 -218.593395) (xy 188.239156 -218.593395) (xy 188.231213 -218.646099) (xy 188.215503 -218.697029)
			(xy 188.192377 -218.74505) (xy 188.162353 -218.789087) (xy 188.126101 -218.828158) (xy 188.08443 -218.861389)
			(xy 188.038272 -218.888038) (xy 187.988658 -218.90751) (xy 187.936696 -218.91937) (xy 187.883546 -218.923354)
			(xy 187.830396 -218.91937) (xy 187.778434 -218.90751) (xy 187.72882 -218.888038) (xy 187.682662 -218.861389)
			(xy 187.640991 -218.828158) (xy 187.604739 -218.789087) (xy 187.574715 -218.74505) (xy 187.551589 -218.697029)
			(xy 187.535879 -218.646099) (xy 187.527936 -218.593395) (xy 177.251624 -218.593395) (xy 177.243681 -218.646099)
			(xy 177.227971 -218.697029) (xy 177.204845 -218.74505) (xy 177.174821 -218.789087) (xy 177.138569 -218.828158)
			(xy 177.096898 -218.861389) (xy 177.05074 -218.888038) (xy 177.001126 -218.90751) (xy 176.949164 -218.91937)
			(xy 176.896014 -218.923354) (xy 176.842864 -218.91937) (xy 176.790902 -218.90751) (xy 176.741288 -218.888038)
			(xy 176.69513 -218.861389) (xy 176.653459 -218.828158) (xy 176.617207 -218.789087) (xy 176.587183 -218.74505)
			(xy 176.564057 -218.697029) (xy 176.548347 -218.646099) (xy 176.540404 -218.593395) (xy 173.151556 -218.593395)
			(xy 173.143613 -218.646099) (xy 173.127903 -218.697029) (xy 173.104777 -218.74505) (xy 173.074753 -218.789087)
			(xy 173.038501 -218.828158) (xy 172.99683 -218.861389) (xy 172.950672 -218.888038) (xy 172.901058 -218.90751)
			(xy 172.849096 -218.91937) (xy 172.795946 -218.923354) (xy 172.742796 -218.91937) (xy 172.690834 -218.90751)
			(xy 172.64122 -218.888038) (xy 172.595062 -218.861389) (xy 172.553391 -218.828158) (xy 172.517139 -218.789087)
			(xy 172.487115 -218.74505) (xy 172.463989 -218.697029) (xy 172.448279 -218.646099) (xy 172.440336 -218.593395)
			(xy 158.88716 -218.593395) (xy 158.88716 -219.443279) (xy 172.440336 -219.443279) (xy 172.440336 -219.389981)
			(xy 172.448279 -219.337277) (xy 172.463989 -219.286347) (xy 172.487115 -219.238326) (xy 172.517139 -219.194289)
			(xy 172.553391 -219.155218) (xy 172.595062 -219.121987) (xy 172.64122 -219.095338) (xy 172.690834 -219.075866)
			(xy 172.742796 -219.064006) (xy 172.795946 -219.060023) (xy 172.849096 -219.064006) (xy 172.901058 -219.075866)
			(xy 172.950672 -219.095338) (xy 172.99683 -219.121987) (xy 173.038501 -219.155218) (xy 173.074753 -219.194289)
			(xy 173.104777 -219.238326) (xy 173.127903 -219.286347) (xy 173.143613 -219.337277) (xy 173.151556 -219.389981)
			(xy 173.152054 -219.41663) (xy 173.151556 -219.443279) (xy 187.527936 -219.443279) (xy 187.527936 -219.389981)
			(xy 187.535879 -219.337277) (xy 187.551589 -219.286347) (xy 187.574715 -219.238326) (xy 187.604739 -219.194289)
			(xy 187.640991 -219.155218) (xy 187.682662 -219.121987) (xy 187.72882 -219.095338) (xy 187.778434 -219.075866)
			(xy 187.830396 -219.064006) (xy 187.883546 -219.060023) (xy 187.936696 -219.064006) (xy 187.988658 -219.075866)
			(xy 188.038272 -219.095338) (xy 188.08443 -219.121987) (xy 188.126101 -219.155218) (xy 188.162353 -219.194289)
			(xy 188.192377 -219.238326) (xy 188.215503 -219.286347) (xy 188.231213 -219.337277) (xy 188.239156 -219.389981)
			(xy 188.239654 -219.41663) (xy 188.239156 -219.443279) (xy 202.615536 -219.443279) (xy 202.615536 -219.389981)
			(xy 202.623479 -219.337277) (xy 202.639189 -219.286347) (xy 202.662315 -219.238326) (xy 202.692339 -219.194289)
			(xy 202.728591 -219.155218) (xy 202.770262 -219.121987) (xy 202.81642 -219.095338) (xy 202.866034 -219.075866)
			(xy 202.917996 -219.064006) (xy 202.971146 -219.060023) (xy 203.024296 -219.064006) (xy 203.076258 -219.075866)
			(xy 203.125872 -219.095338) (xy 203.17203 -219.121987) (xy 203.213701 -219.155218) (xy 203.249953 -219.194289)
			(xy 203.279977 -219.238326) (xy 203.303103 -219.286347) (xy 203.318813 -219.337277) (xy 203.326756 -219.389981)
			(xy 203.327254 -219.41663) (xy 203.326756 -219.443279) (xy 203.318813 -219.495983) (xy 203.303103 -219.546913)
			(xy 203.279977 -219.594934) (xy 203.249953 -219.638971) (xy 203.213701 -219.678042) (xy 203.17203 -219.711273)
			(xy 203.125872 -219.737922) (xy 203.076258 -219.757394) (xy 203.024296 -219.769254) (xy 202.971146 -219.773238)
			(xy 202.917996 -219.769254) (xy 202.866034 -219.757394) (xy 202.81642 -219.737922) (xy 202.770262 -219.711273)
			(xy 202.728591 -219.678042) (xy 202.692339 -219.638971) (xy 202.662315 -219.594934) (xy 202.639189 -219.546913)
			(xy 202.623479 -219.495983) (xy 202.615536 -219.443279) (xy 188.239156 -219.443279) (xy 188.231213 -219.495983)
			(xy 188.215503 -219.546913) (xy 188.192377 -219.594934) (xy 188.162353 -219.638971) (xy 188.126101 -219.678042)
			(xy 188.08443 -219.711273) (xy 188.038272 -219.737922) (xy 187.988658 -219.757394) (xy 187.936696 -219.769254)
			(xy 187.883546 -219.773238) (xy 187.830396 -219.769254) (xy 187.778434 -219.757394) (xy 187.72882 -219.737922)
			(xy 187.682662 -219.711273) (xy 187.640991 -219.678042) (xy 187.604739 -219.638971) (xy 187.574715 -219.594934)
			(xy 187.551589 -219.546913) (xy 187.535879 -219.495983) (xy 187.527936 -219.443279) (xy 173.151556 -219.443279)
			(xy 173.143613 -219.495983) (xy 173.127903 -219.546913) (xy 173.104777 -219.594934) (xy 173.074753 -219.638971)
			(xy 173.038501 -219.678042) (xy 172.99683 -219.711273) (xy 172.950672 -219.737922) (xy 172.901058 -219.757394)
			(xy 172.849096 -219.769254) (xy 172.795946 -219.773238) (xy 172.742796 -219.769254) (xy 172.690834 -219.757394)
			(xy 172.64122 -219.737922) (xy 172.595062 -219.711273) (xy 172.553391 -219.678042) (xy 172.517139 -219.638971)
			(xy 172.487115 -219.594934) (xy 172.463989 -219.546913) (xy 172.448279 -219.495983) (xy 172.440336 -219.443279)
			(xy 158.88716 -219.443279) (xy 158.88716 -220.293417) (xy 176.540404 -220.293417) (xy 176.540404 -220.240119)
			(xy 176.548347 -220.187415) (xy 176.564057 -220.136485) (xy 176.587183 -220.088464) (xy 176.617207 -220.044427)
			(xy 176.653459 -220.005356) (xy 176.69513 -219.972125) (xy 176.741288 -219.945476) (xy 176.790902 -219.926004)
			(xy 176.842864 -219.914144) (xy 176.896014 -219.910161) (xy 176.949164 -219.914144) (xy 177.001126 -219.926004)
			(xy 177.05074 -219.945476) (xy 177.096898 -219.972125) (xy 177.138569 -220.005356) (xy 177.174821 -220.044427)
			(xy 177.204845 -220.088464) (xy 177.227971 -220.136485) (xy 177.243681 -220.187415) (xy 177.251624 -220.240119)
			(xy 177.252122 -220.266768) (xy 177.251624 -220.293417) (xy 191.628004 -220.293417) (xy 191.628004 -220.240119)
			(xy 191.635947 -220.187415) (xy 191.651657 -220.136485) (xy 191.674783 -220.088464) (xy 191.704807 -220.044427)
			(xy 191.741059 -220.005356) (xy 191.78273 -219.972125) (xy 191.828888 -219.945476) (xy 191.878502 -219.926004)
			(xy 191.930464 -219.914144) (xy 191.983614 -219.910161) (xy 192.036764 -219.914144) (xy 192.088726 -219.926004)
			(xy 192.13834 -219.945476) (xy 192.184498 -219.972125) (xy 192.226169 -220.005356) (xy 192.262421 -220.044427)
			(xy 192.292445 -220.088464) (xy 192.315571 -220.136485) (xy 192.331281 -220.187415) (xy 192.339224 -220.240119)
			(xy 192.339722 -220.266768) (xy 192.339224 -220.293417) (xy 206.715604 -220.293417) (xy 206.715604 -220.240119)
			(xy 206.723547 -220.187415) (xy 206.739257 -220.136485) (xy 206.762383 -220.088464) (xy 206.792407 -220.044427)
			(xy 206.828659 -220.005356) (xy 206.87033 -219.972125) (xy 206.916488 -219.945476) (xy 206.966102 -219.926004)
			(xy 207.018064 -219.914144) (xy 207.071214 -219.910161) (xy 207.124364 -219.914144) (xy 207.176326 -219.926004)
			(xy 207.22594 -219.945476) (xy 207.272098 -219.972125) (xy 207.313769 -220.005356) (xy 207.350021 -220.044427)
			(xy 207.380045 -220.088464) (xy 207.403171 -220.136485) (xy 207.418881 -220.187415) (xy 207.426824 -220.240119)
			(xy 207.427322 -220.266768) (xy 207.426824 -220.293417) (xy 207.418881 -220.346121) (xy 207.403171 -220.397051)
			(xy 207.380045 -220.445072) (xy 207.350021 -220.489109) (xy 207.313769 -220.52818) (xy 207.272098 -220.561411)
			(xy 207.22594 -220.58806) (xy 207.176326 -220.607532) (xy 207.124364 -220.619392) (xy 207.071214 -220.623376)
			(xy 207.018064 -220.619392) (xy 206.966102 -220.607532) (xy 206.916488 -220.58806) (xy 206.87033 -220.561411)
			(xy 206.828659 -220.52818) (xy 206.792407 -220.489109) (xy 206.762383 -220.445072) (xy 206.739257 -220.397051)
			(xy 206.723547 -220.346121) (xy 206.715604 -220.293417) (xy 192.339224 -220.293417) (xy 192.331281 -220.346121)
			(xy 192.315571 -220.397051) (xy 192.292445 -220.445072) (xy 192.262421 -220.489109) (xy 192.226169 -220.52818)
			(xy 192.184498 -220.561411) (xy 192.13834 -220.58806) (xy 192.088726 -220.607532) (xy 192.036764 -220.619392)
			(xy 191.983614 -220.623376) (xy 191.930464 -220.619392) (xy 191.878502 -220.607532) (xy 191.828888 -220.58806)
			(xy 191.78273 -220.561411) (xy 191.741059 -220.52818) (xy 191.704807 -220.489109) (xy 191.674783 -220.445072)
			(xy 191.651657 -220.397051) (xy 191.635947 -220.346121) (xy 191.628004 -220.293417) (xy 177.251624 -220.293417)
			(xy 177.243681 -220.346121) (xy 177.227971 -220.397051) (xy 177.204845 -220.445072) (xy 177.174821 -220.489109)
			(xy 177.138569 -220.52818) (xy 177.096898 -220.561411) (xy 177.05074 -220.58806) (xy 177.001126 -220.607532)
			(xy 176.949164 -220.619392) (xy 176.896014 -220.623376) (xy 176.842864 -220.619392) (xy 176.790902 -220.607532)
			(xy 176.741288 -220.58806) (xy 176.69513 -220.561411) (xy 176.653459 -220.52818) (xy 176.617207 -220.489109)
			(xy 176.587183 -220.445072) (xy 176.564057 -220.397051) (xy 176.548347 -220.346121) (xy 176.540404 -220.293417)
			(xy 158.88716 -220.293417) (xy 158.88716 -221.143301) (xy 172.440336 -221.143301) (xy 172.440336 -221.090003)
			(xy 172.448279 -221.037299) (xy 172.463989 -220.986369) (xy 172.487115 -220.938348) (xy 172.517139 -220.894311)
			(xy 172.553391 -220.85524) (xy 172.595062 -220.822009) (xy 172.64122 -220.79536) (xy 172.690834 -220.775888)
			(xy 172.742796 -220.764028) (xy 172.795946 -220.760045) (xy 172.849096 -220.764028) (xy 172.901058 -220.775888)
			(xy 172.950672 -220.79536) (xy 172.99683 -220.822009) (xy 173.038501 -220.85524) (xy 173.074753 -220.894311)
			(xy 173.104777 -220.938348) (xy 173.127903 -220.986369) (xy 173.143613 -221.037299) (xy 173.151556 -221.090003)
			(xy 173.152054 -221.116652) (xy 173.151556 -221.143301) (xy 187.527936 -221.143301) (xy 187.527936 -221.090003)
			(xy 187.535879 -221.037299) (xy 187.551589 -220.986369) (xy 187.574715 -220.938348) (xy 187.604739 -220.894311)
			(xy 187.640991 -220.85524) (xy 187.682662 -220.822009) (xy 187.72882 -220.79536) (xy 187.778434 -220.775888)
			(xy 187.830396 -220.764028) (xy 187.883546 -220.760045) (xy 187.936696 -220.764028) (xy 187.988658 -220.775888)
			(xy 188.038272 -220.79536) (xy 188.08443 -220.822009) (xy 188.126101 -220.85524) (xy 188.162353 -220.894311)
			(xy 188.192377 -220.938348) (xy 188.215503 -220.986369) (xy 188.231213 -221.037299) (xy 188.239156 -221.090003)
			(xy 188.239654 -221.116652) (xy 188.239156 -221.143301) (xy 202.615536 -221.143301) (xy 202.615536 -221.090003)
			(xy 202.623479 -221.037299) (xy 202.639189 -220.986369) (xy 202.662315 -220.938348) (xy 202.692339 -220.894311)
			(xy 202.728591 -220.85524) (xy 202.770262 -220.822009) (xy 202.81642 -220.79536) (xy 202.866034 -220.775888)
			(xy 202.917996 -220.764028) (xy 202.971146 -220.760045) (xy 203.024296 -220.764028) (xy 203.076258 -220.775888)
			(xy 203.125872 -220.79536) (xy 203.17203 -220.822009) (xy 203.213701 -220.85524) (xy 203.249953 -220.894311)
			(xy 203.279977 -220.938348) (xy 203.303103 -220.986369) (xy 203.318813 -221.037299) (xy 203.326756 -221.090003)
			(xy 203.327254 -221.116652) (xy 203.326756 -221.143301) (xy 203.318813 -221.196005) (xy 203.303103 -221.246935)
			(xy 203.279977 -221.294956) (xy 203.249953 -221.338993) (xy 203.213701 -221.378064) (xy 203.17203 -221.411295)
			(xy 203.125872 -221.437944) (xy 203.076258 -221.457416) (xy 203.024296 -221.469276) (xy 202.971146 -221.47326)
			(xy 202.917996 -221.469276) (xy 202.866034 -221.457416) (xy 202.81642 -221.437944) (xy 202.770262 -221.411295)
			(xy 202.728591 -221.378064) (xy 202.692339 -221.338993) (xy 202.662315 -221.294956) (xy 202.639189 -221.246935)
			(xy 202.623479 -221.196005) (xy 202.615536 -221.143301) (xy 188.239156 -221.143301) (xy 188.231213 -221.196005)
			(xy 188.215503 -221.246935) (xy 188.192377 -221.294956) (xy 188.162353 -221.338993) (xy 188.126101 -221.378064)
			(xy 188.08443 -221.411295) (xy 188.038272 -221.437944) (xy 187.988658 -221.457416) (xy 187.936696 -221.469276)
			(xy 187.883546 -221.47326) (xy 187.830396 -221.469276) (xy 187.778434 -221.457416) (xy 187.72882 -221.437944)
			(xy 187.682662 -221.411295) (xy 187.640991 -221.378064) (xy 187.604739 -221.338993) (xy 187.574715 -221.294956)
			(xy 187.551589 -221.246935) (xy 187.535879 -221.196005) (xy 187.527936 -221.143301) (xy 173.151556 -221.143301)
			(xy 173.143613 -221.196005) (xy 173.127903 -221.246935) (xy 173.104777 -221.294956) (xy 173.074753 -221.338993)
			(xy 173.038501 -221.378064) (xy 172.99683 -221.411295) (xy 172.950672 -221.437944) (xy 172.901058 -221.457416)
			(xy 172.849096 -221.469276) (xy 172.795946 -221.47326) (xy 172.742796 -221.469276) (xy 172.690834 -221.457416)
			(xy 172.64122 -221.437944) (xy 172.595062 -221.411295) (xy 172.553391 -221.378064) (xy 172.517139 -221.338993)
			(xy 172.487115 -221.294956) (xy 172.463989 -221.246935) (xy 172.448279 -221.196005) (xy 172.440336 -221.143301)
			(xy 158.88716 -221.143301) (xy 158.88716 -221.993439) (xy 176.540404 -221.993439) (xy 176.540404 -221.940141)
			(xy 176.548347 -221.887437) (xy 176.564057 -221.836507) (xy 176.587183 -221.788486) (xy 176.617207 -221.744449)
			(xy 176.653459 -221.705378) (xy 176.69513 -221.672147) (xy 176.741288 -221.645498) (xy 176.790902 -221.626026)
			(xy 176.842864 -221.614166) (xy 176.896014 -221.610183) (xy 176.949164 -221.614166) (xy 177.001126 -221.626026)
			(xy 177.05074 -221.645498) (xy 177.096898 -221.672147) (xy 177.138569 -221.705378) (xy 177.174821 -221.744449)
			(xy 177.204845 -221.788486) (xy 177.227971 -221.836507) (xy 177.243681 -221.887437) (xy 177.251624 -221.940141)
			(xy 177.252122 -221.96679) (xy 177.251624 -221.993439) (xy 191.628004 -221.993439) (xy 191.628004 -221.940141)
			(xy 191.635947 -221.887437) (xy 191.651657 -221.836507) (xy 191.674783 -221.788486) (xy 191.704807 -221.744449)
			(xy 191.741059 -221.705378) (xy 191.78273 -221.672147) (xy 191.828888 -221.645498) (xy 191.878502 -221.626026)
			(xy 191.930464 -221.614166) (xy 191.983614 -221.610183) (xy 192.036764 -221.614166) (xy 192.088726 -221.626026)
			(xy 192.13834 -221.645498) (xy 192.184498 -221.672147) (xy 192.226169 -221.705378) (xy 192.262421 -221.744449)
			(xy 192.292445 -221.788486) (xy 192.315571 -221.836507) (xy 192.331281 -221.887437) (xy 192.339224 -221.940141)
			(xy 192.339722 -221.96679) (xy 192.339224 -221.993439) (xy 206.715604 -221.993439) (xy 206.715604 -221.940141)
			(xy 206.723547 -221.887437) (xy 206.739257 -221.836507) (xy 206.762383 -221.788486) (xy 206.792407 -221.744449)
			(xy 206.828659 -221.705378) (xy 206.87033 -221.672147) (xy 206.916488 -221.645498) (xy 206.966102 -221.626026)
			(xy 207.018064 -221.614166) (xy 207.071214 -221.610183) (xy 207.124364 -221.614166) (xy 207.176326 -221.626026)
			(xy 207.22594 -221.645498) (xy 207.272098 -221.672147) (xy 207.313769 -221.705378) (xy 207.350021 -221.744449)
			(xy 207.380045 -221.788486) (xy 207.403171 -221.836507) (xy 207.418881 -221.887437) (xy 207.426824 -221.940141)
			(xy 207.427322 -221.96679) (xy 207.426824 -221.993439) (xy 207.418881 -222.046143) (xy 207.403171 -222.097073)
			(xy 207.380045 -222.145094) (xy 207.350021 -222.189131) (xy 207.313769 -222.228202) (xy 207.272098 -222.261433)
			(xy 207.22594 -222.288082) (xy 207.176326 -222.307554) (xy 207.124364 -222.319414) (xy 207.071214 -222.323398)
			(xy 207.018064 -222.319414) (xy 206.966102 -222.307554) (xy 206.916488 -222.288082) (xy 206.87033 -222.261433)
			(xy 206.828659 -222.228202) (xy 206.792407 -222.189131) (xy 206.762383 -222.145094) (xy 206.739257 -222.097073)
			(xy 206.723547 -222.046143) (xy 206.715604 -221.993439) (xy 192.339224 -221.993439) (xy 192.331281 -222.046143)
			(xy 192.315571 -222.097073) (xy 192.292445 -222.145094) (xy 192.262421 -222.189131) (xy 192.226169 -222.228202)
			(xy 192.184498 -222.261433) (xy 192.13834 -222.288082) (xy 192.088726 -222.307554) (xy 192.036764 -222.319414)
			(xy 191.983614 -222.323398) (xy 191.930464 -222.319414) (xy 191.878502 -222.307554) (xy 191.828888 -222.288082)
			(xy 191.78273 -222.261433) (xy 191.741059 -222.228202) (xy 191.704807 -222.189131) (xy 191.674783 -222.145094)
			(xy 191.651657 -222.097073) (xy 191.635947 -222.046143) (xy 191.628004 -221.993439) (xy 177.251624 -221.993439)
			(xy 177.243681 -222.046143) (xy 177.227971 -222.097073) (xy 177.204845 -222.145094) (xy 177.174821 -222.189131)
			(xy 177.138569 -222.228202) (xy 177.096898 -222.261433) (xy 177.05074 -222.288082) (xy 177.001126 -222.307554)
			(xy 176.949164 -222.319414) (xy 176.896014 -222.323398) (xy 176.842864 -222.319414) (xy 176.790902 -222.307554)
			(xy 176.741288 -222.288082) (xy 176.69513 -222.261433) (xy 176.653459 -222.228202) (xy 176.617207 -222.189131)
			(xy 176.587183 -222.145094) (xy 176.564057 -222.097073) (xy 176.548347 -222.046143) (xy 176.540404 -221.993439)
			(xy 158.88716 -221.993439) (xy 158.88716 -222.843323) (xy 172.440336 -222.843323) (xy 172.440336 -222.790025)
			(xy 172.448279 -222.737321) (xy 172.463989 -222.686391) (xy 172.487115 -222.63837) (xy 172.517139 -222.594333)
			(xy 172.553391 -222.555262) (xy 172.595062 -222.522031) (xy 172.64122 -222.495382) (xy 172.690834 -222.47591)
			(xy 172.742796 -222.46405) (xy 172.795946 -222.460067) (xy 172.849096 -222.46405) (xy 172.901058 -222.47591)
			(xy 172.950672 -222.495382) (xy 172.99683 -222.522031) (xy 173.038501 -222.555262) (xy 173.074753 -222.594333)
			(xy 173.104777 -222.63837) (xy 173.127903 -222.686391) (xy 173.143613 -222.737321) (xy 173.151556 -222.790025)
			(xy 173.152054 -222.816674) (xy 173.151556 -222.843323) (xy 187.527936 -222.843323) (xy 187.527936 -222.790025)
			(xy 187.535879 -222.737321) (xy 187.551589 -222.686391) (xy 187.574715 -222.63837) (xy 187.604739 -222.594333)
			(xy 187.640991 -222.555262) (xy 187.682662 -222.522031) (xy 187.72882 -222.495382) (xy 187.778434 -222.47591)
			(xy 187.830396 -222.46405) (xy 187.883546 -222.460067) (xy 187.936696 -222.46405) (xy 187.988658 -222.47591)
			(xy 188.038272 -222.495382) (xy 188.08443 -222.522031) (xy 188.126101 -222.555262) (xy 188.162353 -222.594333)
			(xy 188.192377 -222.63837) (xy 188.215503 -222.686391) (xy 188.231213 -222.737321) (xy 188.239156 -222.790025)
			(xy 188.239654 -222.816674) (xy 188.239156 -222.843323) (xy 202.615536 -222.843323) (xy 202.615536 -222.790025)
			(xy 202.623479 -222.737321) (xy 202.639189 -222.686391) (xy 202.662315 -222.63837) (xy 202.692339 -222.594333)
			(xy 202.728591 -222.555262) (xy 202.770262 -222.522031) (xy 202.81642 -222.495382) (xy 202.866034 -222.47591)
			(xy 202.917996 -222.46405) (xy 202.971146 -222.460067) (xy 203.024296 -222.46405) (xy 203.076258 -222.47591)
			(xy 203.125872 -222.495382) (xy 203.17203 -222.522031) (xy 203.213701 -222.555262) (xy 203.249953 -222.594333)
			(xy 203.279977 -222.63837) (xy 203.303103 -222.686391) (xy 203.318813 -222.737321) (xy 203.326756 -222.790025)
			(xy 203.327254 -222.816674) (xy 203.326756 -222.843323) (xy 203.318813 -222.896027) (xy 203.303103 -222.946957)
			(xy 203.279977 -222.994978) (xy 203.249953 -223.039015) (xy 203.213701 -223.078086) (xy 203.17203 -223.111317)
			(xy 203.125872 -223.137966) (xy 203.076258 -223.157438) (xy 203.024296 -223.169298) (xy 202.971146 -223.173282)
			(xy 202.917996 -223.169298) (xy 202.866034 -223.157438) (xy 202.81642 -223.137966) (xy 202.770262 -223.111317)
			(xy 202.728591 -223.078086) (xy 202.692339 -223.039015) (xy 202.662315 -222.994978) (xy 202.639189 -222.946957)
			(xy 202.623479 -222.896027) (xy 202.615536 -222.843323) (xy 188.239156 -222.843323) (xy 188.231213 -222.896027)
			(xy 188.215503 -222.946957) (xy 188.192377 -222.994978) (xy 188.162353 -223.039015) (xy 188.126101 -223.078086)
			(xy 188.08443 -223.111317) (xy 188.038272 -223.137966) (xy 187.988658 -223.157438) (xy 187.936696 -223.169298)
			(xy 187.883546 -223.173282) (xy 187.830396 -223.169298) (xy 187.778434 -223.157438) (xy 187.72882 -223.137966)
			(xy 187.682662 -223.111317) (xy 187.640991 -223.078086) (xy 187.604739 -223.039015) (xy 187.574715 -222.994978)
			(xy 187.551589 -222.946957) (xy 187.535879 -222.896027) (xy 187.527936 -222.843323) (xy 173.151556 -222.843323)
			(xy 173.143613 -222.896027) (xy 173.127903 -222.946957) (xy 173.104777 -222.994978) (xy 173.074753 -223.039015)
			(xy 173.038501 -223.078086) (xy 172.99683 -223.111317) (xy 172.950672 -223.137966) (xy 172.901058 -223.157438)
			(xy 172.849096 -223.169298) (xy 172.795946 -223.173282) (xy 172.742796 -223.169298) (xy 172.690834 -223.157438)
			(xy 172.64122 -223.137966) (xy 172.595062 -223.111317) (xy 172.553391 -223.078086) (xy 172.517139 -223.039015)
			(xy 172.487115 -222.994978) (xy 172.463989 -222.946957) (xy 172.448279 -222.896027) (xy 172.440336 -222.843323)
			(xy 158.88716 -222.843323) (xy 158.88716 -223.693207) (xy 161.427404 -223.693207) (xy 161.427404 -223.639909)
			(xy 161.435347 -223.587205) (xy 161.451057 -223.536275) (xy 161.474183 -223.488254) (xy 161.504207 -223.444217)
			(xy 161.540459 -223.405146) (xy 161.58213 -223.371915) (xy 161.628288 -223.345266) (xy 161.677902 -223.325794)
			(xy 161.729864 -223.313934) (xy 161.783014 -223.309951) (xy 161.836164 -223.313934) (xy 161.888126 -223.325794)
			(xy 161.93774 -223.345266) (xy 161.983898 -223.371915) (xy 162.025569 -223.405146) (xy 162.061821 -223.444217)
			(xy 162.091845 -223.488254) (xy 162.114971 -223.536275) (xy 162.130681 -223.587205) (xy 162.138624 -223.639909)
			(xy 162.139122 -223.666558) (xy 162.138624 -223.693207) (xy 176.540404 -223.693207) (xy 176.540404 -223.639909)
			(xy 176.548347 -223.587205) (xy 176.564057 -223.536275) (xy 176.587183 -223.488254) (xy 176.617207 -223.444217)
			(xy 176.653459 -223.405146) (xy 176.69513 -223.371915) (xy 176.741288 -223.345266) (xy 176.790902 -223.325794)
			(xy 176.842864 -223.313934) (xy 176.896014 -223.309951) (xy 176.949164 -223.313934) (xy 177.001126 -223.325794)
			(xy 177.05074 -223.345266) (xy 177.096898 -223.371915) (xy 177.138569 -223.405146) (xy 177.174821 -223.444217)
			(xy 177.204845 -223.488254) (xy 177.227971 -223.536275) (xy 177.243681 -223.587205) (xy 177.251624 -223.639909)
			(xy 177.252122 -223.666558) (xy 177.251624 -223.693207) (xy 191.628004 -223.693207) (xy 191.628004 -223.639909)
			(xy 191.635947 -223.587205) (xy 191.651657 -223.536275) (xy 191.674783 -223.488254) (xy 191.704807 -223.444217)
			(xy 191.741059 -223.405146) (xy 191.78273 -223.371915) (xy 191.828888 -223.345266) (xy 191.878502 -223.325794)
			(xy 191.930464 -223.313934) (xy 191.983614 -223.309951) (xy 192.036764 -223.313934) (xy 192.088726 -223.325794)
			(xy 192.13834 -223.345266) (xy 192.184498 -223.371915) (xy 192.226169 -223.405146) (xy 192.262421 -223.444217)
			(xy 192.292445 -223.488254) (xy 192.315571 -223.536275) (xy 192.331281 -223.587205) (xy 192.339224 -223.639909)
			(xy 192.339722 -223.666558) (xy 192.339224 -223.693207) (xy 206.715604 -223.693207) (xy 206.715604 -223.639909)
			(xy 206.723547 -223.587205) (xy 206.739257 -223.536275) (xy 206.762383 -223.488254) (xy 206.792407 -223.444217)
			(xy 206.828659 -223.405146) (xy 206.87033 -223.371915) (xy 206.916488 -223.345266) (xy 206.966102 -223.325794)
			(xy 207.018064 -223.313934) (xy 207.071214 -223.309951) (xy 207.124364 -223.313934) (xy 207.176326 -223.325794)
			(xy 207.22594 -223.345266) (xy 207.272098 -223.371915) (xy 207.313769 -223.405146) (xy 207.350021 -223.444217)
			(xy 207.380045 -223.488254) (xy 207.403171 -223.536275) (xy 207.418881 -223.587205) (xy 207.426824 -223.639909)
			(xy 207.427322 -223.666558) (xy 207.426824 -223.693207) (xy 207.418881 -223.745911) (xy 207.403171 -223.796841)
			(xy 207.380045 -223.844862) (xy 207.350021 -223.888899) (xy 207.313769 -223.92797) (xy 207.272098 -223.961201)
			(xy 207.22594 -223.98785) (xy 207.176326 -224.007322) (xy 207.124364 -224.019182) (xy 207.071214 -224.023166)
			(xy 207.018064 -224.019182) (xy 206.966102 -224.007322) (xy 206.916488 -223.98785) (xy 206.87033 -223.961201)
			(xy 206.828659 -223.92797) (xy 206.792407 -223.888899) (xy 206.762383 -223.844862) (xy 206.739257 -223.796841)
			(xy 206.723547 -223.745911) (xy 206.715604 -223.693207) (xy 192.339224 -223.693207) (xy 192.331281 -223.745911)
			(xy 192.315571 -223.796841) (xy 192.292445 -223.844862) (xy 192.262421 -223.888899) (xy 192.226169 -223.92797)
			(xy 192.184498 -223.961201) (xy 192.13834 -223.98785) (xy 192.088726 -224.007322) (xy 192.036764 -224.019182)
			(xy 191.983614 -224.023166) (xy 191.930464 -224.019182) (xy 191.878502 -224.007322) (xy 191.828888 -223.98785)
			(xy 191.78273 -223.961201) (xy 191.741059 -223.92797) (xy 191.704807 -223.888899) (xy 191.674783 -223.844862)
			(xy 191.651657 -223.796841) (xy 191.635947 -223.745911) (xy 191.628004 -223.693207) (xy 177.251624 -223.693207)
			(xy 177.243681 -223.745911) (xy 177.227971 -223.796841) (xy 177.204845 -223.844862) (xy 177.174821 -223.888899)
			(xy 177.138569 -223.92797) (xy 177.096898 -223.961201) (xy 177.05074 -223.98785) (xy 177.001126 -224.007322)
			(xy 176.949164 -224.019182) (xy 176.896014 -224.023166) (xy 176.842864 -224.019182) (xy 176.790902 -224.007322)
			(xy 176.741288 -223.98785) (xy 176.69513 -223.961201) (xy 176.653459 -223.92797) (xy 176.617207 -223.888899)
			(xy 176.587183 -223.844862) (xy 176.564057 -223.796841) (xy 176.548347 -223.745911) (xy 176.540404 -223.693207)
			(xy 162.138624 -223.693207) (xy 162.130681 -223.745911) (xy 162.114971 -223.796841) (xy 162.091845 -223.844862)
			(xy 162.061821 -223.888899) (xy 162.025569 -223.92797) (xy 161.983898 -223.961201) (xy 161.93774 -223.98785)
			(xy 161.888126 -224.007322) (xy 161.836164 -224.019182) (xy 161.783014 -224.023166) (xy 161.729864 -224.019182)
			(xy 161.677902 -224.007322) (xy 161.628288 -223.98785) (xy 161.58213 -223.961201) (xy 161.540459 -223.92797)
			(xy 161.504207 -223.888899) (xy 161.474183 -223.844862) (xy 161.451057 -223.796841) (xy 161.435347 -223.745911)
			(xy 161.427404 -223.693207) (xy 158.88716 -223.693207) (xy 158.88716 -224.543345) (xy 172.440336 -224.543345)
			(xy 172.440336 -224.490047) (xy 172.448279 -224.437343) (xy 172.463989 -224.386413) (xy 172.487115 -224.338392)
			(xy 172.517139 -224.294355) (xy 172.553391 -224.255284) (xy 172.595062 -224.222053) (xy 172.64122 -224.195404)
			(xy 172.690834 -224.175932) (xy 172.742796 -224.164072) (xy 172.795946 -224.160089) (xy 172.849096 -224.164072)
			(xy 172.901058 -224.175932) (xy 172.950672 -224.195404) (xy 172.99683 -224.222053) (xy 173.038501 -224.255284)
			(xy 173.074753 -224.294355) (xy 173.104777 -224.338392) (xy 173.127903 -224.386413) (xy 173.143613 -224.437343)
			(xy 173.151556 -224.490047) (xy 173.152054 -224.516696) (xy 173.151556 -224.543345) (xy 187.527936 -224.543345)
			(xy 187.527936 -224.490047) (xy 187.535879 -224.437343) (xy 187.551589 -224.386413) (xy 187.574715 -224.338392)
			(xy 187.604739 -224.294355) (xy 187.640991 -224.255284) (xy 187.682662 -224.222053) (xy 187.72882 -224.195404)
			(xy 187.778434 -224.175932) (xy 187.830396 -224.164072) (xy 187.883546 -224.160089) (xy 187.936696 -224.164072)
			(xy 187.988658 -224.175932) (xy 188.038272 -224.195404) (xy 188.08443 -224.222053) (xy 188.126101 -224.255284)
			(xy 188.162353 -224.294355) (xy 188.192377 -224.338392) (xy 188.215503 -224.386413) (xy 188.231213 -224.437343)
			(xy 188.239156 -224.490047) (xy 188.239654 -224.516696) (xy 188.239156 -224.543345) (xy 202.615536 -224.543345)
			(xy 202.615536 -224.490047) (xy 202.623479 -224.437343) (xy 202.639189 -224.386413) (xy 202.662315 -224.338392)
			(xy 202.692339 -224.294355) (xy 202.728591 -224.255284) (xy 202.770262 -224.222053) (xy 202.81642 -224.195404)
			(xy 202.866034 -224.175932) (xy 202.917996 -224.164072) (xy 202.971146 -224.160089) (xy 203.024296 -224.164072)
			(xy 203.076258 -224.175932) (xy 203.125872 -224.195404) (xy 203.17203 -224.222053) (xy 203.213701 -224.255284)
			(xy 203.249953 -224.294355) (xy 203.279977 -224.338392) (xy 203.303103 -224.386413) (xy 203.318813 -224.437343)
			(xy 203.326756 -224.490047) (xy 203.327254 -224.516696) (xy 203.326756 -224.543345) (xy 203.318813 -224.596049)
			(xy 203.303103 -224.646979) (xy 203.279977 -224.695) (xy 203.249953 -224.739037) (xy 203.213701 -224.778108)
			(xy 203.17203 -224.811339) (xy 203.125872 -224.837988) (xy 203.076258 -224.85746) (xy 203.024296 -224.86932)
			(xy 202.971146 -224.873304) (xy 202.917996 -224.86932) (xy 202.866034 -224.85746) (xy 202.81642 -224.837988)
			(xy 202.770262 -224.811339) (xy 202.728591 -224.778108) (xy 202.692339 -224.739037) (xy 202.662315 -224.695)
			(xy 202.639189 -224.646979) (xy 202.623479 -224.596049) (xy 202.615536 -224.543345) (xy 188.239156 -224.543345)
			(xy 188.231213 -224.596049) (xy 188.215503 -224.646979) (xy 188.192377 -224.695) (xy 188.162353 -224.739037)
			(xy 188.126101 -224.778108) (xy 188.08443 -224.811339) (xy 188.038272 -224.837988) (xy 187.988658 -224.85746)
			(xy 187.936696 -224.86932) (xy 187.883546 -224.873304) (xy 187.830396 -224.86932) (xy 187.778434 -224.85746)
			(xy 187.72882 -224.837988) (xy 187.682662 -224.811339) (xy 187.640991 -224.778108) (xy 187.604739 -224.739037)
			(xy 187.574715 -224.695) (xy 187.551589 -224.646979) (xy 187.535879 -224.596049) (xy 187.527936 -224.543345)
			(xy 173.151556 -224.543345) (xy 173.143613 -224.596049) (xy 173.127903 -224.646979) (xy 173.104777 -224.695)
			(xy 173.074753 -224.739037) (xy 173.038501 -224.778108) (xy 172.99683 -224.811339) (xy 172.950672 -224.837988)
			(xy 172.901058 -224.85746) (xy 172.849096 -224.86932) (xy 172.795946 -224.873304) (xy 172.742796 -224.86932)
			(xy 172.690834 -224.85746) (xy 172.64122 -224.837988) (xy 172.595062 -224.811339) (xy 172.553391 -224.778108)
			(xy 172.517139 -224.739037) (xy 172.487115 -224.695) (xy 172.463989 -224.646979) (xy 172.448279 -224.596049)
			(xy 172.440336 -224.543345) (xy 158.88716 -224.543345) (xy 158.88716 -225.393229) (xy 161.427404 -225.393229)
			(xy 161.427404 -225.339931) (xy 161.435347 -225.287227) (xy 161.451057 -225.236297) (xy 161.474183 -225.188276)
			(xy 161.504207 -225.144239) (xy 161.540459 -225.105168) (xy 161.58213 -225.071937) (xy 161.628288 -225.045288)
			(xy 161.677902 -225.025816) (xy 161.729864 -225.013956) (xy 161.783014 -225.009973) (xy 161.836164 -225.013956)
			(xy 161.888126 -225.025816) (xy 161.93774 -225.045288) (xy 161.983898 -225.071937) (xy 162.025569 -225.105168)
			(xy 162.061821 -225.144239) (xy 162.091845 -225.188276) (xy 162.114971 -225.236297) (xy 162.130681 -225.287227)
			(xy 162.138624 -225.339931) (xy 162.139122 -225.36658) (xy 162.138624 -225.393229) (xy 176.540404 -225.393229)
			(xy 176.540404 -225.339931) (xy 176.548347 -225.287227) (xy 176.564057 -225.236297) (xy 176.587183 -225.188276)
			(xy 176.617207 -225.144239) (xy 176.653459 -225.105168) (xy 176.69513 -225.071937) (xy 176.741288 -225.045288)
			(xy 176.790902 -225.025816) (xy 176.842864 -225.013956) (xy 176.896014 -225.009973) (xy 176.949164 -225.013956)
			(xy 177.001126 -225.025816) (xy 177.05074 -225.045288) (xy 177.096898 -225.071937) (xy 177.138569 -225.105168)
			(xy 177.174821 -225.144239) (xy 177.204845 -225.188276) (xy 177.227971 -225.236297) (xy 177.243681 -225.287227)
			(xy 177.251624 -225.339931) (xy 177.252122 -225.36658) (xy 177.251624 -225.393229) (xy 191.628004 -225.393229)
			(xy 191.628004 -225.339931) (xy 191.635947 -225.287227) (xy 191.651657 -225.236297) (xy 191.674783 -225.188276)
			(xy 191.704807 -225.144239) (xy 191.741059 -225.105168) (xy 191.78273 -225.071937) (xy 191.828888 -225.045288)
			(xy 191.878502 -225.025816) (xy 191.930464 -225.013956) (xy 191.983614 -225.009973) (xy 192.036764 -225.013956)
			(xy 192.088726 -225.025816) (xy 192.13834 -225.045288) (xy 192.184498 -225.071937) (xy 192.226169 -225.105168)
			(xy 192.262421 -225.144239) (xy 192.292445 -225.188276) (xy 192.315571 -225.236297) (xy 192.331281 -225.287227)
			(xy 192.339224 -225.339931) (xy 192.339722 -225.36658) (xy 192.339224 -225.393229) (xy 206.715604 -225.393229)
			(xy 206.715604 -225.339931) (xy 206.723547 -225.287227) (xy 206.739257 -225.236297) (xy 206.762383 -225.188276)
			(xy 206.792407 -225.144239) (xy 206.828659 -225.105168) (xy 206.87033 -225.071937) (xy 206.916488 -225.045288)
			(xy 206.966102 -225.025816) (xy 207.018064 -225.013956) (xy 207.071214 -225.009973) (xy 207.124364 -225.013956)
			(xy 207.176326 -225.025816) (xy 207.22594 -225.045288) (xy 207.272098 -225.071937) (xy 207.313769 -225.105168)
			(xy 207.350021 -225.144239) (xy 207.380045 -225.188276) (xy 207.403171 -225.236297) (xy 207.418881 -225.287227)
			(xy 207.426824 -225.339931) (xy 207.427322 -225.36658) (xy 207.426824 -225.393229) (xy 207.418881 -225.445933)
			(xy 207.403171 -225.496863) (xy 207.380045 -225.544884) (xy 207.350021 -225.588921) (xy 207.313769 -225.627992)
			(xy 207.272098 -225.661223) (xy 207.22594 -225.687872) (xy 207.176326 -225.707344) (xy 207.124364 -225.719204)
			(xy 207.071214 -225.723188) (xy 207.018064 -225.719204) (xy 206.966102 -225.707344) (xy 206.916488 -225.687872)
			(xy 206.87033 -225.661223) (xy 206.828659 -225.627992) (xy 206.792407 -225.588921) (xy 206.762383 -225.544884)
			(xy 206.739257 -225.496863) (xy 206.723547 -225.445933) (xy 206.715604 -225.393229) (xy 192.339224 -225.393229)
			(xy 192.331281 -225.445933) (xy 192.315571 -225.496863) (xy 192.292445 -225.544884) (xy 192.262421 -225.588921)
			(xy 192.226169 -225.627992) (xy 192.184498 -225.661223) (xy 192.13834 -225.687872) (xy 192.088726 -225.707344)
			(xy 192.036764 -225.719204) (xy 191.983614 -225.723188) (xy 191.930464 -225.719204) (xy 191.878502 -225.707344)
			(xy 191.828888 -225.687872) (xy 191.78273 -225.661223) (xy 191.741059 -225.627992) (xy 191.704807 -225.588921)
			(xy 191.674783 -225.544884) (xy 191.651657 -225.496863) (xy 191.635947 -225.445933) (xy 191.628004 -225.393229)
			(xy 177.251624 -225.393229) (xy 177.243681 -225.445933) (xy 177.227971 -225.496863) (xy 177.204845 -225.544884)
			(xy 177.174821 -225.588921) (xy 177.138569 -225.627992) (xy 177.096898 -225.661223) (xy 177.05074 -225.687872)
			(xy 177.001126 -225.707344) (xy 176.949164 -225.719204) (xy 176.896014 -225.723188) (xy 176.842864 -225.719204)
			(xy 176.790902 -225.707344) (xy 176.741288 -225.687872) (xy 176.69513 -225.661223) (xy 176.653459 -225.627992)
			(xy 176.617207 -225.588921) (xy 176.587183 -225.544884) (xy 176.564057 -225.496863) (xy 176.548347 -225.445933)
			(xy 176.540404 -225.393229) (xy 162.138624 -225.393229) (xy 162.130681 -225.445933) (xy 162.114971 -225.496863)
			(xy 162.091845 -225.544884) (xy 162.061821 -225.588921) (xy 162.025569 -225.627992) (xy 161.983898 -225.661223)
			(xy 161.93774 -225.687872) (xy 161.888126 -225.707344) (xy 161.836164 -225.719204) (xy 161.783014 -225.723188)
			(xy 161.729864 -225.719204) (xy 161.677902 -225.707344) (xy 161.628288 -225.687872) (xy 161.58213 -225.661223)
			(xy 161.540459 -225.627992) (xy 161.504207 -225.588921) (xy 161.474183 -225.544884) (xy 161.451057 -225.496863)
			(xy 161.435347 -225.445933) (xy 161.427404 -225.393229) (xy 158.88716 -225.393229) (xy 158.88716 -226.243367)
			(xy 172.440336 -226.243367) (xy 172.440336 -226.190069) (xy 172.448279 -226.137365) (xy 172.463989 -226.086435)
			(xy 172.487115 -226.038414) (xy 172.517139 -225.994377) (xy 172.553391 -225.955306) (xy 172.595062 -225.922075)
			(xy 172.64122 -225.895426) (xy 172.690834 -225.875954) (xy 172.742796 -225.864094) (xy 172.795946 -225.860111)
			(xy 172.849096 -225.864094) (xy 172.901058 -225.875954) (xy 172.950672 -225.895426) (xy 172.99683 -225.922075)
			(xy 173.038501 -225.955306) (xy 173.074753 -225.994377) (xy 173.104777 -226.038414) (xy 173.127903 -226.086435)
			(xy 173.143613 -226.137365) (xy 173.151556 -226.190069) (xy 173.152054 -226.216718) (xy 173.151556 -226.243367)
			(xy 187.527936 -226.243367) (xy 187.527936 -226.190069) (xy 187.535879 -226.137365) (xy 187.551589 -226.086435)
			(xy 187.574715 -226.038414) (xy 187.604739 -225.994377) (xy 187.640991 -225.955306) (xy 187.682662 -225.922075)
			(xy 187.72882 -225.895426) (xy 187.778434 -225.875954) (xy 187.830396 -225.864094) (xy 187.883546 -225.860111)
			(xy 187.936696 -225.864094) (xy 187.988658 -225.875954) (xy 188.038272 -225.895426) (xy 188.08443 -225.922075)
			(xy 188.126101 -225.955306) (xy 188.162353 -225.994377) (xy 188.192377 -226.038414) (xy 188.215503 -226.086435)
			(xy 188.231213 -226.137365) (xy 188.239156 -226.190069) (xy 188.239654 -226.216718) (xy 188.239156 -226.243367)
			(xy 202.615536 -226.243367) (xy 202.615536 -226.190069) (xy 202.623479 -226.137365) (xy 202.639189 -226.086435)
			(xy 202.662315 -226.038414) (xy 202.692339 -225.994377) (xy 202.728591 -225.955306) (xy 202.770262 -225.922075)
			(xy 202.81642 -225.895426) (xy 202.866034 -225.875954) (xy 202.917996 -225.864094) (xy 202.971146 -225.860111)
			(xy 203.024296 -225.864094) (xy 203.076258 -225.875954) (xy 203.125872 -225.895426) (xy 203.17203 -225.922075)
			(xy 203.213701 -225.955306) (xy 203.249953 -225.994377) (xy 203.279977 -226.038414) (xy 203.303103 -226.086435)
			(xy 203.318813 -226.137365) (xy 203.326756 -226.190069) (xy 203.327254 -226.216718) (xy 203.326756 -226.243367)
			(xy 203.318813 -226.296071) (xy 203.303103 -226.347001) (xy 203.279977 -226.395022) (xy 203.249953 -226.439059)
			(xy 203.213701 -226.47813) (xy 203.17203 -226.511361) (xy 203.125872 -226.53801) (xy 203.076258 -226.557482)
			(xy 203.024296 -226.569342) (xy 202.971146 -226.573326) (xy 202.917996 -226.569342) (xy 202.866034 -226.557482)
			(xy 202.81642 -226.53801) (xy 202.770262 -226.511361) (xy 202.728591 -226.47813) (xy 202.692339 -226.439059)
			(xy 202.662315 -226.395022) (xy 202.639189 -226.347001) (xy 202.623479 -226.296071) (xy 202.615536 -226.243367)
			(xy 188.239156 -226.243367) (xy 188.231213 -226.296071) (xy 188.215503 -226.347001) (xy 188.192377 -226.395022)
			(xy 188.162353 -226.439059) (xy 188.126101 -226.47813) (xy 188.08443 -226.511361) (xy 188.038272 -226.53801)
			(xy 187.988658 -226.557482) (xy 187.936696 -226.569342) (xy 187.883546 -226.573326) (xy 187.830396 -226.569342)
			(xy 187.778434 -226.557482) (xy 187.72882 -226.53801) (xy 187.682662 -226.511361) (xy 187.640991 -226.47813)
			(xy 187.604739 -226.439059) (xy 187.574715 -226.395022) (xy 187.551589 -226.347001) (xy 187.535879 -226.296071)
			(xy 187.527936 -226.243367) (xy 173.151556 -226.243367) (xy 173.143613 -226.296071) (xy 173.127903 -226.347001)
			(xy 173.104777 -226.395022) (xy 173.074753 -226.439059) (xy 173.038501 -226.47813) (xy 172.99683 -226.511361)
			(xy 172.950672 -226.53801) (xy 172.901058 -226.557482) (xy 172.849096 -226.569342) (xy 172.795946 -226.573326)
			(xy 172.742796 -226.569342) (xy 172.690834 -226.557482) (xy 172.64122 -226.53801) (xy 172.595062 -226.511361)
			(xy 172.553391 -226.47813) (xy 172.517139 -226.439059) (xy 172.487115 -226.395022) (xy 172.463989 -226.347001)
			(xy 172.448279 -226.296071) (xy 172.440336 -226.243367) (xy 158.88716 -226.243367) (xy 158.88716 -227.093251)
			(xy 161.427404 -227.093251) (xy 161.427404 -227.039953) (xy 161.435347 -226.987249) (xy 161.451057 -226.936319)
			(xy 161.474183 -226.888298) (xy 161.504207 -226.844261) (xy 161.540459 -226.80519) (xy 161.58213 -226.771959)
			(xy 161.628288 -226.74531) (xy 161.677902 -226.725838) (xy 161.729864 -226.713978) (xy 161.783014 -226.709995)
			(xy 161.836164 -226.713978) (xy 161.888126 -226.725838) (xy 161.93774 -226.74531) (xy 161.983898 -226.771959)
			(xy 162.025569 -226.80519) (xy 162.061821 -226.844261) (xy 162.091845 -226.888298) (xy 162.114971 -226.936319)
			(xy 162.130681 -226.987249) (xy 162.138624 -227.039953) (xy 162.139122 -227.066602) (xy 162.138624 -227.093251)
			(xy 176.540404 -227.093251) (xy 176.540404 -227.039953) (xy 176.548347 -226.987249) (xy 176.564057 -226.936319)
			(xy 176.587183 -226.888298) (xy 176.617207 -226.844261) (xy 176.653459 -226.80519) (xy 176.69513 -226.771959)
			(xy 176.741288 -226.74531) (xy 176.790902 -226.725838) (xy 176.842864 -226.713978) (xy 176.896014 -226.709995)
			(xy 176.949164 -226.713978) (xy 177.001126 -226.725838) (xy 177.05074 -226.74531) (xy 177.096898 -226.771959)
			(xy 177.138569 -226.80519) (xy 177.174821 -226.844261) (xy 177.204845 -226.888298) (xy 177.227971 -226.936319)
			(xy 177.243681 -226.987249) (xy 177.251624 -227.039953) (xy 177.252122 -227.066602) (xy 177.251624 -227.093251)
			(xy 191.628004 -227.093251) (xy 191.628004 -227.039953) (xy 191.635947 -226.987249) (xy 191.651657 -226.936319)
			(xy 191.674783 -226.888298) (xy 191.704807 -226.844261) (xy 191.741059 -226.80519) (xy 191.78273 -226.771959)
			(xy 191.828888 -226.74531) (xy 191.878502 -226.725838) (xy 191.930464 -226.713978) (xy 191.983614 -226.709995)
			(xy 192.036764 -226.713978) (xy 192.088726 -226.725838) (xy 192.13834 -226.74531) (xy 192.184498 -226.771959)
			(xy 192.226169 -226.80519) (xy 192.262421 -226.844261) (xy 192.292445 -226.888298) (xy 192.315571 -226.936319)
			(xy 192.331281 -226.987249) (xy 192.339224 -227.039953) (xy 192.339722 -227.066602) (xy 192.339224 -227.093251)
			(xy 206.715604 -227.093251) (xy 206.715604 -227.039953) (xy 206.723547 -226.987249) (xy 206.739257 -226.936319)
			(xy 206.762383 -226.888298) (xy 206.792407 -226.844261) (xy 206.828659 -226.80519) (xy 206.87033 -226.771959)
			(xy 206.916488 -226.74531) (xy 206.966102 -226.725838) (xy 207.018064 -226.713978) (xy 207.071214 -226.709995)
			(xy 207.124364 -226.713978) (xy 207.176326 -226.725838) (xy 207.22594 -226.74531) (xy 207.272098 -226.771959)
			(xy 207.313769 -226.80519) (xy 207.350021 -226.844261) (xy 207.380045 -226.888298) (xy 207.403171 -226.936319)
			(xy 207.418881 -226.987249) (xy 207.426824 -227.039953) (xy 207.427322 -227.066602) (xy 207.426824 -227.093251)
			(xy 207.418881 -227.145955) (xy 207.403171 -227.196885) (xy 207.380045 -227.244906) (xy 207.350021 -227.288943)
			(xy 207.313769 -227.328014) (xy 207.272098 -227.361245) (xy 207.22594 -227.387894) (xy 207.176326 -227.407366)
			(xy 207.124364 -227.419226) (xy 207.071214 -227.42321) (xy 207.018064 -227.419226) (xy 206.966102 -227.407366)
			(xy 206.916488 -227.387894) (xy 206.87033 -227.361245) (xy 206.828659 -227.328014) (xy 206.792407 -227.288943)
			(xy 206.762383 -227.244906) (xy 206.739257 -227.196885) (xy 206.723547 -227.145955) (xy 206.715604 -227.093251)
			(xy 192.339224 -227.093251) (xy 192.331281 -227.145955) (xy 192.315571 -227.196885) (xy 192.292445 -227.244906)
			(xy 192.262421 -227.288943) (xy 192.226169 -227.328014) (xy 192.184498 -227.361245) (xy 192.13834 -227.387894)
			(xy 192.088726 -227.407366) (xy 192.036764 -227.419226) (xy 191.983614 -227.42321) (xy 191.930464 -227.419226)
			(xy 191.878502 -227.407366) (xy 191.828888 -227.387894) (xy 191.78273 -227.361245) (xy 191.741059 -227.328014)
			(xy 191.704807 -227.288943) (xy 191.674783 -227.244906) (xy 191.651657 -227.196885) (xy 191.635947 -227.145955)
			(xy 191.628004 -227.093251) (xy 177.251624 -227.093251) (xy 177.243681 -227.145955) (xy 177.227971 -227.196885)
			(xy 177.204845 -227.244906) (xy 177.174821 -227.288943) (xy 177.138569 -227.328014) (xy 177.096898 -227.361245)
			(xy 177.05074 -227.387894) (xy 177.001126 -227.407366) (xy 176.949164 -227.419226) (xy 176.896014 -227.42321)
			(xy 176.842864 -227.419226) (xy 176.790902 -227.407366) (xy 176.741288 -227.387894) (xy 176.69513 -227.361245)
			(xy 176.653459 -227.328014) (xy 176.617207 -227.288943) (xy 176.587183 -227.244906) (xy 176.564057 -227.196885)
			(xy 176.548347 -227.145955) (xy 176.540404 -227.093251) (xy 162.138624 -227.093251) (xy 162.130681 -227.145955)
			(xy 162.114971 -227.196885) (xy 162.091845 -227.244906) (xy 162.061821 -227.288943) (xy 162.025569 -227.328014)
			(xy 161.983898 -227.361245) (xy 161.93774 -227.387894) (xy 161.888126 -227.407366) (xy 161.836164 -227.419226)
			(xy 161.783014 -227.42321) (xy 161.729864 -227.419226) (xy 161.677902 -227.407366) (xy 161.628288 -227.387894)
			(xy 161.58213 -227.361245) (xy 161.540459 -227.328014) (xy 161.504207 -227.288943) (xy 161.474183 -227.244906)
			(xy 161.451057 -227.196885) (xy 161.435347 -227.145955) (xy 161.427404 -227.093251) (xy 158.88716 -227.093251)
			(xy 158.88716 -227.943389) (xy 161.427404 -227.943389) (xy 161.427404 -227.890091) (xy 161.435347 -227.837387)
			(xy 161.451057 -227.786457) (xy 161.474183 -227.738436) (xy 161.504207 -227.694399) (xy 161.540459 -227.655328)
			(xy 161.58213 -227.622097) (xy 161.628288 -227.595448) (xy 161.677902 -227.575976) (xy 161.729864 -227.564116)
			(xy 161.783014 -227.560133) (xy 161.836164 -227.564116) (xy 161.888126 -227.575976) (xy 161.93774 -227.595448)
			(xy 161.983898 -227.622097) (xy 162.025569 -227.655328) (xy 162.061821 -227.694399) (xy 162.091845 -227.738436)
			(xy 162.114971 -227.786457) (xy 162.130681 -227.837387) (xy 162.138624 -227.890091) (xy 162.139122 -227.91674)
			(xy 162.138624 -227.943389) (xy 172.440336 -227.943389) (xy 172.440336 -227.890091) (xy 172.448279 -227.837387)
			(xy 172.463989 -227.786457) (xy 172.487115 -227.738436) (xy 172.517139 -227.694399) (xy 172.553391 -227.655328)
			(xy 172.595062 -227.622097) (xy 172.64122 -227.595448) (xy 172.690834 -227.575976) (xy 172.742796 -227.564116)
			(xy 172.795946 -227.560133) (xy 172.849096 -227.564116) (xy 172.901058 -227.575976) (xy 172.950672 -227.595448)
			(xy 172.99683 -227.622097) (xy 173.038501 -227.655328) (xy 173.074753 -227.694399) (xy 173.104777 -227.738436)
			(xy 173.127903 -227.786457) (xy 173.143613 -227.837387) (xy 173.151556 -227.890091) (xy 173.152054 -227.91674)
			(xy 173.151556 -227.943389) (xy 176.540404 -227.943389) (xy 176.540404 -227.890091) (xy 176.548347 -227.837387)
			(xy 176.564057 -227.786457) (xy 176.587183 -227.738436) (xy 176.617207 -227.694399) (xy 176.653459 -227.655328)
			(xy 176.69513 -227.622097) (xy 176.741288 -227.595448) (xy 176.790902 -227.575976) (xy 176.842864 -227.564116)
			(xy 176.896014 -227.560133) (xy 176.949164 -227.564116) (xy 177.001126 -227.575976) (xy 177.05074 -227.595448)
			(xy 177.096898 -227.622097) (xy 177.138569 -227.655328) (xy 177.174821 -227.694399) (xy 177.204845 -227.738436)
			(xy 177.227971 -227.786457) (xy 177.243681 -227.837387) (xy 177.251624 -227.890091) (xy 177.252122 -227.91674)
			(xy 177.251624 -227.943389) (xy 187.527936 -227.943389) (xy 187.527936 -227.890091) (xy 187.535879 -227.837387)
			(xy 187.551589 -227.786457) (xy 187.574715 -227.738436) (xy 187.604739 -227.694399) (xy 187.640991 -227.655328)
			(xy 187.682662 -227.622097) (xy 187.72882 -227.595448) (xy 187.778434 -227.575976) (xy 187.830396 -227.564116)
			(xy 187.883546 -227.560133) (xy 187.936696 -227.564116) (xy 187.988658 -227.575976) (xy 188.038272 -227.595448)
			(xy 188.08443 -227.622097) (xy 188.126101 -227.655328) (xy 188.162353 -227.694399) (xy 188.192377 -227.738436)
			(xy 188.215503 -227.786457) (xy 188.231213 -227.837387) (xy 188.239156 -227.890091) (xy 188.239654 -227.91674)
			(xy 188.239156 -227.943389) (xy 191.628004 -227.943389) (xy 191.628004 -227.890091) (xy 191.635947 -227.837387)
			(xy 191.651657 -227.786457) (xy 191.674783 -227.738436) (xy 191.704807 -227.694399) (xy 191.741059 -227.655328)
			(xy 191.78273 -227.622097) (xy 191.828888 -227.595448) (xy 191.878502 -227.575976) (xy 191.930464 -227.564116)
			(xy 191.983614 -227.560133) (xy 192.036764 -227.564116) (xy 192.088726 -227.575976) (xy 192.13834 -227.595448)
			(xy 192.184498 -227.622097) (xy 192.226169 -227.655328) (xy 192.262421 -227.694399) (xy 192.292445 -227.738436)
			(xy 192.315571 -227.786457) (xy 192.331281 -227.837387) (xy 192.339224 -227.890091) (xy 192.339722 -227.91674)
			(xy 192.339224 -227.943389) (xy 202.615536 -227.943389) (xy 202.615536 -227.890091) (xy 202.623479 -227.837387)
			(xy 202.639189 -227.786457) (xy 202.662315 -227.738436) (xy 202.692339 -227.694399) (xy 202.728591 -227.655328)
			(xy 202.770262 -227.622097) (xy 202.81642 -227.595448) (xy 202.866034 -227.575976) (xy 202.917996 -227.564116)
			(xy 202.971146 -227.560133) (xy 203.024296 -227.564116) (xy 203.076258 -227.575976) (xy 203.125872 -227.595448)
			(xy 203.17203 -227.622097) (xy 203.213701 -227.655328) (xy 203.249953 -227.694399) (xy 203.279977 -227.738436)
			(xy 203.303103 -227.786457) (xy 203.318813 -227.837387) (xy 203.326756 -227.890091) (xy 203.327254 -227.91674)
			(xy 203.326756 -227.943389) (xy 206.715604 -227.943389) (xy 206.715604 -227.890091) (xy 206.723547 -227.837387)
			(xy 206.739257 -227.786457) (xy 206.762383 -227.738436) (xy 206.792407 -227.694399) (xy 206.828659 -227.655328)
			(xy 206.87033 -227.622097) (xy 206.916488 -227.595448) (xy 206.966102 -227.575976) (xy 207.018064 -227.564116)
			(xy 207.071214 -227.560133) (xy 207.124364 -227.564116) (xy 207.176326 -227.575976) (xy 207.22594 -227.595448)
			(xy 207.272098 -227.622097) (xy 207.313769 -227.655328) (xy 207.350021 -227.694399) (xy 207.380045 -227.738436)
			(xy 207.403171 -227.786457) (xy 207.418881 -227.837387) (xy 207.426824 -227.890091) (xy 207.427322 -227.91674)
			(xy 207.426824 -227.943389) (xy 207.418881 -227.996093) (xy 207.403171 -228.047023) (xy 207.380045 -228.095044)
			(xy 207.350021 -228.139081) (xy 207.313769 -228.178152) (xy 207.272098 -228.211383) (xy 207.22594 -228.238032)
			(xy 207.176326 -228.257504) (xy 207.124364 -228.269364) (xy 207.071214 -228.273348) (xy 207.018064 -228.269364)
			(xy 206.966102 -228.257504) (xy 206.916488 -228.238032) (xy 206.87033 -228.211383) (xy 206.828659 -228.178152)
			(xy 206.792407 -228.139081) (xy 206.762383 -228.095044) (xy 206.739257 -228.047023) (xy 206.723547 -227.996093)
			(xy 206.715604 -227.943389) (xy 203.326756 -227.943389) (xy 203.318813 -227.996093) (xy 203.303103 -228.047023)
			(xy 203.279977 -228.095044) (xy 203.249953 -228.139081) (xy 203.213701 -228.178152) (xy 203.17203 -228.211383)
			(xy 203.125872 -228.238032) (xy 203.076258 -228.257504) (xy 203.024296 -228.269364) (xy 202.971146 -228.273348)
			(xy 202.917996 -228.269364) (xy 202.866034 -228.257504) (xy 202.81642 -228.238032) (xy 202.770262 -228.211383)
			(xy 202.728591 -228.178152) (xy 202.692339 -228.139081) (xy 202.662315 -228.095044) (xy 202.639189 -228.047023)
			(xy 202.623479 -227.996093) (xy 202.615536 -227.943389) (xy 192.339224 -227.943389) (xy 192.331281 -227.996093)
			(xy 192.315571 -228.047023) (xy 192.292445 -228.095044) (xy 192.262421 -228.139081) (xy 192.226169 -228.178152)
			(xy 192.184498 -228.211383) (xy 192.13834 -228.238032) (xy 192.088726 -228.257504) (xy 192.036764 -228.269364)
			(xy 191.983614 -228.273348) (xy 191.930464 -228.269364) (xy 191.878502 -228.257504) (xy 191.828888 -228.238032)
			(xy 191.78273 -228.211383) (xy 191.741059 -228.178152) (xy 191.704807 -228.139081) (xy 191.674783 -228.095044)
			(xy 191.651657 -228.047023) (xy 191.635947 -227.996093) (xy 191.628004 -227.943389) (xy 188.239156 -227.943389)
			(xy 188.231213 -227.996093) (xy 188.215503 -228.047023) (xy 188.192377 -228.095044) (xy 188.162353 -228.139081)
			(xy 188.126101 -228.178152) (xy 188.08443 -228.211383) (xy 188.038272 -228.238032) (xy 187.988658 -228.257504)
			(xy 187.936696 -228.269364) (xy 187.883546 -228.273348) (xy 187.830396 -228.269364) (xy 187.778434 -228.257504)
			(xy 187.72882 -228.238032) (xy 187.682662 -228.211383) (xy 187.640991 -228.178152) (xy 187.604739 -228.139081)
			(xy 187.574715 -228.095044) (xy 187.551589 -228.047023) (xy 187.535879 -227.996093) (xy 187.527936 -227.943389)
			(xy 177.251624 -227.943389) (xy 177.243681 -227.996093) (xy 177.227971 -228.047023) (xy 177.204845 -228.095044)
			(xy 177.174821 -228.139081) (xy 177.138569 -228.178152) (xy 177.096898 -228.211383) (xy 177.05074 -228.238032)
			(xy 177.001126 -228.257504) (xy 176.949164 -228.269364) (xy 176.896014 -228.273348) (xy 176.842864 -228.269364)
			(xy 176.790902 -228.257504) (xy 176.741288 -228.238032) (xy 176.69513 -228.211383) (xy 176.653459 -228.178152)
			(xy 176.617207 -228.139081) (xy 176.587183 -228.095044) (xy 176.564057 -228.047023) (xy 176.548347 -227.996093)
			(xy 176.540404 -227.943389) (xy 173.151556 -227.943389) (xy 173.143613 -227.996093) (xy 173.127903 -228.047023)
			(xy 173.104777 -228.095044) (xy 173.074753 -228.139081) (xy 173.038501 -228.178152) (xy 172.99683 -228.211383)
			(xy 172.950672 -228.238032) (xy 172.901058 -228.257504) (xy 172.849096 -228.269364) (xy 172.795946 -228.273348)
			(xy 172.742796 -228.269364) (xy 172.690834 -228.257504) (xy 172.64122 -228.238032) (xy 172.595062 -228.211383)
			(xy 172.553391 -228.178152) (xy 172.517139 -228.139081) (xy 172.487115 -228.095044) (xy 172.463989 -228.047023)
			(xy 172.448279 -227.996093) (xy 172.440336 -227.943389) (xy 162.138624 -227.943389) (xy 162.130681 -227.996093)
			(xy 162.114971 -228.047023) (xy 162.091845 -228.095044) (xy 162.061821 -228.139081) (xy 162.025569 -228.178152)
			(xy 161.983898 -228.211383) (xy 161.93774 -228.238032) (xy 161.888126 -228.257504) (xy 161.836164 -228.269364)
			(xy 161.783014 -228.273348) (xy 161.729864 -228.269364) (xy 161.677902 -228.257504) (xy 161.628288 -228.238032)
			(xy 161.58213 -228.211383) (xy 161.540459 -228.178152) (xy 161.504207 -228.139081) (xy 161.474183 -228.095044)
			(xy 161.451057 -228.047023) (xy 161.435347 -227.996093) (xy 161.427404 -227.943389) (xy 158.88716 -227.943389)
			(xy 158.88716 -228.793273) (xy 172.440336 -228.793273) (xy 172.440336 -228.739975) (xy 172.448279 -228.687271)
			(xy 172.463989 -228.636341) (xy 172.487115 -228.58832) (xy 172.517139 -228.544283) (xy 172.553391 -228.505212)
			(xy 172.595062 -228.471981) (xy 172.64122 -228.445332) (xy 172.690834 -228.42586) (xy 172.742796 -228.414)
			(xy 172.795946 -228.410017) (xy 172.849096 -228.414) (xy 172.901058 -228.42586) (xy 172.950672 -228.445332)
			(xy 172.99683 -228.471981) (xy 173.038501 -228.505212) (xy 173.074753 -228.544283) (xy 173.104777 -228.58832)
			(xy 173.127903 -228.636341) (xy 173.143613 -228.687271) (xy 173.151556 -228.739975) (xy 173.152054 -228.766624)
			(xy 173.151556 -228.793273) (xy 187.527936 -228.793273) (xy 187.527936 -228.739975) (xy 187.535879 -228.687271)
			(xy 187.551589 -228.636341) (xy 187.574715 -228.58832) (xy 187.604739 -228.544283) (xy 187.640991 -228.505212)
			(xy 187.682662 -228.471981) (xy 187.72882 -228.445332) (xy 187.778434 -228.42586) (xy 187.830396 -228.414)
			(xy 187.883546 -228.410017) (xy 187.936696 -228.414) (xy 187.988658 -228.42586) (xy 188.038272 -228.445332)
			(xy 188.08443 -228.471981) (xy 188.126101 -228.505212) (xy 188.162353 -228.544283) (xy 188.192377 -228.58832)
			(xy 188.215503 -228.636341) (xy 188.231213 -228.687271) (xy 188.239156 -228.739975) (xy 188.239654 -228.766624)
			(xy 188.239156 -228.793273) (xy 202.615536 -228.793273) (xy 202.615536 -228.739975) (xy 202.623479 -228.687271)
			(xy 202.639189 -228.636341) (xy 202.662315 -228.58832) (xy 202.692339 -228.544283) (xy 202.728591 -228.505212)
			(xy 202.770262 -228.471981) (xy 202.81642 -228.445332) (xy 202.866034 -228.42586) (xy 202.917996 -228.414)
			(xy 202.971146 -228.410017) (xy 203.024296 -228.414) (xy 203.076258 -228.42586) (xy 203.125872 -228.445332)
			(xy 203.17203 -228.471981) (xy 203.213701 -228.505212) (xy 203.249953 -228.544283) (xy 203.279977 -228.58832)
			(xy 203.303103 -228.636341) (xy 203.318813 -228.687271) (xy 203.326756 -228.739975) (xy 203.327254 -228.766624)
			(xy 203.326756 -228.793273) (xy 203.318813 -228.845977) (xy 203.303103 -228.896907) (xy 203.279977 -228.944928)
			(xy 203.249953 -228.988965) (xy 203.213701 -229.028036) (xy 203.17203 -229.061267) (xy 203.125872 -229.087916)
			(xy 203.076258 -229.107388) (xy 203.024296 -229.119248) (xy 202.971146 -229.123232) (xy 202.917996 -229.119248)
			(xy 202.866034 -229.107388) (xy 202.81642 -229.087916) (xy 202.770262 -229.061267) (xy 202.728591 -229.028036)
			(xy 202.692339 -228.988965) (xy 202.662315 -228.944928) (xy 202.639189 -228.896907) (xy 202.623479 -228.845977)
			(xy 202.615536 -228.793273) (xy 188.239156 -228.793273) (xy 188.231213 -228.845977) (xy 188.215503 -228.896907)
			(xy 188.192377 -228.944928) (xy 188.162353 -228.988965) (xy 188.126101 -229.028036) (xy 188.08443 -229.061267)
			(xy 188.038272 -229.087916) (xy 187.988658 -229.107388) (xy 187.936696 -229.119248) (xy 187.883546 -229.123232)
			(xy 187.830396 -229.119248) (xy 187.778434 -229.107388) (xy 187.72882 -229.087916) (xy 187.682662 -229.061267)
			(xy 187.640991 -229.028036) (xy 187.604739 -228.988965) (xy 187.574715 -228.944928) (xy 187.551589 -228.896907)
			(xy 187.535879 -228.845977) (xy 187.527936 -228.793273) (xy 173.151556 -228.793273) (xy 173.143613 -228.845977)
			(xy 173.127903 -228.896907) (xy 173.104777 -228.944928) (xy 173.074753 -228.988965) (xy 173.038501 -229.028036)
			(xy 172.99683 -229.061267) (xy 172.950672 -229.087916) (xy 172.901058 -229.107388) (xy 172.849096 -229.119248)
			(xy 172.795946 -229.123232) (xy 172.742796 -229.119248) (xy 172.690834 -229.107388) (xy 172.64122 -229.087916)
			(xy 172.595062 -229.061267) (xy 172.553391 -229.028036) (xy 172.517139 -228.988965) (xy 172.487115 -228.944928)
			(xy 172.463989 -228.896907) (xy 172.448279 -228.845977) (xy 172.440336 -228.793273) (xy 158.88716 -228.793273)
			(xy 158.88716 -229.643411) (xy 161.427404 -229.643411) (xy 161.427404 -229.590113) (xy 161.435347 -229.537409)
			(xy 161.451057 -229.486479) (xy 161.474183 -229.438458) (xy 161.504207 -229.394421) (xy 161.540459 -229.35535)
			(xy 161.58213 -229.322119) (xy 161.628288 -229.29547) (xy 161.677902 -229.275998) (xy 161.729864 -229.264138)
			(xy 161.783014 -229.260155) (xy 161.836164 -229.264138) (xy 161.888126 -229.275998) (xy 161.93774 -229.29547)
			(xy 161.983898 -229.322119) (xy 162.025569 -229.35535) (xy 162.061821 -229.394421) (xy 162.091845 -229.438458)
			(xy 162.114971 -229.486479) (xy 162.130681 -229.537409) (xy 162.138624 -229.590113) (xy 162.139122 -229.616762)
			(xy 162.138624 -229.643411) (xy 176.540404 -229.643411) (xy 176.540404 -229.590113) (xy 176.548347 -229.537409)
			(xy 176.564057 -229.486479) (xy 176.587183 -229.438458) (xy 176.617207 -229.394421) (xy 176.653459 -229.35535)
			(xy 176.69513 -229.322119) (xy 176.741288 -229.29547) (xy 176.790902 -229.275998) (xy 176.842864 -229.264138)
			(xy 176.896014 -229.260155) (xy 176.949164 -229.264138) (xy 177.001126 -229.275998) (xy 177.05074 -229.29547)
			(xy 177.096898 -229.322119) (xy 177.138569 -229.35535) (xy 177.174821 -229.394421) (xy 177.204845 -229.438458)
			(xy 177.227971 -229.486479) (xy 177.243681 -229.537409) (xy 177.251624 -229.590113) (xy 177.252122 -229.616762)
			(xy 177.251624 -229.643411) (xy 191.628004 -229.643411) (xy 191.628004 -229.590113) (xy 191.635947 -229.537409)
			(xy 191.651657 -229.486479) (xy 191.674783 -229.438458) (xy 191.704807 -229.394421) (xy 191.741059 -229.35535)
			(xy 191.78273 -229.322119) (xy 191.828888 -229.29547) (xy 191.878502 -229.275998) (xy 191.930464 -229.264138)
			(xy 191.983614 -229.260155) (xy 192.036764 -229.264138) (xy 192.088726 -229.275998) (xy 192.13834 -229.29547)
			(xy 192.184498 -229.322119) (xy 192.226169 -229.35535) (xy 192.262421 -229.394421) (xy 192.292445 -229.438458)
			(xy 192.315571 -229.486479) (xy 192.331281 -229.537409) (xy 192.339224 -229.590113) (xy 192.339722 -229.616762)
			(xy 192.339224 -229.643411) (xy 206.715604 -229.643411) (xy 206.715604 -229.590113) (xy 206.723547 -229.537409)
			(xy 206.739257 -229.486479) (xy 206.762383 -229.438458) (xy 206.792407 -229.394421) (xy 206.828659 -229.35535)
			(xy 206.87033 -229.322119) (xy 206.916488 -229.29547) (xy 206.966102 -229.275998) (xy 207.018064 -229.264138)
			(xy 207.071214 -229.260155) (xy 207.124364 -229.264138) (xy 207.176326 -229.275998) (xy 207.22594 -229.29547)
			(xy 207.272098 -229.322119) (xy 207.313769 -229.35535) (xy 207.350021 -229.394421) (xy 207.380045 -229.438458)
			(xy 207.403171 -229.486479) (xy 207.418881 -229.537409) (xy 207.426824 -229.590113) (xy 207.427322 -229.616762)
			(xy 207.426824 -229.643411) (xy 207.418881 -229.696115) (xy 207.403171 -229.747045) (xy 207.380045 -229.795066)
			(xy 207.350021 -229.839103) (xy 207.313769 -229.878174) (xy 207.272098 -229.911405) (xy 207.22594 -229.938054)
			(xy 207.176326 -229.957526) (xy 207.124364 -229.969386) (xy 207.071214 -229.97337) (xy 207.018064 -229.969386)
			(xy 206.966102 -229.957526) (xy 206.916488 -229.938054) (xy 206.87033 -229.911405) (xy 206.828659 -229.878174)
			(xy 206.792407 -229.839103) (xy 206.762383 -229.795066) (xy 206.739257 -229.747045) (xy 206.723547 -229.696115)
			(xy 206.715604 -229.643411) (xy 192.339224 -229.643411) (xy 192.331281 -229.696115) (xy 192.315571 -229.747045)
			(xy 192.292445 -229.795066) (xy 192.262421 -229.839103) (xy 192.226169 -229.878174) (xy 192.184498 -229.911405)
			(xy 192.13834 -229.938054) (xy 192.088726 -229.957526) (xy 192.036764 -229.969386) (xy 191.983614 -229.97337)
			(xy 191.930464 -229.969386) (xy 191.878502 -229.957526) (xy 191.828888 -229.938054) (xy 191.78273 -229.911405)
			(xy 191.741059 -229.878174) (xy 191.704807 -229.839103) (xy 191.674783 -229.795066) (xy 191.651657 -229.747045)
			(xy 191.635947 -229.696115) (xy 191.628004 -229.643411) (xy 177.251624 -229.643411) (xy 177.243681 -229.696115)
			(xy 177.227971 -229.747045) (xy 177.204845 -229.795066) (xy 177.174821 -229.839103) (xy 177.138569 -229.878174)
			(xy 177.096898 -229.911405) (xy 177.05074 -229.938054) (xy 177.001126 -229.957526) (xy 176.949164 -229.969386)
			(xy 176.896014 -229.97337) (xy 176.842864 -229.969386) (xy 176.790902 -229.957526) (xy 176.741288 -229.938054)
			(xy 176.69513 -229.911405) (xy 176.653459 -229.878174) (xy 176.617207 -229.839103) (xy 176.587183 -229.795066)
			(xy 176.564057 -229.747045) (xy 176.548347 -229.696115) (xy 176.540404 -229.643411) (xy 162.138624 -229.643411)
			(xy 162.130681 -229.696115) (xy 162.114971 -229.747045) (xy 162.091845 -229.795066) (xy 162.061821 -229.839103)
			(xy 162.025569 -229.878174) (xy 161.983898 -229.911405) (xy 161.93774 -229.938054) (xy 161.888126 -229.957526)
			(xy 161.836164 -229.969386) (xy 161.783014 -229.97337) (xy 161.729864 -229.969386) (xy 161.677902 -229.957526)
			(xy 161.628288 -229.938054) (xy 161.58213 -229.911405) (xy 161.540459 -229.878174) (xy 161.504207 -229.839103)
			(xy 161.474183 -229.795066) (xy 161.451057 -229.747045) (xy 161.435347 -229.696115) (xy 161.427404 -229.643411)
			(xy 158.88716 -229.643411) (xy 158.88716 -230.493295) (xy 172.440336 -230.493295) (xy 172.440336 -230.439997)
			(xy 172.448279 -230.387293) (xy 172.463989 -230.336363) (xy 172.487115 -230.288342) (xy 172.517139 -230.244305)
			(xy 172.553391 -230.205234) (xy 172.595062 -230.172003) (xy 172.64122 -230.145354) (xy 172.690834 -230.125882)
			(xy 172.742796 -230.114022) (xy 172.795946 -230.110039) (xy 172.849096 -230.114022) (xy 172.901058 -230.125882)
			(xy 172.950672 -230.145354) (xy 172.99683 -230.172003) (xy 173.038501 -230.205234) (xy 173.074753 -230.244305)
			(xy 173.104777 -230.288342) (xy 173.127903 -230.336363) (xy 173.143613 -230.387293) (xy 173.151556 -230.439997)
			(xy 173.152054 -230.466646) (xy 173.151556 -230.493295) (xy 187.527936 -230.493295) (xy 187.527936 -230.439997)
			(xy 187.535879 -230.387293) (xy 187.551589 -230.336363) (xy 187.574715 -230.288342) (xy 187.604739 -230.244305)
			(xy 187.640991 -230.205234) (xy 187.682662 -230.172003) (xy 187.72882 -230.145354) (xy 187.778434 -230.125882)
			(xy 187.830396 -230.114022) (xy 187.883546 -230.110039) (xy 187.936696 -230.114022) (xy 187.988658 -230.125882)
			(xy 188.038272 -230.145354) (xy 188.08443 -230.172003) (xy 188.126101 -230.205234) (xy 188.162353 -230.244305)
			(xy 188.192377 -230.288342) (xy 188.215503 -230.336363) (xy 188.231213 -230.387293) (xy 188.239156 -230.439997)
			(xy 188.239654 -230.466646) (xy 188.239156 -230.493295) (xy 202.615536 -230.493295) (xy 202.615536 -230.439997)
			(xy 202.623479 -230.387293) (xy 202.639189 -230.336363) (xy 202.662315 -230.288342) (xy 202.692339 -230.244305)
			(xy 202.728591 -230.205234) (xy 202.770262 -230.172003) (xy 202.81642 -230.145354) (xy 202.866034 -230.125882)
			(xy 202.917996 -230.114022) (xy 202.971146 -230.110039) (xy 203.024296 -230.114022) (xy 203.076258 -230.125882)
			(xy 203.125872 -230.145354) (xy 203.17203 -230.172003) (xy 203.213701 -230.205234) (xy 203.249953 -230.244305)
			(xy 203.279977 -230.288342) (xy 203.303103 -230.336363) (xy 203.318813 -230.387293) (xy 203.326756 -230.439997)
			(xy 203.327254 -230.466646) (xy 203.326756 -230.493295) (xy 203.318813 -230.545999) (xy 203.303103 -230.596929)
			(xy 203.279977 -230.64495) (xy 203.249953 -230.688987) (xy 203.213701 -230.728058) (xy 203.17203 -230.761289)
			(xy 203.125872 -230.787938) (xy 203.076258 -230.80741) (xy 203.024296 -230.81927) (xy 202.971146 -230.823254)
			(xy 202.917996 -230.81927) (xy 202.866034 -230.80741) (xy 202.81642 -230.787938) (xy 202.770262 -230.761289)
			(xy 202.728591 -230.728058) (xy 202.692339 -230.688987) (xy 202.662315 -230.64495) (xy 202.639189 -230.596929)
			(xy 202.623479 -230.545999) (xy 202.615536 -230.493295) (xy 188.239156 -230.493295) (xy 188.231213 -230.545999)
			(xy 188.215503 -230.596929) (xy 188.192377 -230.64495) (xy 188.162353 -230.688987) (xy 188.126101 -230.728058)
			(xy 188.08443 -230.761289) (xy 188.038272 -230.787938) (xy 187.988658 -230.80741) (xy 187.936696 -230.81927)
			(xy 187.883546 -230.823254) (xy 187.830396 -230.81927) (xy 187.778434 -230.80741) (xy 187.72882 -230.787938)
			(xy 187.682662 -230.761289) (xy 187.640991 -230.728058) (xy 187.604739 -230.688987) (xy 187.574715 -230.64495)
			(xy 187.551589 -230.596929) (xy 187.535879 -230.545999) (xy 187.527936 -230.493295) (xy 173.151556 -230.493295)
			(xy 173.143613 -230.545999) (xy 173.127903 -230.596929) (xy 173.104777 -230.64495) (xy 173.074753 -230.688987)
			(xy 173.038501 -230.728058) (xy 172.99683 -230.761289) (xy 172.950672 -230.787938) (xy 172.901058 -230.80741)
			(xy 172.849096 -230.81927) (xy 172.795946 -230.823254) (xy 172.742796 -230.81927) (xy 172.690834 -230.80741)
			(xy 172.64122 -230.787938) (xy 172.595062 -230.761289) (xy 172.553391 -230.728058) (xy 172.517139 -230.688987)
			(xy 172.487115 -230.64495) (xy 172.463989 -230.596929) (xy 172.448279 -230.545999) (xy 172.440336 -230.493295)
			(xy 158.88716 -230.493295) (xy 158.88716 -231.343433) (xy 161.427404 -231.343433) (xy 161.427404 -231.290135)
			(xy 161.435347 -231.237431) (xy 161.451057 -231.186501) (xy 161.474183 -231.13848) (xy 161.504207 -231.094443)
			(xy 161.540459 -231.055372) (xy 161.58213 -231.022141) (xy 161.628288 -230.995492) (xy 161.677902 -230.97602)
			(xy 161.729864 -230.96416) (xy 161.783014 -230.960177) (xy 161.836164 -230.96416) (xy 161.888126 -230.97602)
			(xy 161.93774 -230.995492) (xy 161.983898 -231.022141) (xy 162.025569 -231.055372) (xy 162.061821 -231.094443)
			(xy 162.091845 -231.13848) (xy 162.114971 -231.186501) (xy 162.130681 -231.237431) (xy 162.138624 -231.290135)
			(xy 162.139122 -231.316784) (xy 162.138624 -231.343433) (xy 176.540404 -231.343433) (xy 176.540404 -231.290135)
			(xy 176.548347 -231.237431) (xy 176.564057 -231.186501) (xy 176.587183 -231.13848) (xy 176.617207 -231.094443)
			(xy 176.653459 -231.055372) (xy 176.69513 -231.022141) (xy 176.741288 -230.995492) (xy 176.790902 -230.97602)
			(xy 176.842864 -230.96416) (xy 176.896014 -230.960177) (xy 176.949164 -230.96416) (xy 177.001126 -230.97602)
			(xy 177.05074 -230.995492) (xy 177.096898 -231.022141) (xy 177.138569 -231.055372) (xy 177.174821 -231.094443)
			(xy 177.204845 -231.13848) (xy 177.227971 -231.186501) (xy 177.243681 -231.237431) (xy 177.251624 -231.290135)
			(xy 177.252122 -231.316784) (xy 177.251624 -231.343433) (xy 191.628004 -231.343433) (xy 191.628004 -231.290135)
			(xy 191.635947 -231.237431) (xy 191.651657 -231.186501) (xy 191.674783 -231.13848) (xy 191.704807 -231.094443)
			(xy 191.741059 -231.055372) (xy 191.78273 -231.022141) (xy 191.828888 -230.995492) (xy 191.878502 -230.97602)
			(xy 191.930464 -230.96416) (xy 191.983614 -230.960177) (xy 192.036764 -230.96416) (xy 192.088726 -230.97602)
			(xy 192.13834 -230.995492) (xy 192.184498 -231.022141) (xy 192.226169 -231.055372) (xy 192.262421 -231.094443)
			(xy 192.292445 -231.13848) (xy 192.315571 -231.186501) (xy 192.331281 -231.237431) (xy 192.339224 -231.290135)
			(xy 192.339722 -231.316784) (xy 192.339224 -231.343433) (xy 206.715604 -231.343433) (xy 206.715604 -231.290135)
			(xy 206.723547 -231.237431) (xy 206.739257 -231.186501) (xy 206.762383 -231.13848) (xy 206.792407 -231.094443)
			(xy 206.828659 -231.055372) (xy 206.87033 -231.022141) (xy 206.916488 -230.995492) (xy 206.966102 -230.97602)
			(xy 207.018064 -230.96416) (xy 207.071214 -230.960177) (xy 207.124364 -230.96416) (xy 207.176326 -230.97602)
			(xy 207.22594 -230.995492) (xy 207.272098 -231.022141) (xy 207.313769 -231.055372) (xy 207.350021 -231.094443)
			(xy 207.380045 -231.13848) (xy 207.403171 -231.186501) (xy 207.418881 -231.237431) (xy 207.426824 -231.290135)
			(xy 207.427322 -231.316784) (xy 207.426824 -231.343433) (xy 207.418881 -231.396137) (xy 207.403171 -231.447067)
			(xy 207.380045 -231.495088) (xy 207.350021 -231.539125) (xy 207.313769 -231.578196) (xy 207.272098 -231.611427)
			(xy 207.22594 -231.638076) (xy 207.176326 -231.657548) (xy 207.124364 -231.669408) (xy 207.071214 -231.673392)
			(xy 207.018064 -231.669408) (xy 206.966102 -231.657548) (xy 206.916488 -231.638076) (xy 206.87033 -231.611427)
			(xy 206.828659 -231.578196) (xy 206.792407 -231.539125) (xy 206.762383 -231.495088) (xy 206.739257 -231.447067)
			(xy 206.723547 -231.396137) (xy 206.715604 -231.343433) (xy 192.339224 -231.343433) (xy 192.331281 -231.396137)
			(xy 192.315571 -231.447067) (xy 192.292445 -231.495088) (xy 192.262421 -231.539125) (xy 192.226169 -231.578196)
			(xy 192.184498 -231.611427) (xy 192.13834 -231.638076) (xy 192.088726 -231.657548) (xy 192.036764 -231.669408)
			(xy 191.983614 -231.673392) (xy 191.930464 -231.669408) (xy 191.878502 -231.657548) (xy 191.828888 -231.638076)
			(xy 191.78273 -231.611427) (xy 191.741059 -231.578196) (xy 191.704807 -231.539125) (xy 191.674783 -231.495088)
			(xy 191.651657 -231.447067) (xy 191.635947 -231.396137) (xy 191.628004 -231.343433) (xy 177.251624 -231.343433)
			(xy 177.243681 -231.396137) (xy 177.227971 -231.447067) (xy 177.204845 -231.495088) (xy 177.174821 -231.539125)
			(xy 177.138569 -231.578196) (xy 177.096898 -231.611427) (xy 177.05074 -231.638076) (xy 177.001126 -231.657548)
			(xy 176.949164 -231.669408) (xy 176.896014 -231.673392) (xy 176.842864 -231.669408) (xy 176.790902 -231.657548)
			(xy 176.741288 -231.638076) (xy 176.69513 -231.611427) (xy 176.653459 -231.578196) (xy 176.617207 -231.539125)
			(xy 176.587183 -231.495088) (xy 176.564057 -231.447067) (xy 176.548347 -231.396137) (xy 176.540404 -231.343433)
			(xy 162.138624 -231.343433) (xy 162.130681 -231.396137) (xy 162.114971 -231.447067) (xy 162.091845 -231.495088)
			(xy 162.061821 -231.539125) (xy 162.025569 -231.578196) (xy 161.983898 -231.611427) (xy 161.93774 -231.638076)
			(xy 161.888126 -231.657548) (xy 161.836164 -231.669408) (xy 161.783014 -231.673392) (xy 161.729864 -231.669408)
			(xy 161.677902 -231.657548) (xy 161.628288 -231.638076) (xy 161.58213 -231.611427) (xy 161.540459 -231.578196)
			(xy 161.504207 -231.539125) (xy 161.474183 -231.495088) (xy 161.451057 -231.447067) (xy 161.435347 -231.396137)
			(xy 161.427404 -231.343433) (xy 158.88716 -231.343433) (xy 158.88716 -232.193317) (xy 172.440336 -232.193317)
			(xy 172.440336 -232.140019) (xy 172.448279 -232.087315) (xy 172.463989 -232.036385) (xy 172.487115 -231.988364)
			(xy 172.517139 -231.944327) (xy 172.553391 -231.905256) (xy 172.595062 -231.872025) (xy 172.64122 -231.845376)
			(xy 172.690834 -231.825904) (xy 172.742796 -231.814044) (xy 172.795946 -231.810061) (xy 172.849096 -231.814044)
			(xy 172.901058 -231.825904) (xy 172.950672 -231.845376) (xy 172.99683 -231.872025) (xy 173.038501 -231.905256)
			(xy 173.074753 -231.944327) (xy 173.104777 -231.988364) (xy 173.127903 -232.036385) (xy 173.143613 -232.087315)
			(xy 173.151556 -232.140019) (xy 173.152054 -232.166668) (xy 173.151556 -232.193317) (xy 187.527936 -232.193317)
			(xy 187.527936 -232.140019) (xy 187.535879 -232.087315) (xy 187.551589 -232.036385) (xy 187.574715 -231.988364)
			(xy 187.604739 -231.944327) (xy 187.640991 -231.905256) (xy 187.682662 -231.872025) (xy 187.72882 -231.845376)
			(xy 187.778434 -231.825904) (xy 187.830396 -231.814044) (xy 187.883546 -231.810061) (xy 187.936696 -231.814044)
			(xy 187.988658 -231.825904) (xy 188.038272 -231.845376) (xy 188.08443 -231.872025) (xy 188.126101 -231.905256)
			(xy 188.162353 -231.944327) (xy 188.192377 -231.988364) (xy 188.215503 -232.036385) (xy 188.231213 -232.087315)
			(xy 188.239156 -232.140019) (xy 188.239654 -232.166668) (xy 188.239156 -232.193317) (xy 202.615536 -232.193317)
			(xy 202.615536 -232.140019) (xy 202.623479 -232.087315) (xy 202.639189 -232.036385) (xy 202.662315 -231.988364)
			(xy 202.692339 -231.944327) (xy 202.728591 -231.905256) (xy 202.770262 -231.872025) (xy 202.81642 -231.845376)
			(xy 202.866034 -231.825904) (xy 202.917996 -231.814044) (xy 202.971146 -231.810061) (xy 203.024296 -231.814044)
			(xy 203.076258 -231.825904) (xy 203.125872 -231.845376) (xy 203.17203 -231.872025) (xy 203.213701 -231.905256)
			(xy 203.249953 -231.944327) (xy 203.279977 -231.988364) (xy 203.303103 -232.036385) (xy 203.318813 -232.087315)
			(xy 203.326756 -232.140019) (xy 203.327254 -232.166668) (xy 203.326756 -232.193317) (xy 203.318813 -232.246021)
			(xy 203.303103 -232.296951) (xy 203.279977 -232.344972) (xy 203.249953 -232.389009) (xy 203.213701 -232.42808)
			(xy 203.17203 -232.461311) (xy 203.125872 -232.48796) (xy 203.076258 -232.507432) (xy 203.024296 -232.519292)
			(xy 202.971146 -232.523276) (xy 202.917996 -232.519292) (xy 202.866034 -232.507432) (xy 202.81642 -232.48796)
			(xy 202.770262 -232.461311) (xy 202.728591 -232.42808) (xy 202.692339 -232.389009) (xy 202.662315 -232.344972)
			(xy 202.639189 -232.296951) (xy 202.623479 -232.246021) (xy 202.615536 -232.193317) (xy 188.239156 -232.193317)
			(xy 188.231213 -232.246021) (xy 188.215503 -232.296951) (xy 188.192377 -232.344972) (xy 188.162353 -232.389009)
			(xy 188.126101 -232.42808) (xy 188.08443 -232.461311) (xy 188.038272 -232.48796) (xy 187.988658 -232.507432)
			(xy 187.936696 -232.519292) (xy 187.883546 -232.523276) (xy 187.830396 -232.519292) (xy 187.778434 -232.507432)
			(xy 187.72882 -232.48796) (xy 187.682662 -232.461311) (xy 187.640991 -232.42808) (xy 187.604739 -232.389009)
			(xy 187.574715 -232.344972) (xy 187.551589 -232.296951) (xy 187.535879 -232.246021) (xy 187.527936 -232.193317)
			(xy 173.151556 -232.193317) (xy 173.143613 -232.246021) (xy 173.127903 -232.296951) (xy 173.104777 -232.344972)
			(xy 173.074753 -232.389009) (xy 173.038501 -232.42808) (xy 172.99683 -232.461311) (xy 172.950672 -232.48796)
			(xy 172.901058 -232.507432) (xy 172.849096 -232.519292) (xy 172.795946 -232.523276) (xy 172.742796 -232.519292)
			(xy 172.690834 -232.507432) (xy 172.64122 -232.48796) (xy 172.595062 -232.461311) (xy 172.553391 -232.42808)
			(xy 172.517139 -232.389009) (xy 172.487115 -232.344972) (xy 172.463989 -232.296951) (xy 172.448279 -232.246021)
			(xy 172.440336 -232.193317) (xy 158.88716 -232.193317) (xy 158.88716 -233.043455) (xy 176.540404 -233.043455)
			(xy 176.540404 -232.990157) (xy 176.548347 -232.937453) (xy 176.564057 -232.886523) (xy 176.587183 -232.838502)
			(xy 176.617207 -232.794465) (xy 176.653459 -232.755394) (xy 176.69513 -232.722163) (xy 176.741288 -232.695514)
			(xy 176.790902 -232.676042) (xy 176.842864 -232.664182) (xy 176.896014 -232.660199) (xy 176.949164 -232.664182)
			(xy 177.001126 -232.676042) (xy 177.05074 -232.695514) (xy 177.096898 -232.722163) (xy 177.138569 -232.755394)
			(xy 177.174821 -232.794465) (xy 177.204845 -232.838502) (xy 177.227971 -232.886523) (xy 177.243681 -232.937453)
			(xy 177.251624 -232.990157) (xy 177.252122 -233.016806) (xy 177.251624 -233.043455) (xy 191.628004 -233.043455)
			(xy 191.628004 -232.990157) (xy 191.635947 -232.937453) (xy 191.651657 -232.886523) (xy 191.674783 -232.838502)
			(xy 191.704807 -232.794465) (xy 191.741059 -232.755394) (xy 191.78273 -232.722163) (xy 191.828888 -232.695514)
			(xy 191.878502 -232.676042) (xy 191.930464 -232.664182) (xy 191.983614 -232.660199) (xy 192.036764 -232.664182)
			(xy 192.088726 -232.676042) (xy 192.13834 -232.695514) (xy 192.184498 -232.722163) (xy 192.226169 -232.755394)
			(xy 192.262421 -232.794465) (xy 192.292445 -232.838502) (xy 192.315571 -232.886523) (xy 192.331281 -232.937453)
			(xy 192.339224 -232.990157) (xy 192.339722 -233.016806) (xy 192.339224 -233.043455) (xy 206.715604 -233.043455)
			(xy 206.715604 -232.990157) (xy 206.723547 -232.937453) (xy 206.739257 -232.886523) (xy 206.762383 -232.838502)
			(xy 206.792407 -232.794465) (xy 206.828659 -232.755394) (xy 206.87033 -232.722163) (xy 206.916488 -232.695514)
			(xy 206.966102 -232.676042) (xy 207.018064 -232.664182) (xy 207.071214 -232.660199) (xy 207.124364 -232.664182)
			(xy 207.176326 -232.676042) (xy 207.22594 -232.695514) (xy 207.272098 -232.722163) (xy 207.313769 -232.755394)
			(xy 207.350021 -232.794465) (xy 207.380045 -232.838502) (xy 207.403171 -232.886523) (xy 207.418881 -232.937453)
			(xy 207.426824 -232.990157) (xy 207.427322 -233.016806) (xy 207.426824 -233.043455) (xy 207.418881 -233.096159)
			(xy 207.403171 -233.147089) (xy 207.380045 -233.19511) (xy 207.350021 -233.239147) (xy 207.313769 -233.278218)
			(xy 207.272098 -233.311449) (xy 207.22594 -233.338098) (xy 207.176326 -233.35757) (xy 207.124364 -233.36943)
			(xy 207.071214 -233.373414) (xy 207.018064 -233.36943) (xy 206.966102 -233.35757) (xy 206.916488 -233.338098)
			(xy 206.87033 -233.311449) (xy 206.828659 -233.278218) (xy 206.792407 -233.239147) (xy 206.762383 -233.19511)
			(xy 206.739257 -233.147089) (xy 206.723547 -233.096159) (xy 206.715604 -233.043455) (xy 192.339224 -233.043455)
			(xy 192.331281 -233.096159) (xy 192.315571 -233.147089) (xy 192.292445 -233.19511) (xy 192.262421 -233.239147)
			(xy 192.226169 -233.278218) (xy 192.184498 -233.311449) (xy 192.13834 -233.338098) (xy 192.088726 -233.35757)
			(xy 192.036764 -233.36943) (xy 191.983614 -233.373414) (xy 191.930464 -233.36943) (xy 191.878502 -233.35757)
			(xy 191.828888 -233.338098) (xy 191.78273 -233.311449) (xy 191.741059 -233.278218) (xy 191.704807 -233.239147)
			(xy 191.674783 -233.19511) (xy 191.651657 -233.147089) (xy 191.635947 -233.096159) (xy 191.628004 -233.043455)
			(xy 177.251624 -233.043455) (xy 177.243681 -233.096159) (xy 177.227971 -233.147089) (xy 177.204845 -233.19511)
			(xy 177.174821 -233.239147) (xy 177.138569 -233.278218) (xy 177.096898 -233.311449) (xy 177.05074 -233.338098)
			(xy 177.001126 -233.35757) (xy 176.949164 -233.36943) (xy 176.896014 -233.373414) (xy 176.842864 -233.36943)
			(xy 176.790902 -233.35757) (xy 176.741288 -233.338098) (xy 176.69513 -233.311449) (xy 176.653459 -233.278218)
			(xy 176.617207 -233.239147) (xy 176.587183 -233.19511) (xy 176.564057 -233.147089) (xy 176.548347 -233.096159)
			(xy 176.540404 -233.043455) (xy 158.88716 -233.043455) (xy 158.88716 -233.893339) (xy 172.440336 -233.893339)
			(xy 172.440336 -233.840041) (xy 172.448279 -233.787337) (xy 172.463989 -233.736407) (xy 172.487115 -233.688386)
			(xy 172.517139 -233.644349) (xy 172.553391 -233.605278) (xy 172.595062 -233.572047) (xy 172.64122 -233.545398)
			(xy 172.690834 -233.525926) (xy 172.742796 -233.514066) (xy 172.795946 -233.510083) (xy 172.849096 -233.514066)
			(xy 172.901058 -233.525926) (xy 172.950672 -233.545398) (xy 172.99683 -233.572047) (xy 173.038501 -233.605278)
			(xy 173.074753 -233.644349) (xy 173.104777 -233.688386) (xy 173.127903 -233.736407) (xy 173.143613 -233.787337)
			(xy 173.151556 -233.840041) (xy 173.152054 -233.86669) (xy 173.151556 -233.893339) (xy 187.527936 -233.893339)
			(xy 187.527936 -233.840041) (xy 187.535879 -233.787337) (xy 187.551589 -233.736407) (xy 187.574715 -233.688386)
			(xy 187.604739 -233.644349) (xy 187.640991 -233.605278) (xy 187.682662 -233.572047) (xy 187.72882 -233.545398)
			(xy 187.778434 -233.525926) (xy 187.830396 -233.514066) (xy 187.883546 -233.510083) (xy 187.936696 -233.514066)
			(xy 187.988658 -233.525926) (xy 188.038272 -233.545398) (xy 188.08443 -233.572047) (xy 188.126101 -233.605278)
			(xy 188.162353 -233.644349) (xy 188.192377 -233.688386) (xy 188.215503 -233.736407) (xy 188.231213 -233.787337)
			(xy 188.239156 -233.840041) (xy 188.239654 -233.86669) (xy 188.239156 -233.893339) (xy 202.615536 -233.893339)
			(xy 202.615536 -233.840041) (xy 202.623479 -233.787337) (xy 202.639189 -233.736407) (xy 202.662315 -233.688386)
			(xy 202.692339 -233.644349) (xy 202.728591 -233.605278) (xy 202.770262 -233.572047) (xy 202.81642 -233.545398)
			(xy 202.866034 -233.525926) (xy 202.917996 -233.514066) (xy 202.971146 -233.510083) (xy 203.024296 -233.514066)
			(xy 203.076258 -233.525926) (xy 203.125872 -233.545398) (xy 203.17203 -233.572047) (xy 203.213701 -233.605278)
			(xy 203.249953 -233.644349) (xy 203.279977 -233.688386) (xy 203.303103 -233.736407) (xy 203.318813 -233.787337)
			(xy 203.326756 -233.840041) (xy 203.327254 -233.86669) (xy 203.326756 -233.893339) (xy 203.318813 -233.946043)
			(xy 203.303103 -233.996973) (xy 203.279977 -234.044994) (xy 203.249953 -234.089031) (xy 203.213701 -234.128102)
			(xy 203.17203 -234.161333) (xy 203.125872 -234.187982) (xy 203.076258 -234.207454) (xy 203.024296 -234.219314)
			(xy 202.971146 -234.223298) (xy 202.917996 -234.219314) (xy 202.866034 -234.207454) (xy 202.81642 -234.187982)
			(xy 202.770262 -234.161333) (xy 202.728591 -234.128102) (xy 202.692339 -234.089031) (xy 202.662315 -234.044994)
			(xy 202.639189 -233.996973) (xy 202.623479 -233.946043) (xy 202.615536 -233.893339) (xy 188.239156 -233.893339)
			(xy 188.231213 -233.946043) (xy 188.215503 -233.996973) (xy 188.192377 -234.044994) (xy 188.162353 -234.089031)
			(xy 188.126101 -234.128102) (xy 188.08443 -234.161333) (xy 188.038272 -234.187982) (xy 187.988658 -234.207454)
			(xy 187.936696 -234.219314) (xy 187.883546 -234.223298) (xy 187.830396 -234.219314) (xy 187.778434 -234.207454)
			(xy 187.72882 -234.187982) (xy 187.682662 -234.161333) (xy 187.640991 -234.128102) (xy 187.604739 -234.089031)
			(xy 187.574715 -234.044994) (xy 187.551589 -233.996973) (xy 187.535879 -233.946043) (xy 187.527936 -233.893339)
			(xy 173.151556 -233.893339) (xy 173.143613 -233.946043) (xy 173.127903 -233.996973) (xy 173.104777 -234.044994)
			(xy 173.074753 -234.089031) (xy 173.038501 -234.128102) (xy 172.99683 -234.161333) (xy 172.950672 -234.187982)
			(xy 172.901058 -234.207454) (xy 172.849096 -234.219314) (xy 172.795946 -234.223298) (xy 172.742796 -234.219314)
			(xy 172.690834 -234.207454) (xy 172.64122 -234.187982) (xy 172.595062 -234.161333) (xy 172.553391 -234.128102)
			(xy 172.517139 -234.089031) (xy 172.487115 -234.044994) (xy 172.463989 -233.996973) (xy 172.448279 -233.946043)
			(xy 172.440336 -233.893339) (xy 158.88716 -233.893339) (xy 158.88716 -234.743223) (xy 176.540404 -234.743223)
			(xy 176.540404 -234.689925) (xy 176.548347 -234.637221) (xy 176.564057 -234.586291) (xy 176.587183 -234.53827)
			(xy 176.617207 -234.494233) (xy 176.653459 -234.455162) (xy 176.69513 -234.421931) (xy 176.741288 -234.395282)
			(xy 176.790902 -234.37581) (xy 176.842864 -234.36395) (xy 176.896014 -234.359967) (xy 176.949164 -234.36395)
			(xy 177.001126 -234.37581) (xy 177.05074 -234.395282) (xy 177.096898 -234.421931) (xy 177.138569 -234.455162)
			(xy 177.174821 -234.494233) (xy 177.204845 -234.53827) (xy 177.227971 -234.586291) (xy 177.243681 -234.637221)
			(xy 177.251624 -234.689925) (xy 177.252122 -234.716574) (xy 177.251624 -234.743223) (xy 191.628004 -234.743223)
			(xy 191.628004 -234.689925) (xy 191.635947 -234.637221) (xy 191.651657 -234.586291) (xy 191.674783 -234.53827)
			(xy 191.704807 -234.494233) (xy 191.741059 -234.455162) (xy 191.78273 -234.421931) (xy 191.828888 -234.395282)
			(xy 191.878502 -234.37581) (xy 191.930464 -234.36395) (xy 191.983614 -234.359967) (xy 192.036764 -234.36395)
			(xy 192.088726 -234.37581) (xy 192.13834 -234.395282) (xy 192.184498 -234.421931) (xy 192.226169 -234.455162)
			(xy 192.262421 -234.494233) (xy 192.292445 -234.53827) (xy 192.315571 -234.586291) (xy 192.331281 -234.637221)
			(xy 192.339224 -234.689925) (xy 192.339722 -234.716574) (xy 192.339224 -234.743223) (xy 206.715604 -234.743223)
			(xy 206.715604 -234.689925) (xy 206.723547 -234.637221) (xy 206.739257 -234.586291) (xy 206.762383 -234.53827)
			(xy 206.792407 -234.494233) (xy 206.828659 -234.455162) (xy 206.87033 -234.421931) (xy 206.916488 -234.395282)
			(xy 206.966102 -234.37581) (xy 207.018064 -234.36395) (xy 207.071214 -234.359967) (xy 207.124364 -234.36395)
			(xy 207.176326 -234.37581) (xy 207.22594 -234.395282) (xy 207.272098 -234.421931) (xy 207.313769 -234.455162)
			(xy 207.350021 -234.494233) (xy 207.380045 -234.53827) (xy 207.403171 -234.586291) (xy 207.418881 -234.637221)
			(xy 207.426824 -234.689925) (xy 207.427322 -234.716574) (xy 207.426824 -234.743223) (xy 207.418881 -234.795927)
			(xy 207.403171 -234.846857) (xy 207.380045 -234.894878) (xy 207.350021 -234.938915) (xy 207.313769 -234.977986)
			(xy 207.272098 -235.011217) (xy 207.22594 -235.037866) (xy 207.176326 -235.057338) (xy 207.124364 -235.069198)
			(xy 207.071214 -235.073182) (xy 207.018064 -235.069198) (xy 206.966102 -235.057338) (xy 206.916488 -235.037866)
			(xy 206.87033 -235.011217) (xy 206.828659 -234.977986) (xy 206.792407 -234.938915) (xy 206.762383 -234.894878)
			(xy 206.739257 -234.846857) (xy 206.723547 -234.795927) (xy 206.715604 -234.743223) (xy 192.339224 -234.743223)
			(xy 192.331281 -234.795927) (xy 192.315571 -234.846857) (xy 192.292445 -234.894878) (xy 192.262421 -234.938915)
			(xy 192.226169 -234.977986) (xy 192.184498 -235.011217) (xy 192.13834 -235.037866) (xy 192.088726 -235.057338)
			(xy 192.036764 -235.069198) (xy 191.983614 -235.073182) (xy 191.930464 -235.069198) (xy 191.878502 -235.057338)
			(xy 191.828888 -235.037866) (xy 191.78273 -235.011217) (xy 191.741059 -234.977986) (xy 191.704807 -234.938915)
			(xy 191.674783 -234.894878) (xy 191.651657 -234.846857) (xy 191.635947 -234.795927) (xy 191.628004 -234.743223)
			(xy 177.251624 -234.743223) (xy 177.243681 -234.795927) (xy 177.227971 -234.846857) (xy 177.204845 -234.894878)
			(xy 177.174821 -234.938915) (xy 177.138569 -234.977986) (xy 177.096898 -235.011217) (xy 177.05074 -235.037866)
			(xy 177.001126 -235.057338) (xy 176.949164 -235.069198) (xy 176.896014 -235.073182) (xy 176.842864 -235.069198)
			(xy 176.790902 -235.057338) (xy 176.741288 -235.037866) (xy 176.69513 -235.011217) (xy 176.653459 -234.977986)
			(xy 176.617207 -234.938915) (xy 176.587183 -234.894878) (xy 176.564057 -234.846857) (xy 176.548347 -234.795927)
			(xy 176.540404 -234.743223) (xy 158.88716 -234.743223) (xy 158.88716 -235.593361) (xy 172.440336 -235.593361)
			(xy 172.440336 -235.540063) (xy 172.448279 -235.487359) (xy 172.463989 -235.436429) (xy 172.487115 -235.388408)
			(xy 172.517139 -235.344371) (xy 172.553391 -235.3053) (xy 172.595062 -235.272069) (xy 172.64122 -235.24542)
			(xy 172.690834 -235.225948) (xy 172.742796 -235.214088) (xy 172.795946 -235.210105) (xy 172.849096 -235.214088)
			(xy 172.901058 -235.225948) (xy 172.950672 -235.24542) (xy 172.99683 -235.272069) (xy 173.038501 -235.3053)
			(xy 173.074753 -235.344371) (xy 173.104777 -235.388408) (xy 173.127903 -235.436429) (xy 173.143613 -235.487359)
			(xy 173.151556 -235.540063) (xy 173.152054 -235.566712) (xy 173.151556 -235.593361) (xy 187.527936 -235.593361)
			(xy 187.527936 -235.540063) (xy 187.535879 -235.487359) (xy 187.551589 -235.436429) (xy 187.574715 -235.388408)
			(xy 187.604739 -235.344371) (xy 187.640991 -235.3053) (xy 187.682662 -235.272069) (xy 187.72882 -235.24542)
			(xy 187.778434 -235.225948) (xy 187.830396 -235.214088) (xy 187.883546 -235.210105) (xy 187.936696 -235.214088)
			(xy 187.988658 -235.225948) (xy 188.038272 -235.24542) (xy 188.08443 -235.272069) (xy 188.126101 -235.3053)
			(xy 188.162353 -235.344371) (xy 188.192377 -235.388408) (xy 188.215503 -235.436429) (xy 188.231213 -235.487359)
			(xy 188.239156 -235.540063) (xy 188.239654 -235.566712) (xy 188.239156 -235.593361) (xy 202.615536 -235.593361)
			(xy 202.615536 -235.540063) (xy 202.623479 -235.487359) (xy 202.639189 -235.436429) (xy 202.662315 -235.388408)
			(xy 202.692339 -235.344371) (xy 202.728591 -235.3053) (xy 202.770262 -235.272069) (xy 202.81642 -235.24542)
			(xy 202.866034 -235.225948) (xy 202.917996 -235.214088) (xy 202.971146 -235.210105) (xy 203.024296 -235.214088)
			(xy 203.076258 -235.225948) (xy 203.125872 -235.24542) (xy 203.17203 -235.272069) (xy 203.213701 -235.3053)
			(xy 203.249953 -235.344371) (xy 203.279977 -235.388408) (xy 203.303103 -235.436429) (xy 203.318813 -235.487359)
			(xy 203.326756 -235.540063) (xy 203.327254 -235.566712) (xy 203.326756 -235.593361) (xy 203.318813 -235.646065)
			(xy 203.303103 -235.696995) (xy 203.279977 -235.745016) (xy 203.249953 -235.789053) (xy 203.213701 -235.828124)
			(xy 203.17203 -235.861355) (xy 203.125872 -235.888004) (xy 203.076258 -235.907476) (xy 203.024296 -235.919336)
			(xy 202.971146 -235.92332) (xy 202.917996 -235.919336) (xy 202.866034 -235.907476) (xy 202.81642 -235.888004)
			(xy 202.770262 -235.861355) (xy 202.728591 -235.828124) (xy 202.692339 -235.789053) (xy 202.662315 -235.745016)
			(xy 202.639189 -235.696995) (xy 202.623479 -235.646065) (xy 202.615536 -235.593361) (xy 188.239156 -235.593361)
			(xy 188.231213 -235.646065) (xy 188.215503 -235.696995) (xy 188.192377 -235.745016) (xy 188.162353 -235.789053)
			(xy 188.126101 -235.828124) (xy 188.08443 -235.861355) (xy 188.038272 -235.888004) (xy 187.988658 -235.907476)
			(xy 187.936696 -235.919336) (xy 187.883546 -235.92332) (xy 187.830396 -235.919336) (xy 187.778434 -235.907476)
			(xy 187.72882 -235.888004) (xy 187.682662 -235.861355) (xy 187.640991 -235.828124) (xy 187.604739 -235.789053)
			(xy 187.574715 -235.745016) (xy 187.551589 -235.696995) (xy 187.535879 -235.646065) (xy 187.527936 -235.593361)
			(xy 173.151556 -235.593361) (xy 173.143613 -235.646065) (xy 173.127903 -235.696995) (xy 173.104777 -235.745016)
			(xy 173.074753 -235.789053) (xy 173.038501 -235.828124) (xy 172.99683 -235.861355) (xy 172.950672 -235.888004)
			(xy 172.901058 -235.907476) (xy 172.849096 -235.919336) (xy 172.795946 -235.92332) (xy 172.742796 -235.919336)
			(xy 172.690834 -235.907476) (xy 172.64122 -235.888004) (xy 172.595062 -235.861355) (xy 172.553391 -235.828124)
			(xy 172.517139 -235.789053) (xy 172.487115 -235.745016) (xy 172.463989 -235.696995) (xy 172.448279 -235.646065)
			(xy 172.440336 -235.593361) (xy 158.88716 -235.593361) (xy 158.88716 -236.443245) (xy 176.540404 -236.443245)
			(xy 176.540404 -236.389947) (xy 176.548347 -236.337243) (xy 176.564057 -236.286313) (xy 176.587183 -236.238292)
			(xy 176.617207 -236.194255) (xy 176.653459 -236.155184) (xy 176.69513 -236.121953) (xy 176.741288 -236.095304)
			(xy 176.790902 -236.075832) (xy 176.842864 -236.063972) (xy 176.896014 -236.059989) (xy 176.949164 -236.063972)
			(xy 177.001126 -236.075832) (xy 177.05074 -236.095304) (xy 177.096898 -236.121953) (xy 177.138569 -236.155184)
			(xy 177.174821 -236.194255) (xy 177.204845 -236.238292) (xy 177.227971 -236.286313) (xy 177.243681 -236.337243)
			(xy 177.251624 -236.389947) (xy 177.252122 -236.416596) (xy 177.251624 -236.443245) (xy 191.628004 -236.443245)
			(xy 191.628004 -236.389947) (xy 191.635947 -236.337243) (xy 191.651657 -236.286313) (xy 191.674783 -236.238292)
			(xy 191.704807 -236.194255) (xy 191.741059 -236.155184) (xy 191.78273 -236.121953) (xy 191.828888 -236.095304)
			(xy 191.878502 -236.075832) (xy 191.930464 -236.063972) (xy 191.983614 -236.059989) (xy 192.036764 -236.063972)
			(xy 192.088726 -236.075832) (xy 192.13834 -236.095304) (xy 192.184498 -236.121953) (xy 192.226169 -236.155184)
			(xy 192.262421 -236.194255) (xy 192.292445 -236.238292) (xy 192.315571 -236.286313) (xy 192.331281 -236.337243)
			(xy 192.339224 -236.389947) (xy 192.339722 -236.416596) (xy 192.339224 -236.443245) (xy 206.715604 -236.443245)
			(xy 206.715604 -236.389947) (xy 206.723547 -236.337243) (xy 206.739257 -236.286313) (xy 206.762383 -236.238292)
			(xy 206.792407 -236.194255) (xy 206.828659 -236.155184) (xy 206.87033 -236.121953) (xy 206.916488 -236.095304)
			(xy 206.966102 -236.075832) (xy 207.018064 -236.063972) (xy 207.071214 -236.059989) (xy 207.124364 -236.063972)
			(xy 207.176326 -236.075832) (xy 207.22594 -236.095304) (xy 207.272098 -236.121953) (xy 207.313769 -236.155184)
			(xy 207.350021 -236.194255) (xy 207.380045 -236.238292) (xy 207.403171 -236.286313) (xy 207.418881 -236.337243)
			(xy 207.426824 -236.389947) (xy 207.427322 -236.416596) (xy 207.426824 -236.443245) (xy 207.418881 -236.495949)
			(xy 207.403171 -236.546879) (xy 207.380045 -236.5949) (xy 207.350021 -236.638937) (xy 207.313769 -236.678008)
			(xy 207.272098 -236.711239) (xy 207.22594 -236.737888) (xy 207.176326 -236.75736) (xy 207.124364 -236.76922)
			(xy 207.071214 -236.773204) (xy 207.018064 -236.76922) (xy 206.966102 -236.75736) (xy 206.916488 -236.737888)
			(xy 206.87033 -236.711239) (xy 206.828659 -236.678008) (xy 206.792407 -236.638937) (xy 206.762383 -236.5949)
			(xy 206.739257 -236.546879) (xy 206.723547 -236.495949) (xy 206.715604 -236.443245) (xy 192.339224 -236.443245)
			(xy 192.331281 -236.495949) (xy 192.315571 -236.546879) (xy 192.292445 -236.5949) (xy 192.262421 -236.638937)
			(xy 192.226169 -236.678008) (xy 192.184498 -236.711239) (xy 192.13834 -236.737888) (xy 192.088726 -236.75736)
			(xy 192.036764 -236.76922) (xy 191.983614 -236.773204) (xy 191.930464 -236.76922) (xy 191.878502 -236.75736)
			(xy 191.828888 -236.737888) (xy 191.78273 -236.711239) (xy 191.741059 -236.678008) (xy 191.704807 -236.638937)
			(xy 191.674783 -236.5949) (xy 191.651657 -236.546879) (xy 191.635947 -236.495949) (xy 191.628004 -236.443245)
			(xy 177.251624 -236.443245) (xy 177.243681 -236.495949) (xy 177.227971 -236.546879) (xy 177.204845 -236.5949)
			(xy 177.174821 -236.638937) (xy 177.138569 -236.678008) (xy 177.096898 -236.711239) (xy 177.05074 -236.737888)
			(xy 177.001126 -236.75736) (xy 176.949164 -236.76922) (xy 176.896014 -236.773204) (xy 176.842864 -236.76922)
			(xy 176.790902 -236.75736) (xy 176.741288 -236.737888) (xy 176.69513 -236.711239) (xy 176.653459 -236.678008)
			(xy 176.617207 -236.638937) (xy 176.587183 -236.5949) (xy 176.564057 -236.546879) (xy 176.548347 -236.495949)
			(xy 176.540404 -236.443245) (xy 158.88716 -236.443245) (xy 158.88716 -237.293383) (xy 172.440336 -237.293383)
			(xy 172.440336 -237.240085) (xy 172.448279 -237.187381) (xy 172.463989 -237.136451) (xy 172.487115 -237.08843)
			(xy 172.517139 -237.044393) (xy 172.553391 -237.005322) (xy 172.595062 -236.972091) (xy 172.64122 -236.945442)
			(xy 172.690834 -236.92597) (xy 172.742796 -236.91411) (xy 172.795946 -236.910127) (xy 172.849096 -236.91411)
			(xy 172.901058 -236.92597) (xy 172.950672 -236.945442) (xy 172.99683 -236.972091) (xy 173.038501 -237.005322)
			(xy 173.074753 -237.044393) (xy 173.104777 -237.08843) (xy 173.127903 -237.136451) (xy 173.143613 -237.187381)
			(xy 173.151556 -237.240085) (xy 173.152054 -237.266734) (xy 173.151556 -237.293383) (xy 176.540404 -237.293383)
			(xy 176.540404 -237.240085) (xy 176.548347 -237.187381) (xy 176.564057 -237.136451) (xy 176.587183 -237.08843)
			(xy 176.617207 -237.044393) (xy 176.653459 -237.005322) (xy 176.69513 -236.972091) (xy 176.741288 -236.945442)
			(xy 176.790902 -236.92597) (xy 176.842864 -236.91411) (xy 176.896014 -236.910127) (xy 176.949164 -236.91411)
			(xy 177.001126 -236.92597) (xy 177.05074 -236.945442) (xy 177.096898 -236.972091) (xy 177.138569 -237.005322)
			(xy 177.174821 -237.044393) (xy 177.204845 -237.08843) (xy 177.227971 -237.136451) (xy 177.243681 -237.187381)
			(xy 177.251624 -237.240085) (xy 177.252122 -237.266734) (xy 177.251624 -237.293383) (xy 187.527936 -237.293383)
			(xy 187.527936 -237.240085) (xy 187.535879 -237.187381) (xy 187.551589 -237.136451) (xy 187.574715 -237.08843)
			(xy 187.604739 -237.044393) (xy 187.640991 -237.005322) (xy 187.682662 -236.972091) (xy 187.72882 -236.945442)
			(xy 187.778434 -236.92597) (xy 187.830396 -236.91411) (xy 187.883546 -236.910127) (xy 187.936696 -236.91411)
			(xy 187.988658 -236.92597) (xy 188.038272 -236.945442) (xy 188.08443 -236.972091) (xy 188.126101 -237.005322)
			(xy 188.162353 -237.044393) (xy 188.192377 -237.08843) (xy 188.215503 -237.136451) (xy 188.231213 -237.187381)
			(xy 188.239156 -237.240085) (xy 188.239654 -237.266734) (xy 188.239156 -237.293383) (xy 191.628004 -237.293383)
			(xy 191.628004 -237.240085) (xy 191.635947 -237.187381) (xy 191.651657 -237.136451) (xy 191.674783 -237.08843)
			(xy 191.704807 -237.044393) (xy 191.741059 -237.005322) (xy 191.78273 -236.972091) (xy 191.828888 -236.945442)
			(xy 191.878502 -236.92597) (xy 191.930464 -236.91411) (xy 191.983614 -236.910127) (xy 192.036764 -236.91411)
			(xy 192.088726 -236.92597) (xy 192.13834 -236.945442) (xy 192.184498 -236.972091) (xy 192.226169 -237.005322)
			(xy 192.262421 -237.044393) (xy 192.292445 -237.08843) (xy 192.315571 -237.136451) (xy 192.331281 -237.187381)
			(xy 192.339224 -237.240085) (xy 192.339722 -237.266734) (xy 192.339224 -237.293383) (xy 202.615536 -237.293383)
			(xy 202.615536 -237.240085) (xy 202.623479 -237.187381) (xy 202.639189 -237.136451) (xy 202.662315 -237.08843)
			(xy 202.692339 -237.044393) (xy 202.728591 -237.005322) (xy 202.770262 -236.972091) (xy 202.81642 -236.945442)
			(xy 202.866034 -236.92597) (xy 202.917996 -236.91411) (xy 202.971146 -236.910127) (xy 203.024296 -236.91411)
			(xy 203.076258 -236.92597) (xy 203.125872 -236.945442) (xy 203.17203 -236.972091) (xy 203.213701 -237.005322)
			(xy 203.249953 -237.044393) (xy 203.279977 -237.08843) (xy 203.303103 -237.136451) (xy 203.318813 -237.187381)
			(xy 203.326756 -237.240085) (xy 203.327254 -237.266734) (xy 203.326756 -237.293383) (xy 206.715604 -237.293383)
			(xy 206.715604 -237.240085) (xy 206.723547 -237.187381) (xy 206.739257 -237.136451) (xy 206.762383 -237.08843)
			(xy 206.792407 -237.044393) (xy 206.828659 -237.005322) (xy 206.87033 -236.972091) (xy 206.916488 -236.945442)
			(xy 206.966102 -236.92597) (xy 207.018064 -236.91411) (xy 207.071214 -236.910127) (xy 207.124364 -236.91411)
			(xy 207.176326 -236.92597) (xy 207.22594 -236.945442) (xy 207.272098 -236.972091) (xy 207.313769 -237.005322)
			(xy 207.350021 -237.044393) (xy 207.380045 -237.08843) (xy 207.403171 -237.136451) (xy 207.418881 -237.187381)
			(xy 207.426824 -237.240085) (xy 207.427322 -237.266734) (xy 207.426824 -237.293383) (xy 207.418881 -237.346087)
			(xy 207.403171 -237.397017) (xy 207.380045 -237.445038) (xy 207.350021 -237.489075) (xy 207.313769 -237.528146)
			(xy 207.272098 -237.561377) (xy 207.22594 -237.588026) (xy 207.176326 -237.607498) (xy 207.124364 -237.619358)
			(xy 207.071214 -237.623342) (xy 207.018064 -237.619358) (xy 206.966102 -237.607498) (xy 206.916488 -237.588026)
			(xy 206.87033 -237.561377) (xy 206.828659 -237.528146) (xy 206.792407 -237.489075) (xy 206.762383 -237.445038)
			(xy 206.739257 -237.397017) (xy 206.723547 -237.346087) (xy 206.715604 -237.293383) (xy 203.326756 -237.293383)
			(xy 203.318813 -237.346087) (xy 203.303103 -237.397017) (xy 203.279977 -237.445038) (xy 203.249953 -237.489075)
			(xy 203.213701 -237.528146) (xy 203.17203 -237.561377) (xy 203.125872 -237.588026) (xy 203.076258 -237.607498)
			(xy 203.024296 -237.619358) (xy 202.971146 -237.623342) (xy 202.917996 -237.619358) (xy 202.866034 -237.607498)
			(xy 202.81642 -237.588026) (xy 202.770262 -237.561377) (xy 202.728591 -237.528146) (xy 202.692339 -237.489075)
			(xy 202.662315 -237.445038) (xy 202.639189 -237.397017) (xy 202.623479 -237.346087) (xy 202.615536 -237.293383)
			(xy 192.339224 -237.293383) (xy 192.331281 -237.346087) (xy 192.315571 -237.397017) (xy 192.292445 -237.445038)
			(xy 192.262421 -237.489075) (xy 192.226169 -237.528146) (xy 192.184498 -237.561377) (xy 192.13834 -237.588026)
			(xy 192.088726 -237.607498) (xy 192.036764 -237.619358) (xy 191.983614 -237.623342) (xy 191.930464 -237.619358)
			(xy 191.878502 -237.607498) (xy 191.828888 -237.588026) (xy 191.78273 -237.561377) (xy 191.741059 -237.528146)
			(xy 191.704807 -237.489075) (xy 191.674783 -237.445038) (xy 191.651657 -237.397017) (xy 191.635947 -237.346087)
			(xy 191.628004 -237.293383) (xy 188.239156 -237.293383) (xy 188.231213 -237.346087) (xy 188.215503 -237.397017)
			(xy 188.192377 -237.445038) (xy 188.162353 -237.489075) (xy 188.126101 -237.528146) (xy 188.08443 -237.561377)
			(xy 188.038272 -237.588026) (xy 187.988658 -237.607498) (xy 187.936696 -237.619358) (xy 187.883546 -237.623342)
			(xy 187.830396 -237.619358) (xy 187.778434 -237.607498) (xy 187.72882 -237.588026) (xy 187.682662 -237.561377)
			(xy 187.640991 -237.528146) (xy 187.604739 -237.489075) (xy 187.574715 -237.445038) (xy 187.551589 -237.397017)
			(xy 187.535879 -237.346087) (xy 187.527936 -237.293383) (xy 177.251624 -237.293383) (xy 177.243681 -237.346087)
			(xy 177.227971 -237.397017) (xy 177.204845 -237.445038) (xy 177.174821 -237.489075) (xy 177.138569 -237.528146)
			(xy 177.096898 -237.561377) (xy 177.05074 -237.588026) (xy 177.001126 -237.607498) (xy 176.949164 -237.619358)
			(xy 176.896014 -237.623342) (xy 176.842864 -237.619358) (xy 176.790902 -237.607498) (xy 176.741288 -237.588026)
			(xy 176.69513 -237.561377) (xy 176.653459 -237.528146) (xy 176.617207 -237.489075) (xy 176.587183 -237.445038)
			(xy 176.564057 -237.397017) (xy 176.548347 -237.346087) (xy 176.540404 -237.293383) (xy 173.151556 -237.293383)
			(xy 173.143613 -237.346087) (xy 173.127903 -237.397017) (xy 173.104777 -237.445038) (xy 173.074753 -237.489075)
			(xy 173.038501 -237.528146) (xy 172.99683 -237.561377) (xy 172.950672 -237.588026) (xy 172.901058 -237.607498)
			(xy 172.849096 -237.619358) (xy 172.795946 -237.623342) (xy 172.742796 -237.619358) (xy 172.690834 -237.607498)
			(xy 172.64122 -237.588026) (xy 172.595062 -237.561377) (xy 172.553391 -237.528146) (xy 172.517139 -237.489075)
			(xy 172.487115 -237.445038) (xy 172.463989 -237.397017) (xy 172.448279 -237.346087) (xy 172.440336 -237.293383)
			(xy 158.88716 -237.293383) (xy 158.88716 -238.143267) (xy 172.440336 -238.143267) (xy 172.440336 -238.089969)
			(xy 172.448279 -238.037265) (xy 172.463989 -237.986335) (xy 172.487115 -237.938314) (xy 172.517139 -237.894277)
			(xy 172.553391 -237.855206) (xy 172.595062 -237.821975) (xy 172.64122 -237.795326) (xy 172.690834 -237.775854)
			(xy 172.742796 -237.763994) (xy 172.795946 -237.760011) (xy 172.849096 -237.763994) (xy 172.901058 -237.775854)
			(xy 172.950672 -237.795326) (xy 172.99683 -237.821975) (xy 173.038501 -237.855206) (xy 173.074753 -237.894277)
			(xy 173.104777 -237.938314) (xy 173.127903 -237.986335) (xy 173.143613 -238.037265) (xy 173.151556 -238.089969)
			(xy 173.152054 -238.116618) (xy 173.151556 -238.143267) (xy 187.527936 -238.143267) (xy 187.527936 -238.089969)
			(xy 187.535879 -238.037265) (xy 187.551589 -237.986335) (xy 187.574715 -237.938314) (xy 187.604739 -237.894277)
			(xy 187.640991 -237.855206) (xy 187.682662 -237.821975) (xy 187.72882 -237.795326) (xy 187.778434 -237.775854)
			(xy 187.830396 -237.763994) (xy 187.883546 -237.760011) (xy 187.936696 -237.763994) (xy 187.988658 -237.775854)
			(xy 188.038272 -237.795326) (xy 188.08443 -237.821975) (xy 188.126101 -237.855206) (xy 188.162353 -237.894277)
			(xy 188.192377 -237.938314) (xy 188.215503 -237.986335) (xy 188.231213 -238.037265) (xy 188.239156 -238.089969)
			(xy 188.239654 -238.116618) (xy 188.239156 -238.143267) (xy 202.615536 -238.143267) (xy 202.615536 -238.089969)
			(xy 202.623479 -238.037265) (xy 202.639189 -237.986335) (xy 202.662315 -237.938314) (xy 202.692339 -237.894277)
			(xy 202.728591 -237.855206) (xy 202.770262 -237.821975) (xy 202.81642 -237.795326) (xy 202.866034 -237.775854)
			(xy 202.917996 -237.763994) (xy 202.971146 -237.760011) (xy 203.024296 -237.763994) (xy 203.076258 -237.775854)
			(xy 203.125872 -237.795326) (xy 203.17203 -237.821975) (xy 203.213701 -237.855206) (xy 203.249953 -237.894277)
			(xy 203.279977 -237.938314) (xy 203.303103 -237.986335) (xy 203.318813 -238.037265) (xy 203.326756 -238.089969)
			(xy 203.327254 -238.116618) (xy 203.326756 -238.143267) (xy 203.318813 -238.195971) (xy 203.303103 -238.246901)
			(xy 203.279977 -238.294922) (xy 203.249953 -238.338959) (xy 203.213701 -238.37803) (xy 203.17203 -238.411261)
			(xy 203.125872 -238.43791) (xy 203.076258 -238.457382) (xy 203.024296 -238.469242) (xy 202.971146 -238.473226)
			(xy 202.917996 -238.469242) (xy 202.866034 -238.457382) (xy 202.81642 -238.43791) (xy 202.770262 -238.411261)
			(xy 202.728591 -238.37803) (xy 202.692339 -238.338959) (xy 202.662315 -238.294922) (xy 202.639189 -238.246901)
			(xy 202.623479 -238.195971) (xy 202.615536 -238.143267) (xy 188.239156 -238.143267) (xy 188.231213 -238.195971)
			(xy 188.215503 -238.246901) (xy 188.192377 -238.294922) (xy 188.162353 -238.338959) (xy 188.126101 -238.37803)
			(xy 188.08443 -238.411261) (xy 188.038272 -238.43791) (xy 187.988658 -238.457382) (xy 187.936696 -238.469242)
			(xy 187.883546 -238.473226) (xy 187.830396 -238.469242) (xy 187.778434 -238.457382) (xy 187.72882 -238.43791)
			(xy 187.682662 -238.411261) (xy 187.640991 -238.37803) (xy 187.604739 -238.338959) (xy 187.574715 -238.294922)
			(xy 187.551589 -238.246901) (xy 187.535879 -238.195971) (xy 187.527936 -238.143267) (xy 173.151556 -238.143267)
			(xy 173.143613 -238.195971) (xy 173.127903 -238.246901) (xy 173.104777 -238.294922) (xy 173.074753 -238.338959)
			(xy 173.038501 -238.37803) (xy 172.99683 -238.411261) (xy 172.950672 -238.43791) (xy 172.901058 -238.457382)
			(xy 172.849096 -238.469242) (xy 172.795946 -238.473226) (xy 172.742796 -238.469242) (xy 172.690834 -238.457382)
			(xy 172.64122 -238.43791) (xy 172.595062 -238.411261) (xy 172.553391 -238.37803) (xy 172.517139 -238.338959)
			(xy 172.487115 -238.294922) (xy 172.463989 -238.246901) (xy 172.448279 -238.195971) (xy 172.440336 -238.143267)
			(xy 158.88716 -238.143267) (xy 158.88716 -238.993405) (xy 176.540404 -238.993405) (xy 176.540404 -238.940107)
			(xy 176.548347 -238.887403) (xy 176.564057 -238.836473) (xy 176.587183 -238.788452) (xy 176.617207 -238.744415)
			(xy 176.653459 -238.705344) (xy 176.69513 -238.672113) (xy 176.741288 -238.645464) (xy 176.790902 -238.625992)
			(xy 176.842864 -238.614132) (xy 176.896014 -238.610149) (xy 176.949164 -238.614132) (xy 177.001126 -238.625992)
			(xy 177.05074 -238.645464) (xy 177.096898 -238.672113) (xy 177.138569 -238.705344) (xy 177.174821 -238.744415)
			(xy 177.204845 -238.788452) (xy 177.227971 -238.836473) (xy 177.243681 -238.887403) (xy 177.251624 -238.940107)
			(xy 177.252122 -238.966756) (xy 177.251624 -238.993405) (xy 191.628004 -238.993405) (xy 191.628004 -238.940107)
			(xy 191.635947 -238.887403) (xy 191.651657 -238.836473) (xy 191.674783 -238.788452) (xy 191.704807 -238.744415)
			(xy 191.741059 -238.705344) (xy 191.78273 -238.672113) (xy 191.828888 -238.645464) (xy 191.878502 -238.625992)
			(xy 191.930464 -238.614132) (xy 191.983614 -238.610149) (xy 192.036764 -238.614132) (xy 192.088726 -238.625992)
			(xy 192.13834 -238.645464) (xy 192.184498 -238.672113) (xy 192.226169 -238.705344) (xy 192.262421 -238.744415)
			(xy 192.292445 -238.788452) (xy 192.315571 -238.836473) (xy 192.331281 -238.887403) (xy 192.339224 -238.940107)
			(xy 192.339722 -238.966756) (xy 192.339224 -238.993405) (xy 206.715604 -238.993405) (xy 206.715604 -238.940107)
			(xy 206.723547 -238.887403) (xy 206.739257 -238.836473) (xy 206.762383 -238.788452) (xy 206.792407 -238.744415)
			(xy 206.828659 -238.705344) (xy 206.87033 -238.672113) (xy 206.916488 -238.645464) (xy 206.966102 -238.625992)
			(xy 207.018064 -238.614132) (xy 207.071214 -238.610149) (xy 207.124364 -238.614132) (xy 207.176326 -238.625992)
			(xy 207.22594 -238.645464) (xy 207.272098 -238.672113) (xy 207.313769 -238.705344) (xy 207.350021 -238.744415)
			(xy 207.380045 -238.788452) (xy 207.403171 -238.836473) (xy 207.418881 -238.887403) (xy 207.426824 -238.940107)
			(xy 207.427322 -238.966756) (xy 207.426824 -238.993405) (xy 207.418881 -239.046109) (xy 207.403171 -239.097039)
			(xy 207.380045 -239.14506) (xy 207.350021 -239.189097) (xy 207.313769 -239.228168) (xy 207.272098 -239.261399)
			(xy 207.22594 -239.288048) (xy 207.176326 -239.30752) (xy 207.124364 -239.31938) (xy 207.071214 -239.323364)
			(xy 207.018064 -239.31938) (xy 206.966102 -239.30752) (xy 206.916488 -239.288048) (xy 206.87033 -239.261399)
			(xy 206.828659 -239.228168) (xy 206.792407 -239.189097) (xy 206.762383 -239.14506) (xy 206.739257 -239.097039)
			(xy 206.723547 -239.046109) (xy 206.715604 -238.993405) (xy 192.339224 -238.993405) (xy 192.331281 -239.046109)
			(xy 192.315571 -239.097039) (xy 192.292445 -239.14506) (xy 192.262421 -239.189097) (xy 192.226169 -239.228168)
			(xy 192.184498 -239.261399) (xy 192.13834 -239.288048) (xy 192.088726 -239.30752) (xy 192.036764 -239.31938)
			(xy 191.983614 -239.323364) (xy 191.930464 -239.31938) (xy 191.878502 -239.30752) (xy 191.828888 -239.288048)
			(xy 191.78273 -239.261399) (xy 191.741059 -239.228168) (xy 191.704807 -239.189097) (xy 191.674783 -239.14506)
			(xy 191.651657 -239.097039) (xy 191.635947 -239.046109) (xy 191.628004 -238.993405) (xy 177.251624 -238.993405)
			(xy 177.243681 -239.046109) (xy 177.227971 -239.097039) (xy 177.204845 -239.14506) (xy 177.174821 -239.189097)
			(xy 177.138569 -239.228168) (xy 177.096898 -239.261399) (xy 177.05074 -239.288048) (xy 177.001126 -239.30752)
			(xy 176.949164 -239.31938) (xy 176.896014 -239.323364) (xy 176.842864 -239.31938) (xy 176.790902 -239.30752)
			(xy 176.741288 -239.288048) (xy 176.69513 -239.261399) (xy 176.653459 -239.228168) (xy 176.617207 -239.189097)
			(xy 176.587183 -239.14506) (xy 176.564057 -239.097039) (xy 176.548347 -239.046109) (xy 176.540404 -238.993405)
			(xy 158.88716 -238.993405) (xy 158.88716 -239.843289) (xy 172.440336 -239.843289) (xy 172.440336 -239.789991)
			(xy 172.448279 -239.737287) (xy 172.463989 -239.686357) (xy 172.487115 -239.638336) (xy 172.517139 -239.594299)
			(xy 172.553391 -239.555228) (xy 172.595062 -239.521997) (xy 172.64122 -239.495348) (xy 172.690834 -239.475876)
			(xy 172.742796 -239.464016) (xy 172.795946 -239.460033) (xy 172.849096 -239.464016) (xy 172.901058 -239.475876)
			(xy 172.950672 -239.495348) (xy 172.99683 -239.521997) (xy 173.038501 -239.555228) (xy 173.074753 -239.594299)
			(xy 173.104777 -239.638336) (xy 173.127903 -239.686357) (xy 173.143613 -239.737287) (xy 173.151556 -239.789991)
			(xy 173.152054 -239.81664) (xy 173.151556 -239.843289) (xy 187.527936 -239.843289) (xy 187.527936 -239.789991)
			(xy 187.535879 -239.737287) (xy 187.551589 -239.686357) (xy 187.574715 -239.638336) (xy 187.604739 -239.594299)
			(xy 187.640991 -239.555228) (xy 187.682662 -239.521997) (xy 187.72882 -239.495348) (xy 187.778434 -239.475876)
			(xy 187.830396 -239.464016) (xy 187.883546 -239.460033) (xy 187.936696 -239.464016) (xy 187.988658 -239.475876)
			(xy 188.038272 -239.495348) (xy 188.08443 -239.521997) (xy 188.126101 -239.555228) (xy 188.162353 -239.594299)
			(xy 188.192377 -239.638336) (xy 188.215503 -239.686357) (xy 188.231213 -239.737287) (xy 188.239156 -239.789991)
			(xy 188.239654 -239.81664) (xy 188.239156 -239.843289) (xy 202.615536 -239.843289) (xy 202.615536 -239.789991)
			(xy 202.623479 -239.737287) (xy 202.639189 -239.686357) (xy 202.662315 -239.638336) (xy 202.692339 -239.594299)
			(xy 202.728591 -239.555228) (xy 202.770262 -239.521997) (xy 202.81642 -239.495348) (xy 202.866034 -239.475876)
			(xy 202.917996 -239.464016) (xy 202.971146 -239.460033) (xy 203.024296 -239.464016) (xy 203.076258 -239.475876)
			(xy 203.125872 -239.495348) (xy 203.17203 -239.521997) (xy 203.213701 -239.555228) (xy 203.249953 -239.594299)
			(xy 203.279977 -239.638336) (xy 203.303103 -239.686357) (xy 203.318813 -239.737287) (xy 203.326756 -239.789991)
			(xy 203.327254 -239.81664) (xy 203.326756 -239.843289) (xy 203.318813 -239.895993) (xy 203.303103 -239.946923)
			(xy 203.279977 -239.994944) (xy 203.249953 -240.038981) (xy 203.213701 -240.078052) (xy 203.17203 -240.111283)
			(xy 203.125872 -240.137932) (xy 203.076258 -240.157404) (xy 203.024296 -240.169264) (xy 202.971146 -240.173248)
			(xy 202.917996 -240.169264) (xy 202.866034 -240.157404) (xy 202.81642 -240.137932) (xy 202.770262 -240.111283)
			(xy 202.728591 -240.078052) (xy 202.692339 -240.038981) (xy 202.662315 -239.994944) (xy 202.639189 -239.946923)
			(xy 202.623479 -239.895993) (xy 202.615536 -239.843289) (xy 188.239156 -239.843289) (xy 188.231213 -239.895993)
			(xy 188.215503 -239.946923) (xy 188.192377 -239.994944) (xy 188.162353 -240.038981) (xy 188.126101 -240.078052)
			(xy 188.08443 -240.111283) (xy 188.038272 -240.137932) (xy 187.988658 -240.157404) (xy 187.936696 -240.169264)
			(xy 187.883546 -240.173248) (xy 187.830396 -240.169264) (xy 187.778434 -240.157404) (xy 187.72882 -240.137932)
			(xy 187.682662 -240.111283) (xy 187.640991 -240.078052) (xy 187.604739 -240.038981) (xy 187.574715 -239.994944)
			(xy 187.551589 -239.946923) (xy 187.535879 -239.895993) (xy 187.527936 -239.843289) (xy 173.151556 -239.843289)
			(xy 173.143613 -239.895993) (xy 173.127903 -239.946923) (xy 173.104777 -239.994944) (xy 173.074753 -240.038981)
			(xy 173.038501 -240.078052) (xy 172.99683 -240.111283) (xy 172.950672 -240.137932) (xy 172.901058 -240.157404)
			(xy 172.849096 -240.169264) (xy 172.795946 -240.173248) (xy 172.742796 -240.169264) (xy 172.690834 -240.157404)
			(xy 172.64122 -240.137932) (xy 172.595062 -240.111283) (xy 172.553391 -240.078052) (xy 172.517139 -240.038981)
			(xy 172.487115 -239.994944) (xy 172.463989 -239.946923) (xy 172.448279 -239.895993) (xy 172.440336 -239.843289)
			(xy 158.88716 -239.843289) (xy 158.88716 -240.693427) (xy 176.540404 -240.693427) (xy 176.540404 -240.640129)
			(xy 176.548347 -240.587425) (xy 176.564057 -240.536495) (xy 176.587183 -240.488474) (xy 176.617207 -240.444437)
			(xy 176.653459 -240.405366) (xy 176.69513 -240.372135) (xy 176.741288 -240.345486) (xy 176.790902 -240.326014)
			(xy 176.842864 -240.314154) (xy 176.896014 -240.310171) (xy 176.949164 -240.314154) (xy 177.001126 -240.326014)
			(xy 177.05074 -240.345486) (xy 177.096898 -240.372135) (xy 177.138569 -240.405366) (xy 177.174821 -240.444437)
			(xy 177.204845 -240.488474) (xy 177.227971 -240.536495) (xy 177.243681 -240.587425) (xy 177.251624 -240.640129)
			(xy 177.252122 -240.666778) (xy 177.251624 -240.693427) (xy 191.628004 -240.693427) (xy 191.628004 -240.640129)
			(xy 191.635947 -240.587425) (xy 191.651657 -240.536495) (xy 191.674783 -240.488474) (xy 191.704807 -240.444437)
			(xy 191.741059 -240.405366) (xy 191.78273 -240.372135) (xy 191.828888 -240.345486) (xy 191.878502 -240.326014)
			(xy 191.930464 -240.314154) (xy 191.983614 -240.310171) (xy 192.036764 -240.314154) (xy 192.088726 -240.326014)
			(xy 192.13834 -240.345486) (xy 192.184498 -240.372135) (xy 192.226169 -240.405366) (xy 192.262421 -240.444437)
			(xy 192.292445 -240.488474) (xy 192.315571 -240.536495) (xy 192.331281 -240.587425) (xy 192.339224 -240.640129)
			(xy 192.339722 -240.666778) (xy 192.339224 -240.693427) (xy 206.715604 -240.693427) (xy 206.715604 -240.640129)
			(xy 206.723547 -240.587425) (xy 206.739257 -240.536495) (xy 206.762383 -240.488474) (xy 206.792407 -240.444437)
			(xy 206.828659 -240.405366) (xy 206.87033 -240.372135) (xy 206.916488 -240.345486) (xy 206.966102 -240.326014)
			(xy 207.018064 -240.314154) (xy 207.071214 -240.310171) (xy 207.124364 -240.314154) (xy 207.176326 -240.326014)
			(xy 207.22594 -240.345486) (xy 207.272098 -240.372135) (xy 207.313769 -240.405366) (xy 207.350021 -240.444437)
			(xy 207.380045 -240.488474) (xy 207.403171 -240.536495) (xy 207.418881 -240.587425) (xy 207.426824 -240.640129)
			(xy 207.427322 -240.666778) (xy 207.426824 -240.693427) (xy 207.418881 -240.746131) (xy 207.403171 -240.797061)
			(xy 207.380045 -240.845082) (xy 207.350021 -240.889119) (xy 207.313769 -240.92819) (xy 207.272098 -240.961421)
			(xy 207.22594 -240.98807) (xy 207.176326 -241.007542) (xy 207.124364 -241.019402) (xy 207.071214 -241.023386)
			(xy 207.018064 -241.019402) (xy 206.966102 -241.007542) (xy 206.916488 -240.98807) (xy 206.87033 -240.961421)
			(xy 206.828659 -240.92819) (xy 206.792407 -240.889119) (xy 206.762383 -240.845082) (xy 206.739257 -240.797061)
			(xy 206.723547 -240.746131) (xy 206.715604 -240.693427) (xy 192.339224 -240.693427) (xy 192.331281 -240.746131)
			(xy 192.315571 -240.797061) (xy 192.292445 -240.845082) (xy 192.262421 -240.889119) (xy 192.226169 -240.92819)
			(xy 192.184498 -240.961421) (xy 192.13834 -240.98807) (xy 192.088726 -241.007542) (xy 192.036764 -241.019402)
			(xy 191.983614 -241.023386) (xy 191.930464 -241.019402) (xy 191.878502 -241.007542) (xy 191.828888 -240.98807)
			(xy 191.78273 -240.961421) (xy 191.741059 -240.92819) (xy 191.704807 -240.889119) (xy 191.674783 -240.845082)
			(xy 191.651657 -240.797061) (xy 191.635947 -240.746131) (xy 191.628004 -240.693427) (xy 177.251624 -240.693427)
			(xy 177.243681 -240.746131) (xy 177.227971 -240.797061) (xy 177.204845 -240.845082) (xy 177.174821 -240.889119)
			(xy 177.138569 -240.92819) (xy 177.096898 -240.961421) (xy 177.05074 -240.98807) (xy 177.001126 -241.007542)
			(xy 176.949164 -241.019402) (xy 176.896014 -241.023386) (xy 176.842864 -241.019402) (xy 176.790902 -241.007542)
			(xy 176.741288 -240.98807) (xy 176.69513 -240.961421) (xy 176.653459 -240.92819) (xy 176.617207 -240.889119)
			(xy 176.587183 -240.845082) (xy 176.564057 -240.797061) (xy 176.548347 -240.746131) (xy 176.540404 -240.693427)
			(xy 158.88716 -240.693427) (xy 158.88716 -241.543311) (xy 172.440336 -241.543311) (xy 172.440336 -241.490013)
			(xy 172.448279 -241.437309) (xy 172.463989 -241.386379) (xy 172.487115 -241.338358) (xy 172.517139 -241.294321)
			(xy 172.553391 -241.25525) (xy 172.595062 -241.222019) (xy 172.64122 -241.19537) (xy 172.690834 -241.175898)
			(xy 172.742796 -241.164038) (xy 172.795946 -241.160055) (xy 172.849096 -241.164038) (xy 172.901058 -241.175898)
			(xy 172.950672 -241.19537) (xy 172.99683 -241.222019) (xy 173.038501 -241.25525) (xy 173.074753 -241.294321)
			(xy 173.104777 -241.338358) (xy 173.127903 -241.386379) (xy 173.143613 -241.437309) (xy 173.151556 -241.490013)
			(xy 173.152054 -241.516662) (xy 173.151556 -241.543311) (xy 187.527936 -241.543311) (xy 187.527936 -241.490013)
			(xy 187.535879 -241.437309) (xy 187.551589 -241.386379) (xy 187.574715 -241.338358) (xy 187.604739 -241.294321)
			(xy 187.640991 -241.25525) (xy 187.682662 -241.222019) (xy 187.72882 -241.19537) (xy 187.778434 -241.175898)
			(xy 187.830396 -241.164038) (xy 187.883546 -241.160055) (xy 187.936696 -241.164038) (xy 187.988658 -241.175898)
			(xy 188.038272 -241.19537) (xy 188.08443 -241.222019) (xy 188.126101 -241.25525) (xy 188.162353 -241.294321)
			(xy 188.192377 -241.338358) (xy 188.215503 -241.386379) (xy 188.231213 -241.437309) (xy 188.239156 -241.490013)
			(xy 188.239654 -241.516662) (xy 188.239156 -241.543311) (xy 202.615536 -241.543311) (xy 202.615536 -241.490013)
			(xy 202.623479 -241.437309) (xy 202.639189 -241.386379) (xy 202.662315 -241.338358) (xy 202.692339 -241.294321)
			(xy 202.728591 -241.25525) (xy 202.770262 -241.222019) (xy 202.81642 -241.19537) (xy 202.866034 -241.175898)
			(xy 202.917996 -241.164038) (xy 202.971146 -241.160055) (xy 203.024296 -241.164038) (xy 203.076258 -241.175898)
			(xy 203.125872 -241.19537) (xy 203.17203 -241.222019) (xy 203.213701 -241.25525) (xy 203.249953 -241.294321)
			(xy 203.279977 -241.338358) (xy 203.303103 -241.386379) (xy 203.318813 -241.437309) (xy 203.326756 -241.490013)
			(xy 203.327254 -241.516662) (xy 203.326756 -241.543311) (xy 203.318813 -241.596015) (xy 203.303103 -241.646945)
			(xy 203.279977 -241.694966) (xy 203.249953 -241.739003) (xy 203.213701 -241.778074) (xy 203.17203 -241.811305)
			(xy 203.125872 -241.837954) (xy 203.076258 -241.857426) (xy 203.024296 -241.869286) (xy 202.971146 -241.87327)
			(xy 202.917996 -241.869286) (xy 202.866034 -241.857426) (xy 202.81642 -241.837954) (xy 202.770262 -241.811305)
			(xy 202.728591 -241.778074) (xy 202.692339 -241.739003) (xy 202.662315 -241.694966) (xy 202.639189 -241.646945)
			(xy 202.623479 -241.596015) (xy 202.615536 -241.543311) (xy 188.239156 -241.543311) (xy 188.231213 -241.596015)
			(xy 188.215503 -241.646945) (xy 188.192377 -241.694966) (xy 188.162353 -241.739003) (xy 188.126101 -241.778074)
			(xy 188.08443 -241.811305) (xy 188.038272 -241.837954) (xy 187.988658 -241.857426) (xy 187.936696 -241.869286)
			(xy 187.883546 -241.87327) (xy 187.830396 -241.869286) (xy 187.778434 -241.857426) (xy 187.72882 -241.837954)
			(xy 187.682662 -241.811305) (xy 187.640991 -241.778074) (xy 187.604739 -241.739003) (xy 187.574715 -241.694966)
			(xy 187.551589 -241.646945) (xy 187.535879 -241.596015) (xy 187.527936 -241.543311) (xy 173.151556 -241.543311)
			(xy 173.143613 -241.596015) (xy 173.127903 -241.646945) (xy 173.104777 -241.694966) (xy 173.074753 -241.739003)
			(xy 173.038501 -241.778074) (xy 172.99683 -241.811305) (xy 172.950672 -241.837954) (xy 172.901058 -241.857426)
			(xy 172.849096 -241.869286) (xy 172.795946 -241.87327) (xy 172.742796 -241.869286) (xy 172.690834 -241.857426)
			(xy 172.64122 -241.837954) (xy 172.595062 -241.811305) (xy 172.553391 -241.778074) (xy 172.517139 -241.739003)
			(xy 172.487115 -241.694966) (xy 172.463989 -241.646945) (xy 172.448279 -241.596015) (xy 172.440336 -241.543311)
			(xy 158.88716 -241.543311) (xy 158.88716 -242.393449) (xy 161.427404 -242.393449) (xy 161.427404 -242.340151)
			(xy 161.435347 -242.287447) (xy 161.451057 -242.236517) (xy 161.474183 -242.188496) (xy 161.504207 -242.144459)
			(xy 161.540459 -242.105388) (xy 161.58213 -242.072157) (xy 161.628288 -242.045508) (xy 161.677902 -242.026036)
			(xy 161.729864 -242.014176) (xy 161.783014 -242.010193) (xy 161.836164 -242.014176) (xy 161.888126 -242.026036)
			(xy 161.93774 -242.045508) (xy 161.983898 -242.072157) (xy 162.025569 -242.105388) (xy 162.061821 -242.144459)
			(xy 162.091845 -242.188496) (xy 162.114971 -242.236517) (xy 162.130681 -242.287447) (xy 162.138624 -242.340151)
			(xy 162.139122 -242.3668) (xy 162.138624 -242.393449) (xy 168.971204 -242.393449) (xy 168.971204 -242.340151)
			(xy 168.979147 -242.287447) (xy 168.994857 -242.236517) (xy 169.017983 -242.188496) (xy 169.048007 -242.144459)
			(xy 169.084259 -242.105388) (xy 169.12593 -242.072157) (xy 169.172088 -242.045508) (xy 169.221702 -242.026036)
			(xy 169.273664 -242.014176) (xy 169.326814 -242.010193) (xy 169.379964 -242.014176) (xy 169.431926 -242.026036)
			(xy 169.48154 -242.045508) (xy 169.527698 -242.072157) (xy 169.569369 -242.105388) (xy 169.605621 -242.144459)
			(xy 169.635645 -242.188496) (xy 169.658771 -242.236517) (xy 169.674481 -242.287447) (xy 169.682424 -242.340151)
			(xy 169.682922 -242.3668) (xy 169.682424 -242.393449) (xy 176.540404 -242.393449) (xy 176.540404 -242.340151)
			(xy 176.548347 -242.287447) (xy 176.564057 -242.236517) (xy 176.587183 -242.188496) (xy 176.617207 -242.144459)
			(xy 176.653459 -242.105388) (xy 176.69513 -242.072157) (xy 176.741288 -242.045508) (xy 176.790902 -242.026036)
			(xy 176.842864 -242.014176) (xy 176.896014 -242.010193) (xy 176.949164 -242.014176) (xy 177.001126 -242.026036)
			(xy 177.05074 -242.045508) (xy 177.096898 -242.072157) (xy 177.138569 -242.105388) (xy 177.174821 -242.144459)
			(xy 177.204845 -242.188496) (xy 177.227971 -242.236517) (xy 177.243681 -242.287447) (xy 177.251624 -242.340151)
			(xy 177.252122 -242.3668) (xy 177.251624 -242.393449) (xy 184.058804 -242.393449) (xy 184.058804 -242.340151)
			(xy 184.066747 -242.287447) (xy 184.082457 -242.236517) (xy 184.105583 -242.188496) (xy 184.135607 -242.144459)
			(xy 184.171859 -242.105388) (xy 184.21353 -242.072157) (xy 184.259688 -242.045508) (xy 184.309302 -242.026036)
			(xy 184.361264 -242.014176) (xy 184.414414 -242.010193) (xy 184.467564 -242.014176) (xy 184.519526 -242.026036)
			(xy 184.56914 -242.045508) (xy 184.615298 -242.072157) (xy 184.656969 -242.105388) (xy 184.693221 -242.144459)
			(xy 184.723245 -242.188496) (xy 184.746371 -242.236517) (xy 184.762081 -242.287447) (xy 184.770024 -242.340151)
			(xy 184.770522 -242.3668) (xy 184.770024 -242.393449) (xy 191.628004 -242.393449) (xy 191.628004 -242.340151)
			(xy 191.635947 -242.287447) (xy 191.651657 -242.236517) (xy 191.674783 -242.188496) (xy 191.704807 -242.144459)
			(xy 191.741059 -242.105388) (xy 191.78273 -242.072157) (xy 191.828888 -242.045508) (xy 191.878502 -242.026036)
			(xy 191.930464 -242.014176) (xy 191.983614 -242.010193) (xy 192.036764 -242.014176) (xy 192.088726 -242.026036)
			(xy 192.13834 -242.045508) (xy 192.184498 -242.072157) (xy 192.226169 -242.105388) (xy 192.262421 -242.144459)
			(xy 192.292445 -242.188496) (xy 192.315571 -242.236517) (xy 192.331281 -242.287447) (xy 192.339224 -242.340151)
			(xy 192.339722 -242.3668) (xy 192.339224 -242.393449) (xy 199.171804 -242.393449) (xy 199.171804 -242.340151)
			(xy 199.179747 -242.287447) (xy 199.195457 -242.236517) (xy 199.218583 -242.188496) (xy 199.248607 -242.144459)
			(xy 199.284859 -242.105388) (xy 199.32653 -242.072157) (xy 199.372688 -242.045508) (xy 199.422302 -242.026036)
			(xy 199.474264 -242.014176) (xy 199.527414 -242.010193) (xy 199.580564 -242.014176) (xy 199.632526 -242.026036)
			(xy 199.68214 -242.045508) (xy 199.728298 -242.072157) (xy 199.769969 -242.105388) (xy 199.806221 -242.144459)
			(xy 199.836245 -242.188496) (xy 199.859371 -242.236517) (xy 199.875081 -242.287447) (xy 199.883024 -242.340151)
			(xy 199.883522 -242.3668) (xy 199.883024 -242.393449) (xy 206.715604 -242.393449) (xy 206.715604 -242.340151)
			(xy 206.723547 -242.287447) (xy 206.739257 -242.236517) (xy 206.762383 -242.188496) (xy 206.792407 -242.144459)
			(xy 206.828659 -242.105388) (xy 206.87033 -242.072157) (xy 206.916488 -242.045508) (xy 206.966102 -242.026036)
			(xy 207.018064 -242.014176) (xy 207.071214 -242.010193) (xy 207.124364 -242.014176) (xy 207.176326 -242.026036)
			(xy 207.22594 -242.045508) (xy 207.272098 -242.072157) (xy 207.313769 -242.105388) (xy 207.350021 -242.144459)
			(xy 207.380045 -242.188496) (xy 207.403171 -242.236517) (xy 207.418881 -242.287447) (xy 207.426824 -242.340151)
			(xy 207.427322 -242.3668) (xy 207.426824 -242.393449) (xy 214.234004 -242.393449) (xy 214.234004 -242.340151)
			(xy 214.241947 -242.287447) (xy 214.257657 -242.236517) (xy 214.280783 -242.188496) (xy 214.310807 -242.144459)
			(xy 214.347059 -242.105388) (xy 214.38873 -242.072157) (xy 214.434888 -242.045508) (xy 214.484502 -242.026036)
			(xy 214.536464 -242.014176) (xy 214.589614 -242.010193) (xy 214.642764 -242.014176) (xy 214.694726 -242.026036)
			(xy 214.74434 -242.045508) (xy 214.790498 -242.072157) (xy 214.832169 -242.105388) (xy 214.868421 -242.144459)
			(xy 214.898445 -242.188496) (xy 214.921571 -242.236517) (xy 214.937281 -242.287447) (xy 214.945224 -242.340151)
			(xy 214.945722 -242.3668) (xy 214.945224 -242.393449) (xy 214.937281 -242.446153) (xy 214.921571 -242.497083)
			(xy 214.898445 -242.545104) (xy 214.868421 -242.589141) (xy 214.832169 -242.628212) (xy 214.790498 -242.661443)
			(xy 214.74434 -242.688092) (xy 214.694726 -242.707564) (xy 214.642764 -242.719424) (xy 214.589614 -242.723408)
			(xy 214.536464 -242.719424) (xy 214.484502 -242.707564) (xy 214.434888 -242.688092) (xy 214.38873 -242.661443)
			(xy 214.347059 -242.628212) (xy 214.310807 -242.589141) (xy 214.280783 -242.545104) (xy 214.257657 -242.497083)
			(xy 214.241947 -242.446153) (xy 214.234004 -242.393449) (xy 207.426824 -242.393449) (xy 207.418881 -242.446153)
			(xy 207.403171 -242.497083) (xy 207.380045 -242.545104) (xy 207.350021 -242.589141) (xy 207.313769 -242.628212)
			(xy 207.272098 -242.661443) (xy 207.22594 -242.688092) (xy 207.176326 -242.707564) (xy 207.124364 -242.719424)
			(xy 207.071214 -242.723408) (xy 207.018064 -242.719424) (xy 206.966102 -242.707564) (xy 206.916488 -242.688092)
			(xy 206.87033 -242.661443) (xy 206.828659 -242.628212) (xy 206.792407 -242.589141) (xy 206.762383 -242.545104)
			(xy 206.739257 -242.497083) (xy 206.723547 -242.446153) (xy 206.715604 -242.393449) (xy 199.883024 -242.393449)
			(xy 199.875081 -242.446153) (xy 199.859371 -242.497083) (xy 199.836245 -242.545104) (xy 199.806221 -242.589141)
			(xy 199.769969 -242.628212) (xy 199.728298 -242.661443) (xy 199.68214 -242.688092) (xy 199.632526 -242.707564)
			(xy 199.580564 -242.719424) (xy 199.527414 -242.723408) (xy 199.474264 -242.719424) (xy 199.422302 -242.707564)
			(xy 199.372688 -242.688092) (xy 199.32653 -242.661443) (xy 199.284859 -242.628212) (xy 199.248607 -242.589141)
			(xy 199.218583 -242.545104) (xy 199.195457 -242.497083) (xy 199.179747 -242.446153) (xy 199.171804 -242.393449)
			(xy 192.339224 -242.393449) (xy 192.331281 -242.446153) (xy 192.315571 -242.497083) (xy 192.292445 -242.545104)
			(xy 192.262421 -242.589141) (xy 192.226169 -242.628212) (xy 192.184498 -242.661443) (xy 192.13834 -242.688092)
			(xy 192.088726 -242.707564) (xy 192.036764 -242.719424) (xy 191.983614 -242.723408) (xy 191.930464 -242.719424)
			(xy 191.878502 -242.707564) (xy 191.828888 -242.688092) (xy 191.78273 -242.661443) (xy 191.741059 -242.628212)
			(xy 191.704807 -242.589141) (xy 191.674783 -242.545104) (xy 191.651657 -242.497083) (xy 191.635947 -242.446153)
			(xy 191.628004 -242.393449) (xy 184.770024 -242.393449) (xy 184.762081 -242.446153) (xy 184.746371 -242.497083)
			(xy 184.723245 -242.545104) (xy 184.693221 -242.589141) (xy 184.656969 -242.628212) (xy 184.615298 -242.661443)
			(xy 184.56914 -242.688092) (xy 184.519526 -242.707564) (xy 184.467564 -242.719424) (xy 184.414414 -242.723408)
			(xy 184.361264 -242.719424) (xy 184.309302 -242.707564) (xy 184.259688 -242.688092) (xy 184.21353 -242.661443)
			(xy 184.171859 -242.628212) (xy 184.135607 -242.589141) (xy 184.105583 -242.545104) (xy 184.082457 -242.497083)
			(xy 184.066747 -242.446153) (xy 184.058804 -242.393449) (xy 177.251624 -242.393449) (xy 177.243681 -242.446153)
			(xy 177.227971 -242.497083) (xy 177.204845 -242.545104) (xy 177.174821 -242.589141) (xy 177.138569 -242.628212)
			(xy 177.096898 -242.661443) (xy 177.05074 -242.688092) (xy 177.001126 -242.707564) (xy 176.949164 -242.719424)
			(xy 176.896014 -242.723408) (xy 176.842864 -242.719424) (xy 176.790902 -242.707564) (xy 176.741288 -242.688092)
			(xy 176.69513 -242.661443) (xy 176.653459 -242.628212) (xy 176.617207 -242.589141) (xy 176.587183 -242.545104)
			(xy 176.564057 -242.497083) (xy 176.548347 -242.446153) (xy 176.540404 -242.393449) (xy 169.682424 -242.393449)
			(xy 169.674481 -242.446153) (xy 169.658771 -242.497083) (xy 169.635645 -242.545104) (xy 169.605621 -242.589141)
			(xy 169.569369 -242.628212) (xy 169.527698 -242.661443) (xy 169.48154 -242.688092) (xy 169.431926 -242.707564)
			(xy 169.379964 -242.719424) (xy 169.326814 -242.723408) (xy 169.273664 -242.719424) (xy 169.221702 -242.707564)
			(xy 169.172088 -242.688092) (xy 169.12593 -242.661443) (xy 169.084259 -242.628212) (xy 169.048007 -242.589141)
			(xy 169.017983 -242.545104) (xy 168.994857 -242.497083) (xy 168.979147 -242.446153) (xy 168.971204 -242.393449)
			(xy 162.138624 -242.393449) (xy 162.130681 -242.446153) (xy 162.114971 -242.497083) (xy 162.091845 -242.545104)
			(xy 162.061821 -242.589141) (xy 162.025569 -242.628212) (xy 161.983898 -242.661443) (xy 161.93774 -242.688092)
			(xy 161.888126 -242.707564) (xy 161.836164 -242.719424) (xy 161.783014 -242.723408) (xy 161.729864 -242.719424)
			(xy 161.677902 -242.707564) (xy 161.628288 -242.688092) (xy 161.58213 -242.661443) (xy 161.540459 -242.628212)
			(xy 161.504207 -242.589141) (xy 161.474183 -242.545104) (xy 161.451057 -242.497083) (xy 161.435347 -242.446153)
			(xy 161.427404 -242.393449) (xy 158.88716 -242.393449) (xy 158.88716 -243.243333) (xy 161.427404 -243.243333)
			(xy 161.427404 -243.190035) (xy 161.435347 -243.137331) (xy 161.451057 -243.086401) (xy 161.474183 -243.03838)
			(xy 161.504207 -242.994343) (xy 161.540459 -242.955272) (xy 161.58213 -242.922041) (xy 161.628288 -242.895392)
			(xy 161.677902 -242.87592) (xy 161.729864 -242.86406) (xy 161.783014 -242.860077) (xy 161.836164 -242.86406)
			(xy 161.888126 -242.87592) (xy 161.93774 -242.895392) (xy 161.983898 -242.922041) (xy 162.025569 -242.955272)
			(xy 162.061821 -242.994343) (xy 162.091845 -243.03838) (xy 162.114971 -243.086401) (xy 162.130681 -243.137331)
			(xy 162.138624 -243.190035) (xy 162.139122 -243.216684) (xy 162.138624 -243.243333) (xy 164.871136 -243.243333)
			(xy 164.871136 -243.190035) (xy 164.879079 -243.137331) (xy 164.894789 -243.086401) (xy 164.917915 -243.03838)
			(xy 164.947939 -242.994343) (xy 164.984191 -242.955272) (xy 165.025862 -242.922041) (xy 165.07202 -242.895392)
			(xy 165.121634 -242.87592) (xy 165.173596 -242.86406) (xy 165.226746 -242.860077) (xy 165.279896 -242.86406)
			(xy 165.331858 -242.87592) (xy 165.381472 -242.895392) (xy 165.42763 -242.922041) (xy 165.469301 -242.955272)
			(xy 165.505553 -242.994343) (xy 165.535577 -243.03838) (xy 165.558703 -243.086401) (xy 165.574413 -243.137331)
			(xy 165.582356 -243.190035) (xy 165.582854 -243.216684) (xy 165.582356 -243.243333) (xy 168.971204 -243.243333)
			(xy 168.971204 -243.190035) (xy 168.979147 -243.137331) (xy 168.994857 -243.086401) (xy 169.017983 -243.03838)
			(xy 169.048007 -242.994343) (xy 169.084259 -242.955272) (xy 169.12593 -242.922041) (xy 169.172088 -242.895392)
			(xy 169.221702 -242.87592) (xy 169.273664 -242.86406) (xy 169.326814 -242.860077) (xy 169.379964 -242.86406)
			(xy 169.431926 -242.87592) (xy 169.48154 -242.895392) (xy 169.527698 -242.922041) (xy 169.569369 -242.955272)
			(xy 169.605621 -242.994343) (xy 169.635645 -243.03838) (xy 169.658771 -243.086401) (xy 169.674481 -243.137331)
			(xy 169.682424 -243.190035) (xy 169.682922 -243.216684) (xy 169.682424 -243.243333) (xy 172.440336 -243.243333)
			(xy 172.440336 -243.190035) (xy 172.448279 -243.137331) (xy 172.463989 -243.086401) (xy 172.487115 -243.03838)
			(xy 172.517139 -242.994343) (xy 172.553391 -242.955272) (xy 172.595062 -242.922041) (xy 172.64122 -242.895392)
			(xy 172.690834 -242.87592) (xy 172.742796 -242.86406) (xy 172.795946 -242.860077) (xy 172.849096 -242.86406)
			(xy 172.901058 -242.87592) (xy 172.950672 -242.895392) (xy 172.99683 -242.922041) (xy 173.038501 -242.955272)
			(xy 173.074753 -242.994343) (xy 173.104777 -243.03838) (xy 173.127903 -243.086401) (xy 173.143613 -243.137331)
			(xy 173.151556 -243.190035) (xy 173.152054 -243.216684) (xy 173.151556 -243.243333) (xy 176.540404 -243.243333)
			(xy 176.540404 -243.190035) (xy 176.548347 -243.137331) (xy 176.564057 -243.086401) (xy 176.587183 -243.03838)
			(xy 176.617207 -242.994343) (xy 176.653459 -242.955272) (xy 176.69513 -242.922041) (xy 176.741288 -242.895392)
			(xy 176.790902 -242.87592) (xy 176.842864 -242.86406) (xy 176.896014 -242.860077) (xy 176.949164 -242.86406)
			(xy 177.001126 -242.87592) (xy 177.05074 -242.895392) (xy 177.096898 -242.922041) (xy 177.138569 -242.955272)
			(xy 177.174821 -242.994343) (xy 177.204845 -243.03838) (xy 177.227971 -243.086401) (xy 177.243681 -243.137331)
			(xy 177.251624 -243.190035) (xy 177.252122 -243.216684) (xy 177.251624 -243.243333) (xy 179.958736 -243.243333)
			(xy 179.958736 -243.190035) (xy 179.966679 -243.137331) (xy 179.982389 -243.086401) (xy 180.005515 -243.03838)
			(xy 180.035539 -242.994343) (xy 180.071791 -242.955272) (xy 180.113462 -242.922041) (xy 180.15962 -242.895392)
			(xy 180.209234 -242.87592) (xy 180.261196 -242.86406) (xy 180.314346 -242.860077) (xy 180.367496 -242.86406)
			(xy 180.419458 -242.87592) (xy 180.469072 -242.895392) (xy 180.51523 -242.922041) (xy 180.556901 -242.955272)
			(xy 180.593153 -242.994343) (xy 180.623177 -243.03838) (xy 180.646303 -243.086401) (xy 180.662013 -243.137331)
			(xy 180.669956 -243.190035) (xy 180.670454 -243.216684) (xy 180.669956 -243.243333) (xy 184.058804 -243.243333)
			(xy 184.058804 -243.190035) (xy 184.066747 -243.137331) (xy 184.082457 -243.086401) (xy 184.105583 -243.03838)
			(xy 184.135607 -242.994343) (xy 184.171859 -242.955272) (xy 184.21353 -242.922041) (xy 184.259688 -242.895392)
			(xy 184.309302 -242.87592) (xy 184.361264 -242.86406) (xy 184.414414 -242.860077) (xy 184.467564 -242.86406)
			(xy 184.519526 -242.87592) (xy 184.56914 -242.895392) (xy 184.615298 -242.922041) (xy 184.656969 -242.955272)
			(xy 184.693221 -242.994343) (xy 184.723245 -243.03838) (xy 184.746371 -243.086401) (xy 184.762081 -243.137331)
			(xy 184.770024 -243.190035) (xy 184.770522 -243.216684) (xy 184.770024 -243.243333) (xy 187.527936 -243.243333)
			(xy 187.527936 -243.190035) (xy 187.535879 -243.137331) (xy 187.551589 -243.086401) (xy 187.574715 -243.03838)
			(xy 187.604739 -242.994343) (xy 187.640991 -242.955272) (xy 187.682662 -242.922041) (xy 187.72882 -242.895392)
			(xy 187.778434 -242.87592) (xy 187.830396 -242.86406) (xy 187.883546 -242.860077) (xy 187.936696 -242.86406)
			(xy 187.988658 -242.87592) (xy 188.038272 -242.895392) (xy 188.08443 -242.922041) (xy 188.126101 -242.955272)
			(xy 188.162353 -242.994343) (xy 188.192377 -243.03838) (xy 188.215503 -243.086401) (xy 188.231213 -243.137331)
			(xy 188.239156 -243.190035) (xy 188.239654 -243.216684) (xy 188.239156 -243.243333) (xy 191.628004 -243.243333)
			(xy 191.628004 -243.190035) (xy 191.635947 -243.137331) (xy 191.651657 -243.086401) (xy 191.674783 -243.03838)
			(xy 191.704807 -242.994343) (xy 191.741059 -242.955272) (xy 191.78273 -242.922041) (xy 191.828888 -242.895392)
			(xy 191.878502 -242.87592) (xy 191.930464 -242.86406) (xy 191.983614 -242.860077) (xy 192.036764 -242.86406)
			(xy 192.088726 -242.87592) (xy 192.13834 -242.895392) (xy 192.184498 -242.922041) (xy 192.226169 -242.955272)
			(xy 192.262421 -242.994343) (xy 192.292445 -243.03838) (xy 192.315571 -243.086401) (xy 192.331281 -243.137331)
			(xy 192.339224 -243.190035) (xy 192.339722 -243.216684) (xy 192.339224 -243.243333) (xy 195.071736 -243.243333)
			(xy 195.071736 -243.190035) (xy 195.079679 -243.137331) (xy 195.095389 -243.086401) (xy 195.118515 -243.03838)
			(xy 195.148539 -242.994343) (xy 195.184791 -242.955272) (xy 195.226462 -242.922041) (xy 195.27262 -242.895392)
			(xy 195.322234 -242.87592) (xy 195.374196 -242.86406) (xy 195.427346 -242.860077) (xy 195.480496 -242.86406)
			(xy 195.532458 -242.87592) (xy 195.582072 -242.895392) (xy 195.62823 -242.922041) (xy 195.669901 -242.955272)
			(xy 195.706153 -242.994343) (xy 195.736177 -243.03838) (xy 195.759303 -243.086401) (xy 195.775013 -243.137331)
			(xy 195.782956 -243.190035) (xy 195.783454 -243.216684) (xy 195.782956 -243.243333) (xy 199.171804 -243.243333)
			(xy 199.171804 -243.190035) (xy 199.179747 -243.137331) (xy 199.195457 -243.086401) (xy 199.218583 -243.03838)
			(xy 199.248607 -242.994343) (xy 199.284859 -242.955272) (xy 199.32653 -242.922041) (xy 199.372688 -242.895392)
			(xy 199.422302 -242.87592) (xy 199.474264 -242.86406) (xy 199.527414 -242.860077) (xy 199.580564 -242.86406)
			(xy 199.632526 -242.87592) (xy 199.68214 -242.895392) (xy 199.728298 -242.922041) (xy 199.769969 -242.955272)
			(xy 199.806221 -242.994343) (xy 199.836245 -243.03838) (xy 199.859371 -243.086401) (xy 199.875081 -243.137331)
			(xy 199.883024 -243.190035) (xy 199.883522 -243.216684) (xy 199.883024 -243.243333) (xy 202.615536 -243.243333)
			(xy 202.615536 -243.190035) (xy 202.623479 -243.137331) (xy 202.639189 -243.086401) (xy 202.662315 -243.03838)
			(xy 202.692339 -242.994343) (xy 202.728591 -242.955272) (xy 202.770262 -242.922041) (xy 202.81642 -242.895392)
			(xy 202.866034 -242.87592) (xy 202.917996 -242.86406) (xy 202.971146 -242.860077) (xy 203.024296 -242.86406)
			(xy 203.076258 -242.87592) (xy 203.125872 -242.895392) (xy 203.17203 -242.922041) (xy 203.213701 -242.955272)
			(xy 203.249953 -242.994343) (xy 203.279977 -243.03838) (xy 203.303103 -243.086401) (xy 203.318813 -243.137331)
			(xy 203.326756 -243.190035) (xy 203.327254 -243.216684) (xy 203.326756 -243.243333) (xy 206.715604 -243.243333)
			(xy 206.715604 -243.190035) (xy 206.723547 -243.137331) (xy 206.739257 -243.086401) (xy 206.762383 -243.03838)
			(xy 206.792407 -242.994343) (xy 206.828659 -242.955272) (xy 206.87033 -242.922041) (xy 206.916488 -242.895392)
			(xy 206.966102 -242.87592) (xy 207.018064 -242.86406) (xy 207.071214 -242.860077) (xy 207.124364 -242.86406)
			(xy 207.176326 -242.87592) (xy 207.22594 -242.895392) (xy 207.272098 -242.922041) (xy 207.313769 -242.955272)
			(xy 207.350021 -242.994343) (xy 207.380045 -243.03838) (xy 207.403171 -243.086401) (xy 207.418881 -243.137331)
			(xy 207.426824 -243.190035) (xy 207.427322 -243.216684) (xy 207.426824 -243.243333) (xy 210.159336 -243.243333)
			(xy 210.159336 -243.190035) (xy 210.167279 -243.137331) (xy 210.182989 -243.086401) (xy 210.206115 -243.03838)
			(xy 210.236139 -242.994343) (xy 210.272391 -242.955272) (xy 210.314062 -242.922041) (xy 210.36022 -242.895392)
			(xy 210.409834 -242.87592) (xy 210.461796 -242.86406) (xy 210.514946 -242.860077) (xy 210.568096 -242.86406)
			(xy 210.620058 -242.87592) (xy 210.669672 -242.895392) (xy 210.71583 -242.922041) (xy 210.757501 -242.955272)
			(xy 210.793753 -242.994343) (xy 210.823777 -243.03838) (xy 210.846903 -243.086401) (xy 210.862613 -243.137331)
			(xy 210.870556 -243.190035) (xy 210.871054 -243.216684) (xy 210.870556 -243.243333) (xy 214.234004 -243.243333)
			(xy 214.234004 -243.190035) (xy 214.241947 -243.137331) (xy 214.257657 -243.086401) (xy 214.280783 -243.03838)
			(xy 214.310807 -242.994343) (xy 214.347059 -242.955272) (xy 214.38873 -242.922041) (xy 214.434888 -242.895392)
			(xy 214.484502 -242.87592) (xy 214.536464 -242.86406) (xy 214.589614 -242.860077) (xy 214.642764 -242.86406)
			(xy 214.694726 -242.87592) (xy 214.74434 -242.895392) (xy 214.790498 -242.922041) (xy 214.832169 -242.955272)
			(xy 214.868421 -242.994343) (xy 214.898445 -243.03838) (xy 214.921571 -243.086401) (xy 214.937281 -243.137331)
			(xy 214.945224 -243.190035) (xy 214.945722 -243.216684) (xy 214.945224 -243.243333) (xy 214.937281 -243.296037)
			(xy 214.921571 -243.346967) (xy 214.898445 -243.394988) (xy 214.868421 -243.439025) (xy 214.832169 -243.478096)
			(xy 214.790498 -243.511327) (xy 214.74434 -243.537976) (xy 214.694726 -243.557448) (xy 214.642764 -243.569308)
			(xy 214.589614 -243.573292) (xy 214.536464 -243.569308) (xy 214.484502 -243.557448) (xy 214.434888 -243.537976)
			(xy 214.38873 -243.511327) (xy 214.347059 -243.478096) (xy 214.310807 -243.439025) (xy 214.280783 -243.394988)
			(xy 214.257657 -243.346967) (xy 214.241947 -243.296037) (xy 214.234004 -243.243333) (xy 210.870556 -243.243333)
			(xy 210.862613 -243.296037) (xy 210.846903 -243.346967) (xy 210.823777 -243.394988) (xy 210.793753 -243.439025)
			(xy 210.757501 -243.478096) (xy 210.71583 -243.511327) (xy 210.669672 -243.537976) (xy 210.620058 -243.557448)
			(xy 210.568096 -243.569308) (xy 210.514946 -243.573292) (xy 210.461796 -243.569308) (xy 210.409834 -243.557448)
			(xy 210.36022 -243.537976) (xy 210.314062 -243.511327) (xy 210.272391 -243.478096) (xy 210.236139 -243.439025)
			(xy 210.206115 -243.394988) (xy 210.182989 -243.346967) (xy 210.167279 -243.296037) (xy 210.159336 -243.243333)
			(xy 207.426824 -243.243333) (xy 207.418881 -243.296037) (xy 207.403171 -243.346967) (xy 207.380045 -243.394988)
			(xy 207.350021 -243.439025) (xy 207.313769 -243.478096) (xy 207.272098 -243.511327) (xy 207.22594 -243.537976)
			(xy 207.176326 -243.557448) (xy 207.124364 -243.569308) (xy 207.071214 -243.573292) (xy 207.018064 -243.569308)
			(xy 206.966102 -243.557448) (xy 206.916488 -243.537976) (xy 206.87033 -243.511327) (xy 206.828659 -243.478096)
			(xy 206.792407 -243.439025) (xy 206.762383 -243.394988) (xy 206.739257 -243.346967) (xy 206.723547 -243.296037)
			(xy 206.715604 -243.243333) (xy 203.326756 -243.243333) (xy 203.318813 -243.296037) (xy 203.303103 -243.346967)
			(xy 203.279977 -243.394988) (xy 203.249953 -243.439025) (xy 203.213701 -243.478096) (xy 203.17203 -243.511327)
			(xy 203.125872 -243.537976) (xy 203.076258 -243.557448) (xy 203.024296 -243.569308) (xy 202.971146 -243.573292)
			(xy 202.917996 -243.569308) (xy 202.866034 -243.557448) (xy 202.81642 -243.537976) (xy 202.770262 -243.511327)
			(xy 202.728591 -243.478096) (xy 202.692339 -243.439025) (xy 202.662315 -243.394988) (xy 202.639189 -243.346967)
			(xy 202.623479 -243.296037) (xy 202.615536 -243.243333) (xy 199.883024 -243.243333) (xy 199.875081 -243.296037)
			(xy 199.859371 -243.346967) (xy 199.836245 -243.394988) (xy 199.806221 -243.439025) (xy 199.769969 -243.478096)
			(xy 199.728298 -243.511327) (xy 199.68214 -243.537976) (xy 199.632526 -243.557448) (xy 199.580564 -243.569308)
			(xy 199.527414 -243.573292) (xy 199.474264 -243.569308) (xy 199.422302 -243.557448) (xy 199.372688 -243.537976)
			(xy 199.32653 -243.511327) (xy 199.284859 -243.478096) (xy 199.248607 -243.439025) (xy 199.218583 -243.394988)
			(xy 199.195457 -243.346967) (xy 199.179747 -243.296037) (xy 199.171804 -243.243333) (xy 195.782956 -243.243333)
			(xy 195.775013 -243.296037) (xy 195.759303 -243.346967) (xy 195.736177 -243.394988) (xy 195.706153 -243.439025)
			(xy 195.669901 -243.478096) (xy 195.62823 -243.511327) (xy 195.582072 -243.537976) (xy 195.532458 -243.557448)
			(xy 195.480496 -243.569308) (xy 195.427346 -243.573292) (xy 195.374196 -243.569308) (xy 195.322234 -243.557448)
			(xy 195.27262 -243.537976) (xy 195.226462 -243.511327) (xy 195.184791 -243.478096) (xy 195.148539 -243.439025)
			(xy 195.118515 -243.394988) (xy 195.095389 -243.346967) (xy 195.079679 -243.296037) (xy 195.071736 -243.243333)
			(xy 192.339224 -243.243333) (xy 192.331281 -243.296037) (xy 192.315571 -243.346967) (xy 192.292445 -243.394988)
			(xy 192.262421 -243.439025) (xy 192.226169 -243.478096) (xy 192.184498 -243.511327) (xy 192.13834 -243.537976)
			(xy 192.088726 -243.557448) (xy 192.036764 -243.569308) (xy 191.983614 -243.573292) (xy 191.930464 -243.569308)
			(xy 191.878502 -243.557448) (xy 191.828888 -243.537976) (xy 191.78273 -243.511327) (xy 191.741059 -243.478096)
			(xy 191.704807 -243.439025) (xy 191.674783 -243.394988) (xy 191.651657 -243.346967) (xy 191.635947 -243.296037)
			(xy 191.628004 -243.243333) (xy 188.239156 -243.243333) (xy 188.231213 -243.296037) (xy 188.215503 -243.346967)
			(xy 188.192377 -243.394988) (xy 188.162353 -243.439025) (xy 188.126101 -243.478096) (xy 188.08443 -243.511327)
			(xy 188.038272 -243.537976) (xy 187.988658 -243.557448) (xy 187.936696 -243.569308) (xy 187.883546 -243.573292)
			(xy 187.830396 -243.569308) (xy 187.778434 -243.557448) (xy 187.72882 -243.537976) (xy 187.682662 -243.511327)
			(xy 187.640991 -243.478096) (xy 187.604739 -243.439025) (xy 187.574715 -243.394988) (xy 187.551589 -243.346967)
			(xy 187.535879 -243.296037) (xy 187.527936 -243.243333) (xy 184.770024 -243.243333) (xy 184.762081 -243.296037)
			(xy 184.746371 -243.346967) (xy 184.723245 -243.394988) (xy 184.693221 -243.439025) (xy 184.656969 -243.478096)
			(xy 184.615298 -243.511327) (xy 184.56914 -243.537976) (xy 184.519526 -243.557448) (xy 184.467564 -243.569308)
			(xy 184.414414 -243.573292) (xy 184.361264 -243.569308) (xy 184.309302 -243.557448) (xy 184.259688 -243.537976)
			(xy 184.21353 -243.511327) (xy 184.171859 -243.478096) (xy 184.135607 -243.439025) (xy 184.105583 -243.394988)
			(xy 184.082457 -243.346967) (xy 184.066747 -243.296037) (xy 184.058804 -243.243333) (xy 180.669956 -243.243333)
			(xy 180.662013 -243.296037) (xy 180.646303 -243.346967) (xy 180.623177 -243.394988) (xy 180.593153 -243.439025)
			(xy 180.556901 -243.478096) (xy 180.51523 -243.511327) (xy 180.469072 -243.537976) (xy 180.419458 -243.557448)
			(xy 180.367496 -243.569308) (xy 180.314346 -243.573292) (xy 180.261196 -243.569308) (xy 180.209234 -243.557448)
			(xy 180.15962 -243.537976) (xy 180.113462 -243.511327) (xy 180.071791 -243.478096) (xy 180.035539 -243.439025)
			(xy 180.005515 -243.394988) (xy 179.982389 -243.346967) (xy 179.966679 -243.296037) (xy 179.958736 -243.243333)
			(xy 177.251624 -243.243333) (xy 177.243681 -243.296037) (xy 177.227971 -243.346967) (xy 177.204845 -243.394988)
			(xy 177.174821 -243.439025) (xy 177.138569 -243.478096) (xy 177.096898 -243.511327) (xy 177.05074 -243.537976)
			(xy 177.001126 -243.557448) (xy 176.949164 -243.569308) (xy 176.896014 -243.573292) (xy 176.842864 -243.569308)
			(xy 176.790902 -243.557448) (xy 176.741288 -243.537976) (xy 176.69513 -243.511327) (xy 176.653459 -243.478096)
			(xy 176.617207 -243.439025) (xy 176.587183 -243.394988) (xy 176.564057 -243.346967) (xy 176.548347 -243.296037)
			(xy 176.540404 -243.243333) (xy 173.151556 -243.243333) (xy 173.143613 -243.296037) (xy 173.127903 -243.346967)
			(xy 173.104777 -243.394988) (xy 173.074753 -243.439025) (xy 173.038501 -243.478096) (xy 172.99683 -243.511327)
			(xy 172.950672 -243.537976) (xy 172.901058 -243.557448) (xy 172.849096 -243.569308) (xy 172.795946 -243.573292)
			(xy 172.742796 -243.569308) (xy 172.690834 -243.557448) (xy 172.64122 -243.537976) (xy 172.595062 -243.511327)
			(xy 172.553391 -243.478096) (xy 172.517139 -243.439025) (xy 172.487115 -243.394988) (xy 172.463989 -243.346967)
			(xy 172.448279 -243.296037) (xy 172.440336 -243.243333) (xy 169.682424 -243.243333) (xy 169.674481 -243.296037)
			(xy 169.658771 -243.346967) (xy 169.635645 -243.394988) (xy 169.605621 -243.439025) (xy 169.569369 -243.478096)
			(xy 169.527698 -243.511327) (xy 169.48154 -243.537976) (xy 169.431926 -243.557448) (xy 169.379964 -243.569308)
			(xy 169.326814 -243.573292) (xy 169.273664 -243.569308) (xy 169.221702 -243.557448) (xy 169.172088 -243.537976)
			(xy 169.12593 -243.511327) (xy 169.084259 -243.478096) (xy 169.048007 -243.439025) (xy 169.017983 -243.394988)
			(xy 168.994857 -243.346967) (xy 168.979147 -243.296037) (xy 168.971204 -243.243333) (xy 165.582356 -243.243333)
			(xy 165.574413 -243.296037) (xy 165.558703 -243.346967) (xy 165.535577 -243.394988) (xy 165.505553 -243.439025)
			(xy 165.469301 -243.478096) (xy 165.42763 -243.511327) (xy 165.381472 -243.537976) (xy 165.331858 -243.557448)
			(xy 165.279896 -243.569308) (xy 165.226746 -243.573292) (xy 165.173596 -243.569308) (xy 165.121634 -243.557448)
			(xy 165.07202 -243.537976) (xy 165.025862 -243.511327) (xy 164.984191 -243.478096) (xy 164.947939 -243.439025)
			(xy 164.917915 -243.394988) (xy 164.894789 -243.346967) (xy 164.879079 -243.296037) (xy 164.871136 -243.243333)
			(xy 162.138624 -243.243333) (xy 162.130681 -243.296037) (xy 162.114971 -243.346967) (xy 162.091845 -243.394988)
			(xy 162.061821 -243.439025) (xy 162.025569 -243.478096) (xy 161.983898 -243.511327) (xy 161.93774 -243.537976)
			(xy 161.888126 -243.557448) (xy 161.836164 -243.569308) (xy 161.783014 -243.573292) (xy 161.729864 -243.569308)
			(xy 161.677902 -243.557448) (xy 161.628288 -243.537976) (xy 161.58213 -243.511327) (xy 161.540459 -243.478096)
			(xy 161.504207 -243.439025) (xy 161.474183 -243.394988) (xy 161.451057 -243.346967) (xy 161.435347 -243.296037)
			(xy 161.427404 -243.243333) (xy 158.88716 -243.243333) (xy 158.88716 -244.093217) (xy 164.871136 -244.093217)
			(xy 164.871136 -244.039919) (xy 164.879079 -243.987215) (xy 164.894789 -243.936285) (xy 164.917915 -243.888264)
			(xy 164.947939 -243.844227) (xy 164.984191 -243.805156) (xy 165.025862 -243.771925) (xy 165.07202 -243.745276)
			(xy 165.121634 -243.725804) (xy 165.173596 -243.713944) (xy 165.226746 -243.709961) (xy 165.279896 -243.713944)
			(xy 165.331858 -243.725804) (xy 165.381472 -243.745276) (xy 165.42763 -243.771925) (xy 165.469301 -243.805156)
			(xy 165.505553 -243.844227) (xy 165.535577 -243.888264) (xy 165.558703 -243.936285) (xy 165.574413 -243.987215)
			(xy 165.582356 -244.039919) (xy 165.582854 -244.066568) (xy 165.582356 -244.093217) (xy 172.440336 -244.093217)
			(xy 172.440336 -244.039919) (xy 172.448279 -243.987215) (xy 172.463989 -243.936285) (xy 172.487115 -243.888264)
			(xy 172.517139 -243.844227) (xy 172.553391 -243.805156) (xy 172.595062 -243.771925) (xy 172.64122 -243.745276)
			(xy 172.690834 -243.725804) (xy 172.742796 -243.713944) (xy 172.795946 -243.709961) (xy 172.849096 -243.713944)
			(xy 172.901058 -243.725804) (xy 172.950672 -243.745276) (xy 172.99683 -243.771925) (xy 173.038501 -243.805156)
			(xy 173.074753 -243.844227) (xy 173.104777 -243.888264) (xy 173.127903 -243.936285) (xy 173.143613 -243.987215)
			(xy 173.151556 -244.039919) (xy 173.152054 -244.066568) (xy 173.151556 -244.093217) (xy 179.958736 -244.093217)
			(xy 179.958736 -244.039919) (xy 179.966679 -243.987215) (xy 179.982389 -243.936285) (xy 180.005515 -243.888264)
			(xy 180.035539 -243.844227) (xy 180.071791 -243.805156) (xy 180.113462 -243.771925) (xy 180.15962 -243.745276)
			(xy 180.209234 -243.725804) (xy 180.261196 -243.713944) (xy 180.314346 -243.709961) (xy 180.367496 -243.713944)
			(xy 180.419458 -243.725804) (xy 180.469072 -243.745276) (xy 180.51523 -243.771925) (xy 180.556901 -243.805156)
			(xy 180.593153 -243.844227) (xy 180.623177 -243.888264) (xy 180.646303 -243.936285) (xy 180.662013 -243.987215)
			(xy 180.669956 -244.039919) (xy 180.670454 -244.066568) (xy 180.669956 -244.093217) (xy 187.527936 -244.093217)
			(xy 187.527936 -244.039919) (xy 187.535879 -243.987215) (xy 187.551589 -243.936285) (xy 187.574715 -243.888264)
			(xy 187.604739 -243.844227) (xy 187.640991 -243.805156) (xy 187.682662 -243.771925) (xy 187.72882 -243.745276)
			(xy 187.778434 -243.725804) (xy 187.830396 -243.713944) (xy 187.883546 -243.709961) (xy 187.936696 -243.713944)
			(xy 187.988658 -243.725804) (xy 188.038272 -243.745276) (xy 188.08443 -243.771925) (xy 188.126101 -243.805156)
			(xy 188.162353 -243.844227) (xy 188.192377 -243.888264) (xy 188.215503 -243.936285) (xy 188.231213 -243.987215)
			(xy 188.239156 -244.039919) (xy 188.239654 -244.066568) (xy 188.239156 -244.093217) (xy 195.071736 -244.093217)
			(xy 195.071736 -244.039919) (xy 195.079679 -243.987215) (xy 195.095389 -243.936285) (xy 195.118515 -243.888264)
			(xy 195.148539 -243.844227) (xy 195.184791 -243.805156) (xy 195.226462 -243.771925) (xy 195.27262 -243.745276)
			(xy 195.322234 -243.725804) (xy 195.374196 -243.713944) (xy 195.427346 -243.709961) (xy 195.480496 -243.713944)
			(xy 195.532458 -243.725804) (xy 195.582072 -243.745276) (xy 195.62823 -243.771925) (xy 195.669901 -243.805156)
			(xy 195.706153 -243.844227) (xy 195.736177 -243.888264) (xy 195.759303 -243.936285) (xy 195.775013 -243.987215)
			(xy 195.782956 -244.039919) (xy 195.783454 -244.066568) (xy 195.782956 -244.093217) (xy 202.615536 -244.093217)
			(xy 202.615536 -244.039919) (xy 202.623479 -243.987215) (xy 202.639189 -243.936285) (xy 202.662315 -243.888264)
			(xy 202.692339 -243.844227) (xy 202.728591 -243.805156) (xy 202.770262 -243.771925) (xy 202.81642 -243.745276)
			(xy 202.866034 -243.725804) (xy 202.917996 -243.713944) (xy 202.971146 -243.709961) (xy 203.024296 -243.713944)
			(xy 203.076258 -243.725804) (xy 203.125872 -243.745276) (xy 203.17203 -243.771925) (xy 203.213701 -243.805156)
			(xy 203.249953 -243.844227) (xy 203.279977 -243.888264) (xy 203.303103 -243.936285) (xy 203.318813 -243.987215)
			(xy 203.326756 -244.039919) (xy 203.327254 -244.066568) (xy 203.326756 -244.093217) (xy 210.159336 -244.093217)
			(xy 210.159336 -244.039919) (xy 210.167279 -243.987215) (xy 210.182989 -243.936285) (xy 210.206115 -243.888264)
			(xy 210.236139 -243.844227) (xy 210.272391 -243.805156) (xy 210.314062 -243.771925) (xy 210.36022 -243.745276)
			(xy 210.409834 -243.725804) (xy 210.461796 -243.713944) (xy 210.514946 -243.709961) (xy 210.568096 -243.713944)
			(xy 210.620058 -243.725804) (xy 210.669672 -243.745276) (xy 210.71583 -243.771925) (xy 210.757501 -243.805156)
			(xy 210.793753 -243.844227) (xy 210.823777 -243.888264) (xy 210.846903 -243.936285) (xy 210.862613 -243.987215)
			(xy 210.870556 -244.039919) (xy 210.871054 -244.066568) (xy 210.870556 -244.093217) (xy 210.862613 -244.145921)
			(xy 210.846903 -244.196851) (xy 210.823777 -244.244872) (xy 210.793753 -244.288909) (xy 210.757501 -244.32798)
			(xy 210.71583 -244.361211) (xy 210.669672 -244.38786) (xy 210.620058 -244.407332) (xy 210.568096 -244.419192)
			(xy 210.514946 -244.423176) (xy 210.461796 -244.419192) (xy 210.409834 -244.407332) (xy 210.36022 -244.38786)
			(xy 210.314062 -244.361211) (xy 210.272391 -244.32798) (xy 210.236139 -244.288909) (xy 210.206115 -244.244872)
			(xy 210.182989 -244.196851) (xy 210.167279 -244.145921) (xy 210.159336 -244.093217) (xy 203.326756 -244.093217)
			(xy 203.318813 -244.145921) (xy 203.303103 -244.196851) (xy 203.279977 -244.244872) (xy 203.249953 -244.288909)
			(xy 203.213701 -244.32798) (xy 203.17203 -244.361211) (xy 203.125872 -244.38786) (xy 203.076258 -244.407332)
			(xy 203.024296 -244.419192) (xy 202.971146 -244.423176) (xy 202.917996 -244.419192) (xy 202.866034 -244.407332)
			(xy 202.81642 -244.38786) (xy 202.770262 -244.361211) (xy 202.728591 -244.32798) (xy 202.692339 -244.288909)
			(xy 202.662315 -244.244872) (xy 202.639189 -244.196851) (xy 202.623479 -244.145921) (xy 202.615536 -244.093217)
			(xy 195.782956 -244.093217) (xy 195.775013 -244.145921) (xy 195.759303 -244.196851) (xy 195.736177 -244.244872)
			(xy 195.706153 -244.288909) (xy 195.669901 -244.32798) (xy 195.62823 -244.361211) (xy 195.582072 -244.38786)
			(xy 195.532458 -244.407332) (xy 195.480496 -244.419192) (xy 195.427346 -244.423176) (xy 195.374196 -244.419192)
			(xy 195.322234 -244.407332) (xy 195.27262 -244.38786) (xy 195.226462 -244.361211) (xy 195.184791 -244.32798)
			(xy 195.148539 -244.288909) (xy 195.118515 -244.244872) (xy 195.095389 -244.196851) (xy 195.079679 -244.145921)
			(xy 195.071736 -244.093217) (xy 188.239156 -244.093217) (xy 188.231213 -244.145921) (xy 188.215503 -244.196851)
			(xy 188.192377 -244.244872) (xy 188.162353 -244.288909) (xy 188.126101 -244.32798) (xy 188.08443 -244.361211)
			(xy 188.038272 -244.38786) (xy 187.988658 -244.407332) (xy 187.936696 -244.419192) (xy 187.883546 -244.423176)
			(xy 187.830396 -244.419192) (xy 187.778434 -244.407332) (xy 187.72882 -244.38786) (xy 187.682662 -244.361211)
			(xy 187.640991 -244.32798) (xy 187.604739 -244.288909) (xy 187.574715 -244.244872) (xy 187.551589 -244.196851)
			(xy 187.535879 -244.145921) (xy 187.527936 -244.093217) (xy 180.669956 -244.093217) (xy 180.662013 -244.145921)
			(xy 180.646303 -244.196851) (xy 180.623177 -244.244872) (xy 180.593153 -244.288909) (xy 180.556901 -244.32798)
			(xy 180.51523 -244.361211) (xy 180.469072 -244.38786) (xy 180.419458 -244.407332) (xy 180.367496 -244.419192)
			(xy 180.314346 -244.423176) (xy 180.261196 -244.419192) (xy 180.209234 -244.407332) (xy 180.15962 -244.38786)
			(xy 180.113462 -244.361211) (xy 180.071791 -244.32798) (xy 180.035539 -244.288909) (xy 180.005515 -244.244872)
			(xy 179.982389 -244.196851) (xy 179.966679 -244.145921) (xy 179.958736 -244.093217) (xy 173.151556 -244.093217)
			(xy 173.143613 -244.145921) (xy 173.127903 -244.196851) (xy 173.104777 -244.244872) (xy 173.074753 -244.288909)
			(xy 173.038501 -244.32798) (xy 172.99683 -244.361211) (xy 172.950672 -244.38786) (xy 172.901058 -244.407332)
			(xy 172.849096 -244.419192) (xy 172.795946 -244.423176) (xy 172.742796 -244.419192) (xy 172.690834 -244.407332)
			(xy 172.64122 -244.38786) (xy 172.595062 -244.361211) (xy 172.553391 -244.32798) (xy 172.517139 -244.288909)
			(xy 172.487115 -244.244872) (xy 172.463989 -244.196851) (xy 172.448279 -244.145921) (xy 172.440336 -244.093217)
			(xy 165.582356 -244.093217) (xy 165.574413 -244.145921) (xy 165.558703 -244.196851) (xy 165.535577 -244.244872)
			(xy 165.505553 -244.288909) (xy 165.469301 -244.32798) (xy 165.42763 -244.361211) (xy 165.381472 -244.38786)
			(xy 165.331858 -244.407332) (xy 165.279896 -244.419192) (xy 165.226746 -244.423176) (xy 165.173596 -244.419192)
			(xy 165.121634 -244.407332) (xy 165.07202 -244.38786) (xy 165.025862 -244.361211) (xy 164.984191 -244.32798)
			(xy 164.947939 -244.288909) (xy 164.917915 -244.244872) (xy 164.894789 -244.196851) (xy 164.879079 -244.145921)
			(xy 164.871136 -244.093217) (xy 158.88716 -244.093217) (xy 158.88716 -244.943355) (xy 176.540404 -244.943355)
			(xy 176.540404 -244.890057) (xy 176.548347 -244.837353) (xy 176.564057 -244.786423) (xy 176.587183 -244.738402)
			(xy 176.617207 -244.694365) (xy 176.653459 -244.655294) (xy 176.69513 -244.622063) (xy 176.741288 -244.595414)
			(xy 176.790902 -244.575942) (xy 176.842864 -244.564082) (xy 176.896014 -244.560099) (xy 176.949164 -244.564082)
			(xy 177.001126 -244.575942) (xy 177.05074 -244.595414) (xy 177.096898 -244.622063) (xy 177.138569 -244.655294)
			(xy 177.174821 -244.694365) (xy 177.204845 -244.738402) (xy 177.227971 -244.786423) (xy 177.243681 -244.837353)
			(xy 177.251624 -244.890057) (xy 177.252122 -244.916706) (xy 177.251624 -244.943355) (xy 184.084204 -244.943355)
			(xy 184.084204 -244.890057) (xy 184.092147 -244.837353) (xy 184.107857 -244.786423) (xy 184.130983 -244.738402)
			(xy 184.161007 -244.694365) (xy 184.197259 -244.655294) (xy 184.23893 -244.622063) (xy 184.285088 -244.595414)
			(xy 184.334702 -244.575942) (xy 184.386664 -244.564082) (xy 184.439814 -244.560099) (xy 184.492964 -244.564082)
			(xy 184.544926 -244.575942) (xy 184.59454 -244.595414) (xy 184.640698 -244.622063) (xy 184.682369 -244.655294)
			(xy 184.718621 -244.694365) (xy 184.748645 -244.738402) (xy 184.771771 -244.786423) (xy 184.787481 -244.837353)
			(xy 184.795424 -244.890057) (xy 184.795922 -244.916706) (xy 184.795424 -244.943355) (xy 191.628004 -244.943355)
			(xy 191.628004 -244.890057) (xy 191.635947 -244.837353) (xy 191.651657 -244.786423) (xy 191.674783 -244.738402)
			(xy 191.704807 -244.694365) (xy 191.741059 -244.655294) (xy 191.78273 -244.622063) (xy 191.828888 -244.595414)
			(xy 191.878502 -244.575942) (xy 191.930464 -244.564082) (xy 191.983614 -244.560099) (xy 192.036764 -244.564082)
			(xy 192.088726 -244.575942) (xy 192.13834 -244.595414) (xy 192.184498 -244.622063) (xy 192.226169 -244.655294)
			(xy 192.262421 -244.694365) (xy 192.292445 -244.738402) (xy 192.315571 -244.786423) (xy 192.331281 -244.837353)
			(xy 192.339224 -244.890057) (xy 192.339722 -244.916706) (xy 192.339224 -244.943355) (xy 199.171804 -244.943355)
			(xy 199.171804 -244.890057) (xy 199.179747 -244.837353) (xy 199.195457 -244.786423) (xy 199.218583 -244.738402)
			(xy 199.248607 -244.694365) (xy 199.284859 -244.655294) (xy 199.32653 -244.622063) (xy 199.372688 -244.595414)
			(xy 199.422302 -244.575942) (xy 199.474264 -244.564082) (xy 199.527414 -244.560099) (xy 199.580564 -244.564082)
			(xy 199.632526 -244.575942) (xy 199.68214 -244.595414) (xy 199.728298 -244.622063) (xy 199.769969 -244.655294)
			(xy 199.806221 -244.694365) (xy 199.836245 -244.738402) (xy 199.859371 -244.786423) (xy 199.875081 -244.837353)
			(xy 199.883024 -244.890057) (xy 199.883522 -244.916706) (xy 199.883024 -244.943355) (xy 206.715604 -244.943355)
			(xy 206.715604 -244.890057) (xy 206.723547 -244.837353) (xy 206.739257 -244.786423) (xy 206.762383 -244.738402)
			(xy 206.792407 -244.694365) (xy 206.828659 -244.655294) (xy 206.87033 -244.622063) (xy 206.916488 -244.595414)
			(xy 206.966102 -244.575942) (xy 207.018064 -244.564082) (xy 207.071214 -244.560099) (xy 207.124364 -244.564082)
			(xy 207.176326 -244.575942) (xy 207.22594 -244.595414) (xy 207.272098 -244.622063) (xy 207.313769 -244.655294)
			(xy 207.350021 -244.694365) (xy 207.380045 -244.738402) (xy 207.403171 -244.786423) (xy 207.418881 -244.837353)
			(xy 207.426824 -244.890057) (xy 207.427322 -244.916706) (xy 207.426824 -244.943355) (xy 214.259404 -244.943355)
			(xy 214.259404 -244.890057) (xy 214.267347 -244.837353) (xy 214.283057 -244.786423) (xy 214.306183 -244.738402)
			(xy 214.336207 -244.694365) (xy 214.372459 -244.655294) (xy 214.41413 -244.622063) (xy 214.460288 -244.595414)
			(xy 214.509902 -244.575942) (xy 214.561864 -244.564082) (xy 214.615014 -244.560099) (xy 214.668164 -244.564082)
			(xy 214.720126 -244.575942) (xy 214.76974 -244.595414) (xy 214.815898 -244.622063) (xy 214.857569 -244.655294)
			(xy 214.893821 -244.694365) (xy 214.923845 -244.738402) (xy 214.946971 -244.786423) (xy 214.962681 -244.837353)
			(xy 214.970624 -244.890057) (xy 214.971122 -244.916706) (xy 214.970624 -244.943355) (xy 214.962681 -244.996059)
			(xy 214.946971 -245.046989) (xy 214.923845 -245.09501) (xy 214.893821 -245.139047) (xy 214.857569 -245.178118)
			(xy 214.815898 -245.211349) (xy 214.76974 -245.237998) (xy 214.720126 -245.25747) (xy 214.668164 -245.26933)
			(xy 214.615014 -245.273314) (xy 214.561864 -245.26933) (xy 214.509902 -245.25747) (xy 214.460288 -245.237998)
			(xy 214.41413 -245.211349) (xy 214.372459 -245.178118) (xy 214.336207 -245.139047) (xy 214.306183 -245.09501)
			(xy 214.283057 -245.046989) (xy 214.267347 -244.996059) (xy 214.259404 -244.943355) (xy 207.426824 -244.943355)
			(xy 207.418881 -244.996059) (xy 207.403171 -245.046989) (xy 207.380045 -245.09501) (xy 207.350021 -245.139047)
			(xy 207.313769 -245.178118) (xy 207.272098 -245.211349) (xy 207.22594 -245.237998) (xy 207.176326 -245.25747)
			(xy 207.124364 -245.26933) (xy 207.071214 -245.273314) (xy 207.018064 -245.26933) (xy 206.966102 -245.25747)
			(xy 206.916488 -245.237998) (xy 206.87033 -245.211349) (xy 206.828659 -245.178118) (xy 206.792407 -245.139047)
			(xy 206.762383 -245.09501) (xy 206.739257 -245.046989) (xy 206.723547 -244.996059) (xy 206.715604 -244.943355)
			(xy 199.883024 -244.943355) (xy 199.875081 -244.996059) (xy 199.859371 -245.046989) (xy 199.836245 -245.09501)
			(xy 199.806221 -245.139047) (xy 199.769969 -245.178118) (xy 199.728298 -245.211349) (xy 199.68214 -245.237998)
			(xy 199.632526 -245.25747) (xy 199.580564 -245.26933) (xy 199.527414 -245.273314) (xy 199.474264 -245.26933)
			(xy 199.422302 -245.25747) (xy 199.372688 -245.237998) (xy 199.32653 -245.211349) (xy 199.284859 -245.178118)
			(xy 199.248607 -245.139047) (xy 199.218583 -245.09501) (xy 199.195457 -245.046989) (xy 199.179747 -244.996059)
			(xy 199.171804 -244.943355) (xy 192.339224 -244.943355) (xy 192.331281 -244.996059) (xy 192.315571 -245.046989)
			(xy 192.292445 -245.09501) (xy 192.262421 -245.139047) (xy 192.226169 -245.178118) (xy 192.184498 -245.211349)
			(xy 192.13834 -245.237998) (xy 192.088726 -245.25747) (xy 192.036764 -245.26933) (xy 191.983614 -245.273314)
			(xy 191.930464 -245.26933) (xy 191.878502 -245.25747) (xy 191.828888 -245.237998) (xy 191.78273 -245.211349)
			(xy 191.741059 -245.178118) (xy 191.704807 -245.139047) (xy 191.674783 -245.09501) (xy 191.651657 -245.046989)
			(xy 191.635947 -244.996059) (xy 191.628004 -244.943355) (xy 184.795424 -244.943355) (xy 184.787481 -244.996059)
			(xy 184.771771 -245.046989) (xy 184.748645 -245.09501) (xy 184.718621 -245.139047) (xy 184.682369 -245.178118)
			(xy 184.640698 -245.211349) (xy 184.59454 -245.237998) (xy 184.544926 -245.25747) (xy 184.492964 -245.26933)
			(xy 184.439814 -245.273314) (xy 184.386664 -245.26933) (xy 184.334702 -245.25747) (xy 184.285088 -245.237998)
			(xy 184.23893 -245.211349) (xy 184.197259 -245.178118) (xy 184.161007 -245.139047) (xy 184.130983 -245.09501)
			(xy 184.107857 -245.046989) (xy 184.092147 -244.996059) (xy 184.084204 -244.943355) (xy 177.251624 -244.943355)
			(xy 177.243681 -244.996059) (xy 177.227971 -245.046989) (xy 177.204845 -245.09501) (xy 177.174821 -245.139047)
			(xy 177.138569 -245.178118) (xy 177.096898 -245.211349) (xy 177.05074 -245.237998) (xy 177.001126 -245.25747)
			(xy 176.949164 -245.26933) (xy 176.896014 -245.273314) (xy 176.842864 -245.26933) (xy 176.790902 -245.25747)
			(xy 176.741288 -245.237998) (xy 176.69513 -245.211349) (xy 176.653459 -245.178118) (xy 176.617207 -245.139047)
			(xy 176.587183 -245.09501) (xy 176.564057 -245.046989) (xy 176.548347 -244.996059) (xy 176.540404 -244.943355)
			(xy 158.88716 -244.943355) (xy 158.88716 -245.793239) (xy 172.440336 -245.793239) (xy 172.440336 -245.739941)
			(xy 172.448279 -245.687237) (xy 172.463989 -245.636307) (xy 172.487115 -245.588286) (xy 172.517139 -245.544249)
			(xy 172.553391 -245.505178) (xy 172.595062 -245.471947) (xy 172.64122 -245.445298) (xy 172.690834 -245.425826)
			(xy 172.742796 -245.413966) (xy 172.795946 -245.409983) (xy 172.849096 -245.413966) (xy 172.901058 -245.425826)
			(xy 172.950672 -245.445298) (xy 172.99683 -245.471947) (xy 173.038501 -245.505178) (xy 173.074753 -245.544249)
			(xy 173.104777 -245.588286) (xy 173.127903 -245.636307) (xy 173.143613 -245.687237) (xy 173.151556 -245.739941)
			(xy 173.152054 -245.76659) (xy 173.151556 -245.793239) (xy 179.984136 -245.793239) (xy 179.984136 -245.739941)
			(xy 179.992079 -245.687237) (xy 180.007789 -245.636307) (xy 180.030915 -245.588286) (xy 180.060939 -245.544249)
			(xy 180.097191 -245.505178) (xy 180.138862 -245.471947) (xy 180.18502 -245.445298) (xy 180.234634 -245.425826)
			(xy 180.286596 -245.413966) (xy 180.339746 -245.409983) (xy 180.392896 -245.413966) (xy 180.444858 -245.425826)
			(xy 180.494472 -245.445298) (xy 180.54063 -245.471947) (xy 180.582301 -245.505178) (xy 180.618553 -245.544249)
			(xy 180.648577 -245.588286) (xy 180.671703 -245.636307) (xy 180.687413 -245.687237) (xy 180.695356 -245.739941)
			(xy 180.695854 -245.76659) (xy 180.695356 -245.793239) (xy 187.527936 -245.793239) (xy 187.527936 -245.739941)
			(xy 187.535879 -245.687237) (xy 187.551589 -245.636307) (xy 187.574715 -245.588286) (xy 187.604739 -245.544249)
			(xy 187.640991 -245.505178) (xy 187.682662 -245.471947) (xy 187.72882 -245.445298) (xy 187.778434 -245.425826)
			(xy 187.830396 -245.413966) (xy 187.883546 -245.409983) (xy 187.936696 -245.413966) (xy 187.988658 -245.425826)
			(xy 188.038272 -245.445298) (xy 188.08443 -245.471947) (xy 188.126101 -245.505178) (xy 188.162353 -245.544249)
			(xy 188.192377 -245.588286) (xy 188.215503 -245.636307) (xy 188.231213 -245.687237) (xy 188.239156 -245.739941)
			(xy 188.239654 -245.76659) (xy 188.239156 -245.793239) (xy 195.071736 -245.793239) (xy 195.071736 -245.739941)
			(xy 195.079679 -245.687237) (xy 195.095389 -245.636307) (xy 195.118515 -245.588286) (xy 195.148539 -245.544249)
			(xy 195.184791 -245.505178) (xy 195.226462 -245.471947) (xy 195.27262 -245.445298) (xy 195.322234 -245.425826)
			(xy 195.374196 -245.413966) (xy 195.427346 -245.409983) (xy 195.480496 -245.413966) (xy 195.532458 -245.425826)
			(xy 195.582072 -245.445298) (xy 195.62823 -245.471947) (xy 195.669901 -245.505178) (xy 195.706153 -245.544249)
			(xy 195.736177 -245.588286) (xy 195.759303 -245.636307) (xy 195.775013 -245.687237) (xy 195.782956 -245.739941)
			(xy 195.783454 -245.76659) (xy 195.782956 -245.793239) (xy 202.615536 -245.793239) (xy 202.615536 -245.739941)
			(xy 202.623479 -245.687237) (xy 202.639189 -245.636307) (xy 202.662315 -245.588286) (xy 202.692339 -245.544249)
			(xy 202.728591 -245.505178) (xy 202.770262 -245.471947) (xy 202.81642 -245.445298) (xy 202.866034 -245.425826)
			(xy 202.917996 -245.413966) (xy 202.971146 -245.409983) (xy 203.024296 -245.413966) (xy 203.076258 -245.425826)
			(xy 203.125872 -245.445298) (xy 203.17203 -245.471947) (xy 203.213701 -245.505178) (xy 203.249953 -245.544249)
			(xy 203.279977 -245.588286) (xy 203.303103 -245.636307) (xy 203.318813 -245.687237) (xy 203.326756 -245.739941)
			(xy 203.327254 -245.76659) (xy 203.326756 -245.793239) (xy 210.159336 -245.793239) (xy 210.159336 -245.739941)
			(xy 210.167279 -245.687237) (xy 210.182989 -245.636307) (xy 210.206115 -245.588286) (xy 210.236139 -245.544249)
			(xy 210.272391 -245.505178) (xy 210.314062 -245.471947) (xy 210.36022 -245.445298) (xy 210.409834 -245.425826)
			(xy 210.461796 -245.413966) (xy 210.514946 -245.409983) (xy 210.568096 -245.413966) (xy 210.620058 -245.425826)
			(xy 210.669672 -245.445298) (xy 210.71583 -245.471947) (xy 210.757501 -245.505178) (xy 210.793753 -245.544249)
			(xy 210.823777 -245.588286) (xy 210.846903 -245.636307) (xy 210.862613 -245.687237) (xy 210.870556 -245.739941)
			(xy 210.871054 -245.76659) (xy 210.870556 -245.793239) (xy 210.862613 -245.845943) (xy 210.846903 -245.896873)
			(xy 210.823777 -245.944894) (xy 210.793753 -245.988931) (xy 210.757501 -246.028002) (xy 210.71583 -246.061233)
			(xy 210.669672 -246.087882) (xy 210.620058 -246.107354) (xy 210.568096 -246.119214) (xy 210.514946 -246.123198)
			(xy 210.461796 -246.119214) (xy 210.409834 -246.107354) (xy 210.36022 -246.087882) (xy 210.314062 -246.061233)
			(xy 210.272391 -246.028002) (xy 210.236139 -245.988931) (xy 210.206115 -245.944894) (xy 210.182989 -245.896873)
			(xy 210.167279 -245.845943) (xy 210.159336 -245.793239) (xy 203.326756 -245.793239) (xy 203.318813 -245.845943)
			(xy 203.303103 -245.896873) (xy 203.279977 -245.944894) (xy 203.249953 -245.988931) (xy 203.213701 -246.028002)
			(xy 203.17203 -246.061233) (xy 203.125872 -246.087882) (xy 203.076258 -246.107354) (xy 203.024296 -246.119214)
			(xy 202.971146 -246.123198) (xy 202.917996 -246.119214) (xy 202.866034 -246.107354) (xy 202.81642 -246.087882)
			(xy 202.770262 -246.061233) (xy 202.728591 -246.028002) (xy 202.692339 -245.988931) (xy 202.662315 -245.944894)
			(xy 202.639189 -245.896873) (xy 202.623479 -245.845943) (xy 202.615536 -245.793239) (xy 195.782956 -245.793239)
			(xy 195.775013 -245.845943) (xy 195.759303 -245.896873) (xy 195.736177 -245.944894) (xy 195.706153 -245.988931)
			(xy 195.669901 -246.028002) (xy 195.62823 -246.061233) (xy 195.582072 -246.087882) (xy 195.532458 -246.107354)
			(xy 195.480496 -246.119214) (xy 195.427346 -246.123198) (xy 195.374196 -246.119214) (xy 195.322234 -246.107354)
			(xy 195.27262 -246.087882) (xy 195.226462 -246.061233) (xy 195.184791 -246.028002) (xy 195.148539 -245.988931)
			(xy 195.118515 -245.944894) (xy 195.095389 -245.896873) (xy 195.079679 -245.845943) (xy 195.071736 -245.793239)
			(xy 188.239156 -245.793239) (xy 188.231213 -245.845943) (xy 188.215503 -245.896873) (xy 188.192377 -245.944894)
			(xy 188.162353 -245.988931) (xy 188.126101 -246.028002) (xy 188.08443 -246.061233) (xy 188.038272 -246.087882)
			(xy 187.988658 -246.107354) (xy 187.936696 -246.119214) (xy 187.883546 -246.123198) (xy 187.830396 -246.119214)
			(xy 187.778434 -246.107354) (xy 187.72882 -246.087882) (xy 187.682662 -246.061233) (xy 187.640991 -246.028002)
			(xy 187.604739 -245.988931) (xy 187.574715 -245.944894) (xy 187.551589 -245.896873) (xy 187.535879 -245.845943)
			(xy 187.527936 -245.793239) (xy 180.695356 -245.793239) (xy 180.687413 -245.845943) (xy 180.671703 -245.896873)
			(xy 180.648577 -245.944894) (xy 180.618553 -245.988931) (xy 180.582301 -246.028002) (xy 180.54063 -246.061233)
			(xy 180.494472 -246.087882) (xy 180.444858 -246.107354) (xy 180.392896 -246.119214) (xy 180.339746 -246.123198)
			(xy 180.286596 -246.119214) (xy 180.234634 -246.107354) (xy 180.18502 -246.087882) (xy 180.138862 -246.061233)
			(xy 180.097191 -246.028002) (xy 180.060939 -245.988931) (xy 180.030915 -245.944894) (xy 180.007789 -245.896873)
			(xy 179.992079 -245.845943) (xy 179.984136 -245.793239) (xy 173.151556 -245.793239) (xy 173.143613 -245.845943)
			(xy 173.127903 -245.896873) (xy 173.104777 -245.944894) (xy 173.074753 -245.988931) (xy 173.038501 -246.028002)
			(xy 172.99683 -246.061233) (xy 172.950672 -246.087882) (xy 172.901058 -246.107354) (xy 172.849096 -246.119214)
			(xy 172.795946 -246.123198) (xy 172.742796 -246.119214) (xy 172.690834 -246.107354) (xy 172.64122 -246.087882)
			(xy 172.595062 -246.061233) (xy 172.553391 -246.028002) (xy 172.517139 -245.988931) (xy 172.487115 -245.944894)
			(xy 172.463989 -245.896873) (xy 172.448279 -245.845943) (xy 172.440336 -245.793239) (xy 158.88716 -245.793239)
			(xy 158.88716 -246.643377) (xy 176.540404 -246.643377) (xy 176.540404 -246.590079) (xy 176.548347 -246.537375)
			(xy 176.564057 -246.486445) (xy 176.587183 -246.438424) (xy 176.617207 -246.394387) (xy 176.653459 -246.355316)
			(xy 176.69513 -246.322085) (xy 176.741288 -246.295436) (xy 176.790902 -246.275964) (xy 176.842864 -246.264104)
			(xy 176.896014 -246.260121) (xy 176.949164 -246.264104) (xy 177.001126 -246.275964) (xy 177.05074 -246.295436)
			(xy 177.096898 -246.322085) (xy 177.138569 -246.355316) (xy 177.174821 -246.394387) (xy 177.204845 -246.438424)
			(xy 177.227971 -246.486445) (xy 177.243681 -246.537375) (xy 177.251624 -246.590079) (xy 177.252122 -246.616728)
			(xy 177.251624 -246.643377) (xy 191.602604 -246.643377) (xy 191.602604 -246.590079) (xy 191.610547 -246.537375)
			(xy 191.626257 -246.486445) (xy 191.649383 -246.438424) (xy 191.679407 -246.394387) (xy 191.715659 -246.355316)
			(xy 191.75733 -246.322085) (xy 191.803488 -246.295436) (xy 191.853102 -246.275964) (xy 191.905064 -246.264104)
			(xy 191.958214 -246.260121) (xy 192.011364 -246.264104) (xy 192.063326 -246.275964) (xy 192.11294 -246.295436)
			(xy 192.159098 -246.322085) (xy 192.200769 -246.355316) (xy 192.237021 -246.394387) (xy 192.267045 -246.438424)
			(xy 192.290171 -246.486445) (xy 192.305881 -246.537375) (xy 192.313824 -246.590079) (xy 192.314322 -246.616728)
			(xy 192.313824 -246.643377) (xy 206.715604 -246.643377) (xy 206.715604 -246.590079) (xy 206.723547 -246.537375)
			(xy 206.739257 -246.486445) (xy 206.762383 -246.438424) (xy 206.792407 -246.394387) (xy 206.828659 -246.355316)
			(xy 206.87033 -246.322085) (xy 206.916488 -246.295436) (xy 206.966102 -246.275964) (xy 207.018064 -246.264104)
			(xy 207.071214 -246.260121) (xy 207.124364 -246.264104) (xy 207.176326 -246.275964) (xy 207.22594 -246.295436)
			(xy 207.272098 -246.322085) (xy 207.313769 -246.355316) (xy 207.350021 -246.394387) (xy 207.380045 -246.438424)
			(xy 207.403171 -246.486445) (xy 207.418881 -246.537375) (xy 207.426824 -246.590079) (xy 207.427322 -246.616728)
			(xy 207.426824 -246.643377) (xy 207.418881 -246.696081) (xy 207.403171 -246.747011) (xy 207.380045 -246.795032)
			(xy 207.350021 -246.839069) (xy 207.313769 -246.87814) (xy 207.272098 -246.911371) (xy 207.22594 -246.93802)
			(xy 207.176326 -246.957492) (xy 207.124364 -246.969352) (xy 207.071214 -246.973336) (xy 207.018064 -246.969352)
			(xy 206.966102 -246.957492) (xy 206.916488 -246.93802) (xy 206.87033 -246.911371) (xy 206.828659 -246.87814)
			(xy 206.792407 -246.839069) (xy 206.762383 -246.795032) (xy 206.739257 -246.747011) (xy 206.723547 -246.696081)
			(xy 206.715604 -246.643377) (xy 192.313824 -246.643377) (xy 192.305881 -246.696081) (xy 192.290171 -246.747011)
			(xy 192.267045 -246.795032) (xy 192.237021 -246.839069) (xy 192.200769 -246.87814) (xy 192.159098 -246.911371)
			(xy 192.11294 -246.93802) (xy 192.063326 -246.957492) (xy 192.011364 -246.969352) (xy 191.958214 -246.973336)
			(xy 191.905064 -246.969352) (xy 191.853102 -246.957492) (xy 191.803488 -246.93802) (xy 191.75733 -246.911371)
			(xy 191.715659 -246.87814) (xy 191.679407 -246.839069) (xy 191.649383 -246.795032) (xy 191.626257 -246.747011)
			(xy 191.610547 -246.696081) (xy 191.602604 -246.643377) (xy 177.251624 -246.643377) (xy 177.243681 -246.696081)
			(xy 177.227971 -246.747011) (xy 177.204845 -246.795032) (xy 177.174821 -246.839069) (xy 177.138569 -246.87814)
			(xy 177.096898 -246.911371) (xy 177.05074 -246.93802) (xy 177.001126 -246.957492) (xy 176.949164 -246.969352)
			(xy 176.896014 -246.973336) (xy 176.842864 -246.969352) (xy 176.790902 -246.957492) (xy 176.741288 -246.93802)
			(xy 176.69513 -246.911371) (xy 176.653459 -246.87814) (xy 176.617207 -246.839069) (xy 176.587183 -246.795032)
			(xy 176.564057 -246.747011) (xy 176.548347 -246.696081) (xy 176.540404 -246.643377) (xy 158.88716 -246.643377)
			(xy 158.88716 -247.493261) (xy 172.440336 -247.493261) (xy 172.440336 -247.439963) (xy 172.448279 -247.387259)
			(xy 172.463989 -247.336329) (xy 172.487115 -247.288308) (xy 172.517139 -247.244271) (xy 172.553391 -247.2052)
			(xy 172.595062 -247.171969) (xy 172.64122 -247.14532) (xy 172.690834 -247.125848) (xy 172.742796 -247.113988)
			(xy 172.795946 -247.110005) (xy 172.849096 -247.113988) (xy 172.901058 -247.125848) (xy 172.950672 -247.14532)
			(xy 172.99683 -247.171969) (xy 173.038501 -247.2052) (xy 173.074753 -247.244271) (xy 173.104777 -247.288308)
			(xy 173.127903 -247.336329) (xy 173.143613 -247.387259) (xy 173.151556 -247.439963) (xy 173.152054 -247.466612)
			(xy 173.151556 -247.493261) (xy 187.527936 -247.493261) (xy 187.527936 -247.439963) (xy 187.535879 -247.387259)
			(xy 187.551589 -247.336329) (xy 187.574715 -247.288308) (xy 187.604739 -247.244271) (xy 187.640991 -247.2052)
			(xy 187.682662 -247.171969) (xy 187.72882 -247.14532) (xy 187.778434 -247.125848) (xy 187.830396 -247.113988)
			(xy 187.883546 -247.110005) (xy 187.936696 -247.113988) (xy 187.988658 -247.125848) (xy 188.038272 -247.14532)
			(xy 188.08443 -247.171969) (xy 188.126101 -247.2052) (xy 188.162353 -247.244271) (xy 188.192377 -247.288308)
			(xy 188.215503 -247.336329) (xy 188.231213 -247.387259) (xy 188.239156 -247.439963) (xy 188.239654 -247.466612)
			(xy 188.239156 -247.493261) (xy 202.615536 -247.493261) (xy 202.615536 -247.439963) (xy 202.623479 -247.387259)
			(xy 202.639189 -247.336329) (xy 202.662315 -247.288308) (xy 202.692339 -247.244271) (xy 202.728591 -247.2052)
			(xy 202.770262 -247.171969) (xy 202.81642 -247.14532) (xy 202.866034 -247.125848) (xy 202.917996 -247.113988)
			(xy 202.971146 -247.110005) (xy 203.024296 -247.113988) (xy 203.076258 -247.125848) (xy 203.125872 -247.14532)
			(xy 203.17203 -247.171969) (xy 203.213701 -247.2052) (xy 203.249953 -247.244271) (xy 203.279977 -247.288308)
			(xy 203.303103 -247.336329) (xy 203.318813 -247.387259) (xy 203.326756 -247.439963) (xy 203.327254 -247.466612)
			(xy 203.326756 -247.493261) (xy 203.318813 -247.545965) (xy 203.303103 -247.596895) (xy 203.279977 -247.644916)
			(xy 203.249953 -247.688953) (xy 203.213701 -247.728024) (xy 203.17203 -247.761255) (xy 203.125872 -247.787904)
			(xy 203.076258 -247.807376) (xy 203.024296 -247.819236) (xy 202.971146 -247.82322) (xy 202.917996 -247.819236)
			(xy 202.866034 -247.807376) (xy 202.81642 -247.787904) (xy 202.770262 -247.761255) (xy 202.728591 -247.728024)
			(xy 202.692339 -247.688953) (xy 202.662315 -247.644916) (xy 202.639189 -247.596895) (xy 202.623479 -247.545965)
			(xy 202.615536 -247.493261) (xy 188.239156 -247.493261) (xy 188.231213 -247.545965) (xy 188.215503 -247.596895)
			(xy 188.192377 -247.644916) (xy 188.162353 -247.688953) (xy 188.126101 -247.728024) (xy 188.08443 -247.761255)
			(xy 188.038272 -247.787904) (xy 187.988658 -247.807376) (xy 187.936696 -247.819236) (xy 187.883546 -247.82322)
			(xy 187.830396 -247.819236) (xy 187.778434 -247.807376) (xy 187.72882 -247.787904) (xy 187.682662 -247.761255)
			(xy 187.640991 -247.728024) (xy 187.604739 -247.688953) (xy 187.574715 -247.644916) (xy 187.551589 -247.596895)
			(xy 187.535879 -247.545965) (xy 187.527936 -247.493261) (xy 173.151556 -247.493261) (xy 173.143613 -247.545965)
			(xy 173.127903 -247.596895) (xy 173.104777 -247.644916) (xy 173.074753 -247.688953) (xy 173.038501 -247.728024)
			(xy 172.99683 -247.761255) (xy 172.950672 -247.787904) (xy 172.901058 -247.807376) (xy 172.849096 -247.819236)
			(xy 172.795946 -247.82322) (xy 172.742796 -247.819236) (xy 172.690834 -247.807376) (xy 172.64122 -247.787904)
			(xy 172.595062 -247.761255) (xy 172.553391 -247.728024) (xy 172.517139 -247.688953) (xy 172.487115 -247.644916)
			(xy 172.463989 -247.596895) (xy 172.448279 -247.545965) (xy 172.440336 -247.493261) (xy 158.88716 -247.493261)
			(xy 158.88716 -248.343399) (xy 176.540404 -248.343399) (xy 176.540404 -248.290101) (xy 176.548347 -248.237397)
			(xy 176.564057 -248.186467) (xy 176.587183 -248.138446) (xy 176.617207 -248.094409) (xy 176.653459 -248.055338)
			(xy 176.69513 -248.022107) (xy 176.741288 -247.995458) (xy 176.790902 -247.975986) (xy 176.842864 -247.964126)
			(xy 176.896014 -247.960143) (xy 176.949164 -247.964126) (xy 177.001126 -247.975986) (xy 177.05074 -247.995458)
			(xy 177.096898 -248.022107) (xy 177.138569 -248.055338) (xy 177.174821 -248.094409) (xy 177.204845 -248.138446)
			(xy 177.227971 -248.186467) (xy 177.243681 -248.237397) (xy 177.251624 -248.290101) (xy 177.252122 -248.31675)
			(xy 177.251624 -248.343399) (xy 191.628004 -248.343399) (xy 191.628004 -248.290101) (xy 191.635947 -248.237397)
			(xy 191.651657 -248.186467) (xy 191.674783 -248.138446) (xy 191.704807 -248.094409) (xy 191.741059 -248.055338)
			(xy 191.78273 -248.022107) (xy 191.828888 -247.995458) (xy 191.878502 -247.975986) (xy 191.930464 -247.964126)
			(xy 191.983614 -247.960143) (xy 192.036764 -247.964126) (xy 192.088726 -247.975986) (xy 192.13834 -247.995458)
			(xy 192.184498 -248.022107) (xy 192.226169 -248.055338) (xy 192.262421 -248.094409) (xy 192.292445 -248.138446)
			(xy 192.315571 -248.186467) (xy 192.331281 -248.237397) (xy 192.339224 -248.290101) (xy 192.339722 -248.31675)
			(xy 192.339224 -248.343399) (xy 206.715604 -248.343399) (xy 206.715604 -248.290101) (xy 206.723547 -248.237397)
			(xy 206.739257 -248.186467) (xy 206.762383 -248.138446) (xy 206.792407 -248.094409) (xy 206.828659 -248.055338)
			(xy 206.87033 -248.022107) (xy 206.916488 -247.995458) (xy 206.966102 -247.975986) (xy 207.018064 -247.964126)
			(xy 207.071214 -247.960143) (xy 207.124364 -247.964126) (xy 207.176326 -247.975986) (xy 207.22594 -247.995458)
			(xy 207.272098 -248.022107) (xy 207.313769 -248.055338) (xy 207.350021 -248.094409) (xy 207.380045 -248.138446)
			(xy 207.403171 -248.186467) (xy 207.418881 -248.237397) (xy 207.426824 -248.290101) (xy 207.427322 -248.31675)
			(xy 207.426824 -248.343399) (xy 207.418881 -248.396103) (xy 207.403171 -248.447033) (xy 207.380045 -248.495054)
			(xy 207.350021 -248.539091) (xy 207.313769 -248.578162) (xy 207.272098 -248.611393) (xy 207.22594 -248.638042)
			(xy 207.176326 -248.657514) (xy 207.124364 -248.669374) (xy 207.071214 -248.673358) (xy 207.018064 -248.669374)
			(xy 206.966102 -248.657514) (xy 206.916488 -248.638042) (xy 206.87033 -248.611393) (xy 206.828659 -248.578162)
			(xy 206.792407 -248.539091) (xy 206.762383 -248.495054) (xy 206.739257 -248.447033) (xy 206.723547 -248.396103)
			(xy 206.715604 -248.343399) (xy 192.339224 -248.343399) (xy 192.331281 -248.396103) (xy 192.315571 -248.447033)
			(xy 192.292445 -248.495054) (xy 192.262421 -248.539091) (xy 192.226169 -248.578162) (xy 192.184498 -248.611393)
			(xy 192.13834 -248.638042) (xy 192.088726 -248.657514) (xy 192.036764 -248.669374) (xy 191.983614 -248.673358)
			(xy 191.930464 -248.669374) (xy 191.878502 -248.657514) (xy 191.828888 -248.638042) (xy 191.78273 -248.611393)
			(xy 191.741059 -248.578162) (xy 191.704807 -248.539091) (xy 191.674783 -248.495054) (xy 191.651657 -248.447033)
			(xy 191.635947 -248.396103) (xy 191.628004 -248.343399) (xy 177.251624 -248.343399) (xy 177.243681 -248.396103)
			(xy 177.227971 -248.447033) (xy 177.204845 -248.495054) (xy 177.174821 -248.539091) (xy 177.138569 -248.578162)
			(xy 177.096898 -248.611393) (xy 177.05074 -248.638042) (xy 177.001126 -248.657514) (xy 176.949164 -248.669374)
			(xy 176.896014 -248.673358) (xy 176.842864 -248.669374) (xy 176.790902 -248.657514) (xy 176.741288 -248.638042)
			(xy 176.69513 -248.611393) (xy 176.653459 -248.578162) (xy 176.617207 -248.539091) (xy 176.587183 -248.495054)
			(xy 176.564057 -248.447033) (xy 176.548347 -248.396103) (xy 176.540404 -248.343399) (xy 158.88716 -248.343399)
			(xy 158.88716 -249.193283) (xy 172.440336 -249.193283) (xy 172.440336 -249.139985) (xy 172.448279 -249.087281)
			(xy 172.463989 -249.036351) (xy 172.487115 -248.98833) (xy 172.517139 -248.944293) (xy 172.553391 -248.905222)
			(xy 172.595062 -248.871991) (xy 172.64122 -248.845342) (xy 172.690834 -248.82587) (xy 172.742796 -248.81401)
			(xy 172.795946 -248.810027) (xy 172.849096 -248.81401) (xy 172.901058 -248.82587) (xy 172.950672 -248.845342)
			(xy 172.99683 -248.871991) (xy 173.038501 -248.905222) (xy 173.074753 -248.944293) (xy 173.104777 -248.98833)
			(xy 173.127903 -249.036351) (xy 173.143613 -249.087281) (xy 173.151556 -249.139985) (xy 173.152054 -249.166634)
			(xy 173.151556 -249.193283) (xy 187.527936 -249.193283) (xy 187.527936 -249.139985) (xy 187.535879 -249.087281)
			(xy 187.551589 -249.036351) (xy 187.574715 -248.98833) (xy 187.604739 -248.944293) (xy 187.640991 -248.905222)
			(xy 187.682662 -248.871991) (xy 187.72882 -248.845342) (xy 187.778434 -248.82587) (xy 187.830396 -248.81401)
			(xy 187.883546 -248.810027) (xy 187.936696 -248.81401) (xy 187.988658 -248.82587) (xy 188.038272 -248.845342)
			(xy 188.08443 -248.871991) (xy 188.126101 -248.905222) (xy 188.162353 -248.944293) (xy 188.192377 -248.98833)
			(xy 188.215503 -249.036351) (xy 188.231213 -249.087281) (xy 188.239156 -249.139985) (xy 188.239654 -249.166634)
			(xy 188.239156 -249.193283) (xy 202.615536 -249.193283) (xy 202.615536 -249.139985) (xy 202.623479 -249.087281)
			(xy 202.639189 -249.036351) (xy 202.662315 -248.98833) (xy 202.692339 -248.944293) (xy 202.728591 -248.905222)
			(xy 202.770262 -248.871991) (xy 202.81642 -248.845342) (xy 202.866034 -248.82587) (xy 202.917996 -248.81401)
			(xy 202.971146 -248.810027) (xy 203.024296 -248.81401) (xy 203.076258 -248.82587) (xy 203.125872 -248.845342)
			(xy 203.17203 -248.871991) (xy 203.213701 -248.905222) (xy 203.249953 -248.944293) (xy 203.279977 -248.98833)
			(xy 203.303103 -249.036351) (xy 203.318813 -249.087281) (xy 203.326756 -249.139985) (xy 203.327254 -249.166634)
			(xy 203.326756 -249.193283) (xy 203.318813 -249.245987) (xy 203.303103 -249.296917) (xy 203.279977 -249.344938)
			(xy 203.249953 -249.388975) (xy 203.213701 -249.428046) (xy 203.17203 -249.461277) (xy 203.125872 -249.487926)
			(xy 203.076258 -249.507398) (xy 203.024296 -249.519258) (xy 202.971146 -249.523242) (xy 202.917996 -249.519258)
			(xy 202.866034 -249.507398) (xy 202.81642 -249.487926) (xy 202.770262 -249.461277) (xy 202.728591 -249.428046)
			(xy 202.692339 -249.388975) (xy 202.662315 -249.344938) (xy 202.639189 -249.296917) (xy 202.623479 -249.245987)
			(xy 202.615536 -249.193283) (xy 188.239156 -249.193283) (xy 188.231213 -249.245987) (xy 188.215503 -249.296917)
			(xy 188.192377 -249.344938) (xy 188.162353 -249.388975) (xy 188.126101 -249.428046) (xy 188.08443 -249.461277)
			(xy 188.038272 -249.487926) (xy 187.988658 -249.507398) (xy 187.936696 -249.519258) (xy 187.883546 -249.523242)
			(xy 187.830396 -249.519258) (xy 187.778434 -249.507398) (xy 187.72882 -249.487926) (xy 187.682662 -249.461277)
			(xy 187.640991 -249.428046) (xy 187.604739 -249.388975) (xy 187.574715 -249.344938) (xy 187.551589 -249.296917)
			(xy 187.535879 -249.245987) (xy 187.527936 -249.193283) (xy 173.151556 -249.193283) (xy 173.143613 -249.245987)
			(xy 173.127903 -249.296917) (xy 173.104777 -249.344938) (xy 173.074753 -249.388975) (xy 173.038501 -249.428046)
			(xy 172.99683 -249.461277) (xy 172.950672 -249.487926) (xy 172.901058 -249.507398) (xy 172.849096 -249.519258)
			(xy 172.795946 -249.523242) (xy 172.742796 -249.519258) (xy 172.690834 -249.507398) (xy 172.64122 -249.487926)
			(xy 172.595062 -249.461277) (xy 172.553391 -249.428046) (xy 172.517139 -249.388975) (xy 172.487115 -249.344938)
			(xy 172.463989 -249.296917) (xy 172.448279 -249.245987) (xy 172.440336 -249.193283) (xy 158.88716 -249.193283)
			(xy 158.88716 -250.043421) (xy 176.540404 -250.043421) (xy 176.540404 -249.990123) (xy 176.548347 -249.937419)
			(xy 176.564057 -249.886489) (xy 176.587183 -249.838468) (xy 176.617207 -249.794431) (xy 176.653459 -249.75536)
			(xy 176.69513 -249.722129) (xy 176.741288 -249.69548) (xy 176.790902 -249.676008) (xy 176.842864 -249.664148)
			(xy 176.896014 -249.660165) (xy 176.949164 -249.664148) (xy 177.001126 -249.676008) (xy 177.05074 -249.69548)
			(xy 177.096898 -249.722129) (xy 177.138569 -249.75536) (xy 177.174821 -249.794431) (xy 177.204845 -249.838468)
			(xy 177.227971 -249.886489) (xy 177.243681 -249.937419) (xy 177.251624 -249.990123) (xy 177.252122 -250.016772)
			(xy 177.251624 -250.043421) (xy 191.628004 -250.043421) (xy 191.628004 -249.990123) (xy 191.635947 -249.937419)
			(xy 191.651657 -249.886489) (xy 191.674783 -249.838468) (xy 191.704807 -249.794431) (xy 191.741059 -249.75536)
			(xy 191.78273 -249.722129) (xy 191.828888 -249.69548) (xy 191.878502 -249.676008) (xy 191.930464 -249.664148)
			(xy 191.983614 -249.660165) (xy 192.036764 -249.664148) (xy 192.088726 -249.676008) (xy 192.13834 -249.69548)
			(xy 192.184498 -249.722129) (xy 192.226169 -249.75536) (xy 192.262421 -249.794431) (xy 192.292445 -249.838468)
			(xy 192.315571 -249.886489) (xy 192.331281 -249.937419) (xy 192.339224 -249.990123) (xy 192.339722 -250.016772)
			(xy 192.339224 -250.043421) (xy 206.715604 -250.043421) (xy 206.715604 -249.990123) (xy 206.723547 -249.937419)
			(xy 206.739257 -249.886489) (xy 206.762383 -249.838468) (xy 206.792407 -249.794431) (xy 206.828659 -249.75536)
			(xy 206.87033 -249.722129) (xy 206.916488 -249.69548) (xy 206.966102 -249.676008) (xy 207.018064 -249.664148)
			(xy 207.071214 -249.660165) (xy 207.124364 -249.664148) (xy 207.176326 -249.676008) (xy 207.22594 -249.69548)
			(xy 207.272098 -249.722129) (xy 207.313769 -249.75536) (xy 207.350021 -249.794431) (xy 207.380045 -249.838468)
			(xy 207.403171 -249.886489) (xy 207.418881 -249.937419) (xy 207.426824 -249.990123) (xy 207.427322 -250.016772)
			(xy 207.426824 -250.043421) (xy 207.418881 -250.096125) (xy 207.403171 -250.147055) (xy 207.380045 -250.195076)
			(xy 207.350021 -250.239113) (xy 207.313769 -250.278184) (xy 207.272098 -250.311415) (xy 207.22594 -250.338064)
			(xy 207.176326 -250.357536) (xy 207.124364 -250.369396) (xy 207.071214 -250.37338) (xy 207.018064 -250.369396)
			(xy 206.966102 -250.357536) (xy 206.916488 -250.338064) (xy 206.87033 -250.311415) (xy 206.828659 -250.278184)
			(xy 206.792407 -250.239113) (xy 206.762383 -250.195076) (xy 206.739257 -250.147055) (xy 206.723547 -250.096125)
			(xy 206.715604 -250.043421) (xy 192.339224 -250.043421) (xy 192.331281 -250.096125) (xy 192.315571 -250.147055)
			(xy 192.292445 -250.195076) (xy 192.262421 -250.239113) (xy 192.226169 -250.278184) (xy 192.184498 -250.311415)
			(xy 192.13834 -250.338064) (xy 192.088726 -250.357536) (xy 192.036764 -250.369396) (xy 191.983614 -250.37338)
			(xy 191.930464 -250.369396) (xy 191.878502 -250.357536) (xy 191.828888 -250.338064) (xy 191.78273 -250.311415)
			(xy 191.741059 -250.278184) (xy 191.704807 -250.239113) (xy 191.674783 -250.195076) (xy 191.651657 -250.147055)
			(xy 191.635947 -250.096125) (xy 191.628004 -250.043421) (xy 177.251624 -250.043421) (xy 177.243681 -250.096125)
			(xy 177.227971 -250.147055) (xy 177.204845 -250.195076) (xy 177.174821 -250.239113) (xy 177.138569 -250.278184)
			(xy 177.096898 -250.311415) (xy 177.05074 -250.338064) (xy 177.001126 -250.357536) (xy 176.949164 -250.369396)
			(xy 176.896014 -250.37338) (xy 176.842864 -250.369396) (xy 176.790902 -250.357536) (xy 176.741288 -250.338064)
			(xy 176.69513 -250.311415) (xy 176.653459 -250.278184) (xy 176.617207 -250.239113) (xy 176.587183 -250.195076)
			(xy 176.564057 -250.147055) (xy 176.548347 -250.096125) (xy 176.540404 -250.043421) (xy 158.88716 -250.043421)
			(xy 158.88716 -250.893305) (xy 172.440336 -250.893305) (xy 172.440336 -250.840007) (xy 172.448279 -250.787303)
			(xy 172.463989 -250.736373) (xy 172.487115 -250.688352) (xy 172.517139 -250.644315) (xy 172.553391 -250.605244)
			(xy 172.595062 -250.572013) (xy 172.64122 -250.545364) (xy 172.690834 -250.525892) (xy 172.742796 -250.514032)
			(xy 172.795946 -250.510049) (xy 172.849096 -250.514032) (xy 172.901058 -250.525892) (xy 172.950672 -250.545364)
			(xy 172.99683 -250.572013) (xy 173.038501 -250.605244) (xy 173.074753 -250.644315) (xy 173.104777 -250.688352)
			(xy 173.127903 -250.736373) (xy 173.143613 -250.787303) (xy 173.151556 -250.840007) (xy 173.152054 -250.866656)
			(xy 173.151556 -250.893305) (xy 187.527936 -250.893305) (xy 187.527936 -250.840007) (xy 187.535879 -250.787303)
			(xy 187.551589 -250.736373) (xy 187.574715 -250.688352) (xy 187.604739 -250.644315) (xy 187.640991 -250.605244)
			(xy 187.682662 -250.572013) (xy 187.72882 -250.545364) (xy 187.778434 -250.525892) (xy 187.830396 -250.514032)
			(xy 187.883546 -250.510049) (xy 187.936696 -250.514032) (xy 187.988658 -250.525892) (xy 188.038272 -250.545364)
			(xy 188.08443 -250.572013) (xy 188.126101 -250.605244) (xy 188.162353 -250.644315) (xy 188.192377 -250.688352)
			(xy 188.215503 -250.736373) (xy 188.231213 -250.787303) (xy 188.239156 -250.840007) (xy 188.239654 -250.866656)
			(xy 188.239156 -250.893305) (xy 202.615536 -250.893305) (xy 202.615536 -250.840007) (xy 202.623479 -250.787303)
			(xy 202.639189 -250.736373) (xy 202.662315 -250.688352) (xy 202.692339 -250.644315) (xy 202.728591 -250.605244)
			(xy 202.770262 -250.572013) (xy 202.81642 -250.545364) (xy 202.866034 -250.525892) (xy 202.917996 -250.514032)
			(xy 202.971146 -250.510049) (xy 203.024296 -250.514032) (xy 203.076258 -250.525892) (xy 203.125872 -250.545364)
			(xy 203.17203 -250.572013) (xy 203.213701 -250.605244) (xy 203.249953 -250.644315) (xy 203.279977 -250.688352)
			(xy 203.303103 -250.736373) (xy 203.318813 -250.787303) (xy 203.326756 -250.840007) (xy 203.327254 -250.866656)
			(xy 203.326756 -250.893305) (xy 203.318813 -250.946009) (xy 203.303103 -250.996939) (xy 203.279977 -251.04496)
			(xy 203.249953 -251.088997) (xy 203.213701 -251.128068) (xy 203.17203 -251.161299) (xy 203.125872 -251.187948)
			(xy 203.076258 -251.20742) (xy 203.024296 -251.21928) (xy 202.971146 -251.223264) (xy 202.917996 -251.21928)
			(xy 202.866034 -251.20742) (xy 202.81642 -251.187948) (xy 202.770262 -251.161299) (xy 202.728591 -251.128068)
			(xy 202.692339 -251.088997) (xy 202.662315 -251.04496) (xy 202.639189 -250.996939) (xy 202.623479 -250.946009)
			(xy 202.615536 -250.893305) (xy 188.239156 -250.893305) (xy 188.231213 -250.946009) (xy 188.215503 -250.996939)
			(xy 188.192377 -251.04496) (xy 188.162353 -251.088997) (xy 188.126101 -251.128068) (xy 188.08443 -251.161299)
			(xy 188.038272 -251.187948) (xy 187.988658 -251.20742) (xy 187.936696 -251.21928) (xy 187.883546 -251.223264)
			(xy 187.830396 -251.21928) (xy 187.778434 -251.20742) (xy 187.72882 -251.187948) (xy 187.682662 -251.161299)
			(xy 187.640991 -251.128068) (xy 187.604739 -251.088997) (xy 187.574715 -251.04496) (xy 187.551589 -250.996939)
			(xy 187.535879 -250.946009) (xy 187.527936 -250.893305) (xy 173.151556 -250.893305) (xy 173.143613 -250.946009)
			(xy 173.127903 -250.996939) (xy 173.104777 -251.04496) (xy 173.074753 -251.088997) (xy 173.038501 -251.128068)
			(xy 172.99683 -251.161299) (xy 172.950672 -251.187948) (xy 172.901058 -251.20742) (xy 172.849096 -251.21928)
			(xy 172.795946 -251.223264) (xy 172.742796 -251.21928) (xy 172.690834 -251.20742) (xy 172.64122 -251.187948)
			(xy 172.595062 -251.161299) (xy 172.553391 -251.128068) (xy 172.517139 -251.088997) (xy 172.487115 -251.04496)
			(xy 172.463989 -250.996939) (xy 172.448279 -250.946009) (xy 172.440336 -250.893305) (xy 158.88716 -250.893305)
			(xy 158.88716 -251.743443) (xy 176.540404 -251.743443) (xy 176.540404 -251.690145) (xy 176.548347 -251.637441)
			(xy 176.564057 -251.586511) (xy 176.587183 -251.53849) (xy 176.617207 -251.494453) (xy 176.653459 -251.455382)
			(xy 176.69513 -251.422151) (xy 176.741288 -251.395502) (xy 176.790902 -251.37603) (xy 176.842864 -251.36417)
			(xy 176.896014 -251.360187) (xy 176.949164 -251.36417) (xy 177.001126 -251.37603) (xy 177.05074 -251.395502)
			(xy 177.096898 -251.422151) (xy 177.138569 -251.455382) (xy 177.174821 -251.494453) (xy 177.204845 -251.53849)
			(xy 177.227971 -251.586511) (xy 177.243681 -251.637441) (xy 177.251624 -251.690145) (xy 177.252122 -251.716794)
			(xy 177.251624 -251.743443) (xy 191.628004 -251.743443) (xy 191.628004 -251.690145) (xy 191.635947 -251.637441)
			(xy 191.651657 -251.586511) (xy 191.674783 -251.53849) (xy 191.704807 -251.494453) (xy 191.741059 -251.455382)
			(xy 191.78273 -251.422151) (xy 191.828888 -251.395502) (xy 191.878502 -251.37603) (xy 191.930464 -251.36417)
			(xy 191.983614 -251.360187) (xy 192.036764 -251.36417) (xy 192.088726 -251.37603) (xy 192.13834 -251.395502)
			(xy 192.184498 -251.422151) (xy 192.226169 -251.455382) (xy 192.262421 -251.494453) (xy 192.292445 -251.53849)
			(xy 192.315571 -251.586511) (xy 192.331281 -251.637441) (xy 192.339224 -251.690145) (xy 192.339722 -251.716794)
			(xy 192.339224 -251.743443) (xy 206.715604 -251.743443) (xy 206.715604 -251.690145) (xy 206.723547 -251.637441)
			(xy 206.739257 -251.586511) (xy 206.762383 -251.53849) (xy 206.792407 -251.494453) (xy 206.828659 -251.455382)
			(xy 206.87033 -251.422151) (xy 206.916488 -251.395502) (xy 206.966102 -251.37603) (xy 207.018064 -251.36417)
			(xy 207.071214 -251.360187) (xy 207.124364 -251.36417) (xy 207.176326 -251.37603) (xy 207.22594 -251.395502)
			(xy 207.272098 -251.422151) (xy 207.313769 -251.455382) (xy 207.350021 -251.494453) (xy 207.380045 -251.53849)
			(xy 207.403171 -251.586511) (xy 207.418881 -251.637441) (xy 207.426824 -251.690145) (xy 207.427322 -251.716794)
			(xy 207.426824 -251.743443) (xy 207.418881 -251.796147) (xy 207.403171 -251.847077) (xy 207.380045 -251.895098)
			(xy 207.350021 -251.939135) (xy 207.313769 -251.978206) (xy 207.272098 -252.011437) (xy 207.22594 -252.038086)
			(xy 207.176326 -252.057558) (xy 207.124364 -252.069418) (xy 207.071214 -252.073402) (xy 207.018064 -252.069418)
			(xy 206.966102 -252.057558) (xy 206.916488 -252.038086) (xy 206.87033 -252.011437) (xy 206.828659 -251.978206)
			(xy 206.792407 -251.939135) (xy 206.762383 -251.895098) (xy 206.739257 -251.847077) (xy 206.723547 -251.796147)
			(xy 206.715604 -251.743443) (xy 192.339224 -251.743443) (xy 192.331281 -251.796147) (xy 192.315571 -251.847077)
			(xy 192.292445 -251.895098) (xy 192.262421 -251.939135) (xy 192.226169 -251.978206) (xy 192.184498 -252.011437)
			(xy 192.13834 -252.038086) (xy 192.088726 -252.057558) (xy 192.036764 -252.069418) (xy 191.983614 -252.073402)
			(xy 191.930464 -252.069418) (xy 191.878502 -252.057558) (xy 191.828888 -252.038086) (xy 191.78273 -252.011437)
			(xy 191.741059 -251.978206) (xy 191.704807 -251.939135) (xy 191.674783 -251.895098) (xy 191.651657 -251.847077)
			(xy 191.635947 -251.796147) (xy 191.628004 -251.743443) (xy 177.251624 -251.743443) (xy 177.243681 -251.796147)
			(xy 177.227971 -251.847077) (xy 177.204845 -251.895098) (xy 177.174821 -251.939135) (xy 177.138569 -251.978206)
			(xy 177.096898 -252.011437) (xy 177.05074 -252.038086) (xy 177.001126 -252.057558) (xy 176.949164 -252.069418)
			(xy 176.896014 -252.073402) (xy 176.842864 -252.069418) (xy 176.790902 -252.057558) (xy 176.741288 -252.038086)
			(xy 176.69513 -252.011437) (xy 176.653459 -251.978206) (xy 176.617207 -251.939135) (xy 176.587183 -251.895098)
			(xy 176.564057 -251.847077) (xy 176.548347 -251.796147) (xy 176.540404 -251.743443) (xy 158.88716 -251.743443)
			(xy 158.88716 -252.593327) (xy 172.440336 -252.593327) (xy 172.440336 -252.540029) (xy 172.448279 -252.487325)
			(xy 172.463989 -252.436395) (xy 172.487115 -252.388374) (xy 172.517139 -252.344337) (xy 172.553391 -252.305266)
			(xy 172.595062 -252.272035) (xy 172.64122 -252.245386) (xy 172.690834 -252.225914) (xy 172.742796 -252.214054)
			(xy 172.795946 -252.210071) (xy 172.849096 -252.214054) (xy 172.901058 -252.225914) (xy 172.950672 -252.245386)
			(xy 172.99683 -252.272035) (xy 173.038501 -252.305266) (xy 173.074753 -252.344337) (xy 173.104777 -252.388374)
			(xy 173.127903 -252.436395) (xy 173.143613 -252.487325) (xy 173.151556 -252.540029) (xy 173.152054 -252.566678)
			(xy 173.151556 -252.593327) (xy 176.540404 -252.593327) (xy 176.540404 -252.540029) (xy 176.548347 -252.487325)
			(xy 176.564057 -252.436395) (xy 176.587183 -252.388374) (xy 176.617207 -252.344337) (xy 176.653459 -252.305266)
			(xy 176.69513 -252.272035) (xy 176.741288 -252.245386) (xy 176.790902 -252.225914) (xy 176.842864 -252.214054)
			(xy 176.896014 -252.210071) (xy 176.949164 -252.214054) (xy 177.001126 -252.225914) (xy 177.05074 -252.245386)
			(xy 177.096898 -252.272035) (xy 177.138569 -252.305266) (xy 177.174821 -252.344337) (xy 177.204845 -252.388374)
			(xy 177.227971 -252.436395) (xy 177.243681 -252.487325) (xy 177.251624 -252.540029) (xy 177.252122 -252.566678)
			(xy 177.251624 -252.593327) (xy 184.058804 -252.593327) (xy 184.058804 -252.540029) (xy 184.066747 -252.487325)
			(xy 184.082457 -252.436395) (xy 184.105583 -252.388374) (xy 184.135607 -252.344337) (xy 184.171859 -252.305266)
			(xy 184.21353 -252.272035) (xy 184.259688 -252.245386) (xy 184.309302 -252.225914) (xy 184.361264 -252.214054)
			(xy 184.414414 -252.210071) (xy 184.467564 -252.214054) (xy 184.519526 -252.225914) (xy 184.56914 -252.245386)
			(xy 184.615298 -252.272035) (xy 184.656969 -252.305266) (xy 184.693221 -252.344337) (xy 184.723245 -252.388374)
			(xy 184.746371 -252.436395) (xy 184.762081 -252.487325) (xy 184.770024 -252.540029) (xy 184.770522 -252.566678)
			(xy 184.770024 -252.593327) (xy 187.527936 -252.593327) (xy 187.527936 -252.540029) (xy 187.535879 -252.487325)
			(xy 187.551589 -252.436395) (xy 187.574715 -252.388374) (xy 187.604739 -252.344337) (xy 187.640991 -252.305266)
			(xy 187.682662 -252.272035) (xy 187.72882 -252.245386) (xy 187.778434 -252.225914) (xy 187.830396 -252.214054)
			(xy 187.883546 -252.210071) (xy 187.936696 -252.214054) (xy 187.988658 -252.225914) (xy 188.038272 -252.245386)
			(xy 188.08443 -252.272035) (xy 188.126101 -252.305266) (xy 188.162353 -252.344337) (xy 188.192377 -252.388374)
			(xy 188.215503 -252.436395) (xy 188.231213 -252.487325) (xy 188.239156 -252.540029) (xy 188.239654 -252.566678)
			(xy 188.239156 -252.593327) (xy 191.628004 -252.593327) (xy 191.628004 -252.540029) (xy 191.635947 -252.487325)
			(xy 191.651657 -252.436395) (xy 191.674783 -252.388374) (xy 191.704807 -252.344337) (xy 191.741059 -252.305266)
			(xy 191.78273 -252.272035) (xy 191.828888 -252.245386) (xy 191.878502 -252.225914) (xy 191.930464 -252.214054)
			(xy 191.983614 -252.210071) (xy 192.036764 -252.214054) (xy 192.088726 -252.225914) (xy 192.13834 -252.245386)
			(xy 192.184498 -252.272035) (xy 192.226169 -252.305266) (xy 192.262421 -252.344337) (xy 192.292445 -252.388374)
			(xy 192.315571 -252.436395) (xy 192.331281 -252.487325) (xy 192.339224 -252.540029) (xy 192.339722 -252.566678)
			(xy 192.339224 -252.593327) (xy 199.171804 -252.593327) (xy 199.171804 -252.540029) (xy 199.179747 -252.487325)
			(xy 199.195457 -252.436395) (xy 199.218583 -252.388374) (xy 199.248607 -252.344337) (xy 199.284859 -252.305266)
			(xy 199.32653 -252.272035) (xy 199.372688 -252.245386) (xy 199.422302 -252.225914) (xy 199.474264 -252.214054)
			(xy 199.527414 -252.210071) (xy 199.580564 -252.214054) (xy 199.632526 -252.225914) (xy 199.68214 -252.245386)
			(xy 199.728298 -252.272035) (xy 199.769969 -252.305266) (xy 199.806221 -252.344337) (xy 199.836245 -252.388374)
			(xy 199.859371 -252.436395) (xy 199.875081 -252.487325) (xy 199.883024 -252.540029) (xy 199.883522 -252.566678)
			(xy 199.883024 -252.593327) (xy 202.615536 -252.593327) (xy 202.615536 -252.540029) (xy 202.623479 -252.487325)
			(xy 202.639189 -252.436395) (xy 202.662315 -252.388374) (xy 202.692339 -252.344337) (xy 202.728591 -252.305266)
			(xy 202.770262 -252.272035) (xy 202.81642 -252.245386) (xy 202.866034 -252.225914) (xy 202.917996 -252.214054)
			(xy 202.971146 -252.210071) (xy 203.024296 -252.214054) (xy 203.076258 -252.225914) (xy 203.125872 -252.245386)
			(xy 203.17203 -252.272035) (xy 203.213701 -252.305266) (xy 203.249953 -252.344337) (xy 203.279977 -252.388374)
			(xy 203.303103 -252.436395) (xy 203.318813 -252.487325) (xy 203.326756 -252.540029) (xy 203.327254 -252.566678)
			(xy 203.326756 -252.593327) (xy 206.715604 -252.593327) (xy 206.715604 -252.540029) (xy 206.723547 -252.487325)
			(xy 206.739257 -252.436395) (xy 206.762383 -252.388374) (xy 206.792407 -252.344337) (xy 206.828659 -252.305266)
			(xy 206.87033 -252.272035) (xy 206.916488 -252.245386) (xy 206.966102 -252.225914) (xy 207.018064 -252.214054)
			(xy 207.071214 -252.210071) (xy 207.124364 -252.214054) (xy 207.176326 -252.225914) (xy 207.22594 -252.245386)
			(xy 207.272098 -252.272035) (xy 207.313769 -252.305266) (xy 207.350021 -252.344337) (xy 207.380045 -252.388374)
			(xy 207.403171 -252.436395) (xy 207.418881 -252.487325) (xy 207.426824 -252.540029) (xy 207.427322 -252.566678)
			(xy 207.426824 -252.593327) (xy 214.234004 -252.593327) (xy 214.234004 -252.540029) (xy 214.241947 -252.487325)
			(xy 214.257657 -252.436395) (xy 214.280783 -252.388374) (xy 214.310807 -252.344337) (xy 214.347059 -252.305266)
			(xy 214.38873 -252.272035) (xy 214.434888 -252.245386) (xy 214.484502 -252.225914) (xy 214.536464 -252.214054)
			(xy 214.589614 -252.210071) (xy 214.642764 -252.214054) (xy 214.694726 -252.225914) (xy 214.74434 -252.245386)
			(xy 214.790498 -252.272035) (xy 214.832169 -252.305266) (xy 214.868421 -252.344337) (xy 214.898445 -252.388374)
			(xy 214.921571 -252.436395) (xy 214.937281 -252.487325) (xy 214.945224 -252.540029) (xy 214.945722 -252.566678)
			(xy 214.945224 -252.593327) (xy 214.937281 -252.646031) (xy 214.921571 -252.696961) (xy 214.898445 -252.744982)
			(xy 214.868421 -252.789019) (xy 214.832169 -252.82809) (xy 214.790498 -252.861321) (xy 214.74434 -252.88797)
			(xy 214.694726 -252.907442) (xy 214.642764 -252.919302) (xy 214.589614 -252.923286) (xy 214.536464 -252.919302)
			(xy 214.484502 -252.907442) (xy 214.434888 -252.88797) (xy 214.38873 -252.861321) (xy 214.347059 -252.82809)
			(xy 214.310807 -252.789019) (xy 214.280783 -252.744982) (xy 214.257657 -252.696961) (xy 214.241947 -252.646031)
			(xy 214.234004 -252.593327) (xy 207.426824 -252.593327) (xy 207.418881 -252.646031) (xy 207.403171 -252.696961)
			(xy 207.380045 -252.744982) (xy 207.350021 -252.789019) (xy 207.313769 -252.82809) (xy 207.272098 -252.861321)
			(xy 207.22594 -252.88797) (xy 207.176326 -252.907442) (xy 207.124364 -252.919302) (xy 207.071214 -252.923286)
			(xy 207.018064 -252.919302) (xy 206.966102 -252.907442) (xy 206.916488 -252.88797) (xy 206.87033 -252.861321)
			(xy 206.828659 -252.82809) (xy 206.792407 -252.789019) (xy 206.762383 -252.744982) (xy 206.739257 -252.696961)
			(xy 206.723547 -252.646031) (xy 206.715604 -252.593327) (xy 203.326756 -252.593327) (xy 203.318813 -252.646031)
			(xy 203.303103 -252.696961) (xy 203.279977 -252.744982) (xy 203.249953 -252.789019) (xy 203.213701 -252.82809)
			(xy 203.17203 -252.861321) (xy 203.125872 -252.88797) (xy 203.076258 -252.907442) (xy 203.024296 -252.919302)
			(xy 202.971146 -252.923286) (xy 202.917996 -252.919302) (xy 202.866034 -252.907442) (xy 202.81642 -252.88797)
			(xy 202.770262 -252.861321) (xy 202.728591 -252.82809) (xy 202.692339 -252.789019) (xy 202.662315 -252.744982)
			(xy 202.639189 -252.696961) (xy 202.623479 -252.646031) (xy 202.615536 -252.593327) (xy 199.883024 -252.593327)
			(xy 199.875081 -252.646031) (xy 199.859371 -252.696961) (xy 199.836245 -252.744982) (xy 199.806221 -252.789019)
			(xy 199.769969 -252.82809) (xy 199.728298 -252.861321) (xy 199.68214 -252.88797) (xy 199.632526 -252.907442)
			(xy 199.580564 -252.919302) (xy 199.527414 -252.923286) (xy 199.474264 -252.919302) (xy 199.422302 -252.907442)
			(xy 199.372688 -252.88797) (xy 199.32653 -252.861321) (xy 199.284859 -252.82809) (xy 199.248607 -252.789019)
			(xy 199.218583 -252.744982) (xy 199.195457 -252.696961) (xy 199.179747 -252.646031) (xy 199.171804 -252.593327)
			(xy 192.339224 -252.593327) (xy 192.331281 -252.646031) (xy 192.315571 -252.696961) (xy 192.292445 -252.744982)
			(xy 192.262421 -252.789019) (xy 192.226169 -252.82809) (xy 192.184498 -252.861321) (xy 192.13834 -252.88797)
			(xy 192.088726 -252.907442) (xy 192.036764 -252.919302) (xy 191.983614 -252.923286) (xy 191.930464 -252.919302)
			(xy 191.878502 -252.907442) (xy 191.828888 -252.88797) (xy 191.78273 -252.861321) (xy 191.741059 -252.82809)
			(xy 191.704807 -252.789019) (xy 191.674783 -252.744982) (xy 191.651657 -252.696961) (xy 191.635947 -252.646031)
			(xy 191.628004 -252.593327) (xy 188.239156 -252.593327) (xy 188.231213 -252.646031) (xy 188.215503 -252.696961)
			(xy 188.192377 -252.744982) (xy 188.162353 -252.789019) (xy 188.126101 -252.82809) (xy 188.08443 -252.861321)
			(xy 188.038272 -252.88797) (xy 187.988658 -252.907442) (xy 187.936696 -252.919302) (xy 187.883546 -252.923286)
			(xy 187.830396 -252.919302) (xy 187.778434 -252.907442) (xy 187.72882 -252.88797) (xy 187.682662 -252.861321)
			(xy 187.640991 -252.82809) (xy 187.604739 -252.789019) (xy 187.574715 -252.744982) (xy 187.551589 -252.696961)
			(xy 187.535879 -252.646031) (xy 187.527936 -252.593327) (xy 184.770024 -252.593327) (xy 184.762081 -252.646031)
			(xy 184.746371 -252.696961) (xy 184.723245 -252.744982) (xy 184.693221 -252.789019) (xy 184.656969 -252.82809)
			(xy 184.615298 -252.861321) (xy 184.56914 -252.88797) (xy 184.519526 -252.907442) (xy 184.467564 -252.919302)
			(xy 184.414414 -252.923286) (xy 184.361264 -252.919302) (xy 184.309302 -252.907442) (xy 184.259688 -252.88797)
			(xy 184.21353 -252.861321) (xy 184.171859 -252.82809) (xy 184.135607 -252.789019) (xy 184.105583 -252.744982)
			(xy 184.082457 -252.696961) (xy 184.066747 -252.646031) (xy 184.058804 -252.593327) (xy 177.251624 -252.593327)
			(xy 177.243681 -252.646031) (xy 177.227971 -252.696961) (xy 177.204845 -252.744982) (xy 177.174821 -252.789019)
			(xy 177.138569 -252.82809) (xy 177.096898 -252.861321) (xy 177.05074 -252.88797) (xy 177.001126 -252.907442)
			(xy 176.949164 -252.919302) (xy 176.896014 -252.923286) (xy 176.842864 -252.919302) (xy 176.790902 -252.907442)
			(xy 176.741288 -252.88797) (xy 176.69513 -252.861321) (xy 176.653459 -252.82809) (xy 176.617207 -252.789019)
			(xy 176.587183 -252.744982) (xy 176.564057 -252.696961) (xy 176.548347 -252.646031) (xy 176.540404 -252.593327)
			(xy 173.151556 -252.593327) (xy 173.143613 -252.646031) (xy 173.127903 -252.696961) (xy 173.104777 -252.744982)
			(xy 173.074753 -252.789019) (xy 173.038501 -252.82809) (xy 172.99683 -252.861321) (xy 172.950672 -252.88797)
			(xy 172.901058 -252.907442) (xy 172.849096 -252.919302) (xy 172.795946 -252.923286) (xy 172.742796 -252.919302)
			(xy 172.690834 -252.907442) (xy 172.64122 -252.88797) (xy 172.595062 -252.861321) (xy 172.553391 -252.82809)
			(xy 172.517139 -252.789019) (xy 172.487115 -252.744982) (xy 172.463989 -252.696961) (xy 172.448279 -252.646031)
			(xy 172.440336 -252.593327) (xy 158.88716 -252.593327) (xy 158.88716 -253.594616) (xy 158.887757 -253.609665)
			(xy 158.896618 -253.638435) (xy 158.913454 -253.66339) (xy 158.936813 -253.68238) (xy 158.96468 -253.693765)
			(xy 158.979616 -253.695708) (xy 159.005879 -253.698502) (xy 159.057229 -253.710857) (xy 159.106189 -253.730662)
			(xy 159.151685 -253.757485) (xy 159.192719 -253.790736) (xy 159.228389 -253.829684) (xy 159.257913 -253.873476)
			(xy 159.280643 -253.921149) (xy 159.296079 -253.971657) (xy 159.303883 -254.023892) (xy 159.303883 -254.076707)
			(xy 159.296079 -254.128941) (xy 159.280644 -254.17945) (xy 159.257914 -254.227123) (xy 159.22839 -254.270915)
			(xy 159.19272 -254.309863) (xy 159.151686 -254.343114) (xy 159.10619 -254.369937) (xy 159.05723 -254.389743)
			(xy 159.005881 -254.402097) (xy 158.979616 -254.404876) (xy 158.964655 -254.406755) (xy 158.936728 -254.41808)
			(xy 158.913329 -254.437072) (xy 158.896501 -254.462072) (xy 158.887713 -254.490899) (xy 158.88716 -254.505968)
			(xy 158.88716 -254.79629) (xy 162.28695 -254.79629) (xy 162.287463 -254.7682) (xy 162.296307 -254.712722)
			(xy 162.313757 -254.659321) (xy 162.339381 -254.609326) (xy 162.372542 -254.563977) (xy 162.392106 -254.543814)
			(xy 162.402266 -254.532941) (xy 162.416416 -254.50678) (xy 162.422445 -254.477654) (xy 162.419841 -254.448025)
			(xy 162.408827 -254.420397) (xy 162.39998 -254.408432) (xy 162.381811 -254.384627) (xy 162.352886 -254.332197)
			(xy 162.333138 -254.275667) (xy 162.323124 -254.21663) (xy 162.32251 -254.18669) (xy 162.323008 -254.160041)
			(xy 162.330951 -254.107337) (xy 162.346661 -254.056407) (xy 162.369787 -254.008386) (xy 162.399811 -253.964349)
			(xy 162.436063 -253.925278) (xy 162.477734 -253.892047) (xy 162.523892 -253.865398) (xy 162.573506 -253.845926)
			(xy 162.625468 -253.834066) (xy 162.678618 -253.830083) (xy 162.731768 -253.834066) (xy 162.78373 -253.845926)
			(xy 162.833344 -253.865398) (xy 162.879502 -253.892047) (xy 162.921173 -253.925278) (xy 162.957425 -253.964349)
			(xy 162.987449 -254.008386) (xy 163.010575 -254.056407) (xy 163.018639 -254.08255) (xy 163.28517 -254.08255)
			(xy 163.285695 -254.054567) (xy 163.294457 -253.99929) (xy 163.311757 -253.946064) (xy 163.337169 -253.896199)
			(xy 163.370068 -253.850923) (xy 163.409644 -253.81135) (xy 163.454923 -253.778454) (xy 163.50479 -253.753046)
			(xy 163.558017 -253.73575) (xy 163.613295 -253.726993) (xy 163.641278 -253.726442) (xy 163.666737 -253.726852)
			(xy 163.717134 -253.734114) (xy 163.765984 -253.748478) (xy 163.812291 -253.769652) (xy 163.85511 -253.797204)
			(xy 163.89357 -253.830572) (xy 163.926886 -253.869077) (xy 163.940998 -253.890272) (xy 163.948609 -253.901422)
			(xy 163.96864 -253.91951) (xy 163.992708 -253.931722) (xy 164.019134 -253.937206) (xy 164.046074 -253.935579)
			(xy 164.071649 -253.926955) (xy 164.094073 -253.911936) (xy 164.111782 -253.891569) (xy 164.118036 -253.879604)
			(xy 164.130976 -253.854157) (xy 164.163662 -253.807357) (xy 164.203393 -253.766369) (xy 164.249151 -253.732241)
			(xy 164.299767 -253.705848) (xy 164.353944 -253.687864) (xy 164.410296 -253.678751) (xy 164.438838 -253.678182)
			(xy 164.466822 -253.678706) (xy 164.469794 -253.679177) (xy 170.348392 -253.679177) (xy 170.348392 -253.625879)
			(xy 170.356335 -253.573175) (xy 170.372045 -253.522245) (xy 170.395171 -253.474224) (xy 170.425195 -253.430187)
			(xy 170.461447 -253.391116) (xy 170.503118 -253.357885) (xy 170.549276 -253.331236) (xy 170.59889 -253.311764)
			(xy 170.650852 -253.299904) (xy 170.704002 -253.295921) (xy 170.757152 -253.299904) (xy 170.809114 -253.311764)
			(xy 170.858728 -253.331236) (xy 170.904886 -253.357885) (xy 170.946557 -253.391116) (xy 170.982809 -253.430187)
			(xy 171.012833 -253.474224) (xy 171.035959 -253.522245) (xy 171.051669 -253.573175) (xy 171.059612 -253.625879)
			(xy 171.06011 -253.652528) (xy 171.059612 -253.679177) (xy 171.051669 -253.731881) (xy 171.035959 -253.782811)
			(xy 171.012833 -253.830832) (xy 170.982809 -253.874869) (xy 170.946557 -253.91394) (xy 170.904886 -253.947171)
			(xy 170.858728 -253.97382) (xy 170.809114 -253.993292) (xy 170.757152 -254.005152) (xy 170.704002 -254.009136)
			(xy 170.650852 -254.005152) (xy 170.59889 -253.993292) (xy 170.549276 -253.97382) (xy 170.503118 -253.947171)
			(xy 170.461447 -253.91394) (xy 170.425195 -253.874869) (xy 170.395171 -253.830832) (xy 170.372045 -253.782811)
			(xy 170.356335 -253.731881) (xy 170.348392 -253.679177) (xy 164.469794 -253.679177) (xy 164.522099 -253.687466)
			(xy 164.575326 -253.704765) (xy 164.625192 -253.730177) (xy 164.670468 -253.763077) (xy 164.710042 -253.802653)
			(xy 164.742937 -253.847932) (xy 164.768345 -253.8978) (xy 164.78564 -253.951028) (xy 164.794396 -254.006306)
			(xy 164.794946 -254.03429) (xy 164.794528 -254.059268) (xy 164.787531 -254.108732) (xy 164.773686 -254.156732)
			(xy 164.753266 -254.202324) (xy 164.726671 -254.244614) (xy 164.694425 -254.282769) (xy 164.676074 -254.29972)
			(xy 164.665535 -254.309817) (xy 164.650164 -254.334611) (xy 164.642426 -254.362737) (xy 164.642951 -254.391905)
			(xy 164.651697 -254.419735) (xy 164.667951 -254.443959) (xy 164.678868 -254.453644) (xy 164.687275 -254.460691)
			(xy 164.703288 -254.47569) (xy 164.710872 -254.483616) (xy 164.720912 -254.493477) (xy 164.745077 -254.507871)
			(xy 164.77225 -254.515133) (xy 164.800374 -254.514713) (xy 164.827319 -254.506642) (xy 164.851043 -254.491533)
			(xy 164.860732 -254.48133) (xy 164.877677 -254.462806) (xy 164.915924 -254.430286) (xy 164.95836 -254.403462)
			(xy 165.004145 -254.382868) (xy 165.052369 -254.36891) (xy 165.102076 -254.361867) (xy 165.127178 -254.361442)
			(xy 165.157427 -254.362086) (xy 165.217058 -254.372298) (xy 165.245796 -254.381762) (xy 165.260356 -254.386374)
			(xy 165.290859 -254.387641) (xy 165.320375 -254.379844) (xy 165.346274 -254.363681) (xy 165.366246 -254.340592)
			(xy 165.37851 -254.312635) (xy 165.381974 -254.282304) (xy 165.379654 -254.267208) (xy 165.376564 -254.249783)
			(xy 165.37326 -254.214546) (xy 165.37305 -254.19685) (xy 165.373501 -254.169592) (xy 165.381253 -254.11563)
			(xy 165.396606 -254.063321) (xy 165.419247 -254.013729) (xy 165.448716 -253.967865) (xy 165.484412 -253.926661)
			(xy 165.525609 -253.890958) (xy 165.571468 -253.86148) (xy 165.621056 -253.83883) (xy 165.673362 -253.823468)
			(xy 165.727323 -253.815706) (xy 165.781839 -253.815704) (xy 165.8358 -253.82346) (xy 165.888108 -253.838817)
			(xy 165.937698 -253.861462) (xy 165.98356 -253.890934) (xy 166.02476 -253.926634) (xy 166.060461 -253.967834)
			(xy 166.089934 -254.013695) (xy 166.112581 -254.063285) (xy 166.127939 -254.115592) (xy 166.135696 -254.169553)
			(xy 166.135694 -254.224069) (xy 166.127934 -254.27803) (xy 166.112573 -254.330336) (xy 166.089923 -254.379924)
			(xy 166.060447 -254.425784) (xy 166.024744 -254.466982) (xy 165.983542 -254.502679) (xy 165.937678 -254.532149)
			(xy 165.888086 -254.554791) (xy 165.835777 -254.570145) (xy 165.781816 -254.577898) (xy 165.754558 -254.578358)
			(xy 165.75405 -254.578358) (xy 165.730519 -254.578007) (xy 165.683817 -254.572178) (xy 165.638187 -254.560651)
			(xy 165.616128 -254.55245) (xy 165.601727 -254.547476) (xy 165.571353 -254.545324) (xy 165.541693 -254.552218)
			(xy 165.515381 -254.567545) (xy 165.494753 -254.589944) (xy 165.481641 -254.617426) (xy 165.477208 -254.647552)
			(xy 165.478968 -254.662686) (xy 165.480977 -254.676313) (xy 165.483135 -254.703776) (xy 165.483286 -254.71755)
			(xy 165.482805 -254.745536) (xy 165.474042 -254.800817) (xy 165.456739 -254.854046) (xy 165.431323 -254.903914)
			(xy 165.398419 -254.949192) (xy 165.358837 -254.988766) (xy 165.313553 -255.021661) (xy 165.26368 -255.047067)
			(xy 165.210446 -255.064359) (xy 165.155164 -255.073111) (xy 165.127178 -255.073658) (xy 165.098111 -255.073111)
			(xy 165.040748 -255.063677) (xy 164.98568 -255.045049) (xy 164.93437 -255.01772) (xy 164.888183 -254.982418)
			(xy 164.867844 -254.961644) (xy 164.85788 -254.951701) (xy 164.833692 -254.937318) (xy 164.806499 -254.93007)
			(xy 164.778361 -254.930506) (xy 164.751406 -254.938593) (xy 164.727675 -254.953719) (xy 164.717984 -254.96393)
			(xy 164.701023 -254.982438) (xy 164.66278 -255.014961) (xy 164.620347 -255.041788) (xy 164.574566 -255.062386)
			(xy 164.526344 -255.076346) (xy 164.476639 -255.083392) (xy 164.451538 -255.083818) (xy 164.423174 -255.083258)
			(xy 164.367159 -255.074288) (xy 164.313275 -255.056554) (xy 164.262882 -255.030503) (xy 164.217256 -254.996794)
			(xy 164.177549 -254.95628) (xy 164.160708 -254.93345) (xy 164.151561 -254.921343) (xy 164.127572 -254.902783)
			(xy 164.099187 -254.892092) (xy 164.068914 -254.890214) (xy 164.039426 -254.897314) (xy 164.013326 -254.912766)
			(xy 163.992919 -254.935206) (xy 163.985956 -254.94869) (xy 163.974834 -254.971228) (xy 163.947158 -255.013179)
			(xy 163.913856 -255.050821) (xy 163.875592 -255.083405) (xy 163.833125 -255.110283) (xy 163.7873 -255.130922)
			(xy 163.739027 -255.14491) (xy 163.689267 -255.15197) (xy 163.664138 -255.152398) (xy 163.636153 -255.151852)
			(xy 163.580872 -255.143102) (xy 163.52764 -255.125811) (xy 163.47777 -255.100404) (xy 163.432487 -255.067509)
			(xy 163.39291 -255.027934) (xy 163.36001 -254.982654) (xy 163.3346 -254.932786) (xy 163.317305 -254.879555)
			(xy 163.30855 -254.824275) (xy 163.30803 -254.79629) (xy 163.308456 -254.770676) (xy 163.315786 -254.719976)
			(xy 163.330308 -254.67085) (xy 163.351722 -254.624313) (xy 163.379585 -254.581325) (xy 163.413322 -254.542776)
			(xy 163.43249 -254.52578) (xy 163.443696 -254.51551) (xy 163.459946 -254.489839) (xy 163.467935 -254.460525)
			(xy 163.466956 -254.430159) (xy 163.457095 -254.401421) (xy 163.439225 -254.37685) (xy 163.42741 -254.367284)
			(xy 163.405739 -254.350328) (xy 163.36735 -254.310912) (xy 163.335479 -254.266061) (xy 163.310886 -254.216842)
			(xy 163.294156 -254.164426) (xy 163.285686 -254.110061) (xy 163.28517 -254.08255) (xy 163.018639 -254.08255)
			(xy 163.026285 -254.107337) (xy 163.034228 -254.160041) (xy 163.034726 -254.18669) (xy 163.034207 -254.214779)
			(xy 163.025366 -254.270258) (xy 163.007917 -254.323659) (xy 162.982294 -254.373654) (xy 162.949134 -254.419003)
			(xy 162.92957 -254.439166) (xy 162.919427 -254.450055) (xy 162.905265 -254.476209) (xy 162.899229 -254.505332)
			(xy 162.90183 -254.53496) (xy 162.912847 -254.562586) (xy 162.921696 -254.574548) (xy 162.939853 -254.598362)
			(xy 162.968781 -254.650789) (xy 162.988532 -254.707316) (xy 162.99855 -254.766351) (xy 162.999166 -254.79629)
			(xy 162.998668 -254.822939) (xy 162.990725 -254.875643) (xy 162.975015 -254.926573) (xy 162.951889 -254.974594)
			(xy 162.921865 -255.018631) (xy 162.885613 -255.057702) (xy 162.843942 -255.090933) (xy 162.797784 -255.117582)
			(xy 162.74817 -255.137054) (xy 162.696208 -255.148914) (xy 162.643058 -255.152898) (xy 162.589908 -255.148914)
			(xy 162.537946 -255.137054) (xy 162.488332 -255.117582) (xy 162.442174 -255.090933) (xy 162.400503 -255.057702)
			(xy 162.364251 -255.018631) (xy 162.334227 -254.974594) (xy 162.311101 -254.926573) (xy 162.295391 -254.875643)
			(xy 162.287448 -254.822939) (xy 162.28695 -254.79629) (xy 158.88716 -254.79629) (xy 158.88716 -256.24663)
			(xy 206.828388 -256.24663) (xy 206.832459 -256.191008) (xy 206.844585 -256.136571) (xy 206.864508 -256.08448)
			(xy 206.891804 -256.035845) (xy 206.92589 -255.991702) (xy 206.966039 -255.952993) (xy 207.011397 -255.920542)
			(xy 207.060997 -255.895041) (xy 207.113781 -255.877034) (xy 207.168624 -255.866904) (xy 207.224358 -255.864867)
			(xy 207.279795 -255.870967) (xy 207.333752 -255.885073) (xy 207.385081 -255.906885) (xy 207.432687 -255.935939)
			(xy 207.475555 -255.971614) (xy 207.512772 -256.013151) (xy 207.543545 -256.059664) (xy 207.567217 -256.110161)
			(xy 207.583285 -256.163568) (xy 207.591405 -256.218744) (xy 207.591914 -256.24663) (xy 207.591405 -256.274516)
			(xy 207.583285 -256.329692) (xy 207.567217 -256.383099) (xy 207.543545 -256.433596) (xy 207.512772 -256.480109)
			(xy 207.475555 -256.521646) (xy 207.432687 -256.557321) (xy 207.385081 -256.586375) (xy 207.333752 -256.608187)
			(xy 207.279795 -256.622293) (xy 207.224358 -256.628393) (xy 207.168624 -256.626356) (xy 207.113781 -256.616226)
			(xy 207.060997 -256.598219) (xy 207.011397 -256.572718) (xy 206.966039 -256.540267) (xy 206.92589 -256.501558)
			(xy 206.891804 -256.457415) (xy 206.864508 -256.40878) (xy 206.844585 -256.356689) (xy 206.832459 -256.302252)
			(xy 206.828388 -256.24663) (xy 158.88716 -256.24663) (xy 158.88716 -259.393415) (xy 172.440336 -259.393415)
			(xy 172.440336 -259.340117) (xy 172.448279 -259.287413) (xy 172.463989 -259.236483) (xy 172.487115 -259.188462)
			(xy 172.517139 -259.144425) (xy 172.553391 -259.105354) (xy 172.595062 -259.072123) (xy 172.64122 -259.045474)
			(xy 172.690834 -259.026002) (xy 172.742796 -259.014142) (xy 172.795946 -259.010159) (xy 172.849096 -259.014142)
			(xy 172.901058 -259.026002) (xy 172.950672 -259.045474) (xy 172.99683 -259.072123) (xy 173.038501 -259.105354)
			(xy 173.074753 -259.144425) (xy 173.104777 -259.188462) (xy 173.127903 -259.236483) (xy 173.143613 -259.287413)
			(xy 173.151556 -259.340117) (xy 173.152054 -259.366766) (xy 173.151556 -259.393415) (xy 176.540404 -259.393415)
			(xy 176.540404 -259.340117) (xy 176.548347 -259.287413) (xy 176.564057 -259.236483) (xy 176.587183 -259.188462)
			(xy 176.617207 -259.144425) (xy 176.653459 -259.105354) (xy 176.69513 -259.072123) (xy 176.741288 -259.045474)
			(xy 176.790902 -259.026002) (xy 176.842864 -259.014142) (xy 176.896014 -259.010159) (xy 176.949164 -259.014142)
			(xy 177.001126 -259.026002) (xy 177.05074 -259.045474) (xy 177.096898 -259.072123) (xy 177.138569 -259.105354)
			(xy 177.174821 -259.144425) (xy 177.204845 -259.188462) (xy 177.227971 -259.236483) (xy 177.243681 -259.287413)
			(xy 177.251624 -259.340117) (xy 177.252122 -259.366766) (xy 177.251624 -259.393415) (xy 184.084204 -259.393415)
			(xy 184.084204 -259.340117) (xy 184.092147 -259.287413) (xy 184.107857 -259.236483) (xy 184.130983 -259.188462)
			(xy 184.161007 -259.144425) (xy 184.197259 -259.105354) (xy 184.23893 -259.072123) (xy 184.285088 -259.045474)
			(xy 184.334702 -259.026002) (xy 184.386664 -259.014142) (xy 184.439814 -259.010159) (xy 184.492964 -259.014142)
			(xy 184.544926 -259.026002) (xy 184.59454 -259.045474) (xy 184.640698 -259.072123) (xy 184.682369 -259.105354)
			(xy 184.718621 -259.144425) (xy 184.748645 -259.188462) (xy 184.771771 -259.236483) (xy 184.787481 -259.287413)
			(xy 184.795424 -259.340117) (xy 184.795922 -259.366766) (xy 184.795424 -259.393415) (xy 187.527936 -259.393415)
			(xy 187.527936 -259.340117) (xy 187.535879 -259.287413) (xy 187.551589 -259.236483) (xy 187.574715 -259.188462)
			(xy 187.604739 -259.144425) (xy 187.640991 -259.105354) (xy 187.682662 -259.072123) (xy 187.72882 -259.045474)
			(xy 187.778434 -259.026002) (xy 187.830396 -259.014142) (xy 187.883546 -259.010159) (xy 187.936696 -259.014142)
			(xy 187.988658 -259.026002) (xy 188.038272 -259.045474) (xy 188.08443 -259.072123) (xy 188.126101 -259.105354)
			(xy 188.162353 -259.144425) (xy 188.192377 -259.188462) (xy 188.215503 -259.236483) (xy 188.231213 -259.287413)
			(xy 188.239156 -259.340117) (xy 188.239654 -259.366766) (xy 188.239156 -259.393415) (xy 191.628004 -259.393415)
			(xy 191.628004 -259.340117) (xy 191.635947 -259.287413) (xy 191.651657 -259.236483) (xy 191.674783 -259.188462)
			(xy 191.704807 -259.144425) (xy 191.741059 -259.105354) (xy 191.78273 -259.072123) (xy 191.828888 -259.045474)
			(xy 191.878502 -259.026002) (xy 191.930464 -259.014142) (xy 191.983614 -259.010159) (xy 192.036764 -259.014142)
			(xy 192.088726 -259.026002) (xy 192.13834 -259.045474) (xy 192.184498 -259.072123) (xy 192.226169 -259.105354)
			(xy 192.262421 -259.144425) (xy 192.292445 -259.188462) (xy 192.315571 -259.236483) (xy 192.331281 -259.287413)
			(xy 192.339224 -259.340117) (xy 192.339722 -259.366766) (xy 192.339224 -259.393415) (xy 199.171804 -259.393415)
			(xy 199.171804 -259.340117) (xy 199.179747 -259.287413) (xy 199.195457 -259.236483) (xy 199.218583 -259.188462)
			(xy 199.248607 -259.144425) (xy 199.284859 -259.105354) (xy 199.32653 -259.072123) (xy 199.372688 -259.045474)
			(xy 199.422302 -259.026002) (xy 199.474264 -259.014142) (xy 199.527414 -259.010159) (xy 199.580564 -259.014142)
			(xy 199.632526 -259.026002) (xy 199.68214 -259.045474) (xy 199.728298 -259.072123) (xy 199.769969 -259.105354)
			(xy 199.806221 -259.144425) (xy 199.836245 -259.188462) (xy 199.859371 -259.236483) (xy 199.875081 -259.287413)
			(xy 199.883024 -259.340117) (xy 199.883522 -259.366766) (xy 199.883024 -259.393415) (xy 202.615536 -259.393415)
			(xy 202.615536 -259.340117) (xy 202.623479 -259.287413) (xy 202.639189 -259.236483) (xy 202.662315 -259.188462)
			(xy 202.692339 -259.144425) (xy 202.728591 -259.105354) (xy 202.770262 -259.072123) (xy 202.81642 -259.045474)
			(xy 202.866034 -259.026002) (xy 202.917996 -259.014142) (xy 202.971146 -259.010159) (xy 203.024296 -259.014142)
			(xy 203.076258 -259.026002) (xy 203.125872 -259.045474) (xy 203.17203 -259.072123) (xy 203.213701 -259.105354)
			(xy 203.249953 -259.144425) (xy 203.279977 -259.188462) (xy 203.303103 -259.236483) (xy 203.318813 -259.287413)
			(xy 203.326756 -259.340117) (xy 203.327254 -259.366766) (xy 203.326756 -259.393415) (xy 206.715604 -259.393415)
			(xy 206.715604 -259.340117) (xy 206.723547 -259.287413) (xy 206.739257 -259.236483) (xy 206.762383 -259.188462)
			(xy 206.792407 -259.144425) (xy 206.828659 -259.105354) (xy 206.87033 -259.072123) (xy 206.916488 -259.045474)
			(xy 206.966102 -259.026002) (xy 207.018064 -259.014142) (xy 207.071214 -259.010159) (xy 207.124364 -259.014142)
			(xy 207.176326 -259.026002) (xy 207.22594 -259.045474) (xy 207.272098 -259.072123) (xy 207.313769 -259.105354)
			(xy 207.350021 -259.144425) (xy 207.380045 -259.188462) (xy 207.403171 -259.236483) (xy 207.418881 -259.287413)
			(xy 207.426824 -259.340117) (xy 207.427322 -259.366766) (xy 207.426824 -259.393415) (xy 214.259404 -259.393415)
			(xy 214.259404 -259.340117) (xy 214.267347 -259.287413) (xy 214.283057 -259.236483) (xy 214.306183 -259.188462)
			(xy 214.336207 -259.144425) (xy 214.372459 -259.105354) (xy 214.41413 -259.072123) (xy 214.460288 -259.045474)
			(xy 214.509902 -259.026002) (xy 214.561864 -259.014142) (xy 214.615014 -259.010159) (xy 214.668164 -259.014142)
			(xy 214.720126 -259.026002) (xy 214.76974 -259.045474) (xy 214.815898 -259.072123) (xy 214.857569 -259.105354)
			(xy 214.893821 -259.144425) (xy 214.923845 -259.188462) (xy 214.946971 -259.236483) (xy 214.962681 -259.287413)
			(xy 214.970624 -259.340117) (xy 214.971122 -259.366766) (xy 214.970624 -259.393415) (xy 214.962681 -259.446119)
			(xy 214.946971 -259.497049) (xy 214.923845 -259.54507) (xy 214.893821 -259.589107) (xy 214.857569 -259.628178)
			(xy 214.815898 -259.661409) (xy 214.76974 -259.688058) (xy 214.720126 -259.70753) (xy 214.668164 -259.71939)
			(xy 214.615014 -259.723374) (xy 214.561864 -259.71939) (xy 214.509902 -259.70753) (xy 214.460288 -259.688058)
			(xy 214.41413 -259.661409) (xy 214.372459 -259.628178) (xy 214.336207 -259.589107) (xy 214.306183 -259.54507)
			(xy 214.283057 -259.497049) (xy 214.267347 -259.446119) (xy 214.259404 -259.393415) (xy 207.426824 -259.393415)
			(xy 207.418881 -259.446119) (xy 207.403171 -259.497049) (xy 207.380045 -259.54507) (xy 207.350021 -259.589107)
			(xy 207.313769 -259.628178) (xy 207.272098 -259.661409) (xy 207.22594 -259.688058) (xy 207.176326 -259.70753)
			(xy 207.124364 -259.71939) (xy 207.071214 -259.723374) (xy 207.018064 -259.71939) (xy 206.966102 -259.70753)
			(xy 206.916488 -259.688058) (xy 206.87033 -259.661409) (xy 206.828659 -259.628178) (xy 206.792407 -259.589107)
			(xy 206.762383 -259.54507) (xy 206.739257 -259.497049) (xy 206.723547 -259.446119) (xy 206.715604 -259.393415)
			(xy 203.326756 -259.393415) (xy 203.318813 -259.446119) (xy 203.303103 -259.497049) (xy 203.279977 -259.54507)
			(xy 203.249953 -259.589107) (xy 203.213701 -259.628178) (xy 203.17203 -259.661409) (xy 203.125872 -259.688058)
			(xy 203.076258 -259.70753) (xy 203.024296 -259.71939) (xy 202.971146 -259.723374) (xy 202.917996 -259.71939)
			(xy 202.866034 -259.70753) (xy 202.81642 -259.688058) (xy 202.770262 -259.661409) (xy 202.728591 -259.628178)
			(xy 202.692339 -259.589107) (xy 202.662315 -259.54507) (xy 202.639189 -259.497049) (xy 202.623479 -259.446119)
			(xy 202.615536 -259.393415) (xy 199.883024 -259.393415) (xy 199.875081 -259.446119) (xy 199.859371 -259.497049)
			(xy 199.836245 -259.54507) (xy 199.806221 -259.589107) (xy 199.769969 -259.628178) (xy 199.728298 -259.661409)
			(xy 199.68214 -259.688058) (xy 199.632526 -259.70753) (xy 199.580564 -259.71939) (xy 199.527414 -259.723374)
			(xy 199.474264 -259.71939) (xy 199.422302 -259.70753) (xy 199.372688 -259.688058) (xy 199.32653 -259.661409)
			(xy 199.284859 -259.628178) (xy 199.248607 -259.589107) (xy 199.218583 -259.54507) (xy 199.195457 -259.497049)
			(xy 199.179747 -259.446119) (xy 199.171804 -259.393415) (xy 192.339224 -259.393415) (xy 192.331281 -259.446119)
			(xy 192.315571 -259.497049) (xy 192.292445 -259.54507) (xy 192.262421 -259.589107) (xy 192.226169 -259.628178)
			(xy 192.184498 -259.661409) (xy 192.13834 -259.688058) (xy 192.088726 -259.70753) (xy 192.036764 -259.71939)
			(xy 191.983614 -259.723374) (xy 191.930464 -259.71939) (xy 191.878502 -259.70753) (xy 191.828888 -259.688058)
			(xy 191.78273 -259.661409) (xy 191.741059 -259.628178) (xy 191.704807 -259.589107) (xy 191.674783 -259.54507)
			(xy 191.651657 -259.497049) (xy 191.635947 -259.446119) (xy 191.628004 -259.393415) (xy 188.239156 -259.393415)
			(xy 188.231213 -259.446119) (xy 188.215503 -259.497049) (xy 188.192377 -259.54507) (xy 188.162353 -259.589107)
			(xy 188.126101 -259.628178) (xy 188.08443 -259.661409) (xy 188.038272 -259.688058) (xy 187.988658 -259.70753)
			(xy 187.936696 -259.71939) (xy 187.883546 -259.723374) (xy 187.830396 -259.71939) (xy 187.778434 -259.70753)
			(xy 187.72882 -259.688058) (xy 187.682662 -259.661409) (xy 187.640991 -259.628178) (xy 187.604739 -259.589107)
			(xy 187.574715 -259.54507) (xy 187.551589 -259.497049) (xy 187.535879 -259.446119) (xy 187.527936 -259.393415)
			(xy 184.795424 -259.393415) (xy 184.787481 -259.446119) (xy 184.771771 -259.497049) (xy 184.748645 -259.54507)
			(xy 184.718621 -259.589107) (xy 184.682369 -259.628178) (xy 184.640698 -259.661409) (xy 184.59454 -259.688058)
			(xy 184.544926 -259.70753) (xy 184.492964 -259.71939) (xy 184.439814 -259.723374) (xy 184.386664 -259.71939)
			(xy 184.334702 -259.70753) (xy 184.285088 -259.688058) (xy 184.23893 -259.661409) (xy 184.197259 -259.628178)
			(xy 184.161007 -259.589107) (xy 184.130983 -259.54507) (xy 184.107857 -259.497049) (xy 184.092147 -259.446119)
			(xy 184.084204 -259.393415) (xy 177.251624 -259.393415) (xy 177.243681 -259.446119) (xy 177.227971 -259.497049)
			(xy 177.204845 -259.54507) (xy 177.174821 -259.589107) (xy 177.138569 -259.628178) (xy 177.096898 -259.661409)
			(xy 177.05074 -259.688058) (xy 177.001126 -259.70753) (xy 176.949164 -259.71939) (xy 176.896014 -259.723374)
			(xy 176.842864 -259.71939) (xy 176.790902 -259.70753) (xy 176.741288 -259.688058) (xy 176.69513 -259.661409)
			(xy 176.653459 -259.628178) (xy 176.617207 -259.589107) (xy 176.587183 -259.54507) (xy 176.564057 -259.497049)
			(xy 176.548347 -259.446119) (xy 176.540404 -259.393415) (xy 173.151556 -259.393415) (xy 173.143613 -259.446119)
			(xy 173.127903 -259.497049) (xy 173.104777 -259.54507) (xy 173.074753 -259.589107) (xy 173.038501 -259.628178)
			(xy 172.99683 -259.661409) (xy 172.950672 -259.688058) (xy 172.901058 -259.70753) (xy 172.849096 -259.71939)
			(xy 172.795946 -259.723374) (xy 172.742796 -259.71939) (xy 172.690834 -259.70753) (xy 172.64122 -259.688058)
			(xy 172.595062 -259.661409) (xy 172.553391 -259.628178) (xy 172.517139 -259.589107) (xy 172.487115 -259.54507)
			(xy 172.463989 -259.497049) (xy 172.448279 -259.446119) (xy 172.440336 -259.393415) (xy 158.88716 -259.393415)
			(xy 158.88716 -260.243299) (xy 176.540404 -260.243299) (xy 176.540404 -260.190001) (xy 176.548347 -260.137297)
			(xy 176.564057 -260.086367) (xy 176.587183 -260.038346) (xy 176.617207 -259.994309) (xy 176.653459 -259.955238)
			(xy 176.69513 -259.922007) (xy 176.741288 -259.895358) (xy 176.790902 -259.875886) (xy 176.842864 -259.864026)
			(xy 176.896014 -259.860043) (xy 176.949164 -259.864026) (xy 177.001126 -259.875886) (xy 177.05074 -259.895358)
			(xy 177.096898 -259.922007) (xy 177.138569 -259.955238) (xy 177.174821 -259.994309) (xy 177.204845 -260.038346)
			(xy 177.227971 -260.086367) (xy 177.243681 -260.137297) (xy 177.251624 -260.190001) (xy 177.252122 -260.21665)
			(xy 177.251624 -260.243299) (xy 184.084204 -260.243299) (xy 184.084204 -260.190001) (xy 184.092147 -260.137297)
			(xy 184.107857 -260.086367) (xy 184.130983 -260.038346) (xy 184.161007 -259.994309) (xy 184.197259 -259.955238)
			(xy 184.23893 -259.922007) (xy 184.285088 -259.895358) (xy 184.334702 -259.875886) (xy 184.386664 -259.864026)
			(xy 184.439814 -259.860043) (xy 184.492964 -259.864026) (xy 184.544926 -259.875886) (xy 184.59454 -259.895358)
			(xy 184.640698 -259.922007) (xy 184.682369 -259.955238) (xy 184.718621 -259.994309) (xy 184.748645 -260.038346)
			(xy 184.771771 -260.086367) (xy 184.787481 -260.137297) (xy 184.795424 -260.190001) (xy 184.795922 -260.21665)
			(xy 184.795424 -260.243299) (xy 191.628004 -260.243299) (xy 191.628004 -260.190001) (xy 191.635947 -260.137297)
			(xy 191.651657 -260.086367) (xy 191.674783 -260.038346) (xy 191.704807 -259.994309) (xy 191.741059 -259.955238)
			(xy 191.78273 -259.922007) (xy 191.828888 -259.895358) (xy 191.878502 -259.875886) (xy 191.930464 -259.864026)
			(xy 191.983614 -259.860043) (xy 192.036764 -259.864026) (xy 192.088726 -259.875886) (xy 192.13834 -259.895358)
			(xy 192.184498 -259.922007) (xy 192.226169 -259.955238) (xy 192.262421 -259.994309) (xy 192.292445 -260.038346)
			(xy 192.315571 -260.086367) (xy 192.331281 -260.137297) (xy 192.339224 -260.190001) (xy 192.339722 -260.21665)
			(xy 192.339224 -260.243299) (xy 199.171804 -260.243299) (xy 199.171804 -260.190001) (xy 199.179747 -260.137297)
			(xy 199.195457 -260.086367) (xy 199.218583 -260.038346) (xy 199.248607 -259.994309) (xy 199.284859 -259.955238)
			(xy 199.32653 -259.922007) (xy 199.372688 -259.895358) (xy 199.422302 -259.875886) (xy 199.474264 -259.864026)
			(xy 199.527414 -259.860043) (xy 199.580564 -259.864026) (xy 199.632526 -259.875886) (xy 199.68214 -259.895358)
			(xy 199.728298 -259.922007) (xy 199.769969 -259.955238) (xy 199.806221 -259.994309) (xy 199.836245 -260.038346)
			(xy 199.859371 -260.086367) (xy 199.875081 -260.137297) (xy 199.883024 -260.190001) (xy 199.883522 -260.21665)
			(xy 199.883024 -260.243299) (xy 206.715604 -260.243299) (xy 206.715604 -260.190001) (xy 206.723547 -260.137297)
			(xy 206.739257 -260.086367) (xy 206.762383 -260.038346) (xy 206.792407 -259.994309) (xy 206.828659 -259.955238)
			(xy 206.87033 -259.922007) (xy 206.916488 -259.895358) (xy 206.966102 -259.875886) (xy 207.018064 -259.864026)
			(xy 207.071214 -259.860043) (xy 207.124364 -259.864026) (xy 207.176326 -259.875886) (xy 207.22594 -259.895358)
			(xy 207.272098 -259.922007) (xy 207.313769 -259.955238) (xy 207.350021 -259.994309) (xy 207.380045 -260.038346)
			(xy 207.403171 -260.086367) (xy 207.418881 -260.137297) (xy 207.426824 -260.190001) (xy 207.427322 -260.21665)
			(xy 207.426824 -260.243299) (xy 214.259404 -260.243299) (xy 214.259404 -260.190001) (xy 214.267347 -260.137297)
			(xy 214.283057 -260.086367) (xy 214.306183 -260.038346) (xy 214.336207 -259.994309) (xy 214.372459 -259.955238)
			(xy 214.41413 -259.922007) (xy 214.460288 -259.895358) (xy 214.509902 -259.875886) (xy 214.561864 -259.864026)
			(xy 214.615014 -259.860043) (xy 214.668164 -259.864026) (xy 214.720126 -259.875886) (xy 214.76974 -259.895358)
			(xy 214.815898 -259.922007) (xy 214.857569 -259.955238) (xy 214.893821 -259.994309) (xy 214.923845 -260.038346)
			(xy 214.946971 -260.086367) (xy 214.962681 -260.137297) (xy 214.970624 -260.190001) (xy 214.971122 -260.21665)
			(xy 214.970624 -260.243299) (xy 214.962681 -260.296003) (xy 214.946971 -260.346933) (xy 214.923845 -260.394954)
			(xy 214.893821 -260.438991) (xy 214.857569 -260.478062) (xy 214.815898 -260.511293) (xy 214.76974 -260.537942)
			(xy 214.720126 -260.557414) (xy 214.668164 -260.569274) (xy 214.615014 -260.573258) (xy 214.561864 -260.569274)
			(xy 214.509902 -260.557414) (xy 214.460288 -260.537942) (xy 214.41413 -260.511293) (xy 214.372459 -260.478062)
			(xy 214.336207 -260.438991) (xy 214.306183 -260.394954) (xy 214.283057 -260.346933) (xy 214.267347 -260.296003)
			(xy 214.259404 -260.243299) (xy 207.426824 -260.243299) (xy 207.418881 -260.296003) (xy 207.403171 -260.346933)
			(xy 207.380045 -260.394954) (xy 207.350021 -260.438991) (xy 207.313769 -260.478062) (xy 207.272098 -260.511293)
			(xy 207.22594 -260.537942) (xy 207.176326 -260.557414) (xy 207.124364 -260.569274) (xy 207.071214 -260.573258)
			(xy 207.018064 -260.569274) (xy 206.966102 -260.557414) (xy 206.916488 -260.537942) (xy 206.87033 -260.511293)
			(xy 206.828659 -260.478062) (xy 206.792407 -260.438991) (xy 206.762383 -260.394954) (xy 206.739257 -260.346933)
			(xy 206.723547 -260.296003) (xy 206.715604 -260.243299) (xy 199.883024 -260.243299) (xy 199.875081 -260.296003)
			(xy 199.859371 -260.346933) (xy 199.836245 -260.394954) (xy 199.806221 -260.438991) (xy 199.769969 -260.478062)
			(xy 199.728298 -260.511293) (xy 199.68214 -260.537942) (xy 199.632526 -260.557414) (xy 199.580564 -260.569274)
			(xy 199.527414 -260.573258) (xy 199.474264 -260.569274) (xy 199.422302 -260.557414) (xy 199.372688 -260.537942)
			(xy 199.32653 -260.511293) (xy 199.284859 -260.478062) (xy 199.248607 -260.438991) (xy 199.218583 -260.394954)
			(xy 199.195457 -260.346933) (xy 199.179747 -260.296003) (xy 199.171804 -260.243299) (xy 192.339224 -260.243299)
			(xy 192.331281 -260.296003) (xy 192.315571 -260.346933) (xy 192.292445 -260.394954) (xy 192.262421 -260.438991)
			(xy 192.226169 -260.478062) (xy 192.184498 -260.511293) (xy 192.13834 -260.537942) (xy 192.088726 -260.557414)
			(xy 192.036764 -260.569274) (xy 191.983614 -260.573258) (xy 191.930464 -260.569274) (xy 191.878502 -260.557414)
			(xy 191.828888 -260.537942) (xy 191.78273 -260.511293) (xy 191.741059 -260.478062) (xy 191.704807 -260.438991)
			(xy 191.674783 -260.394954) (xy 191.651657 -260.346933) (xy 191.635947 -260.296003) (xy 191.628004 -260.243299)
			(xy 184.795424 -260.243299) (xy 184.787481 -260.296003) (xy 184.771771 -260.346933) (xy 184.748645 -260.394954)
			(xy 184.718621 -260.438991) (xy 184.682369 -260.478062) (xy 184.640698 -260.511293) (xy 184.59454 -260.537942)
			(xy 184.544926 -260.557414) (xy 184.492964 -260.569274) (xy 184.439814 -260.573258) (xy 184.386664 -260.569274)
			(xy 184.334702 -260.557414) (xy 184.285088 -260.537942) (xy 184.23893 -260.511293) (xy 184.197259 -260.478062)
			(xy 184.161007 -260.438991) (xy 184.130983 -260.394954) (xy 184.107857 -260.346933) (xy 184.092147 -260.296003)
			(xy 184.084204 -260.243299) (xy 177.251624 -260.243299) (xy 177.243681 -260.296003) (xy 177.227971 -260.346933)
			(xy 177.204845 -260.394954) (xy 177.174821 -260.438991) (xy 177.138569 -260.478062) (xy 177.096898 -260.511293)
			(xy 177.05074 -260.537942) (xy 177.001126 -260.557414) (xy 176.949164 -260.569274) (xy 176.896014 -260.573258)
			(xy 176.842864 -260.569274) (xy 176.790902 -260.557414) (xy 176.741288 -260.537942) (xy 176.69513 -260.511293)
			(xy 176.653459 -260.478062) (xy 176.617207 -260.438991) (xy 176.587183 -260.394954) (xy 176.564057 -260.346933)
			(xy 176.548347 -260.296003) (xy 176.540404 -260.243299) (xy 158.88716 -260.243299) (xy 158.88716 -261.093437)
			(xy 172.364136 -261.093437) (xy 172.364136 -261.040139) (xy 172.372079 -260.987435) (xy 172.387789 -260.936505)
			(xy 172.410915 -260.888484) (xy 172.440939 -260.844447) (xy 172.477191 -260.805376) (xy 172.518862 -260.772145)
			(xy 172.56502 -260.745496) (xy 172.614634 -260.726024) (xy 172.666596 -260.714164) (xy 172.719746 -260.710181)
			(xy 172.772896 -260.714164) (xy 172.824858 -260.726024) (xy 172.874472 -260.745496) (xy 172.92063 -260.772145)
			(xy 172.962301 -260.805376) (xy 172.998553 -260.844447) (xy 173.028577 -260.888484) (xy 173.051703 -260.936505)
			(xy 173.067413 -260.987435) (xy 173.075356 -261.040139) (xy 173.075854 -261.066788) (xy 173.075356 -261.093437)
			(xy 187.527936 -261.093437) (xy 187.527936 -261.040139) (xy 187.535879 -260.987435) (xy 187.551589 -260.936505)
			(xy 187.574715 -260.888484) (xy 187.604739 -260.844447) (xy 187.640991 -260.805376) (xy 187.682662 -260.772145)
			(xy 187.72882 -260.745496) (xy 187.778434 -260.726024) (xy 187.830396 -260.714164) (xy 187.883546 -260.710181)
			(xy 187.936696 -260.714164) (xy 187.988658 -260.726024) (xy 188.038272 -260.745496) (xy 188.08443 -260.772145)
			(xy 188.126101 -260.805376) (xy 188.162353 -260.844447) (xy 188.192377 -260.888484) (xy 188.215503 -260.936505)
			(xy 188.231213 -260.987435) (xy 188.239156 -261.040139) (xy 188.239654 -261.066788) (xy 188.239156 -261.093437)
			(xy 202.615536 -261.093437) (xy 202.615536 -261.040139) (xy 202.623479 -260.987435) (xy 202.639189 -260.936505)
			(xy 202.662315 -260.888484) (xy 202.692339 -260.844447) (xy 202.728591 -260.805376) (xy 202.770262 -260.772145)
			(xy 202.81642 -260.745496) (xy 202.866034 -260.726024) (xy 202.917996 -260.714164) (xy 202.971146 -260.710181)
			(xy 203.024296 -260.714164) (xy 203.076258 -260.726024) (xy 203.125872 -260.745496) (xy 203.17203 -260.772145)
			(xy 203.213701 -260.805376) (xy 203.249953 -260.844447) (xy 203.279977 -260.888484) (xy 203.303103 -260.936505)
			(xy 203.318813 -260.987435) (xy 203.326756 -261.040139) (xy 203.327254 -261.066788) (xy 203.326756 -261.093437)
			(xy 203.318813 -261.146141) (xy 203.303103 -261.197071) (xy 203.279977 -261.245092) (xy 203.249953 -261.289129)
			(xy 203.213701 -261.3282) (xy 203.17203 -261.361431) (xy 203.125872 -261.38808) (xy 203.076258 -261.407552)
			(xy 203.024296 -261.419412) (xy 202.971146 -261.423396) (xy 202.917996 -261.419412) (xy 202.866034 -261.407552)
			(xy 202.81642 -261.38808) (xy 202.770262 -261.361431) (xy 202.728591 -261.3282) (xy 202.692339 -261.289129)
			(xy 202.662315 -261.245092) (xy 202.639189 -261.197071) (xy 202.623479 -261.146141) (xy 202.615536 -261.093437)
			(xy 188.239156 -261.093437) (xy 188.231213 -261.146141) (xy 188.215503 -261.197071) (xy 188.192377 -261.245092)
			(xy 188.162353 -261.289129) (xy 188.126101 -261.3282) (xy 188.08443 -261.361431) (xy 188.038272 -261.38808)
			(xy 187.988658 -261.407552) (xy 187.936696 -261.419412) (xy 187.883546 -261.423396) (xy 187.830396 -261.419412)
			(xy 187.778434 -261.407552) (xy 187.72882 -261.38808) (xy 187.682662 -261.361431) (xy 187.640991 -261.3282)
			(xy 187.604739 -261.289129) (xy 187.574715 -261.245092) (xy 187.551589 -261.197071) (xy 187.535879 -261.146141)
			(xy 187.527936 -261.093437) (xy 173.075356 -261.093437) (xy 173.067413 -261.146141) (xy 173.051703 -261.197071)
			(xy 173.028577 -261.245092) (xy 172.998553 -261.289129) (xy 172.962301 -261.3282) (xy 172.92063 -261.361431)
			(xy 172.874472 -261.38808) (xy 172.824858 -261.407552) (xy 172.772896 -261.419412) (xy 172.719746 -261.423396)
			(xy 172.666596 -261.419412) (xy 172.614634 -261.407552) (xy 172.56502 -261.38808) (xy 172.518862 -261.361431)
			(xy 172.477191 -261.3282) (xy 172.440939 -261.289129) (xy 172.410915 -261.245092) (xy 172.387789 -261.197071)
			(xy 172.372079 -261.146141) (xy 172.364136 -261.093437) (xy 158.88716 -261.093437) (xy 158.88716 -261.943321)
			(xy 176.540404 -261.943321) (xy 176.540404 -261.890023) (xy 176.548347 -261.837319) (xy 176.564057 -261.786389)
			(xy 176.587183 -261.738368) (xy 176.617207 -261.694331) (xy 176.653459 -261.65526) (xy 176.69513 -261.622029)
			(xy 176.741288 -261.59538) (xy 176.790902 -261.575908) (xy 176.842864 -261.564048) (xy 176.896014 -261.560065)
			(xy 176.949164 -261.564048) (xy 177.001126 -261.575908) (xy 177.05074 -261.59538) (xy 177.096898 -261.622029)
			(xy 177.138569 -261.65526) (xy 177.174821 -261.694331) (xy 177.204845 -261.738368) (xy 177.227971 -261.786389)
			(xy 177.243681 -261.837319) (xy 177.251624 -261.890023) (xy 177.252122 -261.916672) (xy 177.251624 -261.943321)
			(xy 191.628004 -261.943321) (xy 191.628004 -261.890023) (xy 191.635947 -261.837319) (xy 191.651657 -261.786389)
			(xy 191.674783 -261.738368) (xy 191.704807 -261.694331) (xy 191.741059 -261.65526) (xy 191.78273 -261.622029)
			(xy 191.828888 -261.59538) (xy 191.878502 -261.575908) (xy 191.930464 -261.564048) (xy 191.983614 -261.560065)
			(xy 192.036764 -261.564048) (xy 192.088726 -261.575908) (xy 192.13834 -261.59538) (xy 192.184498 -261.622029)
			(xy 192.226169 -261.65526) (xy 192.262421 -261.694331) (xy 192.292445 -261.738368) (xy 192.315571 -261.786389)
			(xy 192.331281 -261.837319) (xy 192.339224 -261.890023) (xy 192.339722 -261.916672) (xy 192.339224 -261.943321)
			(xy 206.715604 -261.943321) (xy 206.715604 -261.890023) (xy 206.723547 -261.837319) (xy 206.739257 -261.786389)
			(xy 206.762383 -261.738368) (xy 206.792407 -261.694331) (xy 206.828659 -261.65526) (xy 206.87033 -261.622029)
			(xy 206.916488 -261.59538) (xy 206.966102 -261.575908) (xy 207.018064 -261.564048) (xy 207.071214 -261.560065)
			(xy 207.124364 -261.564048) (xy 207.176326 -261.575908) (xy 207.22594 -261.59538) (xy 207.272098 -261.622029)
			(xy 207.313769 -261.65526) (xy 207.350021 -261.694331) (xy 207.380045 -261.738368) (xy 207.403171 -261.786389)
			(xy 207.418881 -261.837319) (xy 207.426824 -261.890023) (xy 207.427322 -261.916672) (xy 207.426824 -261.943321)
			(xy 207.418881 -261.996025) (xy 207.403171 -262.046955) (xy 207.380045 -262.094976) (xy 207.350021 -262.139013)
			(xy 207.313769 -262.178084) (xy 207.272098 -262.211315) (xy 207.22594 -262.237964) (xy 207.176326 -262.257436)
			(xy 207.124364 -262.269296) (xy 207.071214 -262.27328) (xy 207.018064 -262.269296) (xy 206.966102 -262.257436)
			(xy 206.916488 -262.237964) (xy 206.87033 -262.211315) (xy 206.828659 -262.178084) (xy 206.792407 -262.139013)
			(xy 206.762383 -262.094976) (xy 206.739257 -262.046955) (xy 206.723547 -261.996025) (xy 206.715604 -261.943321)
			(xy 192.339224 -261.943321) (xy 192.331281 -261.996025) (xy 192.315571 -262.046955) (xy 192.292445 -262.094976)
			(xy 192.262421 -262.139013) (xy 192.226169 -262.178084) (xy 192.184498 -262.211315) (xy 192.13834 -262.237964)
			(xy 192.088726 -262.257436) (xy 192.036764 -262.269296) (xy 191.983614 -262.27328) (xy 191.930464 -262.269296)
			(xy 191.878502 -262.257436) (xy 191.828888 -262.237964) (xy 191.78273 -262.211315) (xy 191.741059 -262.178084)
			(xy 191.704807 -262.139013) (xy 191.674783 -262.094976) (xy 191.651657 -262.046955) (xy 191.635947 -261.996025)
			(xy 191.628004 -261.943321) (xy 177.251624 -261.943321) (xy 177.243681 -261.996025) (xy 177.227971 -262.046955)
			(xy 177.204845 -262.094976) (xy 177.174821 -262.139013) (xy 177.138569 -262.178084) (xy 177.096898 -262.211315)
			(xy 177.05074 -262.237964) (xy 177.001126 -262.257436) (xy 176.949164 -262.269296) (xy 176.896014 -262.27328)
			(xy 176.842864 -262.269296) (xy 176.790902 -262.257436) (xy 176.741288 -262.237964) (xy 176.69513 -262.211315)
			(xy 176.653459 -262.178084) (xy 176.617207 -262.139013) (xy 176.587183 -262.094976) (xy 176.564057 -262.046955)
			(xy 176.548347 -261.996025) (xy 176.540404 -261.943321) (xy 158.88716 -261.943321) (xy 158.88716 -262.793205)
			(xy 172.364136 -262.793205) (xy 172.364136 -262.739907) (xy 172.372079 -262.687203) (xy 172.387789 -262.636273)
			(xy 172.410915 -262.588252) (xy 172.440939 -262.544215) (xy 172.477191 -262.505144) (xy 172.518862 -262.471913)
			(xy 172.56502 -262.445264) (xy 172.614634 -262.425792) (xy 172.666596 -262.413932) (xy 172.719746 -262.409949)
			(xy 172.772896 -262.413932) (xy 172.824858 -262.425792) (xy 172.874472 -262.445264) (xy 172.92063 -262.471913)
			(xy 172.962301 -262.505144) (xy 172.998553 -262.544215) (xy 173.028577 -262.588252) (xy 173.051703 -262.636273)
			(xy 173.067413 -262.687203) (xy 173.075356 -262.739907) (xy 173.075854 -262.766556) (xy 173.075356 -262.793205)
			(xy 187.527936 -262.793205) (xy 187.527936 -262.739907) (xy 187.535879 -262.687203) (xy 187.551589 -262.636273)
			(xy 187.574715 -262.588252) (xy 187.604739 -262.544215) (xy 187.640991 -262.505144) (xy 187.682662 -262.471913)
			(xy 187.72882 -262.445264) (xy 187.778434 -262.425792) (xy 187.830396 -262.413932) (xy 187.883546 -262.409949)
			(xy 187.936696 -262.413932) (xy 187.988658 -262.425792) (xy 188.038272 -262.445264) (xy 188.08443 -262.471913)
			(xy 188.126101 -262.505144) (xy 188.162353 -262.544215) (xy 188.192377 -262.588252) (xy 188.215503 -262.636273)
			(xy 188.231213 -262.687203) (xy 188.239156 -262.739907) (xy 188.239654 -262.766556) (xy 188.239156 -262.793205)
			(xy 188.239118 -262.793459) (xy 202.615536 -262.793459) (xy 202.615536 -262.740161) (xy 202.623479 -262.687457)
			(xy 202.639189 -262.636527) (xy 202.662315 -262.588506) (xy 202.692339 -262.544469) (xy 202.728591 -262.505398)
			(xy 202.770262 -262.472167) (xy 202.81642 -262.445518) (xy 202.866034 -262.426046) (xy 202.917996 -262.414186)
			(xy 202.971146 -262.410203) (xy 203.024296 -262.414186) (xy 203.076258 -262.426046) (xy 203.125872 -262.445518)
			(xy 203.17203 -262.472167) (xy 203.213701 -262.505398) (xy 203.249953 -262.544469) (xy 203.279977 -262.588506)
			(xy 203.303103 -262.636527) (xy 203.318813 -262.687457) (xy 203.326756 -262.740161) (xy 203.327254 -262.76681)
			(xy 203.326756 -262.793459) (xy 203.318813 -262.846163) (xy 203.303103 -262.897093) (xy 203.279977 -262.945114)
			(xy 203.249953 -262.989151) (xy 203.213701 -263.028222) (xy 203.17203 -263.061453) (xy 203.125872 -263.088102)
			(xy 203.076258 -263.107574) (xy 203.024296 -263.119434) (xy 202.971146 -263.123418) (xy 202.917996 -263.119434)
			(xy 202.866034 -263.107574) (xy 202.81642 -263.088102) (xy 202.770262 -263.061453) (xy 202.728591 -263.028222)
			(xy 202.692339 -262.989151) (xy 202.662315 -262.945114) (xy 202.639189 -262.897093) (xy 202.623479 -262.846163)
			(xy 202.615536 -262.793459) (xy 188.239118 -262.793459) (xy 188.231213 -262.845909) (xy 188.215503 -262.896839)
			(xy 188.192377 -262.94486) (xy 188.162353 -262.988897) (xy 188.126101 -263.027968) (xy 188.08443 -263.061199)
			(xy 188.038272 -263.087848) (xy 187.988658 -263.10732) (xy 187.936696 -263.11918) (xy 187.883546 -263.123164)
			(xy 187.830396 -263.11918) (xy 187.778434 -263.10732) (xy 187.72882 -263.087848) (xy 187.682662 -263.061199)
			(xy 187.640991 -263.027968) (xy 187.604739 -262.988897) (xy 187.574715 -262.94486) (xy 187.551589 -262.896839)
			(xy 187.535879 -262.845909) (xy 187.527936 -262.793205) (xy 173.075356 -262.793205) (xy 173.067413 -262.845909)
			(xy 173.051703 -262.896839) (xy 173.028577 -262.94486) (xy 172.998553 -262.988897) (xy 172.962301 -263.027968)
			(xy 172.92063 -263.061199) (xy 172.874472 -263.087848) (xy 172.824858 -263.10732) (xy 172.772896 -263.11918)
			(xy 172.719746 -263.123164) (xy 172.666596 -263.11918) (xy 172.614634 -263.10732) (xy 172.56502 -263.087848)
			(xy 172.518862 -263.061199) (xy 172.477191 -263.027968) (xy 172.440939 -262.988897) (xy 172.410915 -262.94486)
			(xy 172.387789 -262.896839) (xy 172.372079 -262.845909) (xy 172.364136 -262.793205) (xy 158.88716 -262.793205)
			(xy 158.88716 -263.643343) (xy 176.464204 -263.643343) (xy 176.464204 -263.590045) (xy 176.472147 -263.537341)
			(xy 176.487857 -263.486411) (xy 176.510983 -263.43839) (xy 176.541007 -263.394353) (xy 176.577259 -263.355282)
			(xy 176.61893 -263.322051) (xy 176.665088 -263.295402) (xy 176.714702 -263.27593) (xy 176.766664 -263.26407)
			(xy 176.819814 -263.260087) (xy 176.872964 -263.26407) (xy 176.924926 -263.27593) (xy 176.97454 -263.295402)
			(xy 177.020698 -263.322051) (xy 177.062369 -263.355282) (xy 177.098621 -263.394353) (xy 177.128645 -263.43839)
			(xy 177.151771 -263.486411) (xy 177.167481 -263.537341) (xy 177.175424 -263.590045) (xy 177.175922 -263.616694)
			(xy 177.175424 -263.643343) (xy 191.551804 -263.643343) (xy 191.551804 -263.590045) (xy 191.559747 -263.537341)
			(xy 191.575457 -263.486411) (xy 191.598583 -263.43839) (xy 191.628607 -263.394353) (xy 191.664859 -263.355282)
			(xy 191.70653 -263.322051) (xy 191.752688 -263.295402) (xy 191.802302 -263.27593) (xy 191.854264 -263.26407)
			(xy 191.907414 -263.260087) (xy 191.960564 -263.26407) (xy 192.012526 -263.27593) (xy 192.06214 -263.295402)
			(xy 192.108298 -263.322051) (xy 192.149969 -263.355282) (xy 192.186221 -263.394353) (xy 192.216245 -263.43839)
			(xy 192.239371 -263.486411) (xy 192.255081 -263.537341) (xy 192.263024 -263.590045) (xy 192.263522 -263.616694)
			(xy 192.263024 -263.643343) (xy 206.715604 -263.643343) (xy 206.715604 -263.590045) (xy 206.723547 -263.537341)
			(xy 206.739257 -263.486411) (xy 206.762383 -263.43839) (xy 206.792407 -263.394353) (xy 206.828659 -263.355282)
			(xy 206.87033 -263.322051) (xy 206.916488 -263.295402) (xy 206.966102 -263.27593) (xy 207.018064 -263.26407)
			(xy 207.071214 -263.260087) (xy 207.124364 -263.26407) (xy 207.176326 -263.27593) (xy 207.22594 -263.295402)
			(xy 207.272098 -263.322051) (xy 207.313769 -263.355282) (xy 207.350021 -263.394353) (xy 207.380045 -263.43839)
			(xy 207.403171 -263.486411) (xy 207.418881 -263.537341) (xy 207.426824 -263.590045) (xy 207.427322 -263.616694)
			(xy 207.426824 -263.643343) (xy 207.418881 -263.696047) (xy 207.403171 -263.746977) (xy 207.380045 -263.794998)
			(xy 207.350021 -263.839035) (xy 207.313769 -263.878106) (xy 207.272098 -263.911337) (xy 207.22594 -263.937986)
			(xy 207.176326 -263.957458) (xy 207.124364 -263.969318) (xy 207.071214 -263.973302) (xy 207.018064 -263.969318)
			(xy 206.966102 -263.957458) (xy 206.916488 -263.937986) (xy 206.87033 -263.911337) (xy 206.828659 -263.878106)
			(xy 206.792407 -263.839035) (xy 206.762383 -263.794998) (xy 206.739257 -263.746977) (xy 206.723547 -263.696047)
			(xy 206.715604 -263.643343) (xy 192.263024 -263.643343) (xy 192.255081 -263.696047) (xy 192.239371 -263.746977)
			(xy 192.216245 -263.794998) (xy 192.186221 -263.839035) (xy 192.149969 -263.878106) (xy 192.108298 -263.911337)
			(xy 192.06214 -263.937986) (xy 192.012526 -263.957458) (xy 191.960564 -263.969318) (xy 191.907414 -263.973302)
			(xy 191.854264 -263.969318) (xy 191.802302 -263.957458) (xy 191.752688 -263.937986) (xy 191.70653 -263.911337)
			(xy 191.664859 -263.878106) (xy 191.628607 -263.839035) (xy 191.598583 -263.794998) (xy 191.575457 -263.746977)
			(xy 191.559747 -263.696047) (xy 191.551804 -263.643343) (xy 177.175424 -263.643343) (xy 177.167481 -263.696047)
			(xy 177.151771 -263.746977) (xy 177.128645 -263.794998) (xy 177.098621 -263.839035) (xy 177.062369 -263.878106)
			(xy 177.020698 -263.911337) (xy 176.97454 -263.937986) (xy 176.924926 -263.957458) (xy 176.872964 -263.969318)
			(xy 176.819814 -263.973302) (xy 176.766664 -263.969318) (xy 176.714702 -263.957458) (xy 176.665088 -263.937986)
			(xy 176.61893 -263.911337) (xy 176.577259 -263.878106) (xy 176.541007 -263.839035) (xy 176.510983 -263.794998)
			(xy 176.487857 -263.746977) (xy 176.472147 -263.696047) (xy 176.464204 -263.643343) (xy 158.88716 -263.643343)
			(xy 158.88716 -264.493227) (xy 172.364136 -264.493227) (xy 172.364136 -264.439929) (xy 172.372079 -264.387225)
			(xy 172.387789 -264.336295) (xy 172.410915 -264.288274) (xy 172.440939 -264.244237) (xy 172.477191 -264.205166)
			(xy 172.518862 -264.171935) (xy 172.56502 -264.145286) (xy 172.614634 -264.125814) (xy 172.666596 -264.113954)
			(xy 172.719746 -264.109971) (xy 172.772896 -264.113954) (xy 172.824858 -264.125814) (xy 172.874472 -264.145286)
			(xy 172.92063 -264.171935) (xy 172.962301 -264.205166) (xy 172.998553 -264.244237) (xy 173.028577 -264.288274)
			(xy 173.051703 -264.336295) (xy 173.067413 -264.387225) (xy 173.075356 -264.439929) (xy 173.075854 -264.466578)
			(xy 173.075356 -264.493227) (xy 187.527936 -264.493227) (xy 187.527936 -264.439929) (xy 187.535879 -264.387225)
			(xy 187.551589 -264.336295) (xy 187.574715 -264.288274) (xy 187.604739 -264.244237) (xy 187.640991 -264.205166)
			(xy 187.682662 -264.171935) (xy 187.72882 -264.145286) (xy 187.778434 -264.125814) (xy 187.830396 -264.113954)
			(xy 187.883546 -264.109971) (xy 187.936696 -264.113954) (xy 187.988658 -264.125814) (xy 188.038272 -264.145286)
			(xy 188.08443 -264.171935) (xy 188.126101 -264.205166) (xy 188.162353 -264.244237) (xy 188.192377 -264.288274)
			(xy 188.215503 -264.336295) (xy 188.231213 -264.387225) (xy 188.239156 -264.439929) (xy 188.239654 -264.466578)
			(xy 188.239156 -264.493227) (xy 202.615536 -264.493227) (xy 202.615536 -264.439929) (xy 202.623479 -264.387225)
			(xy 202.639189 -264.336295) (xy 202.662315 -264.288274) (xy 202.692339 -264.244237) (xy 202.728591 -264.205166)
			(xy 202.770262 -264.171935) (xy 202.81642 -264.145286) (xy 202.866034 -264.125814) (xy 202.917996 -264.113954)
			(xy 202.971146 -264.109971) (xy 203.024296 -264.113954) (xy 203.076258 -264.125814) (xy 203.125872 -264.145286)
			(xy 203.17203 -264.171935) (xy 203.213701 -264.205166) (xy 203.249953 -264.244237) (xy 203.279977 -264.288274)
			(xy 203.303103 -264.336295) (xy 203.318813 -264.387225) (xy 203.326756 -264.439929) (xy 203.327254 -264.466578)
			(xy 203.326756 -264.493227) (xy 203.318813 -264.545931) (xy 203.303103 -264.596861) (xy 203.279977 -264.644882)
			(xy 203.249953 -264.688919) (xy 203.213701 -264.72799) (xy 203.17203 -264.761221) (xy 203.125872 -264.78787)
			(xy 203.076258 -264.807342) (xy 203.024296 -264.819202) (xy 202.971146 -264.823186) (xy 202.917996 -264.819202)
			(xy 202.866034 -264.807342) (xy 202.81642 -264.78787) (xy 202.770262 -264.761221) (xy 202.728591 -264.72799)
			(xy 202.692339 -264.688919) (xy 202.662315 -264.644882) (xy 202.639189 -264.596861) (xy 202.623479 -264.545931)
			(xy 202.615536 -264.493227) (xy 188.239156 -264.493227) (xy 188.231213 -264.545931) (xy 188.215503 -264.596861)
			(xy 188.192377 -264.644882) (xy 188.162353 -264.688919) (xy 188.126101 -264.72799) (xy 188.08443 -264.761221)
			(xy 188.038272 -264.78787) (xy 187.988658 -264.807342) (xy 187.936696 -264.819202) (xy 187.883546 -264.823186)
			(xy 187.830396 -264.819202) (xy 187.778434 -264.807342) (xy 187.72882 -264.78787) (xy 187.682662 -264.761221)
			(xy 187.640991 -264.72799) (xy 187.604739 -264.688919) (xy 187.574715 -264.644882) (xy 187.551589 -264.596861)
			(xy 187.535879 -264.545931) (xy 187.527936 -264.493227) (xy 173.075356 -264.493227) (xy 173.067413 -264.545931)
			(xy 173.051703 -264.596861) (xy 173.028577 -264.644882) (xy 172.998553 -264.688919) (xy 172.962301 -264.72799)
			(xy 172.92063 -264.761221) (xy 172.874472 -264.78787) (xy 172.824858 -264.807342) (xy 172.772896 -264.819202)
			(xy 172.719746 -264.823186) (xy 172.666596 -264.819202) (xy 172.614634 -264.807342) (xy 172.56502 -264.78787)
			(xy 172.518862 -264.761221) (xy 172.477191 -264.72799) (xy 172.440939 -264.688919) (xy 172.410915 -264.644882)
			(xy 172.387789 -264.596861) (xy 172.372079 -264.545931) (xy 172.364136 -264.493227) (xy 158.88716 -264.493227)
			(xy 158.88716 -265.343365) (xy 176.464204 -265.343365) (xy 176.464204 -265.290067) (xy 176.472147 -265.237363)
			(xy 176.487857 -265.186433) (xy 176.510983 -265.138412) (xy 176.541007 -265.094375) (xy 176.577259 -265.055304)
			(xy 176.61893 -265.022073) (xy 176.665088 -264.995424) (xy 176.714702 -264.975952) (xy 176.766664 -264.964092)
			(xy 176.819814 -264.960109) (xy 176.872964 -264.964092) (xy 176.924926 -264.975952) (xy 176.97454 -264.995424)
			(xy 177.020698 -265.022073) (xy 177.062369 -265.055304) (xy 177.098621 -265.094375) (xy 177.128645 -265.138412)
			(xy 177.151771 -265.186433) (xy 177.167481 -265.237363) (xy 177.175424 -265.290067) (xy 177.175922 -265.316716)
			(xy 177.175424 -265.343365) (xy 191.551804 -265.343365) (xy 191.551804 -265.290067) (xy 191.559747 -265.237363)
			(xy 191.575457 -265.186433) (xy 191.598583 -265.138412) (xy 191.628607 -265.094375) (xy 191.664859 -265.055304)
			(xy 191.70653 -265.022073) (xy 191.752688 -264.995424) (xy 191.802302 -264.975952) (xy 191.854264 -264.964092)
			(xy 191.907414 -264.960109) (xy 191.960564 -264.964092) (xy 192.012526 -264.975952) (xy 192.06214 -264.995424)
			(xy 192.108298 -265.022073) (xy 192.149969 -265.055304) (xy 192.186221 -265.094375) (xy 192.216245 -265.138412)
			(xy 192.239371 -265.186433) (xy 192.255081 -265.237363) (xy 192.263024 -265.290067) (xy 192.263522 -265.316716)
			(xy 192.263024 -265.343365) (xy 206.715604 -265.343365) (xy 206.715604 -265.290067) (xy 206.723547 -265.237363)
			(xy 206.739257 -265.186433) (xy 206.762383 -265.138412) (xy 206.792407 -265.094375) (xy 206.828659 -265.055304)
			(xy 206.87033 -265.022073) (xy 206.916488 -264.995424) (xy 206.966102 -264.975952) (xy 207.018064 -264.964092)
			(xy 207.071214 -264.960109) (xy 207.124364 -264.964092) (xy 207.176326 -264.975952) (xy 207.22594 -264.995424)
			(xy 207.272098 -265.022073) (xy 207.313769 -265.055304) (xy 207.350021 -265.094375) (xy 207.380045 -265.138412)
			(xy 207.403171 -265.186433) (xy 207.418881 -265.237363) (xy 207.426824 -265.290067) (xy 207.427322 -265.316716)
			(xy 207.426824 -265.343365) (xy 207.418881 -265.396069) (xy 207.403171 -265.446999) (xy 207.380045 -265.49502)
			(xy 207.350021 -265.539057) (xy 207.313769 -265.578128) (xy 207.272098 -265.611359) (xy 207.22594 -265.638008)
			(xy 207.176326 -265.65748) (xy 207.124364 -265.66934) (xy 207.071214 -265.673324) (xy 207.018064 -265.66934)
			(xy 206.966102 -265.65748) (xy 206.916488 -265.638008) (xy 206.87033 -265.611359) (xy 206.828659 -265.578128)
			(xy 206.792407 -265.539057) (xy 206.762383 -265.49502) (xy 206.739257 -265.446999) (xy 206.723547 -265.396069)
			(xy 206.715604 -265.343365) (xy 192.263024 -265.343365) (xy 192.255081 -265.396069) (xy 192.239371 -265.446999)
			(xy 192.216245 -265.49502) (xy 192.186221 -265.539057) (xy 192.149969 -265.578128) (xy 192.108298 -265.611359)
			(xy 192.06214 -265.638008) (xy 192.012526 -265.65748) (xy 191.960564 -265.66934) (xy 191.907414 -265.673324)
			(xy 191.854264 -265.66934) (xy 191.802302 -265.65748) (xy 191.752688 -265.638008) (xy 191.70653 -265.611359)
			(xy 191.664859 -265.578128) (xy 191.628607 -265.539057) (xy 191.598583 -265.49502) (xy 191.575457 -265.446999)
			(xy 191.559747 -265.396069) (xy 191.551804 -265.343365) (xy 177.175424 -265.343365) (xy 177.167481 -265.396069)
			(xy 177.151771 -265.446999) (xy 177.128645 -265.49502) (xy 177.098621 -265.539057) (xy 177.062369 -265.578128)
			(xy 177.020698 -265.611359) (xy 176.97454 -265.638008) (xy 176.924926 -265.65748) (xy 176.872964 -265.66934)
			(xy 176.819814 -265.673324) (xy 176.766664 -265.66934) (xy 176.714702 -265.65748) (xy 176.665088 -265.638008)
			(xy 176.61893 -265.611359) (xy 176.577259 -265.578128) (xy 176.541007 -265.539057) (xy 176.510983 -265.49502)
			(xy 176.487857 -265.446999) (xy 176.472147 -265.396069) (xy 176.464204 -265.343365) (xy 158.88716 -265.343365)
			(xy 158.88716 -266.193249) (xy 172.364136 -266.193249) (xy 172.364136 -266.139951) (xy 172.372079 -266.087247)
			(xy 172.387789 -266.036317) (xy 172.410915 -265.988296) (xy 172.440939 -265.944259) (xy 172.477191 -265.905188)
			(xy 172.518862 -265.871957) (xy 172.56502 -265.845308) (xy 172.614634 -265.825836) (xy 172.666596 -265.813976)
			(xy 172.719746 -265.809993) (xy 172.772896 -265.813976) (xy 172.824858 -265.825836) (xy 172.874472 -265.845308)
			(xy 172.92063 -265.871957) (xy 172.962301 -265.905188) (xy 172.998553 -265.944259) (xy 173.028577 -265.988296)
			(xy 173.051703 -266.036317) (xy 173.067413 -266.087247) (xy 173.075356 -266.139951) (xy 173.075854 -266.1666)
			(xy 173.075356 -266.193249) (xy 187.527936 -266.193249) (xy 187.527936 -266.139951) (xy 187.535879 -266.087247)
			(xy 187.551589 -266.036317) (xy 187.574715 -265.988296) (xy 187.604739 -265.944259) (xy 187.640991 -265.905188)
			(xy 187.682662 -265.871957) (xy 187.72882 -265.845308) (xy 187.778434 -265.825836) (xy 187.830396 -265.813976)
			(xy 187.883546 -265.809993) (xy 187.936696 -265.813976) (xy 187.988658 -265.825836) (xy 188.038272 -265.845308)
			(xy 188.08443 -265.871957) (xy 188.126101 -265.905188) (xy 188.162353 -265.944259) (xy 188.192377 -265.988296)
			(xy 188.215503 -266.036317) (xy 188.231213 -266.087247) (xy 188.239156 -266.139951) (xy 188.239654 -266.1666)
			(xy 188.239156 -266.193249) (xy 202.615536 -266.193249) (xy 202.615536 -266.139951) (xy 202.623479 -266.087247)
			(xy 202.639189 -266.036317) (xy 202.662315 -265.988296) (xy 202.692339 -265.944259) (xy 202.728591 -265.905188)
			(xy 202.770262 -265.871957) (xy 202.81642 -265.845308) (xy 202.866034 -265.825836) (xy 202.917996 -265.813976)
			(xy 202.971146 -265.809993) (xy 203.024296 -265.813976) (xy 203.076258 -265.825836) (xy 203.125872 -265.845308)
			(xy 203.17203 -265.871957) (xy 203.213701 -265.905188) (xy 203.249953 -265.944259) (xy 203.279977 -265.988296)
			(xy 203.303103 -266.036317) (xy 203.318813 -266.087247) (xy 203.326756 -266.139951) (xy 203.327254 -266.1666)
			(xy 203.326756 -266.193249) (xy 203.318813 -266.245953) (xy 203.303103 -266.296883) (xy 203.279977 -266.344904)
			(xy 203.249953 -266.388941) (xy 203.213701 -266.428012) (xy 203.17203 -266.461243) (xy 203.125872 -266.487892)
			(xy 203.076258 -266.507364) (xy 203.024296 -266.519224) (xy 202.971146 -266.523208) (xy 202.917996 -266.519224)
			(xy 202.866034 -266.507364) (xy 202.81642 -266.487892) (xy 202.770262 -266.461243) (xy 202.728591 -266.428012)
			(xy 202.692339 -266.388941) (xy 202.662315 -266.344904) (xy 202.639189 -266.296883) (xy 202.623479 -266.245953)
			(xy 202.615536 -266.193249) (xy 188.239156 -266.193249) (xy 188.231213 -266.245953) (xy 188.215503 -266.296883)
			(xy 188.192377 -266.344904) (xy 188.162353 -266.388941) (xy 188.126101 -266.428012) (xy 188.08443 -266.461243)
			(xy 188.038272 -266.487892) (xy 187.988658 -266.507364) (xy 187.936696 -266.519224) (xy 187.883546 -266.523208)
			(xy 187.830396 -266.519224) (xy 187.778434 -266.507364) (xy 187.72882 -266.487892) (xy 187.682662 -266.461243)
			(xy 187.640991 -266.428012) (xy 187.604739 -266.388941) (xy 187.574715 -266.344904) (xy 187.551589 -266.296883)
			(xy 187.535879 -266.245953) (xy 187.527936 -266.193249) (xy 173.075356 -266.193249) (xy 173.067413 -266.245953)
			(xy 173.051703 -266.296883) (xy 173.028577 -266.344904) (xy 172.998553 -266.388941) (xy 172.962301 -266.428012)
			(xy 172.92063 -266.461243) (xy 172.874472 -266.487892) (xy 172.824858 -266.507364) (xy 172.772896 -266.519224)
			(xy 172.719746 -266.523208) (xy 172.666596 -266.519224) (xy 172.614634 -266.507364) (xy 172.56502 -266.487892)
			(xy 172.518862 -266.461243) (xy 172.477191 -266.428012) (xy 172.440939 -266.388941) (xy 172.410915 -266.344904)
			(xy 172.387789 -266.296883) (xy 172.372079 -266.245953) (xy 172.364136 -266.193249) (xy 158.88716 -266.193249)
			(xy 158.88716 -267.043387) (xy 176.540404 -267.043387) (xy 176.540404 -266.990089) (xy 176.548347 -266.937385)
			(xy 176.564057 -266.886455) (xy 176.587183 -266.838434) (xy 176.617207 -266.794397) (xy 176.653459 -266.755326)
			(xy 176.69513 -266.722095) (xy 176.741288 -266.695446) (xy 176.790902 -266.675974) (xy 176.842864 -266.664114)
			(xy 176.896014 -266.660131) (xy 176.949164 -266.664114) (xy 177.001126 -266.675974) (xy 177.05074 -266.695446)
			(xy 177.096898 -266.722095) (xy 177.138569 -266.755326) (xy 177.174821 -266.794397) (xy 177.204845 -266.838434)
			(xy 177.227971 -266.886455) (xy 177.243681 -266.937385) (xy 177.251624 -266.990089) (xy 177.252122 -267.016738)
			(xy 177.251624 -267.043387) (xy 184.084204 -267.043387) (xy 184.084204 -266.990089) (xy 184.092147 -266.937385)
			(xy 184.107857 -266.886455) (xy 184.130983 -266.838434) (xy 184.161007 -266.794397) (xy 184.197259 -266.755326)
			(xy 184.23893 -266.722095) (xy 184.285088 -266.695446) (xy 184.334702 -266.675974) (xy 184.386664 -266.664114)
			(xy 184.439814 -266.660131) (xy 184.492964 -266.664114) (xy 184.544926 -266.675974) (xy 184.59454 -266.695446)
			(xy 184.640698 -266.722095) (xy 184.682369 -266.755326) (xy 184.718621 -266.794397) (xy 184.748645 -266.838434)
			(xy 184.771771 -266.886455) (xy 184.787481 -266.937385) (xy 184.795424 -266.990089) (xy 184.795922 -267.016738)
			(xy 184.795424 -267.043387) (xy 191.628004 -267.043387) (xy 191.628004 -266.990089) (xy 191.635947 -266.937385)
			(xy 191.651657 -266.886455) (xy 191.674783 -266.838434) (xy 191.704807 -266.794397) (xy 191.741059 -266.755326)
			(xy 191.78273 -266.722095) (xy 191.828888 -266.695446) (xy 191.878502 -266.675974) (xy 191.930464 -266.664114)
			(xy 191.983614 -266.660131) (xy 192.036764 -266.664114) (xy 192.088726 -266.675974) (xy 192.13834 -266.695446)
			(xy 192.184498 -266.722095) (xy 192.226169 -266.755326) (xy 192.262421 -266.794397) (xy 192.292445 -266.838434)
			(xy 192.315571 -266.886455) (xy 192.331281 -266.937385) (xy 192.339224 -266.990089) (xy 192.339722 -267.016738)
			(xy 192.339224 -267.043387) (xy 199.171804 -267.043387) (xy 199.171804 -266.990089) (xy 199.179747 -266.937385)
			(xy 199.195457 -266.886455) (xy 199.218583 -266.838434) (xy 199.248607 -266.794397) (xy 199.284859 -266.755326)
			(xy 199.32653 -266.722095) (xy 199.372688 -266.695446) (xy 199.422302 -266.675974) (xy 199.474264 -266.664114)
			(xy 199.527414 -266.660131) (xy 199.580564 -266.664114) (xy 199.632526 -266.675974) (xy 199.68214 -266.695446)
			(xy 199.728298 -266.722095) (xy 199.769969 -266.755326) (xy 199.806221 -266.794397) (xy 199.836245 -266.838434)
			(xy 199.859371 -266.886455) (xy 199.875081 -266.937385) (xy 199.883024 -266.990089) (xy 199.883522 -267.016738)
			(xy 199.883024 -267.043387) (xy 206.639404 -267.043387) (xy 206.639404 -266.990089) (xy 206.647347 -266.937385)
			(xy 206.663057 -266.886455) (xy 206.686183 -266.838434) (xy 206.716207 -266.794397) (xy 206.752459 -266.755326)
			(xy 206.79413 -266.722095) (xy 206.840288 -266.695446) (xy 206.889902 -266.675974) (xy 206.941864 -266.664114)
			(xy 206.995014 -266.660131) (xy 207.048164 -266.664114) (xy 207.100126 -266.675974) (xy 207.14974 -266.695446)
			(xy 207.195898 -266.722095) (xy 207.237569 -266.755326) (xy 207.273821 -266.794397) (xy 207.303845 -266.838434)
			(xy 207.326971 -266.886455) (xy 207.342681 -266.937385) (xy 207.350624 -266.990089) (xy 207.351122 -267.016738)
			(xy 207.350624 -267.043387) (xy 214.259404 -267.043387) (xy 214.259404 -266.990089) (xy 214.267347 -266.937385)
			(xy 214.283057 -266.886455) (xy 214.306183 -266.838434) (xy 214.336207 -266.794397) (xy 214.372459 -266.755326)
			(xy 214.41413 -266.722095) (xy 214.460288 -266.695446) (xy 214.509902 -266.675974) (xy 214.561864 -266.664114)
			(xy 214.615014 -266.660131) (xy 214.668164 -266.664114) (xy 214.720126 -266.675974) (xy 214.76974 -266.695446)
			(xy 214.815898 -266.722095) (xy 214.857569 -266.755326) (xy 214.893821 -266.794397) (xy 214.923845 -266.838434)
			(xy 214.946971 -266.886455) (xy 214.962681 -266.937385) (xy 214.970624 -266.990089) (xy 214.971122 -267.016738)
			(xy 214.970624 -267.043387) (xy 214.962681 -267.096091) (xy 214.946971 -267.147021) (xy 214.923845 -267.195042)
			(xy 214.893821 -267.239079) (xy 214.857569 -267.27815) (xy 214.815898 -267.311381) (xy 214.76974 -267.33803)
			(xy 214.720126 -267.357502) (xy 214.668164 -267.369362) (xy 214.615014 -267.373346) (xy 214.561864 -267.369362)
			(xy 214.509902 -267.357502) (xy 214.460288 -267.33803) (xy 214.41413 -267.311381) (xy 214.372459 -267.27815)
			(xy 214.336207 -267.239079) (xy 214.306183 -267.195042) (xy 214.283057 -267.147021) (xy 214.267347 -267.096091)
			(xy 214.259404 -267.043387) (xy 207.350624 -267.043387) (xy 207.342681 -267.096091) (xy 207.326971 -267.147021)
			(xy 207.303845 -267.195042) (xy 207.273821 -267.239079) (xy 207.237569 -267.27815) (xy 207.195898 -267.311381)
			(xy 207.14974 -267.33803) (xy 207.100126 -267.357502) (xy 207.048164 -267.369362) (xy 206.995014 -267.373346)
			(xy 206.941864 -267.369362) (xy 206.889902 -267.357502) (xy 206.840288 -267.33803) (xy 206.79413 -267.311381)
			(xy 206.752459 -267.27815) (xy 206.716207 -267.239079) (xy 206.686183 -267.195042) (xy 206.663057 -267.147021)
			(xy 206.647347 -267.096091) (xy 206.639404 -267.043387) (xy 199.883024 -267.043387) (xy 199.875081 -267.096091)
			(xy 199.859371 -267.147021) (xy 199.836245 -267.195042) (xy 199.806221 -267.239079) (xy 199.769969 -267.27815)
			(xy 199.728298 -267.311381) (xy 199.68214 -267.33803) (xy 199.632526 -267.357502) (xy 199.580564 -267.369362)
			(xy 199.527414 -267.373346) (xy 199.474264 -267.369362) (xy 199.422302 -267.357502) (xy 199.372688 -267.33803)
			(xy 199.32653 -267.311381) (xy 199.284859 -267.27815) (xy 199.248607 -267.239079) (xy 199.218583 -267.195042)
			(xy 199.195457 -267.147021) (xy 199.179747 -267.096091) (xy 199.171804 -267.043387) (xy 192.339224 -267.043387)
			(xy 192.331281 -267.096091) (xy 192.315571 -267.147021) (xy 192.292445 -267.195042) (xy 192.262421 -267.239079)
			(xy 192.226169 -267.27815) (xy 192.184498 -267.311381) (xy 192.13834 -267.33803) (xy 192.088726 -267.357502)
			(xy 192.036764 -267.369362) (xy 191.983614 -267.373346) (xy 191.930464 -267.369362) (xy 191.878502 -267.357502)
			(xy 191.828888 -267.33803) (xy 191.78273 -267.311381) (xy 191.741059 -267.27815) (xy 191.704807 -267.239079)
			(xy 191.674783 -267.195042) (xy 191.651657 -267.147021) (xy 191.635947 -267.096091) (xy 191.628004 -267.043387)
			(xy 184.795424 -267.043387) (xy 184.787481 -267.096091) (xy 184.771771 -267.147021) (xy 184.748645 -267.195042)
			(xy 184.718621 -267.239079) (xy 184.682369 -267.27815) (xy 184.640698 -267.311381) (xy 184.59454 -267.33803)
			(xy 184.544926 -267.357502) (xy 184.492964 -267.369362) (xy 184.439814 -267.373346) (xy 184.386664 -267.369362)
			(xy 184.334702 -267.357502) (xy 184.285088 -267.33803) (xy 184.23893 -267.311381) (xy 184.197259 -267.27815)
			(xy 184.161007 -267.239079) (xy 184.130983 -267.195042) (xy 184.107857 -267.147021) (xy 184.092147 -267.096091)
			(xy 184.084204 -267.043387) (xy 177.251624 -267.043387) (xy 177.243681 -267.096091) (xy 177.227971 -267.147021)
			(xy 177.204845 -267.195042) (xy 177.174821 -267.239079) (xy 177.138569 -267.27815) (xy 177.096898 -267.311381)
			(xy 177.05074 -267.33803) (xy 177.001126 -267.357502) (xy 176.949164 -267.369362) (xy 176.896014 -267.373346)
			(xy 176.842864 -267.369362) (xy 176.790902 -267.357502) (xy 176.741288 -267.33803) (xy 176.69513 -267.311381)
			(xy 176.653459 -267.27815) (xy 176.617207 -267.239079) (xy 176.587183 -267.195042) (xy 176.564057 -267.147021)
			(xy 176.548347 -267.096091) (xy 176.540404 -267.043387) (xy 158.88716 -267.043387) (xy 158.88716 -267.893271)
			(xy 172.364136 -267.893271) (xy 172.364136 -267.839973) (xy 172.372079 -267.787269) (xy 172.387789 -267.736339)
			(xy 172.410915 -267.688318) (xy 172.440939 -267.644281) (xy 172.477191 -267.60521) (xy 172.518862 -267.571979)
			(xy 172.56502 -267.54533) (xy 172.614634 -267.525858) (xy 172.666596 -267.513998) (xy 172.719746 -267.510015)
			(xy 172.772896 -267.513998) (xy 172.824858 -267.525858) (xy 172.874472 -267.54533) (xy 172.92063 -267.571979)
			(xy 172.962301 -267.60521) (xy 172.998553 -267.644281) (xy 173.028577 -267.688318) (xy 173.051703 -267.736339)
			(xy 173.067413 -267.787269) (xy 173.075356 -267.839973) (xy 173.075854 -267.866622) (xy 173.075356 -267.893271)
			(xy 179.984136 -267.893271) (xy 179.984136 -267.839973) (xy 179.992079 -267.787269) (xy 180.007789 -267.736339)
			(xy 180.030915 -267.688318) (xy 180.060939 -267.644281) (xy 180.097191 -267.60521) (xy 180.138862 -267.571979)
			(xy 180.18502 -267.54533) (xy 180.234634 -267.525858) (xy 180.286596 -267.513998) (xy 180.339746 -267.510015)
			(xy 180.392896 -267.513998) (xy 180.444858 -267.525858) (xy 180.494472 -267.54533) (xy 180.54063 -267.571979)
			(xy 180.582301 -267.60521) (xy 180.618553 -267.644281) (xy 180.648577 -267.688318) (xy 180.671703 -267.736339)
			(xy 180.687413 -267.787269) (xy 180.695356 -267.839973) (xy 180.695854 -267.866622) (xy 180.695356 -267.893271)
			(xy 187.527936 -267.893271) (xy 187.527936 -267.839973) (xy 187.535879 -267.787269) (xy 187.551589 -267.736339)
			(xy 187.574715 -267.688318) (xy 187.604739 -267.644281) (xy 187.640991 -267.60521) (xy 187.682662 -267.571979)
			(xy 187.72882 -267.54533) (xy 187.778434 -267.525858) (xy 187.830396 -267.513998) (xy 187.883546 -267.510015)
			(xy 187.936696 -267.513998) (xy 187.988658 -267.525858) (xy 188.038272 -267.54533) (xy 188.08443 -267.571979)
			(xy 188.126101 -267.60521) (xy 188.162353 -267.644281) (xy 188.192377 -267.688318) (xy 188.215503 -267.736339)
			(xy 188.231213 -267.787269) (xy 188.239156 -267.839973) (xy 188.239654 -267.866622) (xy 188.239156 -267.893271)
			(xy 195.071736 -267.893271) (xy 195.071736 -267.839973) (xy 195.079679 -267.787269) (xy 195.095389 -267.736339)
			(xy 195.118515 -267.688318) (xy 195.148539 -267.644281) (xy 195.184791 -267.60521) (xy 195.226462 -267.571979)
			(xy 195.27262 -267.54533) (xy 195.322234 -267.525858) (xy 195.374196 -267.513998) (xy 195.427346 -267.510015)
			(xy 195.480496 -267.513998) (xy 195.532458 -267.525858) (xy 195.582072 -267.54533) (xy 195.62823 -267.571979)
			(xy 195.669901 -267.60521) (xy 195.706153 -267.644281) (xy 195.736177 -267.688318) (xy 195.759303 -267.736339)
			(xy 195.775013 -267.787269) (xy 195.782956 -267.839973) (xy 195.783454 -267.866622) (xy 195.782956 -267.893271)
			(xy 202.615536 -267.893271) (xy 202.615536 -267.839973) (xy 202.623479 -267.787269) (xy 202.639189 -267.736339)
			(xy 202.662315 -267.688318) (xy 202.692339 -267.644281) (xy 202.728591 -267.60521) (xy 202.770262 -267.571979)
			(xy 202.81642 -267.54533) (xy 202.866034 -267.525858) (xy 202.917996 -267.513998) (xy 202.971146 -267.510015)
			(xy 203.024296 -267.513998) (xy 203.076258 -267.525858) (xy 203.125872 -267.54533) (xy 203.17203 -267.571979)
			(xy 203.213701 -267.60521) (xy 203.249953 -267.644281) (xy 203.279977 -267.688318) (xy 203.303103 -267.736339)
			(xy 203.318813 -267.787269) (xy 203.326756 -267.839973) (xy 203.327254 -267.866622) (xy 203.326756 -267.893271)
			(xy 210.159336 -267.893271) (xy 210.159336 -267.839973) (xy 210.167279 -267.787269) (xy 210.182989 -267.736339)
			(xy 210.206115 -267.688318) (xy 210.236139 -267.644281) (xy 210.272391 -267.60521) (xy 210.314062 -267.571979)
			(xy 210.36022 -267.54533) (xy 210.409834 -267.525858) (xy 210.461796 -267.513998) (xy 210.514946 -267.510015)
			(xy 210.568096 -267.513998) (xy 210.620058 -267.525858) (xy 210.669672 -267.54533) (xy 210.71583 -267.571979)
			(xy 210.757501 -267.60521) (xy 210.793753 -267.644281) (xy 210.823777 -267.688318) (xy 210.846903 -267.736339)
			(xy 210.862613 -267.787269) (xy 210.870556 -267.839973) (xy 210.871054 -267.866622) (xy 210.870556 -267.893271)
			(xy 210.862613 -267.945975) (xy 210.846903 -267.996905) (xy 210.823777 -268.044926) (xy 210.793753 -268.088963)
			(xy 210.757501 -268.128034) (xy 210.71583 -268.161265) (xy 210.669672 -268.187914) (xy 210.620058 -268.207386)
			(xy 210.568096 -268.219246) (xy 210.514946 -268.22323) (xy 210.461796 -268.219246) (xy 210.409834 -268.207386)
			(xy 210.36022 -268.187914) (xy 210.314062 -268.161265) (xy 210.272391 -268.128034) (xy 210.236139 -268.088963)
			(xy 210.206115 -268.044926) (xy 210.182989 -267.996905) (xy 210.167279 -267.945975) (xy 210.159336 -267.893271)
			(xy 203.326756 -267.893271) (xy 203.318813 -267.945975) (xy 203.303103 -267.996905) (xy 203.279977 -268.044926)
			(xy 203.249953 -268.088963) (xy 203.213701 -268.128034) (xy 203.17203 -268.161265) (xy 203.125872 -268.187914)
			(xy 203.076258 -268.207386) (xy 203.024296 -268.219246) (xy 202.971146 -268.22323) (xy 202.917996 -268.219246)
			(xy 202.866034 -268.207386) (xy 202.81642 -268.187914) (xy 202.770262 -268.161265) (xy 202.728591 -268.128034)
			(xy 202.692339 -268.088963) (xy 202.662315 -268.044926) (xy 202.639189 -267.996905) (xy 202.623479 -267.945975)
			(xy 202.615536 -267.893271) (xy 195.782956 -267.893271) (xy 195.775013 -267.945975) (xy 195.759303 -267.996905)
			(xy 195.736177 -268.044926) (xy 195.706153 -268.088963) (xy 195.669901 -268.128034) (xy 195.62823 -268.161265)
			(xy 195.582072 -268.187914) (xy 195.532458 -268.207386) (xy 195.480496 -268.219246) (xy 195.427346 -268.22323)
			(xy 195.374196 -268.219246) (xy 195.322234 -268.207386) (xy 195.27262 -268.187914) (xy 195.226462 -268.161265)
			(xy 195.184791 -268.128034) (xy 195.148539 -268.088963) (xy 195.118515 -268.044926) (xy 195.095389 -267.996905)
			(xy 195.079679 -267.945975) (xy 195.071736 -267.893271) (xy 188.239156 -267.893271) (xy 188.231213 -267.945975)
			(xy 188.215503 -267.996905) (xy 188.192377 -268.044926) (xy 188.162353 -268.088963) (xy 188.126101 -268.128034)
			(xy 188.08443 -268.161265) (xy 188.038272 -268.187914) (xy 187.988658 -268.207386) (xy 187.936696 -268.219246)
			(xy 187.883546 -268.22323) (xy 187.830396 -268.219246) (xy 187.778434 -268.207386) (xy 187.72882 -268.187914)
			(xy 187.682662 -268.161265) (xy 187.640991 -268.128034) (xy 187.604739 -268.088963) (xy 187.574715 -268.044926)
			(xy 187.551589 -267.996905) (xy 187.535879 -267.945975) (xy 187.527936 -267.893271) (xy 180.695356 -267.893271)
			(xy 180.687413 -267.945975) (xy 180.671703 -267.996905) (xy 180.648577 -268.044926) (xy 180.618553 -268.088963)
			(xy 180.582301 -268.128034) (xy 180.54063 -268.161265) (xy 180.494472 -268.187914) (xy 180.444858 -268.207386)
			(xy 180.392896 -268.219246) (xy 180.339746 -268.22323) (xy 180.286596 -268.219246) (xy 180.234634 -268.207386)
			(xy 180.18502 -268.187914) (xy 180.138862 -268.161265) (xy 180.097191 -268.128034) (xy 180.060939 -268.088963)
			(xy 180.030915 -268.044926) (xy 180.007789 -267.996905) (xy 179.992079 -267.945975) (xy 179.984136 -267.893271)
			(xy 173.075356 -267.893271) (xy 173.067413 -267.945975) (xy 173.051703 -267.996905) (xy 173.028577 -268.044926)
			(xy 172.998553 -268.088963) (xy 172.962301 -268.128034) (xy 172.92063 -268.161265) (xy 172.874472 -268.187914)
			(xy 172.824858 -268.207386) (xy 172.772896 -268.219246) (xy 172.719746 -268.22323) (xy 172.666596 -268.219246)
			(xy 172.614634 -268.207386) (xy 172.56502 -268.187914) (xy 172.518862 -268.161265) (xy 172.477191 -268.128034)
			(xy 172.440939 -268.088963) (xy 172.410915 -268.044926) (xy 172.387789 -267.996905) (xy 172.372079 -267.945975)
			(xy 172.364136 -267.893271) (xy 158.88716 -267.893271) (xy 158.88716 -268.743409) (xy 184.084204 -268.743409)
			(xy 184.084204 -268.690111) (xy 184.092147 -268.637407) (xy 184.107857 -268.586477) (xy 184.130983 -268.538456)
			(xy 184.161007 -268.494419) (xy 184.197259 -268.455348) (xy 184.23893 -268.422117) (xy 184.285088 -268.395468)
			(xy 184.334702 -268.375996) (xy 184.386664 -268.364136) (xy 184.439814 -268.360153) (xy 184.492964 -268.364136)
			(xy 184.544926 -268.375996) (xy 184.59454 -268.395468) (xy 184.640698 -268.422117) (xy 184.682369 -268.455348)
			(xy 184.718621 -268.494419) (xy 184.748645 -268.538456) (xy 184.771771 -268.586477) (xy 184.787481 -268.637407)
			(xy 184.795424 -268.690111) (xy 184.795922 -268.71676) (xy 184.795424 -268.743409) (xy 191.551804 -268.743409)
			(xy 191.551804 -268.690111) (xy 191.559747 -268.637407) (xy 191.575457 -268.586477) (xy 191.598583 -268.538456)
			(xy 191.628607 -268.494419) (xy 191.664859 -268.455348) (xy 191.70653 -268.422117) (xy 191.752688 -268.395468)
			(xy 191.802302 -268.375996) (xy 191.854264 -268.364136) (xy 191.907414 -268.360153) (xy 191.960564 -268.364136)
			(xy 192.012526 -268.375996) (xy 192.06214 -268.395468) (xy 192.108298 -268.422117) (xy 192.149969 -268.455348)
			(xy 192.186221 -268.494419) (xy 192.216245 -268.538456) (xy 192.239371 -268.586477) (xy 192.255081 -268.637407)
			(xy 192.263024 -268.690111) (xy 192.263522 -268.71676) (xy 192.263024 -268.743409) (xy 192.255081 -268.796113)
			(xy 192.239371 -268.847043) (xy 192.216245 -268.895064) (xy 192.186221 -268.939101) (xy 192.149969 -268.978172)
			(xy 192.108298 -269.011403) (xy 192.06214 -269.038052) (xy 192.012526 -269.057524) (xy 191.960564 -269.069384)
			(xy 191.907414 -269.073368) (xy 191.854264 -269.069384) (xy 191.802302 -269.057524) (xy 191.752688 -269.038052)
			(xy 191.70653 -269.011403) (xy 191.664859 -268.978172) (xy 191.628607 -268.939101) (xy 191.598583 -268.895064)
			(xy 191.575457 -268.847043) (xy 191.559747 -268.796113) (xy 191.551804 -268.743409) (xy 184.795424 -268.743409)
			(xy 184.787481 -268.796113) (xy 184.771771 -268.847043) (xy 184.748645 -268.895064) (xy 184.718621 -268.939101)
			(xy 184.682369 -268.978172) (xy 184.640698 -269.011403) (xy 184.59454 -269.038052) (xy 184.544926 -269.057524)
			(xy 184.492964 -269.069384) (xy 184.439814 -269.073368) (xy 184.386664 -269.069384) (xy 184.334702 -269.057524)
			(xy 184.285088 -269.038052) (xy 184.23893 -269.011403) (xy 184.197259 -268.978172) (xy 184.161007 -268.939101)
			(xy 184.130983 -268.895064) (xy 184.107857 -268.847043) (xy 184.092147 -268.796113) (xy 184.084204 -268.743409)
			(xy 158.88716 -268.743409) (xy 158.88716 -269.593293) (xy 172.440336 -269.593293) (xy 172.440336 -269.539995)
			(xy 172.448279 -269.487291) (xy 172.463989 -269.436361) (xy 172.487115 -269.38834) (xy 172.517139 -269.344303)
			(xy 172.553391 -269.305232) (xy 172.595062 -269.272001) (xy 172.64122 -269.245352) (xy 172.690834 -269.22588)
			(xy 172.742796 -269.21402) (xy 172.795946 -269.210037) (xy 172.849096 -269.21402) (xy 172.901058 -269.22588)
			(xy 172.950672 -269.245352) (xy 172.99683 -269.272001) (xy 173.038501 -269.305232) (xy 173.074753 -269.344303)
			(xy 173.104777 -269.38834) (xy 173.127903 -269.436361) (xy 173.143613 -269.487291) (xy 173.151556 -269.539995)
			(xy 173.152054 -269.566644) (xy 173.151556 -269.593293) (xy 187.527936 -269.593293) (xy 187.527936 -269.539995)
			(xy 187.535879 -269.487291) (xy 187.551589 -269.436361) (xy 187.574715 -269.38834) (xy 187.604739 -269.344303)
			(xy 187.640991 -269.305232) (xy 187.682662 -269.272001) (xy 187.72882 -269.245352) (xy 187.778434 -269.22588)
			(xy 187.830396 -269.21402) (xy 187.883546 -269.210037) (xy 187.936696 -269.21402) (xy 187.988658 -269.22588)
			(xy 188.038272 -269.245352) (xy 188.08443 -269.272001) (xy 188.126101 -269.305232) (xy 188.162353 -269.344303)
			(xy 188.192377 -269.38834) (xy 188.215503 -269.436361) (xy 188.231213 -269.487291) (xy 188.239156 -269.539995)
			(xy 188.239654 -269.566644) (xy 188.239156 -269.593293) (xy 202.615536 -269.593293) (xy 202.615536 -269.539995)
			(xy 202.623479 -269.487291) (xy 202.639189 -269.436361) (xy 202.662315 -269.38834) (xy 202.692339 -269.344303)
			(xy 202.728591 -269.305232) (xy 202.770262 -269.272001) (xy 202.81642 -269.245352) (xy 202.866034 -269.22588)
			(xy 202.917996 -269.21402) (xy 202.971146 -269.210037) (xy 203.024296 -269.21402) (xy 203.076258 -269.22588)
			(xy 203.125872 -269.245352) (xy 203.17203 -269.272001) (xy 203.213701 -269.305232) (xy 203.249953 -269.344303)
			(xy 203.279977 -269.38834) (xy 203.303103 -269.436361) (xy 203.318813 -269.487291) (xy 203.326756 -269.539995)
			(xy 203.327254 -269.566644) (xy 203.326756 -269.593293) (xy 203.318813 -269.645997) (xy 203.303103 -269.696927)
			(xy 203.279977 -269.744948) (xy 203.249953 -269.788985) (xy 203.213701 -269.828056) (xy 203.17203 -269.861287)
			(xy 203.125872 -269.887936) (xy 203.076258 -269.907408) (xy 203.024296 -269.919268) (xy 202.971146 -269.923252)
			(xy 202.917996 -269.919268) (xy 202.866034 -269.907408) (xy 202.81642 -269.887936) (xy 202.770262 -269.861287)
			(xy 202.728591 -269.828056) (xy 202.692339 -269.788985) (xy 202.662315 -269.744948) (xy 202.639189 -269.696927)
			(xy 202.623479 -269.645997) (xy 202.615536 -269.593293) (xy 188.239156 -269.593293) (xy 188.231213 -269.645997)
			(xy 188.215503 -269.696927) (xy 188.192377 -269.744948) (xy 188.162353 -269.788985) (xy 188.126101 -269.828056)
			(xy 188.08443 -269.861287) (xy 188.038272 -269.887936) (xy 187.988658 -269.907408) (xy 187.936696 -269.919268)
			(xy 187.883546 -269.923252) (xy 187.830396 -269.919268) (xy 187.778434 -269.907408) (xy 187.72882 -269.887936)
			(xy 187.682662 -269.861287) (xy 187.640991 -269.828056) (xy 187.604739 -269.788985) (xy 187.574715 -269.744948)
			(xy 187.551589 -269.696927) (xy 187.535879 -269.645997) (xy 187.527936 -269.593293) (xy 173.151556 -269.593293)
			(xy 173.143613 -269.645997) (xy 173.127903 -269.696927) (xy 173.104777 -269.744948) (xy 173.074753 -269.788985)
			(xy 173.038501 -269.828056) (xy 172.99683 -269.861287) (xy 172.950672 -269.887936) (xy 172.901058 -269.907408)
			(xy 172.849096 -269.919268) (xy 172.795946 -269.923252) (xy 172.742796 -269.919268) (xy 172.690834 -269.907408)
			(xy 172.64122 -269.887936) (xy 172.595062 -269.861287) (xy 172.553391 -269.828056) (xy 172.517139 -269.788985)
			(xy 172.487115 -269.744948) (xy 172.463989 -269.696927) (xy 172.448279 -269.645997) (xy 172.440336 -269.593293)
			(xy 158.88716 -269.593293) (xy 158.88716 -270.443431) (xy 176.540404 -270.443431) (xy 176.540404 -270.390133)
			(xy 176.548347 -270.337429) (xy 176.564057 -270.286499) (xy 176.587183 -270.238478) (xy 176.617207 -270.194441)
			(xy 176.653459 -270.15537) (xy 176.69513 -270.122139) (xy 176.741288 -270.09549) (xy 176.790902 -270.076018)
			(xy 176.842864 -270.064158) (xy 176.896014 -270.060175) (xy 176.949164 -270.064158) (xy 177.001126 -270.076018)
			(xy 177.05074 -270.09549) (xy 177.096898 -270.122139) (xy 177.138569 -270.15537) (xy 177.174821 -270.194441)
			(xy 177.204845 -270.238478) (xy 177.227971 -270.286499) (xy 177.243681 -270.337429) (xy 177.251624 -270.390133)
			(xy 177.252122 -270.416782) (xy 177.251624 -270.443431) (xy 191.602604 -270.443431) (xy 191.602604 -270.390133)
			(xy 191.610547 -270.337429) (xy 191.626257 -270.286499) (xy 191.649383 -270.238478) (xy 191.679407 -270.194441)
			(xy 191.715659 -270.15537) (xy 191.75733 -270.122139) (xy 191.803488 -270.09549) (xy 191.853102 -270.076018)
			(xy 191.905064 -270.064158) (xy 191.958214 -270.060175) (xy 192.011364 -270.064158) (xy 192.063326 -270.076018)
			(xy 192.11294 -270.09549) (xy 192.159098 -270.122139) (xy 192.200769 -270.15537) (xy 192.237021 -270.194441)
			(xy 192.267045 -270.238478) (xy 192.290171 -270.286499) (xy 192.305881 -270.337429) (xy 192.313824 -270.390133)
			(xy 192.314322 -270.416782) (xy 192.313824 -270.443431) (xy 206.715604 -270.443431) (xy 206.715604 -270.390133)
			(xy 206.723547 -270.337429) (xy 206.739257 -270.286499) (xy 206.762383 -270.238478) (xy 206.792407 -270.194441)
			(xy 206.828659 -270.15537) (xy 206.87033 -270.122139) (xy 206.916488 -270.09549) (xy 206.966102 -270.076018)
			(xy 207.018064 -270.064158) (xy 207.071214 -270.060175) (xy 207.124364 -270.064158) (xy 207.176326 -270.076018)
			(xy 207.22594 -270.09549) (xy 207.272098 -270.122139) (xy 207.313769 -270.15537) (xy 207.350021 -270.194441)
			(xy 207.380045 -270.238478) (xy 207.403171 -270.286499) (xy 207.418881 -270.337429) (xy 207.426824 -270.390133)
			(xy 207.427322 -270.416782) (xy 207.426824 -270.443431) (xy 207.418881 -270.496135) (xy 207.403171 -270.547065)
			(xy 207.380045 -270.595086) (xy 207.350021 -270.639123) (xy 207.313769 -270.678194) (xy 207.272098 -270.711425)
			(xy 207.22594 -270.738074) (xy 207.176326 -270.757546) (xy 207.124364 -270.769406) (xy 207.071214 -270.77339)
			(xy 207.018064 -270.769406) (xy 206.966102 -270.757546) (xy 206.916488 -270.738074) (xy 206.87033 -270.711425)
			(xy 206.828659 -270.678194) (xy 206.792407 -270.639123) (xy 206.762383 -270.595086) (xy 206.739257 -270.547065)
			(xy 206.723547 -270.496135) (xy 206.715604 -270.443431) (xy 192.313824 -270.443431) (xy 192.305881 -270.496135)
			(xy 192.290171 -270.547065) (xy 192.267045 -270.595086) (xy 192.237021 -270.639123) (xy 192.200769 -270.678194)
			(xy 192.159098 -270.711425) (xy 192.11294 -270.738074) (xy 192.063326 -270.757546) (xy 192.011364 -270.769406)
			(xy 191.958214 -270.77339) (xy 191.905064 -270.769406) (xy 191.853102 -270.757546) (xy 191.803488 -270.738074)
			(xy 191.75733 -270.711425) (xy 191.715659 -270.678194) (xy 191.679407 -270.639123) (xy 191.649383 -270.595086)
			(xy 191.626257 -270.547065) (xy 191.610547 -270.496135) (xy 191.602604 -270.443431) (xy 177.251624 -270.443431)
			(xy 177.243681 -270.496135) (xy 177.227971 -270.547065) (xy 177.204845 -270.595086) (xy 177.174821 -270.639123)
			(xy 177.138569 -270.678194) (xy 177.096898 -270.711425) (xy 177.05074 -270.738074) (xy 177.001126 -270.757546)
			(xy 176.949164 -270.769406) (xy 176.896014 -270.77339) (xy 176.842864 -270.769406) (xy 176.790902 -270.757546)
			(xy 176.741288 -270.738074) (xy 176.69513 -270.711425) (xy 176.653459 -270.678194) (xy 176.617207 -270.639123)
			(xy 176.587183 -270.595086) (xy 176.564057 -270.547065) (xy 176.548347 -270.496135) (xy 176.540404 -270.443431)
			(xy 158.88716 -270.443431) (xy 158.88716 -271.293315) (xy 172.440336 -271.293315) (xy 172.440336 -271.240017)
			(xy 172.448279 -271.187313) (xy 172.463989 -271.136383) (xy 172.487115 -271.088362) (xy 172.517139 -271.044325)
			(xy 172.553391 -271.005254) (xy 172.595062 -270.972023) (xy 172.64122 -270.945374) (xy 172.690834 -270.925902)
			(xy 172.742796 -270.914042) (xy 172.795946 -270.910059) (xy 172.849096 -270.914042) (xy 172.901058 -270.925902)
			(xy 172.950672 -270.945374) (xy 172.99683 -270.972023) (xy 173.038501 -271.005254) (xy 173.074753 -271.044325)
			(xy 173.104777 -271.088362) (xy 173.127903 -271.136383) (xy 173.143613 -271.187313) (xy 173.151556 -271.240017)
			(xy 173.152054 -271.266666) (xy 173.151556 -271.293315) (xy 187.527936 -271.293315) (xy 187.527936 -271.240017)
			(xy 187.535879 -271.187313) (xy 187.551589 -271.136383) (xy 187.574715 -271.088362) (xy 187.604739 -271.044325)
			(xy 187.640991 -271.005254) (xy 187.682662 -270.972023) (xy 187.72882 -270.945374) (xy 187.778434 -270.925902)
			(xy 187.830396 -270.914042) (xy 187.883546 -270.910059) (xy 187.936696 -270.914042) (xy 187.988658 -270.925902)
			(xy 188.038272 -270.945374) (xy 188.08443 -270.972023) (xy 188.126101 -271.005254) (xy 188.162353 -271.044325)
			(xy 188.192377 -271.088362) (xy 188.215503 -271.136383) (xy 188.231213 -271.187313) (xy 188.239156 -271.240017)
			(xy 188.239654 -271.266666) (xy 188.239156 -271.293315) (xy 202.615536 -271.293315) (xy 202.615536 -271.240017)
			(xy 202.623479 -271.187313) (xy 202.639189 -271.136383) (xy 202.662315 -271.088362) (xy 202.692339 -271.044325)
			(xy 202.728591 -271.005254) (xy 202.770262 -270.972023) (xy 202.81642 -270.945374) (xy 202.866034 -270.925902)
			(xy 202.917996 -270.914042) (xy 202.971146 -270.910059) (xy 203.024296 -270.914042) (xy 203.076258 -270.925902)
			(xy 203.125872 -270.945374) (xy 203.17203 -270.972023) (xy 203.213701 -271.005254) (xy 203.249953 -271.044325)
			(xy 203.279977 -271.088362) (xy 203.303103 -271.136383) (xy 203.318813 -271.187313) (xy 203.326756 -271.240017)
			(xy 203.327254 -271.266666) (xy 203.326756 -271.293315) (xy 203.318813 -271.346019) (xy 203.303103 -271.396949)
			(xy 203.279977 -271.44497) (xy 203.249953 -271.489007) (xy 203.213701 -271.528078) (xy 203.17203 -271.561309)
			(xy 203.125872 -271.587958) (xy 203.076258 -271.60743) (xy 203.024296 -271.61929) (xy 202.971146 -271.623274)
			(xy 202.917996 -271.61929) (xy 202.866034 -271.60743) (xy 202.81642 -271.587958) (xy 202.770262 -271.561309)
			(xy 202.728591 -271.528078) (xy 202.692339 -271.489007) (xy 202.662315 -271.44497) (xy 202.639189 -271.396949)
			(xy 202.623479 -271.346019) (xy 202.615536 -271.293315) (xy 188.239156 -271.293315) (xy 188.231213 -271.346019)
			(xy 188.215503 -271.396949) (xy 188.192377 -271.44497) (xy 188.162353 -271.489007) (xy 188.126101 -271.528078)
			(xy 188.08443 -271.561309) (xy 188.038272 -271.587958) (xy 187.988658 -271.60743) (xy 187.936696 -271.61929)
			(xy 187.883546 -271.623274) (xy 187.830396 -271.61929) (xy 187.778434 -271.60743) (xy 187.72882 -271.587958)
			(xy 187.682662 -271.561309) (xy 187.640991 -271.528078) (xy 187.604739 -271.489007) (xy 187.574715 -271.44497)
			(xy 187.551589 -271.396949) (xy 187.535879 -271.346019) (xy 187.527936 -271.293315) (xy 173.151556 -271.293315)
			(xy 173.143613 -271.346019) (xy 173.127903 -271.396949) (xy 173.104777 -271.44497) (xy 173.074753 -271.489007)
			(xy 173.038501 -271.528078) (xy 172.99683 -271.561309) (xy 172.950672 -271.587958) (xy 172.901058 -271.60743)
			(xy 172.849096 -271.61929) (xy 172.795946 -271.623274) (xy 172.742796 -271.61929) (xy 172.690834 -271.60743)
			(xy 172.64122 -271.587958) (xy 172.595062 -271.561309) (xy 172.553391 -271.528078) (xy 172.517139 -271.489007)
			(xy 172.487115 -271.44497) (xy 172.463989 -271.396949) (xy 172.448279 -271.346019) (xy 172.440336 -271.293315)
			(xy 158.88716 -271.293315) (xy 158.88716 -272.143199) (xy 176.540404 -272.143199) (xy 176.540404 -272.089901)
			(xy 176.548347 -272.037197) (xy 176.564057 -271.986267) (xy 176.587183 -271.938246) (xy 176.617207 -271.894209)
			(xy 176.653459 -271.855138) (xy 176.69513 -271.821907) (xy 176.741288 -271.795258) (xy 176.790902 -271.775786)
			(xy 176.842864 -271.763926) (xy 176.896014 -271.759943) (xy 176.949164 -271.763926) (xy 177.001126 -271.775786)
			(xy 177.05074 -271.795258) (xy 177.096898 -271.821907) (xy 177.138569 -271.855138) (xy 177.174821 -271.894209)
			(xy 177.204845 -271.938246) (xy 177.227971 -271.986267) (xy 177.243681 -272.037197) (xy 177.251624 -272.089901)
			(xy 177.252122 -272.11655) (xy 177.251624 -272.143199) (xy 177.251586 -272.143453) (xy 191.586094 -272.143453)
			(xy 191.586094 -272.090155) (xy 191.594037 -272.037451) (xy 191.609747 -271.986521) (xy 191.632873 -271.9385)
			(xy 191.662897 -271.894463) (xy 191.699149 -271.855392) (xy 191.74082 -271.822161) (xy 191.786978 -271.795512)
			(xy 191.836592 -271.77604) (xy 191.888554 -271.76418) (xy 191.941704 -271.760197) (xy 191.994854 -271.76418)
			(xy 192.046816 -271.77604) (xy 192.09643 -271.795512) (xy 192.142588 -271.822161) (xy 192.184259 -271.855392)
			(xy 192.220511 -271.894463) (xy 192.250535 -271.9385) (xy 192.273661 -271.986521) (xy 192.289371 -272.037451)
			(xy 192.297314 -272.090155) (xy 192.297812 -272.116804) (xy 192.297319 -272.143199) (xy 206.715604 -272.143199)
			(xy 206.715604 -272.089901) (xy 206.723547 -272.037197) (xy 206.739257 -271.986267) (xy 206.762383 -271.938246)
			(xy 206.792407 -271.894209) (xy 206.828659 -271.855138) (xy 206.87033 -271.821907) (xy 206.916488 -271.795258)
			(xy 206.966102 -271.775786) (xy 207.018064 -271.763926) (xy 207.071214 -271.759943) (xy 207.124364 -271.763926)
			(xy 207.176326 -271.775786) (xy 207.22594 -271.795258) (xy 207.272098 -271.821907) (xy 207.313769 -271.855138)
			(xy 207.350021 -271.894209) (xy 207.380045 -271.938246) (xy 207.403171 -271.986267) (xy 207.418881 -272.037197)
			(xy 207.426824 -272.089901) (xy 207.427322 -272.11655) (xy 207.426824 -272.143199) (xy 207.418881 -272.195903)
			(xy 207.403171 -272.246833) (xy 207.380045 -272.294854) (xy 207.350021 -272.338891) (xy 207.313769 -272.377962)
			(xy 207.272098 -272.411193) (xy 207.22594 -272.437842) (xy 207.176326 -272.457314) (xy 207.124364 -272.469174)
			(xy 207.071214 -272.473158) (xy 207.018064 -272.469174) (xy 206.966102 -272.457314) (xy 206.916488 -272.437842)
			(xy 206.87033 -272.411193) (xy 206.828659 -272.377962) (xy 206.792407 -272.338891) (xy 206.762383 -272.294854)
			(xy 206.739257 -272.246833) (xy 206.723547 -272.195903) (xy 206.715604 -272.143199) (xy 192.297319 -272.143199)
			(xy 192.297314 -272.143453) (xy 192.289371 -272.196157) (xy 192.273661 -272.247087) (xy 192.250535 -272.295108)
			(xy 192.220511 -272.339145) (xy 192.184259 -272.378216) (xy 192.142588 -272.411447) (xy 192.09643 -272.438096)
			(xy 192.046816 -272.457568) (xy 191.994854 -272.469428) (xy 191.941704 -272.473412) (xy 191.888554 -272.469428)
			(xy 191.836592 -272.457568) (xy 191.786978 -272.438096) (xy 191.74082 -272.411447) (xy 191.699149 -272.378216)
			(xy 191.662897 -272.339145) (xy 191.632873 -272.295108) (xy 191.609747 -272.247087) (xy 191.594037 -272.196157)
			(xy 191.586094 -272.143453) (xy 177.251586 -272.143453) (xy 177.243681 -272.195903) (xy 177.227971 -272.246833)
			(xy 177.204845 -272.294854) (xy 177.174821 -272.338891) (xy 177.138569 -272.377962) (xy 177.096898 -272.411193)
			(xy 177.05074 -272.437842) (xy 177.001126 -272.457314) (xy 176.949164 -272.469174) (xy 176.896014 -272.473158)
			(xy 176.842864 -272.469174) (xy 176.790902 -272.457314) (xy 176.741288 -272.437842) (xy 176.69513 -272.411193)
			(xy 176.653459 -272.377962) (xy 176.617207 -272.338891) (xy 176.587183 -272.294854) (xy 176.564057 -272.246833)
			(xy 176.548347 -272.195903) (xy 176.540404 -272.143199) (xy 158.88716 -272.143199) (xy 158.88716 -272.993337)
			(xy 172.440336 -272.993337) (xy 172.440336 -272.940039) (xy 172.448279 -272.887335) (xy 172.463989 -272.836405)
			(xy 172.487115 -272.788384) (xy 172.517139 -272.744347) (xy 172.553391 -272.705276) (xy 172.595062 -272.672045)
			(xy 172.64122 -272.645396) (xy 172.690834 -272.625924) (xy 172.742796 -272.614064) (xy 172.795946 -272.610081)
			(xy 172.849096 -272.614064) (xy 172.901058 -272.625924) (xy 172.950672 -272.645396) (xy 172.99683 -272.672045)
			(xy 173.038501 -272.705276) (xy 173.074753 -272.744347) (xy 173.104777 -272.788384) (xy 173.127903 -272.836405)
			(xy 173.143613 -272.887335) (xy 173.151556 -272.940039) (xy 173.152054 -272.966688) (xy 173.151556 -272.993337)
			(xy 187.527936 -272.993337) (xy 187.527936 -272.940039) (xy 187.535879 -272.887335) (xy 187.551589 -272.836405)
			(xy 187.574715 -272.788384) (xy 187.604739 -272.744347) (xy 187.640991 -272.705276) (xy 187.682662 -272.672045)
			(xy 187.72882 -272.645396) (xy 187.778434 -272.625924) (xy 187.830396 -272.614064) (xy 187.883546 -272.610081)
			(xy 187.936696 -272.614064) (xy 187.988658 -272.625924) (xy 188.038272 -272.645396) (xy 188.08443 -272.672045)
			(xy 188.126101 -272.705276) (xy 188.162353 -272.744347) (xy 188.192377 -272.788384) (xy 188.215503 -272.836405)
			(xy 188.231213 -272.887335) (xy 188.239156 -272.940039) (xy 188.239654 -272.966688) (xy 188.239156 -272.993337)
			(xy 202.615536 -272.993337) (xy 202.615536 -272.940039) (xy 202.623479 -272.887335) (xy 202.639189 -272.836405)
			(xy 202.662315 -272.788384) (xy 202.692339 -272.744347) (xy 202.728591 -272.705276) (xy 202.770262 -272.672045)
			(xy 202.81642 -272.645396) (xy 202.866034 -272.625924) (xy 202.917996 -272.614064) (xy 202.971146 -272.610081)
			(xy 203.024296 -272.614064) (xy 203.076258 -272.625924) (xy 203.125872 -272.645396) (xy 203.17203 -272.672045)
			(xy 203.213701 -272.705276) (xy 203.249953 -272.744347) (xy 203.279977 -272.788384) (xy 203.303103 -272.836405)
			(xy 203.318813 -272.887335) (xy 203.326756 -272.940039) (xy 203.327254 -272.966688) (xy 203.326756 -272.993337)
			(xy 203.318813 -273.046041) (xy 203.303103 -273.096971) (xy 203.279977 -273.144992) (xy 203.249953 -273.189029)
			(xy 203.213701 -273.2281) (xy 203.17203 -273.261331) (xy 203.125872 -273.28798) (xy 203.076258 -273.307452)
			(xy 203.024296 -273.319312) (xy 202.971146 -273.323296) (xy 202.917996 -273.319312) (xy 202.866034 -273.307452)
			(xy 202.81642 -273.28798) (xy 202.770262 -273.261331) (xy 202.728591 -273.2281) (xy 202.692339 -273.189029)
			(xy 202.662315 -273.144992) (xy 202.639189 -273.096971) (xy 202.623479 -273.046041) (xy 202.615536 -272.993337)
			(xy 188.239156 -272.993337) (xy 188.231213 -273.046041) (xy 188.215503 -273.096971) (xy 188.192377 -273.144992)
			(xy 188.162353 -273.189029) (xy 188.126101 -273.2281) (xy 188.08443 -273.261331) (xy 188.038272 -273.28798)
			(xy 187.988658 -273.307452) (xy 187.936696 -273.319312) (xy 187.883546 -273.323296) (xy 187.830396 -273.319312)
			(xy 187.778434 -273.307452) (xy 187.72882 -273.28798) (xy 187.682662 -273.261331) (xy 187.640991 -273.2281)
			(xy 187.604739 -273.189029) (xy 187.574715 -273.144992) (xy 187.551589 -273.096971) (xy 187.535879 -273.046041)
			(xy 187.527936 -272.993337) (xy 173.151556 -272.993337) (xy 173.143613 -273.046041) (xy 173.127903 -273.096971)
			(xy 173.104777 -273.144992) (xy 173.074753 -273.189029) (xy 173.038501 -273.2281) (xy 172.99683 -273.261331)
			(xy 172.950672 -273.28798) (xy 172.901058 -273.307452) (xy 172.849096 -273.319312) (xy 172.795946 -273.323296)
			(xy 172.742796 -273.319312) (xy 172.690834 -273.307452) (xy 172.64122 -273.28798) (xy 172.595062 -273.261331)
			(xy 172.553391 -273.2281) (xy 172.517139 -273.189029) (xy 172.487115 -273.144992) (xy 172.463989 -273.096971)
			(xy 172.448279 -273.046041) (xy 172.440336 -272.993337) (xy 158.88716 -272.993337) (xy 158.88716 -273.843221)
			(xy 176.540404 -273.843221) (xy 176.540404 -273.789923) (xy 176.548347 -273.737219) (xy 176.564057 -273.686289)
			(xy 176.587183 -273.638268) (xy 176.617207 -273.594231) (xy 176.653459 -273.55516) (xy 176.69513 -273.521929)
			(xy 176.741288 -273.49528) (xy 176.790902 -273.475808) (xy 176.842864 -273.463948) (xy 176.896014 -273.459965)
			(xy 176.949164 -273.463948) (xy 177.001126 -273.475808) (xy 177.05074 -273.49528) (xy 177.096898 -273.521929)
			(xy 177.138569 -273.55516) (xy 177.174821 -273.594231) (xy 177.204845 -273.638268) (xy 177.227971 -273.686289)
			(xy 177.243681 -273.737219) (xy 177.251624 -273.789923) (xy 177.252122 -273.816572) (xy 177.251624 -273.843221)
			(xy 191.628004 -273.843221) (xy 191.628004 -273.789923) (xy 191.635947 -273.737219) (xy 191.651657 -273.686289)
			(xy 191.674783 -273.638268) (xy 191.704807 -273.594231) (xy 191.741059 -273.55516) (xy 191.78273 -273.521929)
			(xy 191.828888 -273.49528) (xy 191.878502 -273.475808) (xy 191.930464 -273.463948) (xy 191.983614 -273.459965)
			(xy 192.036764 -273.463948) (xy 192.088726 -273.475808) (xy 192.13834 -273.49528) (xy 192.184498 -273.521929)
			(xy 192.226169 -273.55516) (xy 192.262421 -273.594231) (xy 192.292445 -273.638268) (xy 192.315571 -273.686289)
			(xy 192.331281 -273.737219) (xy 192.339224 -273.789923) (xy 192.339722 -273.816572) (xy 192.339224 -273.843221)
			(xy 206.715604 -273.843221) (xy 206.715604 -273.789923) (xy 206.723547 -273.737219) (xy 206.739257 -273.686289)
			(xy 206.762383 -273.638268) (xy 206.792407 -273.594231) (xy 206.828659 -273.55516) (xy 206.87033 -273.521929)
			(xy 206.916488 -273.49528) (xy 206.966102 -273.475808) (xy 207.018064 -273.463948) (xy 207.071214 -273.459965)
			(xy 207.124364 -273.463948) (xy 207.176326 -273.475808) (xy 207.22594 -273.49528) (xy 207.272098 -273.521929)
			(xy 207.313769 -273.55516) (xy 207.350021 -273.594231) (xy 207.380045 -273.638268) (xy 207.403171 -273.686289)
			(xy 207.418881 -273.737219) (xy 207.426824 -273.789923) (xy 207.427322 -273.816572) (xy 207.426824 -273.843221)
			(xy 207.418881 -273.895925) (xy 207.403171 -273.946855) (xy 207.380045 -273.994876) (xy 207.350021 -274.038913)
			(xy 207.313769 -274.077984) (xy 207.272098 -274.111215) (xy 207.22594 -274.137864) (xy 207.176326 -274.157336)
			(xy 207.124364 -274.169196) (xy 207.071214 -274.17318) (xy 207.018064 -274.169196) (xy 206.966102 -274.157336)
			(xy 206.916488 -274.137864) (xy 206.87033 -274.111215) (xy 206.828659 -274.077984) (xy 206.792407 -274.038913)
			(xy 206.762383 -273.994876) (xy 206.739257 -273.946855) (xy 206.723547 -273.895925) (xy 206.715604 -273.843221)
			(xy 192.339224 -273.843221) (xy 192.331281 -273.895925) (xy 192.315571 -273.946855) (xy 192.292445 -273.994876)
			(xy 192.262421 -274.038913) (xy 192.226169 -274.077984) (xy 192.184498 -274.111215) (xy 192.13834 -274.137864)
			(xy 192.088726 -274.157336) (xy 192.036764 -274.169196) (xy 191.983614 -274.17318) (xy 191.930464 -274.169196)
			(xy 191.878502 -274.157336) (xy 191.828888 -274.137864) (xy 191.78273 -274.111215) (xy 191.741059 -274.077984)
			(xy 191.704807 -274.038913) (xy 191.674783 -273.994876) (xy 191.651657 -273.946855) (xy 191.635947 -273.895925)
			(xy 191.628004 -273.843221) (xy 177.251624 -273.843221) (xy 177.243681 -273.895925) (xy 177.227971 -273.946855)
			(xy 177.204845 -273.994876) (xy 177.174821 -274.038913) (xy 177.138569 -274.077984) (xy 177.096898 -274.111215)
			(xy 177.05074 -274.137864) (xy 177.001126 -274.157336) (xy 176.949164 -274.169196) (xy 176.896014 -274.17318)
			(xy 176.842864 -274.169196) (xy 176.790902 -274.157336) (xy 176.741288 -274.137864) (xy 176.69513 -274.111215)
			(xy 176.653459 -274.077984) (xy 176.617207 -274.038913) (xy 176.587183 -273.994876) (xy 176.564057 -273.946855)
			(xy 176.548347 -273.895925) (xy 176.540404 -273.843221) (xy 158.88716 -273.843221) (xy 158.88716 -274.693359)
			(xy 172.440336 -274.693359) (xy 172.440336 -274.640061) (xy 172.448279 -274.587357) (xy 172.463989 -274.536427)
			(xy 172.487115 -274.488406) (xy 172.517139 -274.444369) (xy 172.553391 -274.405298) (xy 172.595062 -274.372067)
			(xy 172.64122 -274.345418) (xy 172.690834 -274.325946) (xy 172.742796 -274.314086) (xy 172.795946 -274.310103)
			(xy 172.849096 -274.314086) (xy 172.901058 -274.325946) (xy 172.950672 -274.345418) (xy 172.99683 -274.372067)
			(xy 173.038501 -274.405298) (xy 173.074753 -274.444369) (xy 173.104777 -274.488406) (xy 173.127903 -274.536427)
			(xy 173.143613 -274.587357) (xy 173.151556 -274.640061) (xy 173.152054 -274.66671) (xy 173.151556 -274.693359)
			(xy 176.540404 -274.693359) (xy 176.540404 -274.640061) (xy 176.548347 -274.587357) (xy 176.564057 -274.536427)
			(xy 176.587183 -274.488406) (xy 176.617207 -274.444369) (xy 176.653459 -274.405298) (xy 176.69513 -274.372067)
			(xy 176.741288 -274.345418) (xy 176.790902 -274.325946) (xy 176.842864 -274.314086) (xy 176.896014 -274.310103)
			(xy 176.949164 -274.314086) (xy 177.001126 -274.325946) (xy 177.05074 -274.345418) (xy 177.096898 -274.372067)
			(xy 177.138569 -274.405298) (xy 177.174821 -274.444369) (xy 177.204845 -274.488406) (xy 177.227971 -274.536427)
			(xy 177.243681 -274.587357) (xy 177.251624 -274.640061) (xy 177.252122 -274.66671) (xy 177.251624 -274.693359)
			(xy 187.527936 -274.693359) (xy 187.527936 -274.640061) (xy 187.535879 -274.587357) (xy 187.551589 -274.536427)
			(xy 187.574715 -274.488406) (xy 187.604739 -274.444369) (xy 187.640991 -274.405298) (xy 187.682662 -274.372067)
			(xy 187.72882 -274.345418) (xy 187.778434 -274.325946) (xy 187.830396 -274.314086) (xy 187.883546 -274.310103)
			(xy 187.936696 -274.314086) (xy 187.988658 -274.325946) (xy 188.038272 -274.345418) (xy 188.08443 -274.372067)
			(xy 188.126101 -274.405298) (xy 188.162353 -274.444369) (xy 188.192377 -274.488406) (xy 188.215503 -274.536427)
			(xy 188.231213 -274.587357) (xy 188.239156 -274.640061) (xy 188.239654 -274.66671) (xy 188.239156 -274.693359)
			(xy 191.628004 -274.693359) (xy 191.628004 -274.640061) (xy 191.635947 -274.587357) (xy 191.651657 -274.536427)
			(xy 191.674783 -274.488406) (xy 191.704807 -274.444369) (xy 191.741059 -274.405298) (xy 191.78273 -274.372067)
			(xy 191.828888 -274.345418) (xy 191.878502 -274.325946) (xy 191.930464 -274.314086) (xy 191.983614 -274.310103)
			(xy 192.036764 -274.314086) (xy 192.088726 -274.325946) (xy 192.13834 -274.345418) (xy 192.184498 -274.372067)
			(xy 192.226169 -274.405298) (xy 192.262421 -274.444369) (xy 192.292445 -274.488406) (xy 192.315571 -274.536427)
			(xy 192.331281 -274.587357) (xy 192.339224 -274.640061) (xy 192.339722 -274.66671) (xy 192.339224 -274.693359)
			(xy 202.615536 -274.693359) (xy 202.615536 -274.640061) (xy 202.623479 -274.587357) (xy 202.639189 -274.536427)
			(xy 202.662315 -274.488406) (xy 202.692339 -274.444369) (xy 202.728591 -274.405298) (xy 202.770262 -274.372067)
			(xy 202.81642 -274.345418) (xy 202.866034 -274.325946) (xy 202.917996 -274.314086) (xy 202.971146 -274.310103)
			(xy 203.024296 -274.314086) (xy 203.076258 -274.325946) (xy 203.125872 -274.345418) (xy 203.17203 -274.372067)
			(xy 203.213701 -274.405298) (xy 203.249953 -274.444369) (xy 203.279977 -274.488406) (xy 203.303103 -274.536427)
			(xy 203.318813 -274.587357) (xy 203.326756 -274.640061) (xy 203.327254 -274.66671) (xy 203.326756 -274.693359)
			(xy 206.715604 -274.693359) (xy 206.715604 -274.640061) (xy 206.723547 -274.587357) (xy 206.739257 -274.536427)
			(xy 206.762383 -274.488406) (xy 206.792407 -274.444369) (xy 206.828659 -274.405298) (xy 206.87033 -274.372067)
			(xy 206.916488 -274.345418) (xy 206.966102 -274.325946) (xy 207.018064 -274.314086) (xy 207.071214 -274.310103)
			(xy 207.124364 -274.314086) (xy 207.176326 -274.325946) (xy 207.22594 -274.345418) (xy 207.272098 -274.372067)
			(xy 207.313769 -274.405298) (xy 207.350021 -274.444369) (xy 207.380045 -274.488406) (xy 207.403171 -274.536427)
			(xy 207.418881 -274.587357) (xy 207.426824 -274.640061) (xy 207.427322 -274.66671) (xy 207.426824 -274.693359)
			(xy 207.418881 -274.746063) (xy 207.403171 -274.796993) (xy 207.380045 -274.845014) (xy 207.350021 -274.889051)
			(xy 207.313769 -274.928122) (xy 207.272098 -274.961353) (xy 207.22594 -274.988002) (xy 207.176326 -275.007474)
			(xy 207.124364 -275.019334) (xy 207.071214 -275.023318) (xy 207.018064 -275.019334) (xy 206.966102 -275.007474)
			(xy 206.916488 -274.988002) (xy 206.87033 -274.961353) (xy 206.828659 -274.928122) (xy 206.792407 -274.889051)
			(xy 206.762383 -274.845014) (xy 206.739257 -274.796993) (xy 206.723547 -274.746063) (xy 206.715604 -274.693359)
			(xy 203.326756 -274.693359) (xy 203.318813 -274.746063) (xy 203.303103 -274.796993) (xy 203.279977 -274.845014)
			(xy 203.249953 -274.889051) (xy 203.213701 -274.928122) (xy 203.17203 -274.961353) (xy 203.125872 -274.988002)
			(xy 203.076258 -275.007474) (xy 203.024296 -275.019334) (xy 202.971146 -275.023318) (xy 202.917996 -275.019334)
			(xy 202.866034 -275.007474) (xy 202.81642 -274.988002) (xy 202.770262 -274.961353) (xy 202.728591 -274.928122)
			(xy 202.692339 -274.889051) (xy 202.662315 -274.845014) (xy 202.639189 -274.796993) (xy 202.623479 -274.746063)
			(xy 202.615536 -274.693359) (xy 192.339224 -274.693359) (xy 192.331281 -274.746063) (xy 192.315571 -274.796993)
			(xy 192.292445 -274.845014) (xy 192.262421 -274.889051) (xy 192.226169 -274.928122) (xy 192.184498 -274.961353)
			(xy 192.13834 -274.988002) (xy 192.088726 -275.007474) (xy 192.036764 -275.019334) (xy 191.983614 -275.023318)
			(xy 191.930464 -275.019334) (xy 191.878502 -275.007474) (xy 191.828888 -274.988002) (xy 191.78273 -274.961353)
			(xy 191.741059 -274.928122) (xy 191.704807 -274.889051) (xy 191.674783 -274.845014) (xy 191.651657 -274.796993)
			(xy 191.635947 -274.746063) (xy 191.628004 -274.693359) (xy 188.239156 -274.693359) (xy 188.231213 -274.746063)
			(xy 188.215503 -274.796993) (xy 188.192377 -274.845014) (xy 188.162353 -274.889051) (xy 188.126101 -274.928122)
			(xy 188.08443 -274.961353) (xy 188.038272 -274.988002) (xy 187.988658 -275.007474) (xy 187.936696 -275.019334)
			(xy 187.883546 -275.023318) (xy 187.830396 -275.019334) (xy 187.778434 -275.007474) (xy 187.72882 -274.988002)
			(xy 187.682662 -274.961353) (xy 187.640991 -274.928122) (xy 187.604739 -274.889051) (xy 187.574715 -274.845014)
			(xy 187.551589 -274.796993) (xy 187.535879 -274.746063) (xy 187.527936 -274.693359) (xy 177.251624 -274.693359)
			(xy 177.243681 -274.746063) (xy 177.227971 -274.796993) (xy 177.204845 -274.845014) (xy 177.174821 -274.889051)
			(xy 177.138569 -274.928122) (xy 177.096898 -274.961353) (xy 177.05074 -274.988002) (xy 177.001126 -275.007474)
			(xy 176.949164 -275.019334) (xy 176.896014 -275.023318) (xy 176.842864 -275.019334) (xy 176.790902 -275.007474)
			(xy 176.741288 -274.988002) (xy 176.69513 -274.961353) (xy 176.653459 -274.928122) (xy 176.617207 -274.889051)
			(xy 176.587183 -274.845014) (xy 176.564057 -274.796993) (xy 176.548347 -274.746063) (xy 176.540404 -274.693359)
			(xy 173.151556 -274.693359) (xy 173.143613 -274.746063) (xy 173.127903 -274.796993) (xy 173.104777 -274.845014)
			(xy 173.074753 -274.889051) (xy 173.038501 -274.928122) (xy 172.99683 -274.961353) (xy 172.950672 -274.988002)
			(xy 172.901058 -275.007474) (xy 172.849096 -275.019334) (xy 172.795946 -275.023318) (xy 172.742796 -275.019334)
			(xy 172.690834 -275.007474) (xy 172.64122 -274.988002) (xy 172.595062 -274.961353) (xy 172.553391 -274.928122)
			(xy 172.517139 -274.889051) (xy 172.487115 -274.845014) (xy 172.463989 -274.796993) (xy 172.448279 -274.746063)
			(xy 172.440336 -274.693359) (xy 158.88716 -274.693359) (xy 158.88716 -275.543243) (xy 172.440336 -275.543243)
			(xy 172.440336 -275.489945) (xy 172.448279 -275.437241) (xy 172.463989 -275.386311) (xy 172.487115 -275.33829)
			(xy 172.517139 -275.294253) (xy 172.553391 -275.255182) (xy 172.595062 -275.221951) (xy 172.64122 -275.195302)
			(xy 172.690834 -275.17583) (xy 172.742796 -275.16397) (xy 172.795946 -275.159987) (xy 172.849096 -275.16397)
			(xy 172.901058 -275.17583) (xy 172.950672 -275.195302) (xy 172.99683 -275.221951) (xy 173.038501 -275.255182)
			(xy 173.074753 -275.294253) (xy 173.104777 -275.33829) (xy 173.127903 -275.386311) (xy 173.143613 -275.437241)
			(xy 173.151556 -275.489945) (xy 173.152054 -275.516594) (xy 173.151556 -275.543243) (xy 187.527936 -275.543243)
			(xy 187.527936 -275.489945) (xy 187.535879 -275.437241) (xy 187.551589 -275.386311) (xy 187.574715 -275.33829)
			(xy 187.604739 -275.294253) (xy 187.640991 -275.255182) (xy 187.682662 -275.221951) (xy 187.72882 -275.195302)
			(xy 187.778434 -275.17583) (xy 187.830396 -275.16397) (xy 187.883546 -275.159987) (xy 187.936696 -275.16397)
			(xy 187.988658 -275.17583) (xy 188.038272 -275.195302) (xy 188.08443 -275.221951) (xy 188.126101 -275.255182)
			(xy 188.162353 -275.294253) (xy 188.192377 -275.33829) (xy 188.215503 -275.386311) (xy 188.231213 -275.437241)
			(xy 188.239156 -275.489945) (xy 188.239654 -275.516594) (xy 188.239156 -275.543243) (xy 202.615536 -275.543243)
			(xy 202.615536 -275.489945) (xy 202.623479 -275.437241) (xy 202.639189 -275.386311) (xy 202.662315 -275.33829)
			(xy 202.692339 -275.294253) (xy 202.728591 -275.255182) (xy 202.770262 -275.221951) (xy 202.81642 -275.195302)
			(xy 202.866034 -275.17583) (xy 202.917996 -275.16397) (xy 202.971146 -275.159987) (xy 203.024296 -275.16397)
			(xy 203.076258 -275.17583) (xy 203.125872 -275.195302) (xy 203.17203 -275.221951) (xy 203.213701 -275.255182)
			(xy 203.249953 -275.294253) (xy 203.279977 -275.33829) (xy 203.303103 -275.386311) (xy 203.318813 -275.437241)
			(xy 203.326756 -275.489945) (xy 203.327254 -275.516594) (xy 203.326756 -275.543243) (xy 203.318813 -275.595947)
			(xy 203.303103 -275.646877) (xy 203.279977 -275.694898) (xy 203.249953 -275.738935) (xy 203.213701 -275.778006)
			(xy 203.17203 -275.811237) (xy 203.125872 -275.837886) (xy 203.076258 -275.857358) (xy 203.024296 -275.869218)
			(xy 202.971146 -275.873202) (xy 202.917996 -275.869218) (xy 202.866034 -275.857358) (xy 202.81642 -275.837886)
			(xy 202.770262 -275.811237) (xy 202.728591 -275.778006) (xy 202.692339 -275.738935) (xy 202.662315 -275.694898)
			(xy 202.639189 -275.646877) (xy 202.623479 -275.595947) (xy 202.615536 -275.543243) (xy 188.239156 -275.543243)
			(xy 188.231213 -275.595947) (xy 188.215503 -275.646877) (xy 188.192377 -275.694898) (xy 188.162353 -275.738935)
			(xy 188.126101 -275.778006) (xy 188.08443 -275.811237) (xy 188.038272 -275.837886) (xy 187.988658 -275.857358)
			(xy 187.936696 -275.869218) (xy 187.883546 -275.873202) (xy 187.830396 -275.869218) (xy 187.778434 -275.857358)
			(xy 187.72882 -275.837886) (xy 187.682662 -275.811237) (xy 187.640991 -275.778006) (xy 187.604739 -275.738935)
			(xy 187.574715 -275.694898) (xy 187.551589 -275.646877) (xy 187.535879 -275.595947) (xy 187.527936 -275.543243)
			(xy 173.151556 -275.543243) (xy 173.143613 -275.595947) (xy 173.127903 -275.646877) (xy 173.104777 -275.694898)
			(xy 173.074753 -275.738935) (xy 173.038501 -275.778006) (xy 172.99683 -275.811237) (xy 172.950672 -275.837886)
			(xy 172.901058 -275.857358) (xy 172.849096 -275.869218) (xy 172.795946 -275.873202) (xy 172.742796 -275.869218)
			(xy 172.690834 -275.857358) (xy 172.64122 -275.837886) (xy 172.595062 -275.811237) (xy 172.553391 -275.778006)
			(xy 172.517139 -275.738935) (xy 172.487115 -275.694898) (xy 172.463989 -275.646877) (xy 172.448279 -275.595947)
			(xy 172.440336 -275.543243) (xy 158.88716 -275.543243) (xy 158.88716 -276.393381) (xy 176.540404 -276.393381)
			(xy 176.540404 -276.340083) (xy 176.548347 -276.287379) (xy 176.564057 -276.236449) (xy 176.587183 -276.188428)
			(xy 176.617207 -276.144391) (xy 176.653459 -276.10532) (xy 176.69513 -276.072089) (xy 176.741288 -276.04544)
			(xy 176.790902 -276.025968) (xy 176.842864 -276.014108) (xy 176.896014 -276.010125) (xy 176.949164 -276.014108)
			(xy 177.001126 -276.025968) (xy 177.05074 -276.04544) (xy 177.096898 -276.072089) (xy 177.138569 -276.10532)
			(xy 177.174821 -276.144391) (xy 177.204845 -276.188428) (xy 177.227971 -276.236449) (xy 177.243681 -276.287379)
			(xy 177.251624 -276.340083) (xy 177.252122 -276.366732) (xy 177.251624 -276.393381) (xy 191.628004 -276.393381)
			(xy 191.628004 -276.340083) (xy 191.635947 -276.287379) (xy 191.651657 -276.236449) (xy 191.674783 -276.188428)
			(xy 191.704807 -276.144391) (xy 191.741059 -276.10532) (xy 191.78273 -276.072089) (xy 191.828888 -276.04544)
			(xy 191.878502 -276.025968) (xy 191.930464 -276.014108) (xy 191.983614 -276.010125) (xy 192.036764 -276.014108)
			(xy 192.088726 -276.025968) (xy 192.13834 -276.04544) (xy 192.184498 -276.072089) (xy 192.226169 -276.10532)
			(xy 192.262421 -276.144391) (xy 192.292445 -276.188428) (xy 192.315571 -276.236449) (xy 192.331281 -276.287379)
			(xy 192.339224 -276.340083) (xy 192.339722 -276.366732) (xy 192.339224 -276.393381) (xy 206.715604 -276.393381)
			(xy 206.715604 -276.340083) (xy 206.723547 -276.287379) (xy 206.739257 -276.236449) (xy 206.762383 -276.188428)
			(xy 206.792407 -276.144391) (xy 206.828659 -276.10532) (xy 206.87033 -276.072089) (xy 206.916488 -276.04544)
			(xy 206.966102 -276.025968) (xy 207.018064 -276.014108) (xy 207.071214 -276.010125) (xy 207.124364 -276.014108)
			(xy 207.176326 -276.025968) (xy 207.22594 -276.04544) (xy 207.272098 -276.072089) (xy 207.313769 -276.10532)
			(xy 207.350021 -276.144391) (xy 207.380045 -276.188428) (xy 207.403171 -276.236449) (xy 207.418881 -276.287379)
			(xy 207.426824 -276.340083) (xy 207.427322 -276.366732) (xy 207.426824 -276.393381) (xy 207.418881 -276.446085)
			(xy 207.403171 -276.497015) (xy 207.380045 -276.545036) (xy 207.350021 -276.589073) (xy 207.313769 -276.628144)
			(xy 207.272098 -276.661375) (xy 207.22594 -276.688024) (xy 207.176326 -276.707496) (xy 207.124364 -276.719356)
			(xy 207.071214 -276.72334) (xy 207.018064 -276.719356) (xy 206.966102 -276.707496) (xy 206.916488 -276.688024)
			(xy 206.87033 -276.661375) (xy 206.828659 -276.628144) (xy 206.792407 -276.589073) (xy 206.762383 -276.545036)
			(xy 206.739257 -276.497015) (xy 206.723547 -276.446085) (xy 206.715604 -276.393381) (xy 192.339224 -276.393381)
			(xy 192.331281 -276.446085) (xy 192.315571 -276.497015) (xy 192.292445 -276.545036) (xy 192.262421 -276.589073)
			(xy 192.226169 -276.628144) (xy 192.184498 -276.661375) (xy 192.13834 -276.688024) (xy 192.088726 -276.707496)
			(xy 192.036764 -276.719356) (xy 191.983614 -276.72334) (xy 191.930464 -276.719356) (xy 191.878502 -276.707496)
			(xy 191.828888 -276.688024) (xy 191.78273 -276.661375) (xy 191.741059 -276.628144) (xy 191.704807 -276.589073)
			(xy 191.674783 -276.545036) (xy 191.651657 -276.497015) (xy 191.635947 -276.446085) (xy 191.628004 -276.393381)
			(xy 177.251624 -276.393381) (xy 177.243681 -276.446085) (xy 177.227971 -276.497015) (xy 177.204845 -276.545036)
			(xy 177.174821 -276.589073) (xy 177.138569 -276.628144) (xy 177.096898 -276.661375) (xy 177.05074 -276.688024)
			(xy 177.001126 -276.707496) (xy 176.949164 -276.719356) (xy 176.896014 -276.72334) (xy 176.842864 -276.719356)
			(xy 176.790902 -276.707496) (xy 176.741288 -276.688024) (xy 176.69513 -276.661375) (xy 176.653459 -276.628144)
			(xy 176.617207 -276.589073) (xy 176.587183 -276.545036) (xy 176.564057 -276.497015) (xy 176.548347 -276.446085)
			(xy 176.540404 -276.393381) (xy 158.88716 -276.393381) (xy 158.88716 -277.243265) (xy 172.440336 -277.243265)
			(xy 172.440336 -277.189967) (xy 172.448279 -277.137263) (xy 172.463989 -277.086333) (xy 172.487115 -277.038312)
			(xy 172.517139 -276.994275) (xy 172.553391 -276.955204) (xy 172.595062 -276.921973) (xy 172.64122 -276.895324)
			(xy 172.690834 -276.875852) (xy 172.742796 -276.863992) (xy 172.795946 -276.860009) (xy 172.849096 -276.863992)
			(xy 172.901058 -276.875852) (xy 172.950672 -276.895324) (xy 172.99683 -276.921973) (xy 173.038501 -276.955204)
			(xy 173.074753 -276.994275) (xy 173.104777 -277.038312) (xy 173.127903 -277.086333) (xy 173.143613 -277.137263)
			(xy 173.151556 -277.189967) (xy 173.152054 -277.216616) (xy 173.151556 -277.243265) (xy 187.527936 -277.243265)
			(xy 187.527936 -277.189967) (xy 187.535879 -277.137263) (xy 187.551589 -277.086333) (xy 187.574715 -277.038312)
			(xy 187.604739 -276.994275) (xy 187.640991 -276.955204) (xy 187.682662 -276.921973) (xy 187.72882 -276.895324)
			(xy 187.778434 -276.875852) (xy 187.830396 -276.863992) (xy 187.883546 -276.860009) (xy 187.936696 -276.863992)
			(xy 187.988658 -276.875852) (xy 188.038272 -276.895324) (xy 188.08443 -276.921973) (xy 188.126101 -276.955204)
			(xy 188.162353 -276.994275) (xy 188.192377 -277.038312) (xy 188.215503 -277.086333) (xy 188.231213 -277.137263)
			(xy 188.239156 -277.189967) (xy 188.239654 -277.216616) (xy 188.239156 -277.243265) (xy 202.615536 -277.243265)
			(xy 202.615536 -277.189967) (xy 202.623479 -277.137263) (xy 202.639189 -277.086333) (xy 202.662315 -277.038312)
			(xy 202.692339 -276.994275) (xy 202.728591 -276.955204) (xy 202.770262 -276.921973) (xy 202.81642 -276.895324)
			(xy 202.866034 -276.875852) (xy 202.917996 -276.863992) (xy 202.971146 -276.860009) (xy 203.024296 -276.863992)
			(xy 203.076258 -276.875852) (xy 203.125872 -276.895324) (xy 203.17203 -276.921973) (xy 203.213701 -276.955204)
			(xy 203.249953 -276.994275) (xy 203.279977 -277.038312) (xy 203.303103 -277.086333) (xy 203.318813 -277.137263)
			(xy 203.326756 -277.189967) (xy 203.327254 -277.216616) (xy 203.326756 -277.243265) (xy 203.318813 -277.295969)
			(xy 203.303103 -277.346899) (xy 203.279977 -277.39492) (xy 203.249953 -277.438957) (xy 203.213701 -277.478028)
			(xy 203.17203 -277.511259) (xy 203.125872 -277.537908) (xy 203.076258 -277.55738) (xy 203.024296 -277.56924)
			(xy 202.971146 -277.573224) (xy 202.917996 -277.56924) (xy 202.866034 -277.55738) (xy 202.81642 -277.537908)
			(xy 202.770262 -277.511259) (xy 202.728591 -277.478028) (xy 202.692339 -277.438957) (xy 202.662315 -277.39492)
			(xy 202.639189 -277.346899) (xy 202.623479 -277.295969) (xy 202.615536 -277.243265) (xy 188.239156 -277.243265)
			(xy 188.231213 -277.295969) (xy 188.215503 -277.346899) (xy 188.192377 -277.39492) (xy 188.162353 -277.438957)
			(xy 188.126101 -277.478028) (xy 188.08443 -277.511259) (xy 188.038272 -277.537908) (xy 187.988658 -277.55738)
			(xy 187.936696 -277.56924) (xy 187.883546 -277.573224) (xy 187.830396 -277.56924) (xy 187.778434 -277.55738)
			(xy 187.72882 -277.537908) (xy 187.682662 -277.511259) (xy 187.640991 -277.478028) (xy 187.604739 -277.438957)
			(xy 187.574715 -277.39492) (xy 187.551589 -277.346899) (xy 187.535879 -277.295969) (xy 187.527936 -277.243265)
			(xy 173.151556 -277.243265) (xy 173.143613 -277.295969) (xy 173.127903 -277.346899) (xy 173.104777 -277.39492)
			(xy 173.074753 -277.438957) (xy 173.038501 -277.478028) (xy 172.99683 -277.511259) (xy 172.950672 -277.537908)
			(xy 172.901058 -277.55738) (xy 172.849096 -277.56924) (xy 172.795946 -277.573224) (xy 172.742796 -277.56924)
			(xy 172.690834 -277.55738) (xy 172.64122 -277.537908) (xy 172.595062 -277.511259) (xy 172.553391 -277.478028)
			(xy 172.517139 -277.438957) (xy 172.487115 -277.39492) (xy 172.463989 -277.346899) (xy 172.448279 -277.295969)
			(xy 172.440336 -277.243265) (xy 158.88716 -277.243265) (xy 158.88716 -278.093403) (xy 176.540404 -278.093403)
			(xy 176.540404 -278.040105) (xy 176.548347 -277.987401) (xy 176.564057 -277.936471) (xy 176.587183 -277.88845)
			(xy 176.617207 -277.844413) (xy 176.653459 -277.805342) (xy 176.69513 -277.772111) (xy 176.741288 -277.745462)
			(xy 176.790902 -277.72599) (xy 176.842864 -277.71413) (xy 176.896014 -277.710147) (xy 176.949164 -277.71413)
			(xy 177.001126 -277.72599) (xy 177.05074 -277.745462) (xy 177.096898 -277.772111) (xy 177.138569 -277.805342)
			(xy 177.174821 -277.844413) (xy 177.204845 -277.88845) (xy 177.227971 -277.936471) (xy 177.243681 -277.987401)
			(xy 177.251624 -278.040105) (xy 177.252122 -278.066754) (xy 177.251624 -278.093403) (xy 191.628004 -278.093403)
			(xy 191.628004 -278.040105) (xy 191.635947 -277.987401) (xy 191.651657 -277.936471) (xy 191.674783 -277.88845)
			(xy 191.704807 -277.844413) (xy 191.741059 -277.805342) (xy 191.78273 -277.772111) (xy 191.828888 -277.745462)
			(xy 191.878502 -277.72599) (xy 191.930464 -277.71413) (xy 191.983614 -277.710147) (xy 192.036764 -277.71413)
			(xy 192.088726 -277.72599) (xy 192.13834 -277.745462) (xy 192.184498 -277.772111) (xy 192.226169 -277.805342)
			(xy 192.262421 -277.844413) (xy 192.292445 -277.88845) (xy 192.315571 -277.936471) (xy 192.331281 -277.987401)
			(xy 192.339224 -278.040105) (xy 192.339722 -278.066754) (xy 192.339224 -278.093403) (xy 206.715604 -278.093403)
			(xy 206.715604 -278.040105) (xy 206.723547 -277.987401) (xy 206.739257 -277.936471) (xy 206.762383 -277.88845)
			(xy 206.792407 -277.844413) (xy 206.828659 -277.805342) (xy 206.87033 -277.772111) (xy 206.916488 -277.745462)
			(xy 206.966102 -277.72599) (xy 207.018064 -277.71413) (xy 207.071214 -277.710147) (xy 207.124364 -277.71413)
			(xy 207.176326 -277.72599) (xy 207.22594 -277.745462) (xy 207.272098 -277.772111) (xy 207.313769 -277.805342)
			(xy 207.350021 -277.844413) (xy 207.380045 -277.88845) (xy 207.403171 -277.936471) (xy 207.418881 -277.987401)
			(xy 207.426824 -278.040105) (xy 207.427322 -278.066754) (xy 207.426824 -278.093403) (xy 207.418881 -278.146107)
			(xy 207.403171 -278.197037) (xy 207.380045 -278.245058) (xy 207.350021 -278.289095) (xy 207.313769 -278.328166)
			(xy 207.272098 -278.361397) (xy 207.22594 -278.388046) (xy 207.176326 -278.407518) (xy 207.124364 -278.419378)
			(xy 207.071214 -278.423362) (xy 207.018064 -278.419378) (xy 206.966102 -278.407518) (xy 206.916488 -278.388046)
			(xy 206.87033 -278.361397) (xy 206.828659 -278.328166) (xy 206.792407 -278.289095) (xy 206.762383 -278.245058)
			(xy 206.739257 -278.197037) (xy 206.723547 -278.146107) (xy 206.715604 -278.093403) (xy 192.339224 -278.093403)
			(xy 192.331281 -278.146107) (xy 192.315571 -278.197037) (xy 192.292445 -278.245058) (xy 192.262421 -278.289095)
			(xy 192.226169 -278.328166) (xy 192.184498 -278.361397) (xy 192.13834 -278.388046) (xy 192.088726 -278.407518)
			(xy 192.036764 -278.419378) (xy 191.983614 -278.423362) (xy 191.930464 -278.419378) (xy 191.878502 -278.407518)
			(xy 191.828888 -278.388046) (xy 191.78273 -278.361397) (xy 191.741059 -278.328166) (xy 191.704807 -278.289095)
			(xy 191.674783 -278.245058) (xy 191.651657 -278.197037) (xy 191.635947 -278.146107) (xy 191.628004 -278.093403)
			(xy 177.251624 -278.093403) (xy 177.243681 -278.146107) (xy 177.227971 -278.197037) (xy 177.204845 -278.245058)
			(xy 177.174821 -278.289095) (xy 177.138569 -278.328166) (xy 177.096898 -278.361397) (xy 177.05074 -278.388046)
			(xy 177.001126 -278.407518) (xy 176.949164 -278.419378) (xy 176.896014 -278.423362) (xy 176.842864 -278.419378)
			(xy 176.790902 -278.407518) (xy 176.741288 -278.388046) (xy 176.69513 -278.361397) (xy 176.653459 -278.328166)
			(xy 176.617207 -278.289095) (xy 176.587183 -278.245058) (xy 176.564057 -278.197037) (xy 176.548347 -278.146107)
			(xy 176.540404 -278.093403) (xy 158.88716 -278.093403) (xy 158.88716 -278.943287) (xy 172.440336 -278.943287)
			(xy 172.440336 -278.889989) (xy 172.448279 -278.837285) (xy 172.463989 -278.786355) (xy 172.487115 -278.738334)
			(xy 172.517139 -278.694297) (xy 172.553391 -278.655226) (xy 172.595062 -278.621995) (xy 172.64122 -278.595346)
			(xy 172.690834 -278.575874) (xy 172.742796 -278.564014) (xy 172.795946 -278.560031) (xy 172.849096 -278.564014)
			(xy 172.901058 -278.575874) (xy 172.950672 -278.595346) (xy 172.99683 -278.621995) (xy 173.038501 -278.655226)
			(xy 173.074753 -278.694297) (xy 173.104777 -278.738334) (xy 173.127903 -278.786355) (xy 173.143613 -278.837285)
			(xy 173.151556 -278.889989) (xy 173.152054 -278.916638) (xy 173.151556 -278.943287) (xy 187.527936 -278.943287)
			(xy 187.527936 -278.889989) (xy 187.535879 -278.837285) (xy 187.551589 -278.786355) (xy 187.574715 -278.738334)
			(xy 187.604739 -278.694297) (xy 187.640991 -278.655226) (xy 187.682662 -278.621995) (xy 187.72882 -278.595346)
			(xy 187.778434 -278.575874) (xy 187.830396 -278.564014) (xy 187.883546 -278.560031) (xy 187.936696 -278.564014)
			(xy 187.988658 -278.575874) (xy 188.038272 -278.595346) (xy 188.08443 -278.621995) (xy 188.126101 -278.655226)
			(xy 188.162353 -278.694297) (xy 188.192377 -278.738334) (xy 188.215503 -278.786355) (xy 188.231213 -278.837285)
			(xy 188.239156 -278.889989) (xy 188.239654 -278.916638) (xy 188.239156 -278.943287) (xy 202.615536 -278.943287)
			(xy 202.615536 -278.889989) (xy 202.623479 -278.837285) (xy 202.639189 -278.786355) (xy 202.662315 -278.738334)
			(xy 202.692339 -278.694297) (xy 202.728591 -278.655226) (xy 202.770262 -278.621995) (xy 202.81642 -278.595346)
			(xy 202.866034 -278.575874) (xy 202.917996 -278.564014) (xy 202.971146 -278.560031) (xy 203.024296 -278.564014)
			(xy 203.076258 -278.575874) (xy 203.125872 -278.595346) (xy 203.17203 -278.621995) (xy 203.213701 -278.655226)
			(xy 203.249953 -278.694297) (xy 203.279977 -278.738334) (xy 203.303103 -278.786355) (xy 203.318813 -278.837285)
			(xy 203.326756 -278.889989) (xy 203.327254 -278.916638) (xy 203.326756 -278.943287) (xy 203.318813 -278.995991)
			(xy 203.303103 -279.046921) (xy 203.279977 -279.094942) (xy 203.249953 -279.138979) (xy 203.213701 -279.17805)
			(xy 203.17203 -279.211281) (xy 203.125872 -279.23793) (xy 203.076258 -279.257402) (xy 203.024296 -279.269262)
			(xy 202.971146 -279.273246) (xy 202.917996 -279.269262) (xy 202.866034 -279.257402) (xy 202.81642 -279.23793)
			(xy 202.770262 -279.211281) (xy 202.728591 -279.17805) (xy 202.692339 -279.138979) (xy 202.662315 -279.094942)
			(xy 202.639189 -279.046921) (xy 202.623479 -278.995991) (xy 202.615536 -278.943287) (xy 188.239156 -278.943287)
			(xy 188.231213 -278.995991) (xy 188.215503 -279.046921) (xy 188.192377 -279.094942) (xy 188.162353 -279.138979)
			(xy 188.126101 -279.17805) (xy 188.08443 -279.211281) (xy 188.038272 -279.23793) (xy 187.988658 -279.257402)
			(xy 187.936696 -279.269262) (xy 187.883546 -279.273246) (xy 187.830396 -279.269262) (xy 187.778434 -279.257402)
			(xy 187.72882 -279.23793) (xy 187.682662 -279.211281) (xy 187.640991 -279.17805) (xy 187.604739 -279.138979)
			(xy 187.574715 -279.094942) (xy 187.551589 -279.046921) (xy 187.535879 -278.995991) (xy 187.527936 -278.943287)
			(xy 173.151556 -278.943287) (xy 173.143613 -278.995991) (xy 173.127903 -279.046921) (xy 173.104777 -279.094942)
			(xy 173.074753 -279.138979) (xy 173.038501 -279.17805) (xy 172.99683 -279.211281) (xy 172.950672 -279.23793)
			(xy 172.901058 -279.257402) (xy 172.849096 -279.269262) (xy 172.795946 -279.273246) (xy 172.742796 -279.269262)
			(xy 172.690834 -279.257402) (xy 172.64122 -279.23793) (xy 172.595062 -279.211281) (xy 172.553391 -279.17805)
			(xy 172.517139 -279.138979) (xy 172.487115 -279.094942) (xy 172.463989 -279.046921) (xy 172.448279 -278.995991)
			(xy 172.440336 -278.943287) (xy 158.88716 -278.943287) (xy 158.88716 -279.793425) (xy 176.540404 -279.793425)
			(xy 176.540404 -279.740127) (xy 176.548347 -279.687423) (xy 176.564057 -279.636493) (xy 176.587183 -279.588472)
			(xy 176.617207 -279.544435) (xy 176.653459 -279.505364) (xy 176.69513 -279.472133) (xy 176.741288 -279.445484)
			(xy 176.790902 -279.426012) (xy 176.842864 -279.414152) (xy 176.896014 -279.410169) (xy 176.949164 -279.414152)
			(xy 177.001126 -279.426012) (xy 177.05074 -279.445484) (xy 177.096898 -279.472133) (xy 177.138569 -279.505364)
			(xy 177.174821 -279.544435) (xy 177.204845 -279.588472) (xy 177.227971 -279.636493) (xy 177.243681 -279.687423)
			(xy 177.251624 -279.740127) (xy 177.252122 -279.766776) (xy 177.251624 -279.793425) (xy 191.628004 -279.793425)
			(xy 191.628004 -279.740127) (xy 191.635947 -279.687423) (xy 191.651657 -279.636493) (xy 191.674783 -279.588472)
			(xy 191.704807 -279.544435) (xy 191.741059 -279.505364) (xy 191.78273 -279.472133) (xy 191.828888 -279.445484)
			(xy 191.878502 -279.426012) (xy 191.930464 -279.414152) (xy 191.983614 -279.410169) (xy 192.036764 -279.414152)
			(xy 192.088726 -279.426012) (xy 192.13834 -279.445484) (xy 192.184498 -279.472133) (xy 192.226169 -279.505364)
			(xy 192.262421 -279.544435) (xy 192.292445 -279.588472) (xy 192.315571 -279.636493) (xy 192.331281 -279.687423)
			(xy 192.339224 -279.740127) (xy 192.339722 -279.766776) (xy 192.339224 -279.793425) (xy 206.715604 -279.793425)
			(xy 206.715604 -279.740127) (xy 206.723547 -279.687423) (xy 206.739257 -279.636493) (xy 206.762383 -279.588472)
			(xy 206.792407 -279.544435) (xy 206.828659 -279.505364) (xy 206.87033 -279.472133) (xy 206.916488 -279.445484)
			(xy 206.966102 -279.426012) (xy 207.018064 -279.414152) (xy 207.071214 -279.410169) (xy 207.124364 -279.414152)
			(xy 207.176326 -279.426012) (xy 207.22594 -279.445484) (xy 207.272098 -279.472133) (xy 207.313769 -279.505364)
			(xy 207.350021 -279.544435) (xy 207.380045 -279.588472) (xy 207.403171 -279.636493) (xy 207.418881 -279.687423)
			(xy 207.426824 -279.740127) (xy 207.427322 -279.766776) (xy 207.426824 -279.793425) (xy 207.418881 -279.846129)
			(xy 207.403171 -279.897059) (xy 207.380045 -279.94508) (xy 207.350021 -279.989117) (xy 207.313769 -280.028188)
			(xy 207.272098 -280.061419) (xy 207.22594 -280.088068) (xy 207.176326 -280.10754) (xy 207.124364 -280.1194)
			(xy 207.071214 -280.123384) (xy 207.018064 -280.1194) (xy 206.966102 -280.10754) (xy 206.916488 -280.088068)
			(xy 206.87033 -280.061419) (xy 206.828659 -280.028188) (xy 206.792407 -279.989117) (xy 206.762383 -279.94508)
			(xy 206.739257 -279.897059) (xy 206.723547 -279.846129) (xy 206.715604 -279.793425) (xy 192.339224 -279.793425)
			(xy 192.331281 -279.846129) (xy 192.315571 -279.897059) (xy 192.292445 -279.94508) (xy 192.262421 -279.989117)
			(xy 192.226169 -280.028188) (xy 192.184498 -280.061419) (xy 192.13834 -280.088068) (xy 192.088726 -280.10754)
			(xy 192.036764 -280.1194) (xy 191.983614 -280.123384) (xy 191.930464 -280.1194) (xy 191.878502 -280.10754)
			(xy 191.828888 -280.088068) (xy 191.78273 -280.061419) (xy 191.741059 -280.028188) (xy 191.704807 -279.989117)
			(xy 191.674783 -279.94508) (xy 191.651657 -279.897059) (xy 191.635947 -279.846129) (xy 191.628004 -279.793425)
			(xy 177.251624 -279.793425) (xy 177.243681 -279.846129) (xy 177.227971 -279.897059) (xy 177.204845 -279.94508)
			(xy 177.174821 -279.989117) (xy 177.138569 -280.028188) (xy 177.096898 -280.061419) (xy 177.05074 -280.088068)
			(xy 177.001126 -280.10754) (xy 176.949164 -280.1194) (xy 176.896014 -280.123384) (xy 176.842864 -280.1194)
			(xy 176.790902 -280.10754) (xy 176.741288 -280.088068) (xy 176.69513 -280.061419) (xy 176.653459 -280.028188)
			(xy 176.617207 -279.989117) (xy 176.587183 -279.94508) (xy 176.564057 -279.897059) (xy 176.548347 -279.846129)
			(xy 176.540404 -279.793425) (xy 158.88716 -279.793425) (xy 158.88716 -280.643309) (xy 172.440336 -280.643309)
			(xy 172.440336 -280.590011) (xy 172.448279 -280.537307) (xy 172.463989 -280.486377) (xy 172.487115 -280.438356)
			(xy 172.517139 -280.394319) (xy 172.553391 -280.355248) (xy 172.595062 -280.322017) (xy 172.64122 -280.295368)
			(xy 172.690834 -280.275896) (xy 172.742796 -280.264036) (xy 172.795946 -280.260053) (xy 172.849096 -280.264036)
			(xy 172.901058 -280.275896) (xy 172.950672 -280.295368) (xy 172.99683 -280.322017) (xy 173.038501 -280.355248)
			(xy 173.074753 -280.394319) (xy 173.104777 -280.438356) (xy 173.127903 -280.486377) (xy 173.143613 -280.537307)
			(xy 173.151556 -280.590011) (xy 173.152054 -280.61666) (xy 173.151556 -280.643309) (xy 187.527936 -280.643309)
			(xy 187.527936 -280.590011) (xy 187.535879 -280.537307) (xy 187.551589 -280.486377) (xy 187.574715 -280.438356)
			(xy 187.604739 -280.394319) (xy 187.640991 -280.355248) (xy 187.682662 -280.322017) (xy 187.72882 -280.295368)
			(xy 187.778434 -280.275896) (xy 187.830396 -280.264036) (xy 187.883546 -280.260053) (xy 187.936696 -280.264036)
			(xy 187.988658 -280.275896) (xy 188.038272 -280.295368) (xy 188.08443 -280.322017) (xy 188.126101 -280.355248)
			(xy 188.162353 -280.394319) (xy 188.192377 -280.438356) (xy 188.215503 -280.486377) (xy 188.231213 -280.537307)
			(xy 188.239156 -280.590011) (xy 188.239654 -280.61666) (xy 188.239156 -280.643309) (xy 202.615536 -280.643309)
			(xy 202.615536 -280.590011) (xy 202.623479 -280.537307) (xy 202.639189 -280.486377) (xy 202.662315 -280.438356)
			(xy 202.692339 -280.394319) (xy 202.728591 -280.355248) (xy 202.770262 -280.322017) (xy 202.81642 -280.295368)
			(xy 202.866034 -280.275896) (xy 202.917996 -280.264036) (xy 202.971146 -280.260053) (xy 203.024296 -280.264036)
			(xy 203.076258 -280.275896) (xy 203.125872 -280.295368) (xy 203.17203 -280.322017) (xy 203.213701 -280.355248)
			(xy 203.249953 -280.394319) (xy 203.279977 -280.438356) (xy 203.303103 -280.486377) (xy 203.318813 -280.537307)
			(xy 203.326756 -280.590011) (xy 203.327254 -280.61666) (xy 203.326756 -280.643309) (xy 203.318813 -280.696013)
			(xy 203.303103 -280.746943) (xy 203.279977 -280.794964) (xy 203.249953 -280.839001) (xy 203.213701 -280.878072)
			(xy 203.17203 -280.911303) (xy 203.125872 -280.937952) (xy 203.076258 -280.957424) (xy 203.024296 -280.969284)
			(xy 202.971146 -280.973268) (xy 202.917996 -280.969284) (xy 202.866034 -280.957424) (xy 202.81642 -280.937952)
			(xy 202.770262 -280.911303) (xy 202.728591 -280.878072) (xy 202.692339 -280.839001) (xy 202.662315 -280.794964)
			(xy 202.639189 -280.746943) (xy 202.623479 -280.696013) (xy 202.615536 -280.643309) (xy 188.239156 -280.643309)
			(xy 188.231213 -280.696013) (xy 188.215503 -280.746943) (xy 188.192377 -280.794964) (xy 188.162353 -280.839001)
			(xy 188.126101 -280.878072) (xy 188.08443 -280.911303) (xy 188.038272 -280.937952) (xy 187.988658 -280.957424)
			(xy 187.936696 -280.969284) (xy 187.883546 -280.973268) (xy 187.830396 -280.969284) (xy 187.778434 -280.957424)
			(xy 187.72882 -280.937952) (xy 187.682662 -280.911303) (xy 187.640991 -280.878072) (xy 187.604739 -280.839001)
			(xy 187.574715 -280.794964) (xy 187.551589 -280.746943) (xy 187.535879 -280.696013) (xy 187.527936 -280.643309)
			(xy 173.151556 -280.643309) (xy 173.143613 -280.696013) (xy 173.127903 -280.746943) (xy 173.104777 -280.794964)
			(xy 173.074753 -280.839001) (xy 173.038501 -280.878072) (xy 172.99683 -280.911303) (xy 172.950672 -280.937952)
			(xy 172.901058 -280.957424) (xy 172.849096 -280.969284) (xy 172.795946 -280.973268) (xy 172.742796 -280.969284)
			(xy 172.690834 -280.957424) (xy 172.64122 -280.937952) (xy 172.595062 -280.911303) (xy 172.553391 -280.878072)
			(xy 172.517139 -280.839001) (xy 172.487115 -280.794964) (xy 172.463989 -280.746943) (xy 172.448279 -280.696013)
			(xy 172.440336 -280.643309) (xy 158.88716 -280.643309) (xy 158.88716 -281.493193) (xy 176.540404 -281.493193)
			(xy 176.540404 -281.439895) (xy 176.548347 -281.387191) (xy 176.564057 -281.336261) (xy 176.587183 -281.28824)
			(xy 176.617207 -281.244203) (xy 176.653459 -281.205132) (xy 176.69513 -281.171901) (xy 176.741288 -281.145252)
			(xy 176.790902 -281.12578) (xy 176.842864 -281.11392) (xy 176.896014 -281.109937) (xy 176.949164 -281.11392)
			(xy 177.001126 -281.12578) (xy 177.05074 -281.145252) (xy 177.096898 -281.171901) (xy 177.138569 -281.205132)
			(xy 177.174821 -281.244203) (xy 177.204845 -281.28824) (xy 177.227971 -281.336261) (xy 177.243681 -281.387191)
			(xy 177.251624 -281.439895) (xy 177.252122 -281.466544) (xy 177.251624 -281.493193) (xy 177.251586 -281.493447)
			(xy 191.586094 -281.493447) (xy 191.586094 -281.440149) (xy 191.594037 -281.387445) (xy 191.609747 -281.336515)
			(xy 191.632873 -281.288494) (xy 191.662897 -281.244457) (xy 191.699149 -281.205386) (xy 191.74082 -281.172155)
			(xy 191.786978 -281.145506) (xy 191.836592 -281.126034) (xy 191.888554 -281.114174) (xy 191.941704 -281.110191)
			(xy 191.994854 -281.114174) (xy 192.046816 -281.126034) (xy 192.09643 -281.145506) (xy 192.142588 -281.172155)
			(xy 192.184259 -281.205386) (xy 192.220511 -281.244457) (xy 192.250535 -281.288494) (xy 192.273661 -281.336515)
			(xy 192.289371 -281.387445) (xy 192.297314 -281.440149) (xy 192.297812 -281.466798) (xy 192.297319 -281.493193)
			(xy 206.715604 -281.493193) (xy 206.715604 -281.439895) (xy 206.723547 -281.387191) (xy 206.739257 -281.336261)
			(xy 206.762383 -281.28824) (xy 206.792407 -281.244203) (xy 206.828659 -281.205132) (xy 206.87033 -281.171901)
			(xy 206.916488 -281.145252) (xy 206.966102 -281.12578) (xy 207.018064 -281.11392) (xy 207.071214 -281.109937)
			(xy 207.124364 -281.11392) (xy 207.176326 -281.12578) (xy 207.22594 -281.145252) (xy 207.272098 -281.171901)
			(xy 207.313769 -281.205132) (xy 207.350021 -281.244203) (xy 207.380045 -281.28824) (xy 207.403171 -281.336261)
			(xy 207.418881 -281.387191) (xy 207.426824 -281.439895) (xy 207.427322 -281.466544) (xy 207.426824 -281.493193)
			(xy 207.418881 -281.545897) (xy 207.403171 -281.596827) (xy 207.380045 -281.644848) (xy 207.350021 -281.688885)
			(xy 207.313769 -281.727956) (xy 207.272098 -281.761187) (xy 207.22594 -281.787836) (xy 207.176326 -281.807308)
			(xy 207.124364 -281.819168) (xy 207.071214 -281.823152) (xy 207.018064 -281.819168) (xy 206.966102 -281.807308)
			(xy 206.916488 -281.787836) (xy 206.87033 -281.761187) (xy 206.828659 -281.727956) (xy 206.792407 -281.688885)
			(xy 206.762383 -281.644848) (xy 206.739257 -281.596827) (xy 206.723547 -281.545897) (xy 206.715604 -281.493193)
			(xy 192.297319 -281.493193) (xy 192.297314 -281.493447) (xy 192.289371 -281.546151) (xy 192.273661 -281.597081)
			(xy 192.250535 -281.645102) (xy 192.220511 -281.689139) (xy 192.184259 -281.72821) (xy 192.142588 -281.761441)
			(xy 192.09643 -281.78809) (xy 192.046816 -281.807562) (xy 191.994854 -281.819422) (xy 191.941704 -281.823406)
			(xy 191.888554 -281.819422) (xy 191.836592 -281.807562) (xy 191.786978 -281.78809) (xy 191.74082 -281.761441)
			(xy 191.699149 -281.72821) (xy 191.662897 -281.689139) (xy 191.632873 -281.645102) (xy 191.609747 -281.597081)
			(xy 191.594037 -281.546151) (xy 191.586094 -281.493447) (xy 177.251586 -281.493447) (xy 177.243681 -281.545897)
			(xy 177.227971 -281.596827) (xy 177.204845 -281.644848) (xy 177.174821 -281.688885) (xy 177.138569 -281.727956)
			(xy 177.096898 -281.761187) (xy 177.05074 -281.787836) (xy 177.001126 -281.807308) (xy 176.949164 -281.819168)
			(xy 176.896014 -281.823152) (xy 176.842864 -281.819168) (xy 176.790902 -281.807308) (xy 176.741288 -281.787836)
			(xy 176.69513 -281.761187) (xy 176.653459 -281.727956) (xy 176.617207 -281.688885) (xy 176.587183 -281.644848)
			(xy 176.564057 -281.596827) (xy 176.548347 -281.545897) (xy 176.540404 -281.493193) (xy 158.88716 -281.493193)
			(xy 158.88716 -282.343331) (xy 172.440336 -282.343331) (xy 172.440336 -282.290033) (xy 172.448279 -282.237329)
			(xy 172.463989 -282.186399) (xy 172.487115 -282.138378) (xy 172.517139 -282.094341) (xy 172.553391 -282.05527)
			(xy 172.595062 -282.022039) (xy 172.64122 -281.99539) (xy 172.690834 -281.975918) (xy 172.742796 -281.964058)
			(xy 172.795946 -281.960075) (xy 172.849096 -281.964058) (xy 172.901058 -281.975918) (xy 172.950672 -281.99539)
			(xy 172.99683 -282.022039) (xy 173.038501 -282.05527) (xy 173.074753 -282.094341) (xy 173.104777 -282.138378)
			(xy 173.127903 -282.186399) (xy 173.143613 -282.237329) (xy 173.151556 -282.290033) (xy 173.152054 -282.316682)
			(xy 173.151556 -282.343331) (xy 187.527936 -282.343331) (xy 187.527936 -282.290033) (xy 187.535879 -282.237329)
			(xy 187.551589 -282.186399) (xy 187.574715 -282.138378) (xy 187.604739 -282.094341) (xy 187.640991 -282.05527)
			(xy 187.682662 -282.022039) (xy 187.72882 -281.99539) (xy 187.778434 -281.975918) (xy 187.830396 -281.964058)
			(xy 187.883546 -281.960075) (xy 187.936696 -281.964058) (xy 187.988658 -281.975918) (xy 188.038272 -281.99539)
			(xy 188.08443 -282.022039) (xy 188.126101 -282.05527) (xy 188.162353 -282.094341) (xy 188.192377 -282.138378)
			(xy 188.215503 -282.186399) (xy 188.231213 -282.237329) (xy 188.239156 -282.290033) (xy 188.239654 -282.316682)
			(xy 188.239156 -282.343331) (xy 202.615536 -282.343331) (xy 202.615536 -282.290033) (xy 202.623479 -282.237329)
			(xy 202.639189 -282.186399) (xy 202.662315 -282.138378) (xy 202.692339 -282.094341) (xy 202.728591 -282.05527)
			(xy 202.770262 -282.022039) (xy 202.81642 -281.99539) (xy 202.866034 -281.975918) (xy 202.917996 -281.964058)
			(xy 202.971146 -281.960075) (xy 203.024296 -281.964058) (xy 203.076258 -281.975918) (xy 203.125872 -281.99539)
			(xy 203.17203 -282.022039) (xy 203.213701 -282.05527) (xy 203.249953 -282.094341) (xy 203.279977 -282.138378)
			(xy 203.303103 -282.186399) (xy 203.318813 -282.237329) (xy 203.326756 -282.290033) (xy 203.327254 -282.316682)
			(xy 203.326756 -282.343331) (xy 203.318813 -282.396035) (xy 203.303103 -282.446965) (xy 203.279977 -282.494986)
			(xy 203.249953 -282.539023) (xy 203.213701 -282.578094) (xy 203.17203 -282.611325) (xy 203.125872 -282.637974)
			(xy 203.076258 -282.657446) (xy 203.024296 -282.669306) (xy 202.971146 -282.67329) (xy 202.917996 -282.669306)
			(xy 202.866034 -282.657446) (xy 202.81642 -282.637974) (xy 202.770262 -282.611325) (xy 202.728591 -282.578094)
			(xy 202.692339 -282.539023) (xy 202.662315 -282.494986) (xy 202.639189 -282.446965) (xy 202.623479 -282.396035)
			(xy 202.615536 -282.343331) (xy 188.239156 -282.343331) (xy 188.231213 -282.396035) (xy 188.215503 -282.446965)
			(xy 188.192377 -282.494986) (xy 188.162353 -282.539023) (xy 188.126101 -282.578094) (xy 188.08443 -282.611325)
			(xy 188.038272 -282.637974) (xy 187.988658 -282.657446) (xy 187.936696 -282.669306) (xy 187.883546 -282.67329)
			(xy 187.830396 -282.669306) (xy 187.778434 -282.657446) (xy 187.72882 -282.637974) (xy 187.682662 -282.611325)
			(xy 187.640991 -282.578094) (xy 187.604739 -282.539023) (xy 187.574715 -282.494986) (xy 187.551589 -282.446965)
			(xy 187.535879 -282.396035) (xy 187.527936 -282.343331) (xy 173.151556 -282.343331) (xy 173.143613 -282.396035)
			(xy 173.127903 -282.446965) (xy 173.104777 -282.494986) (xy 173.074753 -282.539023) (xy 173.038501 -282.578094)
			(xy 172.99683 -282.611325) (xy 172.950672 -282.637974) (xy 172.901058 -282.657446) (xy 172.849096 -282.669306)
			(xy 172.795946 -282.67329) (xy 172.742796 -282.669306) (xy 172.690834 -282.657446) (xy 172.64122 -282.637974)
			(xy 172.595062 -282.611325) (xy 172.553391 -282.578094) (xy 172.517139 -282.539023) (xy 172.487115 -282.494986)
			(xy 172.463989 -282.446965) (xy 172.448279 -282.396035) (xy 172.440336 -282.343331) (xy 158.88716 -282.343331)
			(xy 158.88716 -283.193215) (xy 176.540404 -283.193215) (xy 176.540404 -283.139917) (xy 176.548347 -283.087213)
			(xy 176.564057 -283.036283) (xy 176.587183 -282.988262) (xy 176.617207 -282.944225) (xy 176.653459 -282.905154)
			(xy 176.69513 -282.871923) (xy 176.741288 -282.845274) (xy 176.790902 -282.825802) (xy 176.842864 -282.813942)
			(xy 176.896014 -282.809959) (xy 176.949164 -282.813942) (xy 177.001126 -282.825802) (xy 177.05074 -282.845274)
			(xy 177.096898 -282.871923) (xy 177.138569 -282.905154) (xy 177.174821 -282.944225) (xy 177.204845 -282.988262)
			(xy 177.227971 -283.036283) (xy 177.243681 -283.087213) (xy 177.251624 -283.139917) (xy 177.252122 -283.166566)
			(xy 177.251624 -283.193215) (xy 191.628004 -283.193215) (xy 191.628004 -283.139917) (xy 191.635947 -283.087213)
			(xy 191.651657 -283.036283) (xy 191.674783 -282.988262) (xy 191.704807 -282.944225) (xy 191.741059 -282.905154)
			(xy 191.78273 -282.871923) (xy 191.828888 -282.845274) (xy 191.878502 -282.825802) (xy 191.930464 -282.813942)
			(xy 191.983614 -282.809959) (xy 192.036764 -282.813942) (xy 192.088726 -282.825802) (xy 192.13834 -282.845274)
			(xy 192.184498 -282.871923) (xy 192.226169 -282.905154) (xy 192.262421 -282.944225) (xy 192.292445 -282.988262)
			(xy 192.315571 -283.036283) (xy 192.331281 -283.087213) (xy 192.339224 -283.139917) (xy 192.339722 -283.166566)
			(xy 192.339224 -283.193215) (xy 206.715604 -283.193215) (xy 206.715604 -283.139917) (xy 206.723547 -283.087213)
			(xy 206.739257 -283.036283) (xy 206.762383 -282.988262) (xy 206.792407 -282.944225) (xy 206.828659 -282.905154)
			(xy 206.87033 -282.871923) (xy 206.916488 -282.845274) (xy 206.966102 -282.825802) (xy 207.018064 -282.813942)
			(xy 207.071214 -282.809959) (xy 207.124364 -282.813942) (xy 207.176326 -282.825802) (xy 207.22594 -282.845274)
			(xy 207.272098 -282.871923) (xy 207.313769 -282.905154) (xy 207.350021 -282.944225) (xy 207.380045 -282.988262)
			(xy 207.403171 -283.036283) (xy 207.418881 -283.087213) (xy 207.426824 -283.139917) (xy 207.427322 -283.166566)
			(xy 207.426824 -283.193215) (xy 207.418881 -283.245919) (xy 207.403171 -283.296849) (xy 207.380045 -283.34487)
			(xy 207.350021 -283.388907) (xy 207.313769 -283.427978) (xy 207.272098 -283.461209) (xy 207.22594 -283.487858)
			(xy 207.176326 -283.50733) (xy 207.124364 -283.51919) (xy 207.071214 -283.523174) (xy 207.018064 -283.51919)
			(xy 206.966102 -283.50733) (xy 206.916488 -283.487858) (xy 206.87033 -283.461209) (xy 206.828659 -283.427978)
			(xy 206.792407 -283.388907) (xy 206.762383 -283.34487) (xy 206.739257 -283.296849) (xy 206.723547 -283.245919)
			(xy 206.715604 -283.193215) (xy 192.339224 -283.193215) (xy 192.331281 -283.245919) (xy 192.315571 -283.296849)
			(xy 192.292445 -283.34487) (xy 192.262421 -283.388907) (xy 192.226169 -283.427978) (xy 192.184498 -283.461209)
			(xy 192.13834 -283.487858) (xy 192.088726 -283.50733) (xy 192.036764 -283.51919) (xy 191.983614 -283.523174)
			(xy 191.930464 -283.51919) (xy 191.878502 -283.50733) (xy 191.828888 -283.487858) (xy 191.78273 -283.461209)
			(xy 191.741059 -283.427978) (xy 191.704807 -283.388907) (xy 191.674783 -283.34487) (xy 191.651657 -283.296849)
			(xy 191.635947 -283.245919) (xy 191.628004 -283.193215) (xy 177.251624 -283.193215) (xy 177.243681 -283.245919)
			(xy 177.227971 -283.296849) (xy 177.204845 -283.34487) (xy 177.174821 -283.388907) (xy 177.138569 -283.427978)
			(xy 177.096898 -283.461209) (xy 177.05074 -283.487858) (xy 177.001126 -283.50733) (xy 176.949164 -283.51919)
			(xy 176.896014 -283.523174) (xy 176.842864 -283.51919) (xy 176.790902 -283.50733) (xy 176.741288 -283.487858)
			(xy 176.69513 -283.461209) (xy 176.653459 -283.427978) (xy 176.617207 -283.388907) (xy 176.587183 -283.34487)
			(xy 176.564057 -283.296849) (xy 176.548347 -283.245919) (xy 176.540404 -283.193215) (xy 158.88716 -283.193215)
			(xy 158.88716 -284.043353) (xy 172.440336 -284.043353) (xy 172.440336 -283.990055) (xy 172.448279 -283.937351)
			(xy 172.463989 -283.886421) (xy 172.487115 -283.8384) (xy 172.517139 -283.794363) (xy 172.553391 -283.755292)
			(xy 172.595062 -283.722061) (xy 172.64122 -283.695412) (xy 172.690834 -283.67594) (xy 172.742796 -283.66408)
			(xy 172.795946 -283.660097) (xy 172.849096 -283.66408) (xy 172.901058 -283.67594) (xy 172.950672 -283.695412)
			(xy 172.99683 -283.722061) (xy 173.038501 -283.755292) (xy 173.074753 -283.794363) (xy 173.104777 -283.8384)
			(xy 173.127903 -283.886421) (xy 173.143613 -283.937351) (xy 173.151556 -283.990055) (xy 173.152054 -284.016704)
			(xy 173.151556 -284.043353) (xy 176.540404 -284.043353) (xy 176.540404 -283.990055) (xy 176.548347 -283.937351)
			(xy 176.564057 -283.886421) (xy 176.587183 -283.8384) (xy 176.617207 -283.794363) (xy 176.653459 -283.755292)
			(xy 176.69513 -283.722061) (xy 176.741288 -283.695412) (xy 176.790902 -283.67594) (xy 176.842864 -283.66408)
			(xy 176.896014 -283.660097) (xy 176.949164 -283.66408) (xy 177.001126 -283.67594) (xy 177.05074 -283.695412)
			(xy 177.096898 -283.722061) (xy 177.138569 -283.755292) (xy 177.174821 -283.794363) (xy 177.204845 -283.8384)
			(xy 177.227971 -283.886421) (xy 177.243681 -283.937351) (xy 177.251624 -283.990055) (xy 177.252122 -284.016704)
			(xy 177.251624 -284.043353) (xy 187.527936 -284.043353) (xy 187.527936 -283.990055) (xy 187.535879 -283.937351)
			(xy 187.551589 -283.886421) (xy 187.574715 -283.8384) (xy 187.604739 -283.794363) (xy 187.640991 -283.755292)
			(xy 187.682662 -283.722061) (xy 187.72882 -283.695412) (xy 187.778434 -283.67594) (xy 187.830396 -283.66408)
			(xy 187.883546 -283.660097) (xy 187.936696 -283.66408) (xy 187.988658 -283.67594) (xy 188.038272 -283.695412)
			(xy 188.08443 -283.722061) (xy 188.126101 -283.755292) (xy 188.162353 -283.794363) (xy 188.192377 -283.8384)
			(xy 188.215503 -283.886421) (xy 188.231213 -283.937351) (xy 188.239156 -283.990055) (xy 188.239654 -284.016704)
			(xy 188.239156 -284.043353) (xy 191.628004 -284.043353) (xy 191.628004 -283.990055) (xy 191.635947 -283.937351)
			(xy 191.651657 -283.886421) (xy 191.674783 -283.8384) (xy 191.704807 -283.794363) (xy 191.741059 -283.755292)
			(xy 191.78273 -283.722061) (xy 191.828888 -283.695412) (xy 191.878502 -283.67594) (xy 191.930464 -283.66408)
			(xy 191.983614 -283.660097) (xy 192.036764 -283.66408) (xy 192.088726 -283.67594) (xy 192.13834 -283.695412)
			(xy 192.184498 -283.722061) (xy 192.226169 -283.755292) (xy 192.262421 -283.794363) (xy 192.292445 -283.8384)
			(xy 192.315571 -283.886421) (xy 192.331281 -283.937351) (xy 192.339224 -283.990055) (xy 192.339722 -284.016704)
			(xy 192.339224 -284.043353) (xy 202.615536 -284.043353) (xy 202.615536 -283.990055) (xy 202.623479 -283.937351)
			(xy 202.639189 -283.886421) (xy 202.662315 -283.8384) (xy 202.692339 -283.794363) (xy 202.728591 -283.755292)
			(xy 202.770262 -283.722061) (xy 202.81642 -283.695412) (xy 202.866034 -283.67594) (xy 202.917996 -283.66408)
			(xy 202.971146 -283.660097) (xy 203.024296 -283.66408) (xy 203.076258 -283.67594) (xy 203.125872 -283.695412)
			(xy 203.17203 -283.722061) (xy 203.213701 -283.755292) (xy 203.249953 -283.794363) (xy 203.279977 -283.8384)
			(xy 203.303103 -283.886421) (xy 203.318813 -283.937351) (xy 203.326756 -283.990055) (xy 203.327254 -284.016704)
			(xy 203.326756 -284.043353) (xy 206.715604 -284.043353) (xy 206.715604 -283.990055) (xy 206.723547 -283.937351)
			(xy 206.739257 -283.886421) (xy 206.762383 -283.8384) (xy 206.792407 -283.794363) (xy 206.828659 -283.755292)
			(xy 206.87033 -283.722061) (xy 206.916488 -283.695412) (xy 206.966102 -283.67594) (xy 207.018064 -283.66408)
			(xy 207.071214 -283.660097) (xy 207.124364 -283.66408) (xy 207.176326 -283.67594) (xy 207.22594 -283.695412)
			(xy 207.272098 -283.722061) (xy 207.313769 -283.755292) (xy 207.350021 -283.794363) (xy 207.380045 -283.8384)
			(xy 207.403171 -283.886421) (xy 207.418881 -283.937351) (xy 207.426824 -283.990055) (xy 207.427322 -284.016704)
			(xy 207.426824 -284.043353) (xy 207.418881 -284.096057) (xy 207.403171 -284.146987) (xy 207.380045 -284.195008)
			(xy 207.350021 -284.239045) (xy 207.313769 -284.278116) (xy 207.272098 -284.311347) (xy 207.22594 -284.337996)
			(xy 207.176326 -284.357468) (xy 207.124364 -284.369328) (xy 207.071214 -284.373312) (xy 207.018064 -284.369328)
			(xy 206.966102 -284.357468) (xy 206.916488 -284.337996) (xy 206.87033 -284.311347) (xy 206.828659 -284.278116)
			(xy 206.792407 -284.239045) (xy 206.762383 -284.195008) (xy 206.739257 -284.146987) (xy 206.723547 -284.096057)
			(xy 206.715604 -284.043353) (xy 203.326756 -284.043353) (xy 203.318813 -284.096057) (xy 203.303103 -284.146987)
			(xy 203.279977 -284.195008) (xy 203.249953 -284.239045) (xy 203.213701 -284.278116) (xy 203.17203 -284.311347)
			(xy 203.125872 -284.337996) (xy 203.076258 -284.357468) (xy 203.024296 -284.369328) (xy 202.971146 -284.373312)
			(xy 202.917996 -284.369328) (xy 202.866034 -284.357468) (xy 202.81642 -284.337996) (xy 202.770262 -284.311347)
			(xy 202.728591 -284.278116) (xy 202.692339 -284.239045) (xy 202.662315 -284.195008) (xy 202.639189 -284.146987)
			(xy 202.623479 -284.096057) (xy 202.615536 -284.043353) (xy 192.339224 -284.043353) (xy 192.331281 -284.096057)
			(xy 192.315571 -284.146987) (xy 192.292445 -284.195008) (xy 192.262421 -284.239045) (xy 192.226169 -284.278116)
			(xy 192.184498 -284.311347) (xy 192.13834 -284.337996) (xy 192.088726 -284.357468) (xy 192.036764 -284.369328)
			(xy 191.983614 -284.373312) (xy 191.930464 -284.369328) (xy 191.878502 -284.357468) (xy 191.828888 -284.337996)
			(xy 191.78273 -284.311347) (xy 191.741059 -284.278116) (xy 191.704807 -284.239045) (xy 191.674783 -284.195008)
			(xy 191.651657 -284.146987) (xy 191.635947 -284.096057) (xy 191.628004 -284.043353) (xy 188.239156 -284.043353)
			(xy 188.231213 -284.096057) (xy 188.215503 -284.146987) (xy 188.192377 -284.195008) (xy 188.162353 -284.239045)
			(xy 188.126101 -284.278116) (xy 188.08443 -284.311347) (xy 188.038272 -284.337996) (xy 187.988658 -284.357468)
			(xy 187.936696 -284.369328) (xy 187.883546 -284.373312) (xy 187.830396 -284.369328) (xy 187.778434 -284.357468)
			(xy 187.72882 -284.337996) (xy 187.682662 -284.311347) (xy 187.640991 -284.278116) (xy 187.604739 -284.239045)
			(xy 187.574715 -284.195008) (xy 187.551589 -284.146987) (xy 187.535879 -284.096057) (xy 187.527936 -284.043353)
			(xy 177.251624 -284.043353) (xy 177.243681 -284.096057) (xy 177.227971 -284.146987) (xy 177.204845 -284.195008)
			(xy 177.174821 -284.239045) (xy 177.138569 -284.278116) (xy 177.096898 -284.311347) (xy 177.05074 -284.337996)
			(xy 177.001126 -284.357468) (xy 176.949164 -284.369328) (xy 176.896014 -284.373312) (xy 176.842864 -284.369328)
			(xy 176.790902 -284.357468) (xy 176.741288 -284.337996) (xy 176.69513 -284.311347) (xy 176.653459 -284.278116)
			(xy 176.617207 -284.239045) (xy 176.587183 -284.195008) (xy 176.564057 -284.146987) (xy 176.548347 -284.096057)
			(xy 176.540404 -284.043353) (xy 173.151556 -284.043353) (xy 173.143613 -284.096057) (xy 173.127903 -284.146987)
			(xy 173.104777 -284.195008) (xy 173.074753 -284.239045) (xy 173.038501 -284.278116) (xy 172.99683 -284.311347)
			(xy 172.950672 -284.337996) (xy 172.901058 -284.357468) (xy 172.849096 -284.369328) (xy 172.795946 -284.373312)
			(xy 172.742796 -284.369328) (xy 172.690834 -284.357468) (xy 172.64122 -284.337996) (xy 172.595062 -284.311347)
			(xy 172.553391 -284.278116) (xy 172.517139 -284.239045) (xy 172.487115 -284.195008) (xy 172.463989 -284.146987)
			(xy 172.448279 -284.096057) (xy 172.440336 -284.043353) (xy 158.88716 -284.043353) (xy 158.88716 -284.893237)
			(xy 172.440336 -284.893237) (xy 172.440336 -284.839939) (xy 172.448279 -284.787235) (xy 172.463989 -284.736305)
			(xy 172.487115 -284.688284) (xy 172.517139 -284.644247) (xy 172.553391 -284.605176) (xy 172.595062 -284.571945)
			(xy 172.64122 -284.545296) (xy 172.690834 -284.525824) (xy 172.742796 -284.513964) (xy 172.795946 -284.509981)
			(xy 172.849096 -284.513964) (xy 172.901058 -284.525824) (xy 172.950672 -284.545296) (xy 172.99683 -284.571945)
			(xy 173.038501 -284.605176) (xy 173.074753 -284.644247) (xy 173.104777 -284.688284) (xy 173.127903 -284.736305)
			(xy 173.143613 -284.787235) (xy 173.151556 -284.839939) (xy 173.152054 -284.866588) (xy 173.151556 -284.893237)
			(xy 187.527936 -284.893237) (xy 187.527936 -284.839939) (xy 187.535879 -284.787235) (xy 187.551589 -284.736305)
			(xy 187.574715 -284.688284) (xy 187.604739 -284.644247) (xy 187.640991 -284.605176) (xy 187.682662 -284.571945)
			(xy 187.72882 -284.545296) (xy 187.778434 -284.525824) (xy 187.830396 -284.513964) (xy 187.883546 -284.509981)
			(xy 187.936696 -284.513964) (xy 187.988658 -284.525824) (xy 188.038272 -284.545296) (xy 188.08443 -284.571945)
			(xy 188.126101 -284.605176) (xy 188.162353 -284.644247) (xy 188.192377 -284.688284) (xy 188.215503 -284.736305)
			(xy 188.231213 -284.787235) (xy 188.239156 -284.839939) (xy 188.239654 -284.866588) (xy 188.239156 -284.893237)
			(xy 202.615536 -284.893237) (xy 202.615536 -284.839939) (xy 202.623479 -284.787235) (xy 202.639189 -284.736305)
			(xy 202.662315 -284.688284) (xy 202.692339 -284.644247) (xy 202.728591 -284.605176) (xy 202.770262 -284.571945)
			(xy 202.81642 -284.545296) (xy 202.866034 -284.525824) (xy 202.917996 -284.513964) (xy 202.971146 -284.509981)
			(xy 203.024296 -284.513964) (xy 203.076258 -284.525824) (xy 203.125872 -284.545296) (xy 203.17203 -284.571945)
			(xy 203.213701 -284.605176) (xy 203.249953 -284.644247) (xy 203.279977 -284.688284) (xy 203.303103 -284.736305)
			(xy 203.318813 -284.787235) (xy 203.326756 -284.839939) (xy 203.327254 -284.866588) (xy 203.326756 -284.893237)
			(xy 203.318813 -284.945941) (xy 203.303103 -284.996871) (xy 203.279977 -285.044892) (xy 203.249953 -285.088929)
			(xy 203.213701 -285.128) (xy 203.17203 -285.161231) (xy 203.125872 -285.18788) (xy 203.076258 -285.207352)
			(xy 203.024296 -285.219212) (xy 202.971146 -285.223196) (xy 202.917996 -285.219212) (xy 202.866034 -285.207352)
			(xy 202.81642 -285.18788) (xy 202.770262 -285.161231) (xy 202.728591 -285.128) (xy 202.692339 -285.088929)
			(xy 202.662315 -285.044892) (xy 202.639189 -284.996871) (xy 202.623479 -284.945941) (xy 202.615536 -284.893237)
			(xy 188.239156 -284.893237) (xy 188.231213 -284.945941) (xy 188.215503 -284.996871) (xy 188.192377 -285.044892)
			(xy 188.162353 -285.088929) (xy 188.126101 -285.128) (xy 188.08443 -285.161231) (xy 188.038272 -285.18788)
			(xy 187.988658 -285.207352) (xy 187.936696 -285.219212) (xy 187.883546 -285.223196) (xy 187.830396 -285.219212)
			(xy 187.778434 -285.207352) (xy 187.72882 -285.18788) (xy 187.682662 -285.161231) (xy 187.640991 -285.128)
			(xy 187.604739 -285.088929) (xy 187.574715 -285.044892) (xy 187.551589 -284.996871) (xy 187.535879 -284.945941)
			(xy 187.527936 -284.893237) (xy 173.151556 -284.893237) (xy 173.143613 -284.945941) (xy 173.127903 -284.996871)
			(xy 173.104777 -285.044892) (xy 173.074753 -285.088929) (xy 173.038501 -285.128) (xy 172.99683 -285.161231)
			(xy 172.950672 -285.18788) (xy 172.901058 -285.207352) (xy 172.849096 -285.219212) (xy 172.795946 -285.223196)
			(xy 172.742796 -285.219212) (xy 172.690834 -285.207352) (xy 172.64122 -285.18788) (xy 172.595062 -285.161231)
			(xy 172.553391 -285.128) (xy 172.517139 -285.088929) (xy 172.487115 -285.044892) (xy 172.463989 -284.996871)
			(xy 172.448279 -284.945941) (xy 172.440336 -284.893237) (xy 158.88716 -284.893237) (xy 158.88716 -285.743375)
			(xy 176.540404 -285.743375) (xy 176.540404 -285.690077) (xy 176.548347 -285.637373) (xy 176.564057 -285.586443)
			(xy 176.587183 -285.538422) (xy 176.617207 -285.494385) (xy 176.653459 -285.455314) (xy 176.69513 -285.422083)
			(xy 176.741288 -285.395434) (xy 176.790902 -285.375962) (xy 176.842864 -285.364102) (xy 176.896014 -285.360119)
			(xy 176.949164 -285.364102) (xy 177.001126 -285.375962) (xy 177.05074 -285.395434) (xy 177.096898 -285.422083)
			(xy 177.138569 -285.455314) (xy 177.174821 -285.494385) (xy 177.204845 -285.538422) (xy 177.227971 -285.586443)
			(xy 177.243681 -285.637373) (xy 177.251624 -285.690077) (xy 177.252122 -285.716726) (xy 177.251624 -285.743375)
			(xy 191.628004 -285.743375) (xy 191.628004 -285.690077) (xy 191.635947 -285.637373) (xy 191.651657 -285.586443)
			(xy 191.674783 -285.538422) (xy 191.704807 -285.494385) (xy 191.741059 -285.455314) (xy 191.78273 -285.422083)
			(xy 191.828888 -285.395434) (xy 191.878502 -285.375962) (xy 191.930464 -285.364102) (xy 191.983614 -285.360119)
			(xy 192.036764 -285.364102) (xy 192.088726 -285.375962) (xy 192.13834 -285.395434) (xy 192.184498 -285.422083)
			(xy 192.226169 -285.455314) (xy 192.262421 -285.494385) (xy 192.292445 -285.538422) (xy 192.315571 -285.586443)
			(xy 192.331281 -285.637373) (xy 192.339224 -285.690077) (xy 192.339722 -285.716726) (xy 192.339224 -285.743375)
			(xy 206.715604 -285.743375) (xy 206.715604 -285.690077) (xy 206.723547 -285.637373) (xy 206.739257 -285.586443)
			(xy 206.762383 -285.538422) (xy 206.792407 -285.494385) (xy 206.828659 -285.455314) (xy 206.87033 -285.422083)
			(xy 206.916488 -285.395434) (xy 206.966102 -285.375962) (xy 207.018064 -285.364102) (xy 207.071214 -285.360119)
			(xy 207.124364 -285.364102) (xy 207.176326 -285.375962) (xy 207.22594 -285.395434) (xy 207.272098 -285.422083)
			(xy 207.313769 -285.455314) (xy 207.350021 -285.494385) (xy 207.380045 -285.538422) (xy 207.403171 -285.586443)
			(xy 207.418881 -285.637373) (xy 207.426824 -285.690077) (xy 207.427322 -285.716726) (xy 207.426824 -285.743375)
			(xy 207.418881 -285.796079) (xy 207.403171 -285.847009) (xy 207.380045 -285.89503) (xy 207.350021 -285.939067)
			(xy 207.313769 -285.978138) (xy 207.272098 -286.011369) (xy 207.22594 -286.038018) (xy 207.176326 -286.05749)
			(xy 207.124364 -286.06935) (xy 207.071214 -286.073334) (xy 207.018064 -286.06935) (xy 206.966102 -286.05749)
			(xy 206.916488 -286.038018) (xy 206.87033 -286.011369) (xy 206.828659 -285.978138) (xy 206.792407 -285.939067)
			(xy 206.762383 -285.89503) (xy 206.739257 -285.847009) (xy 206.723547 -285.796079) (xy 206.715604 -285.743375)
			(xy 192.339224 -285.743375) (xy 192.331281 -285.796079) (xy 192.315571 -285.847009) (xy 192.292445 -285.89503)
			(xy 192.262421 -285.939067) (xy 192.226169 -285.978138) (xy 192.184498 -286.011369) (xy 192.13834 -286.038018)
			(xy 192.088726 -286.05749) (xy 192.036764 -286.06935) (xy 191.983614 -286.073334) (xy 191.930464 -286.06935)
			(xy 191.878502 -286.05749) (xy 191.828888 -286.038018) (xy 191.78273 -286.011369) (xy 191.741059 -285.978138)
			(xy 191.704807 -285.939067) (xy 191.674783 -285.89503) (xy 191.651657 -285.847009) (xy 191.635947 -285.796079)
			(xy 191.628004 -285.743375) (xy 177.251624 -285.743375) (xy 177.243681 -285.796079) (xy 177.227971 -285.847009)
			(xy 177.204845 -285.89503) (xy 177.174821 -285.939067) (xy 177.138569 -285.978138) (xy 177.096898 -286.011369)
			(xy 177.05074 -286.038018) (xy 177.001126 -286.05749) (xy 176.949164 -286.06935) (xy 176.896014 -286.073334)
			(xy 176.842864 -286.06935) (xy 176.790902 -286.05749) (xy 176.741288 -286.038018) (xy 176.69513 -286.011369)
			(xy 176.653459 -285.978138) (xy 176.617207 -285.939067) (xy 176.587183 -285.89503) (xy 176.564057 -285.847009)
			(xy 176.548347 -285.796079) (xy 176.540404 -285.743375) (xy 158.88716 -285.743375) (xy 158.88716 -286.593259)
			(xy 172.440336 -286.593259) (xy 172.440336 -286.539961) (xy 172.448279 -286.487257) (xy 172.463989 -286.436327)
			(xy 172.487115 -286.388306) (xy 172.517139 -286.344269) (xy 172.553391 -286.305198) (xy 172.595062 -286.271967)
			(xy 172.64122 -286.245318) (xy 172.690834 -286.225846) (xy 172.742796 -286.213986) (xy 172.795946 -286.210003)
			(xy 172.849096 -286.213986) (xy 172.901058 -286.225846) (xy 172.950672 -286.245318) (xy 172.99683 -286.271967)
			(xy 173.038501 -286.305198) (xy 173.074753 -286.344269) (xy 173.104777 -286.388306) (xy 173.127903 -286.436327)
			(xy 173.143613 -286.487257) (xy 173.151556 -286.539961) (xy 173.152054 -286.56661) (xy 173.151556 -286.593259)
			(xy 187.527936 -286.593259) (xy 187.527936 -286.539961) (xy 187.535879 -286.487257) (xy 187.551589 -286.436327)
			(xy 187.574715 -286.388306) (xy 187.604739 -286.344269) (xy 187.640991 -286.305198) (xy 187.682662 -286.271967)
			(xy 187.72882 -286.245318) (xy 187.778434 -286.225846) (xy 187.830396 -286.213986) (xy 187.883546 -286.210003)
			(xy 187.936696 -286.213986) (xy 187.988658 -286.225846) (xy 188.038272 -286.245318) (xy 188.08443 -286.271967)
			(xy 188.126101 -286.305198) (xy 188.162353 -286.344269) (xy 188.192377 -286.388306) (xy 188.215503 -286.436327)
			(xy 188.231213 -286.487257) (xy 188.239156 -286.539961) (xy 188.239654 -286.56661) (xy 188.239156 -286.593259)
			(xy 202.615536 -286.593259) (xy 202.615536 -286.539961) (xy 202.623479 -286.487257) (xy 202.639189 -286.436327)
			(xy 202.662315 -286.388306) (xy 202.692339 -286.344269) (xy 202.728591 -286.305198) (xy 202.770262 -286.271967)
			(xy 202.81642 -286.245318) (xy 202.866034 -286.225846) (xy 202.917996 -286.213986) (xy 202.971146 -286.210003)
			(xy 203.024296 -286.213986) (xy 203.076258 -286.225846) (xy 203.125872 -286.245318) (xy 203.17203 -286.271967)
			(xy 203.213701 -286.305198) (xy 203.249953 -286.344269) (xy 203.279977 -286.388306) (xy 203.303103 -286.436327)
			(xy 203.318813 -286.487257) (xy 203.326756 -286.539961) (xy 203.327254 -286.56661) (xy 203.326756 -286.593259)
			(xy 203.318813 -286.645963) (xy 203.303103 -286.696893) (xy 203.279977 -286.744914) (xy 203.249953 -286.788951)
			(xy 203.213701 -286.828022) (xy 203.17203 -286.861253) (xy 203.125872 -286.887902) (xy 203.076258 -286.907374)
			(xy 203.024296 -286.919234) (xy 202.971146 -286.923218) (xy 202.917996 -286.919234) (xy 202.866034 -286.907374)
			(xy 202.81642 -286.887902) (xy 202.770262 -286.861253) (xy 202.728591 -286.828022) (xy 202.692339 -286.788951)
			(xy 202.662315 -286.744914) (xy 202.639189 -286.696893) (xy 202.623479 -286.645963) (xy 202.615536 -286.593259)
			(xy 188.239156 -286.593259) (xy 188.231213 -286.645963) (xy 188.215503 -286.696893) (xy 188.192377 -286.744914)
			(xy 188.162353 -286.788951) (xy 188.126101 -286.828022) (xy 188.08443 -286.861253) (xy 188.038272 -286.887902)
			(xy 187.988658 -286.907374) (xy 187.936696 -286.919234) (xy 187.883546 -286.923218) (xy 187.830396 -286.919234)
			(xy 187.778434 -286.907374) (xy 187.72882 -286.887902) (xy 187.682662 -286.861253) (xy 187.640991 -286.828022)
			(xy 187.604739 -286.788951) (xy 187.574715 -286.744914) (xy 187.551589 -286.696893) (xy 187.535879 -286.645963)
			(xy 187.527936 -286.593259) (xy 173.151556 -286.593259) (xy 173.143613 -286.645963) (xy 173.127903 -286.696893)
			(xy 173.104777 -286.744914) (xy 173.074753 -286.788951) (xy 173.038501 -286.828022) (xy 172.99683 -286.861253)
			(xy 172.950672 -286.887902) (xy 172.901058 -286.907374) (xy 172.849096 -286.919234) (xy 172.795946 -286.923218)
			(xy 172.742796 -286.919234) (xy 172.690834 -286.907374) (xy 172.64122 -286.887902) (xy 172.595062 -286.861253)
			(xy 172.553391 -286.828022) (xy 172.517139 -286.788951) (xy 172.487115 -286.744914) (xy 172.463989 -286.696893)
			(xy 172.448279 -286.645963) (xy 172.440336 -286.593259) (xy 158.88716 -286.593259) (xy 158.88716 -287.443397)
			(xy 176.540404 -287.443397) (xy 176.540404 -287.390099) (xy 176.548347 -287.337395) (xy 176.564057 -287.286465)
			(xy 176.587183 -287.238444) (xy 176.617207 -287.194407) (xy 176.653459 -287.155336) (xy 176.69513 -287.122105)
			(xy 176.741288 -287.095456) (xy 176.790902 -287.075984) (xy 176.842864 -287.064124) (xy 176.896014 -287.060141)
			(xy 176.949164 -287.064124) (xy 177.001126 -287.075984) (xy 177.05074 -287.095456) (xy 177.096898 -287.122105)
			(xy 177.138569 -287.155336) (xy 177.174821 -287.194407) (xy 177.204845 -287.238444) (xy 177.227971 -287.286465)
			(xy 177.243681 -287.337395) (xy 177.251624 -287.390099) (xy 177.252122 -287.416748) (xy 177.251624 -287.443397)
			(xy 191.628004 -287.443397) (xy 191.628004 -287.390099) (xy 191.635947 -287.337395) (xy 191.651657 -287.286465)
			(xy 191.674783 -287.238444) (xy 191.704807 -287.194407) (xy 191.741059 -287.155336) (xy 191.78273 -287.122105)
			(xy 191.828888 -287.095456) (xy 191.878502 -287.075984) (xy 191.930464 -287.064124) (xy 191.983614 -287.060141)
			(xy 192.036764 -287.064124) (xy 192.088726 -287.075984) (xy 192.13834 -287.095456) (xy 192.184498 -287.122105)
			(xy 192.226169 -287.155336) (xy 192.262421 -287.194407) (xy 192.292445 -287.238444) (xy 192.315571 -287.286465)
			(xy 192.331281 -287.337395) (xy 192.339224 -287.390099) (xy 192.339722 -287.416748) (xy 192.339224 -287.443397)
			(xy 206.715604 -287.443397) (xy 206.715604 -287.390099) (xy 206.723547 -287.337395) (xy 206.739257 -287.286465)
			(xy 206.762383 -287.238444) (xy 206.792407 -287.194407) (xy 206.828659 -287.155336) (xy 206.87033 -287.122105)
			(xy 206.916488 -287.095456) (xy 206.966102 -287.075984) (xy 207.018064 -287.064124) (xy 207.071214 -287.060141)
			(xy 207.124364 -287.064124) (xy 207.176326 -287.075984) (xy 207.22594 -287.095456) (xy 207.272098 -287.122105)
			(xy 207.313769 -287.155336) (xy 207.350021 -287.194407) (xy 207.380045 -287.238444) (xy 207.403171 -287.286465)
			(xy 207.418881 -287.337395) (xy 207.426824 -287.390099) (xy 207.427322 -287.416748) (xy 207.426824 -287.443397)
			(xy 207.418881 -287.496101) (xy 207.403171 -287.547031) (xy 207.380045 -287.595052) (xy 207.350021 -287.639089)
			(xy 207.313769 -287.67816) (xy 207.272098 -287.711391) (xy 207.22594 -287.73804) (xy 207.176326 -287.757512)
			(xy 207.124364 -287.769372) (xy 207.071214 -287.773356) (xy 207.018064 -287.769372) (xy 206.966102 -287.757512)
			(xy 206.916488 -287.73804) (xy 206.87033 -287.711391) (xy 206.828659 -287.67816) (xy 206.792407 -287.639089)
			(xy 206.762383 -287.595052) (xy 206.739257 -287.547031) (xy 206.723547 -287.496101) (xy 206.715604 -287.443397)
			(xy 192.339224 -287.443397) (xy 192.331281 -287.496101) (xy 192.315571 -287.547031) (xy 192.292445 -287.595052)
			(xy 192.262421 -287.639089) (xy 192.226169 -287.67816) (xy 192.184498 -287.711391) (xy 192.13834 -287.73804)
			(xy 192.088726 -287.757512) (xy 192.036764 -287.769372) (xy 191.983614 -287.773356) (xy 191.930464 -287.769372)
			(xy 191.878502 -287.757512) (xy 191.828888 -287.73804) (xy 191.78273 -287.711391) (xy 191.741059 -287.67816)
			(xy 191.704807 -287.639089) (xy 191.674783 -287.595052) (xy 191.651657 -287.547031) (xy 191.635947 -287.496101)
			(xy 191.628004 -287.443397) (xy 177.251624 -287.443397) (xy 177.243681 -287.496101) (xy 177.227971 -287.547031)
			(xy 177.204845 -287.595052) (xy 177.174821 -287.639089) (xy 177.138569 -287.67816) (xy 177.096898 -287.711391)
			(xy 177.05074 -287.73804) (xy 177.001126 -287.757512) (xy 176.949164 -287.769372) (xy 176.896014 -287.773356)
			(xy 176.842864 -287.769372) (xy 176.790902 -287.757512) (xy 176.741288 -287.73804) (xy 176.69513 -287.711391)
			(xy 176.653459 -287.67816) (xy 176.617207 -287.639089) (xy 176.587183 -287.595052) (xy 176.564057 -287.547031)
			(xy 176.548347 -287.496101) (xy 176.540404 -287.443397) (xy 158.88716 -287.443397) (xy 158.88716 -288.293281)
			(xy 172.440336 -288.293281) (xy 172.440336 -288.239983) (xy 172.448279 -288.187279) (xy 172.463989 -288.136349)
			(xy 172.487115 -288.088328) (xy 172.517139 -288.044291) (xy 172.553391 -288.00522) (xy 172.595062 -287.971989)
			(xy 172.64122 -287.94534) (xy 172.690834 -287.925868) (xy 172.742796 -287.914008) (xy 172.795946 -287.910025)
			(xy 172.849096 -287.914008) (xy 172.901058 -287.925868) (xy 172.950672 -287.94534) (xy 172.99683 -287.971989)
			(xy 173.038501 -288.00522) (xy 173.074753 -288.044291) (xy 173.104777 -288.088328) (xy 173.127903 -288.136349)
			(xy 173.143613 -288.187279) (xy 173.151556 -288.239983) (xy 173.152054 -288.266632) (xy 173.151556 -288.293281)
			(xy 187.527936 -288.293281) (xy 187.527936 -288.239983) (xy 187.535879 -288.187279) (xy 187.551589 -288.136349)
			(xy 187.574715 -288.088328) (xy 187.604739 -288.044291) (xy 187.640991 -288.00522) (xy 187.682662 -287.971989)
			(xy 187.72882 -287.94534) (xy 187.778434 -287.925868) (xy 187.830396 -287.914008) (xy 187.883546 -287.910025)
			(xy 187.936696 -287.914008) (xy 187.988658 -287.925868) (xy 188.038272 -287.94534) (xy 188.08443 -287.971989)
			(xy 188.126101 -288.00522) (xy 188.162353 -288.044291) (xy 188.192377 -288.088328) (xy 188.215503 -288.136349)
			(xy 188.231213 -288.187279) (xy 188.239156 -288.239983) (xy 188.239654 -288.266632) (xy 188.239156 -288.293281)
			(xy 202.615536 -288.293281) (xy 202.615536 -288.239983) (xy 202.623479 -288.187279) (xy 202.639189 -288.136349)
			(xy 202.662315 -288.088328) (xy 202.692339 -288.044291) (xy 202.728591 -288.00522) (xy 202.770262 -287.971989)
			(xy 202.81642 -287.94534) (xy 202.866034 -287.925868) (xy 202.917996 -287.914008) (xy 202.971146 -287.910025)
			(xy 203.024296 -287.914008) (xy 203.076258 -287.925868) (xy 203.125872 -287.94534) (xy 203.17203 -287.971989)
			(xy 203.213701 -288.00522) (xy 203.249953 -288.044291) (xy 203.279977 -288.088328) (xy 203.303103 -288.136349)
			(xy 203.318813 -288.187279) (xy 203.326756 -288.239983) (xy 203.327254 -288.266632) (xy 203.326756 -288.293281)
			(xy 203.318813 -288.345985) (xy 203.303103 -288.396915) (xy 203.279977 -288.444936) (xy 203.249953 -288.488973)
			(xy 203.213701 -288.528044) (xy 203.17203 -288.561275) (xy 203.125872 -288.587924) (xy 203.076258 -288.607396)
			(xy 203.024296 -288.619256) (xy 202.971146 -288.62324) (xy 202.917996 -288.619256) (xy 202.866034 -288.607396)
			(xy 202.81642 -288.587924) (xy 202.770262 -288.561275) (xy 202.728591 -288.528044) (xy 202.692339 -288.488973)
			(xy 202.662315 -288.444936) (xy 202.639189 -288.396915) (xy 202.623479 -288.345985) (xy 202.615536 -288.293281)
			(xy 188.239156 -288.293281) (xy 188.231213 -288.345985) (xy 188.215503 -288.396915) (xy 188.192377 -288.444936)
			(xy 188.162353 -288.488973) (xy 188.126101 -288.528044) (xy 188.08443 -288.561275) (xy 188.038272 -288.587924)
			(xy 187.988658 -288.607396) (xy 187.936696 -288.619256) (xy 187.883546 -288.62324) (xy 187.830396 -288.619256)
			(xy 187.778434 -288.607396) (xy 187.72882 -288.587924) (xy 187.682662 -288.561275) (xy 187.640991 -288.528044)
			(xy 187.604739 -288.488973) (xy 187.574715 -288.444936) (xy 187.551589 -288.396915) (xy 187.535879 -288.345985)
			(xy 187.527936 -288.293281) (xy 173.151556 -288.293281) (xy 173.143613 -288.345985) (xy 173.127903 -288.396915)
			(xy 173.104777 -288.444936) (xy 173.074753 -288.488973) (xy 173.038501 -288.528044) (xy 172.99683 -288.561275)
			(xy 172.950672 -288.587924) (xy 172.901058 -288.607396) (xy 172.849096 -288.619256) (xy 172.795946 -288.62324)
			(xy 172.742796 -288.619256) (xy 172.690834 -288.607396) (xy 172.64122 -288.587924) (xy 172.595062 -288.561275)
			(xy 172.553391 -288.528044) (xy 172.517139 -288.488973) (xy 172.487115 -288.444936) (xy 172.463989 -288.396915)
			(xy 172.448279 -288.345985) (xy 172.440336 -288.293281) (xy 158.88716 -288.293281) (xy 158.88716 -289.143419)
			(xy 176.540404 -289.143419) (xy 176.540404 -289.090121) (xy 176.548347 -289.037417) (xy 176.564057 -288.986487)
			(xy 176.587183 -288.938466) (xy 176.617207 -288.894429) (xy 176.653459 -288.855358) (xy 176.69513 -288.822127)
			(xy 176.741288 -288.795478) (xy 176.790902 -288.776006) (xy 176.842864 -288.764146) (xy 176.896014 -288.760163)
			(xy 176.949164 -288.764146) (xy 177.001126 -288.776006) (xy 177.05074 -288.795478) (xy 177.096898 -288.822127)
			(xy 177.138569 -288.855358) (xy 177.174821 -288.894429) (xy 177.204845 -288.938466) (xy 177.227971 -288.986487)
			(xy 177.243681 -289.037417) (xy 177.251624 -289.090121) (xy 177.252122 -289.11677) (xy 177.251624 -289.143419)
			(xy 191.628004 -289.143419) (xy 191.628004 -289.090121) (xy 191.635947 -289.037417) (xy 191.651657 -288.986487)
			(xy 191.674783 -288.938466) (xy 191.704807 -288.894429) (xy 191.741059 -288.855358) (xy 191.78273 -288.822127)
			(xy 191.828888 -288.795478) (xy 191.878502 -288.776006) (xy 191.930464 -288.764146) (xy 191.983614 -288.760163)
			(xy 192.036764 -288.764146) (xy 192.088726 -288.776006) (xy 192.13834 -288.795478) (xy 192.184498 -288.822127)
			(xy 192.226169 -288.855358) (xy 192.262421 -288.894429) (xy 192.292445 -288.938466) (xy 192.315571 -288.986487)
			(xy 192.331281 -289.037417) (xy 192.339224 -289.090121) (xy 192.339722 -289.11677) (xy 192.339224 -289.143419)
			(xy 206.715604 -289.143419) (xy 206.715604 -289.090121) (xy 206.723547 -289.037417) (xy 206.739257 -288.986487)
			(xy 206.762383 -288.938466) (xy 206.792407 -288.894429) (xy 206.828659 -288.855358) (xy 206.87033 -288.822127)
			(xy 206.916488 -288.795478) (xy 206.966102 -288.776006) (xy 207.018064 -288.764146) (xy 207.071214 -288.760163)
			(xy 207.124364 -288.764146) (xy 207.176326 -288.776006) (xy 207.22594 -288.795478) (xy 207.272098 -288.822127)
			(xy 207.313769 -288.855358) (xy 207.350021 -288.894429) (xy 207.380045 -288.938466) (xy 207.403171 -288.986487)
			(xy 207.418881 -289.037417) (xy 207.426824 -289.090121) (xy 207.427322 -289.11677) (xy 207.426824 -289.143419)
			(xy 207.418881 -289.196123) (xy 207.403171 -289.247053) (xy 207.380045 -289.295074) (xy 207.350021 -289.339111)
			(xy 207.313769 -289.378182) (xy 207.272098 -289.411413) (xy 207.22594 -289.438062) (xy 207.176326 -289.457534)
			(xy 207.124364 -289.469394) (xy 207.071214 -289.473378) (xy 207.018064 -289.469394) (xy 206.966102 -289.457534)
			(xy 206.916488 -289.438062) (xy 206.87033 -289.411413) (xy 206.828659 -289.378182) (xy 206.792407 -289.339111)
			(xy 206.762383 -289.295074) (xy 206.739257 -289.247053) (xy 206.723547 -289.196123) (xy 206.715604 -289.143419)
			(xy 192.339224 -289.143419) (xy 192.331281 -289.196123) (xy 192.315571 -289.247053) (xy 192.292445 -289.295074)
			(xy 192.262421 -289.339111) (xy 192.226169 -289.378182) (xy 192.184498 -289.411413) (xy 192.13834 -289.438062)
			(xy 192.088726 -289.457534) (xy 192.036764 -289.469394) (xy 191.983614 -289.473378) (xy 191.930464 -289.469394)
			(xy 191.878502 -289.457534) (xy 191.828888 -289.438062) (xy 191.78273 -289.411413) (xy 191.741059 -289.378182)
			(xy 191.704807 -289.339111) (xy 191.674783 -289.295074) (xy 191.651657 -289.247053) (xy 191.635947 -289.196123)
			(xy 191.628004 -289.143419) (xy 177.251624 -289.143419) (xy 177.243681 -289.196123) (xy 177.227971 -289.247053)
			(xy 177.204845 -289.295074) (xy 177.174821 -289.339111) (xy 177.138569 -289.378182) (xy 177.096898 -289.411413)
			(xy 177.05074 -289.438062) (xy 177.001126 -289.457534) (xy 176.949164 -289.469394) (xy 176.896014 -289.473378)
			(xy 176.842864 -289.469394) (xy 176.790902 -289.457534) (xy 176.741288 -289.438062) (xy 176.69513 -289.411413)
			(xy 176.653459 -289.378182) (xy 176.617207 -289.339111) (xy 176.587183 -289.295074) (xy 176.564057 -289.247053)
			(xy 176.548347 -289.196123) (xy 176.540404 -289.143419) (xy 158.88716 -289.143419) (xy 158.88716 -289.993303)
			(xy 172.440336 -289.993303) (xy 172.440336 -289.940005) (xy 172.448279 -289.887301) (xy 172.463989 -289.836371)
			(xy 172.487115 -289.78835) (xy 172.517139 -289.744313) (xy 172.553391 -289.705242) (xy 172.595062 -289.672011)
			(xy 172.64122 -289.645362) (xy 172.690834 -289.62589) (xy 172.742796 -289.61403) (xy 172.795946 -289.610047)
			(xy 172.849096 -289.61403) (xy 172.901058 -289.62589) (xy 172.950672 -289.645362) (xy 172.99683 -289.672011)
			(xy 173.038501 -289.705242) (xy 173.074753 -289.744313) (xy 173.104777 -289.78835) (xy 173.127903 -289.836371)
			(xy 173.143613 -289.887301) (xy 173.151556 -289.940005) (xy 173.152054 -289.966654) (xy 173.151556 -289.993303)
			(xy 187.527936 -289.993303) (xy 187.527936 -289.940005) (xy 187.535879 -289.887301) (xy 187.551589 -289.836371)
			(xy 187.574715 -289.78835) (xy 187.604739 -289.744313) (xy 187.640991 -289.705242) (xy 187.682662 -289.672011)
			(xy 187.72882 -289.645362) (xy 187.778434 -289.62589) (xy 187.830396 -289.61403) (xy 187.883546 -289.610047)
			(xy 187.936696 -289.61403) (xy 187.988658 -289.62589) (xy 188.038272 -289.645362) (xy 188.08443 -289.672011)
			(xy 188.126101 -289.705242) (xy 188.162353 -289.744313) (xy 188.192377 -289.78835) (xy 188.215503 -289.836371)
			(xy 188.231213 -289.887301) (xy 188.239156 -289.940005) (xy 188.239654 -289.966654) (xy 188.239156 -289.993303)
			(xy 202.615536 -289.993303) (xy 202.615536 -289.940005) (xy 202.623479 -289.887301) (xy 202.639189 -289.836371)
			(xy 202.662315 -289.78835) (xy 202.692339 -289.744313) (xy 202.728591 -289.705242) (xy 202.770262 -289.672011)
			(xy 202.81642 -289.645362) (xy 202.866034 -289.62589) (xy 202.917996 -289.61403) (xy 202.971146 -289.610047)
			(xy 203.024296 -289.61403) (xy 203.076258 -289.62589) (xy 203.125872 -289.645362) (xy 203.17203 -289.672011)
			(xy 203.213701 -289.705242) (xy 203.249953 -289.744313) (xy 203.279977 -289.78835) (xy 203.303103 -289.836371)
			(xy 203.318813 -289.887301) (xy 203.326756 -289.940005) (xy 203.327254 -289.966654) (xy 203.326756 -289.993303)
			(xy 203.318813 -290.046007) (xy 203.303103 -290.096937) (xy 203.279977 -290.144958) (xy 203.249953 -290.188995)
			(xy 203.213701 -290.228066) (xy 203.17203 -290.261297) (xy 203.125872 -290.287946) (xy 203.076258 -290.307418)
			(xy 203.024296 -290.319278) (xy 202.971146 -290.323262) (xy 202.917996 -290.319278) (xy 202.866034 -290.307418)
			(xy 202.81642 -290.287946) (xy 202.770262 -290.261297) (xy 202.728591 -290.228066) (xy 202.692339 -290.188995)
			(xy 202.662315 -290.144958) (xy 202.639189 -290.096937) (xy 202.623479 -290.046007) (xy 202.615536 -289.993303)
			(xy 188.239156 -289.993303) (xy 188.231213 -290.046007) (xy 188.215503 -290.096937) (xy 188.192377 -290.144958)
			(xy 188.162353 -290.188995) (xy 188.126101 -290.228066) (xy 188.08443 -290.261297) (xy 188.038272 -290.287946)
			(xy 187.988658 -290.307418) (xy 187.936696 -290.319278) (xy 187.883546 -290.323262) (xy 187.830396 -290.319278)
			(xy 187.778434 -290.307418) (xy 187.72882 -290.287946) (xy 187.682662 -290.261297) (xy 187.640991 -290.228066)
			(xy 187.604739 -290.188995) (xy 187.574715 -290.144958) (xy 187.551589 -290.096937) (xy 187.535879 -290.046007)
			(xy 187.527936 -289.993303) (xy 173.151556 -289.993303) (xy 173.143613 -290.046007) (xy 173.127903 -290.096937)
			(xy 173.104777 -290.144958) (xy 173.074753 -290.188995) (xy 173.038501 -290.228066) (xy 172.99683 -290.261297)
			(xy 172.950672 -290.287946) (xy 172.901058 -290.307418) (xy 172.849096 -290.319278) (xy 172.795946 -290.323262)
			(xy 172.742796 -290.319278) (xy 172.690834 -290.307418) (xy 172.64122 -290.287946) (xy 172.595062 -290.261297)
			(xy 172.553391 -290.228066) (xy 172.517139 -290.188995) (xy 172.487115 -290.144958) (xy 172.463989 -290.096937)
			(xy 172.448279 -290.046007) (xy 172.440336 -289.993303) (xy 158.88716 -289.993303) (xy 158.88716 -290.843187)
			(xy 176.540404 -290.843187) (xy 176.540404 -290.789889) (xy 176.548347 -290.737185) (xy 176.564057 -290.686255)
			(xy 176.587183 -290.638234) (xy 176.617207 -290.594197) (xy 176.653459 -290.555126) (xy 176.69513 -290.521895)
			(xy 176.741288 -290.495246) (xy 176.790902 -290.475774) (xy 176.842864 -290.463914) (xy 176.896014 -290.459931)
			(xy 176.949164 -290.463914) (xy 177.001126 -290.475774) (xy 177.05074 -290.495246) (xy 177.096898 -290.521895)
			(xy 177.138569 -290.555126) (xy 177.174821 -290.594197) (xy 177.204845 -290.638234) (xy 177.227971 -290.686255)
			(xy 177.243681 -290.737185) (xy 177.251624 -290.789889) (xy 177.252122 -290.816538) (xy 177.251624 -290.843187)
			(xy 191.628004 -290.843187) (xy 191.628004 -290.789889) (xy 191.635947 -290.737185) (xy 191.651657 -290.686255)
			(xy 191.674783 -290.638234) (xy 191.704807 -290.594197) (xy 191.741059 -290.555126) (xy 191.78273 -290.521895)
			(xy 191.828888 -290.495246) (xy 191.878502 -290.475774) (xy 191.930464 -290.463914) (xy 191.983614 -290.459931)
			(xy 192.036764 -290.463914) (xy 192.088726 -290.475774) (xy 192.13834 -290.495246) (xy 192.184498 -290.521895)
			(xy 192.226169 -290.555126) (xy 192.262421 -290.594197) (xy 192.292445 -290.638234) (xy 192.315571 -290.686255)
			(xy 192.331281 -290.737185) (xy 192.339224 -290.789889) (xy 192.339722 -290.816538) (xy 192.339224 -290.843187)
			(xy 206.715604 -290.843187) (xy 206.715604 -290.789889) (xy 206.723547 -290.737185) (xy 206.739257 -290.686255)
			(xy 206.762383 -290.638234) (xy 206.792407 -290.594197) (xy 206.828659 -290.555126) (xy 206.87033 -290.521895)
			(xy 206.916488 -290.495246) (xy 206.966102 -290.475774) (xy 207.018064 -290.463914) (xy 207.071214 -290.459931)
			(xy 207.124364 -290.463914) (xy 207.176326 -290.475774) (xy 207.22594 -290.495246) (xy 207.272098 -290.521895)
			(xy 207.313769 -290.555126) (xy 207.350021 -290.594197) (xy 207.380045 -290.638234) (xy 207.403171 -290.686255)
			(xy 207.418881 -290.737185) (xy 207.426824 -290.789889) (xy 207.427322 -290.816538) (xy 207.426824 -290.843187)
			(xy 207.418881 -290.895891) (xy 207.403171 -290.946821) (xy 207.380045 -290.994842) (xy 207.350021 -291.038879)
			(xy 207.313769 -291.07795) (xy 207.272098 -291.111181) (xy 207.22594 -291.13783) (xy 207.176326 -291.157302)
			(xy 207.124364 -291.169162) (xy 207.071214 -291.173146) (xy 207.018064 -291.169162) (xy 206.966102 -291.157302)
			(xy 206.916488 -291.13783) (xy 206.87033 -291.111181) (xy 206.828659 -291.07795) (xy 206.792407 -291.038879)
			(xy 206.762383 -290.994842) (xy 206.739257 -290.946821) (xy 206.723547 -290.895891) (xy 206.715604 -290.843187)
			(xy 192.339224 -290.843187) (xy 192.331281 -290.895891) (xy 192.315571 -290.946821) (xy 192.292445 -290.994842)
			(xy 192.262421 -291.038879) (xy 192.226169 -291.07795) (xy 192.184498 -291.111181) (xy 192.13834 -291.13783)
			(xy 192.088726 -291.157302) (xy 192.036764 -291.169162) (xy 191.983614 -291.173146) (xy 191.930464 -291.169162)
			(xy 191.878502 -291.157302) (xy 191.828888 -291.13783) (xy 191.78273 -291.111181) (xy 191.741059 -291.07795)
			(xy 191.704807 -291.038879) (xy 191.674783 -290.994842) (xy 191.651657 -290.946821) (xy 191.635947 -290.895891)
			(xy 191.628004 -290.843187) (xy 177.251624 -290.843187) (xy 177.243681 -290.895891) (xy 177.227971 -290.946821)
			(xy 177.204845 -290.994842) (xy 177.174821 -291.038879) (xy 177.138569 -291.07795) (xy 177.096898 -291.111181)
			(xy 177.05074 -291.13783) (xy 177.001126 -291.157302) (xy 176.949164 -291.169162) (xy 176.896014 -291.173146)
			(xy 176.842864 -291.169162) (xy 176.790902 -291.157302) (xy 176.741288 -291.13783) (xy 176.69513 -291.111181)
			(xy 176.653459 -291.07795) (xy 176.617207 -291.038879) (xy 176.587183 -290.994842) (xy 176.564057 -290.946821)
			(xy 176.548347 -290.895891) (xy 176.540404 -290.843187) (xy 158.88716 -290.843187) (xy 158.88716 -291.693325)
			(xy 172.440336 -291.693325) (xy 172.440336 -291.640027) (xy 172.448279 -291.587323) (xy 172.463989 -291.536393)
			(xy 172.487115 -291.488372) (xy 172.517139 -291.444335) (xy 172.553391 -291.405264) (xy 172.595062 -291.372033)
			(xy 172.64122 -291.345384) (xy 172.690834 -291.325912) (xy 172.742796 -291.314052) (xy 172.795946 -291.310069)
			(xy 172.849096 -291.314052) (xy 172.901058 -291.325912) (xy 172.950672 -291.345384) (xy 172.99683 -291.372033)
			(xy 173.038501 -291.405264) (xy 173.074753 -291.444335) (xy 173.104777 -291.488372) (xy 173.127903 -291.536393)
			(xy 173.143613 -291.587323) (xy 173.151556 -291.640027) (xy 173.152054 -291.666676) (xy 173.151556 -291.693325)
			(xy 187.527936 -291.693325) (xy 187.527936 -291.640027) (xy 187.535879 -291.587323) (xy 187.551589 -291.536393)
			(xy 187.574715 -291.488372) (xy 187.604739 -291.444335) (xy 187.640991 -291.405264) (xy 187.682662 -291.372033)
			(xy 187.72882 -291.345384) (xy 187.778434 -291.325912) (xy 187.830396 -291.314052) (xy 187.883546 -291.310069)
			(xy 187.936696 -291.314052) (xy 187.988658 -291.325912) (xy 188.038272 -291.345384) (xy 188.08443 -291.372033)
			(xy 188.126101 -291.405264) (xy 188.162353 -291.444335) (xy 188.192377 -291.488372) (xy 188.215503 -291.536393)
			(xy 188.231213 -291.587323) (xy 188.239156 -291.640027) (xy 188.239654 -291.666676) (xy 188.239156 -291.693325)
			(xy 202.615536 -291.693325) (xy 202.615536 -291.640027) (xy 202.623479 -291.587323) (xy 202.639189 -291.536393)
			(xy 202.662315 -291.488372) (xy 202.692339 -291.444335) (xy 202.728591 -291.405264) (xy 202.770262 -291.372033)
			(xy 202.81642 -291.345384) (xy 202.866034 -291.325912) (xy 202.917996 -291.314052) (xy 202.971146 -291.310069)
			(xy 203.024296 -291.314052) (xy 203.076258 -291.325912) (xy 203.125872 -291.345384) (xy 203.17203 -291.372033)
			(xy 203.213701 -291.405264) (xy 203.249953 -291.444335) (xy 203.279977 -291.488372) (xy 203.303103 -291.536393)
			(xy 203.318813 -291.587323) (xy 203.326756 -291.640027) (xy 203.327254 -291.666676) (xy 203.326756 -291.693325)
			(xy 203.318813 -291.746029) (xy 203.303103 -291.796959) (xy 203.279977 -291.84498) (xy 203.249953 -291.889017)
			(xy 203.213701 -291.928088) (xy 203.17203 -291.961319) (xy 203.125872 -291.987968) (xy 203.076258 -292.00744)
			(xy 203.024296 -292.0193) (xy 202.971146 -292.023284) (xy 202.917996 -292.0193) (xy 202.866034 -292.00744)
			(xy 202.81642 -291.987968) (xy 202.770262 -291.961319) (xy 202.728591 -291.928088) (xy 202.692339 -291.889017)
			(xy 202.662315 -291.84498) (xy 202.639189 -291.796959) (xy 202.623479 -291.746029) (xy 202.615536 -291.693325)
			(xy 188.239156 -291.693325) (xy 188.231213 -291.746029) (xy 188.215503 -291.796959) (xy 188.192377 -291.84498)
			(xy 188.162353 -291.889017) (xy 188.126101 -291.928088) (xy 188.08443 -291.961319) (xy 188.038272 -291.987968)
			(xy 187.988658 -292.00744) (xy 187.936696 -292.0193) (xy 187.883546 -292.023284) (xy 187.830396 -292.0193)
			(xy 187.778434 -292.00744) (xy 187.72882 -291.987968) (xy 187.682662 -291.961319) (xy 187.640991 -291.928088)
			(xy 187.604739 -291.889017) (xy 187.574715 -291.84498) (xy 187.551589 -291.796959) (xy 187.535879 -291.746029)
			(xy 187.527936 -291.693325) (xy 173.151556 -291.693325) (xy 173.143613 -291.746029) (xy 173.127903 -291.796959)
			(xy 173.104777 -291.84498) (xy 173.074753 -291.889017) (xy 173.038501 -291.928088) (xy 172.99683 -291.961319)
			(xy 172.950672 -291.987968) (xy 172.901058 -292.00744) (xy 172.849096 -292.0193) (xy 172.795946 -292.023284)
			(xy 172.742796 -292.0193) (xy 172.690834 -292.00744) (xy 172.64122 -291.987968) (xy 172.595062 -291.961319)
			(xy 172.553391 -291.928088) (xy 172.517139 -291.889017) (xy 172.487115 -291.84498) (xy 172.463989 -291.796959)
			(xy 172.448279 -291.746029) (xy 172.440336 -291.693325) (xy 158.88716 -291.693325) (xy 158.88716 -292.543209)
			(xy 176.540404 -292.543209) (xy 176.540404 -292.489911) (xy 176.548347 -292.437207) (xy 176.564057 -292.386277)
			(xy 176.587183 -292.338256) (xy 176.617207 -292.294219) (xy 176.653459 -292.255148) (xy 176.69513 -292.221917)
			(xy 176.741288 -292.195268) (xy 176.790902 -292.175796) (xy 176.842864 -292.163936) (xy 176.896014 -292.159953)
			(xy 176.949164 -292.163936) (xy 177.001126 -292.175796) (xy 177.05074 -292.195268) (xy 177.096898 -292.221917)
			(xy 177.138569 -292.255148) (xy 177.174821 -292.294219) (xy 177.204845 -292.338256) (xy 177.227971 -292.386277)
			(xy 177.243681 -292.437207) (xy 177.251624 -292.489911) (xy 177.252122 -292.51656) (xy 177.251624 -292.543209)
			(xy 191.628004 -292.543209) (xy 191.628004 -292.489911) (xy 191.635947 -292.437207) (xy 191.651657 -292.386277)
			(xy 191.674783 -292.338256) (xy 191.704807 -292.294219) (xy 191.741059 -292.255148) (xy 191.78273 -292.221917)
			(xy 191.828888 -292.195268) (xy 191.878502 -292.175796) (xy 191.930464 -292.163936) (xy 191.983614 -292.159953)
			(xy 192.036764 -292.163936) (xy 192.088726 -292.175796) (xy 192.13834 -292.195268) (xy 192.184498 -292.221917)
			(xy 192.226169 -292.255148) (xy 192.262421 -292.294219) (xy 192.292445 -292.338256) (xy 192.315571 -292.386277)
			(xy 192.331281 -292.437207) (xy 192.339224 -292.489911) (xy 192.339722 -292.51656) (xy 192.339224 -292.543209)
			(xy 206.715604 -292.543209) (xy 206.715604 -292.489911) (xy 206.723547 -292.437207) (xy 206.739257 -292.386277)
			(xy 206.762383 -292.338256) (xy 206.792407 -292.294219) (xy 206.828659 -292.255148) (xy 206.87033 -292.221917)
			(xy 206.916488 -292.195268) (xy 206.966102 -292.175796) (xy 207.018064 -292.163936) (xy 207.071214 -292.159953)
			(xy 207.124364 -292.163936) (xy 207.176326 -292.175796) (xy 207.22594 -292.195268) (xy 207.272098 -292.221917)
			(xy 207.313769 -292.255148) (xy 207.350021 -292.294219) (xy 207.380045 -292.338256) (xy 207.403171 -292.386277)
			(xy 207.418881 -292.437207) (xy 207.426824 -292.489911) (xy 207.427322 -292.51656) (xy 207.426824 -292.543209)
			(xy 207.418881 -292.595913) (xy 207.403171 -292.646843) (xy 207.380045 -292.694864) (xy 207.350021 -292.738901)
			(xy 207.313769 -292.777972) (xy 207.272098 -292.811203) (xy 207.22594 -292.837852) (xy 207.176326 -292.857324)
			(xy 207.124364 -292.869184) (xy 207.071214 -292.873168) (xy 207.018064 -292.869184) (xy 206.966102 -292.857324)
			(xy 206.916488 -292.837852) (xy 206.87033 -292.811203) (xy 206.828659 -292.777972) (xy 206.792407 -292.738901)
			(xy 206.762383 -292.694864) (xy 206.739257 -292.646843) (xy 206.723547 -292.595913) (xy 206.715604 -292.543209)
			(xy 192.339224 -292.543209) (xy 192.331281 -292.595913) (xy 192.315571 -292.646843) (xy 192.292445 -292.694864)
			(xy 192.262421 -292.738901) (xy 192.226169 -292.777972) (xy 192.184498 -292.811203) (xy 192.13834 -292.837852)
			(xy 192.088726 -292.857324) (xy 192.036764 -292.869184) (xy 191.983614 -292.873168) (xy 191.930464 -292.869184)
			(xy 191.878502 -292.857324) (xy 191.828888 -292.837852) (xy 191.78273 -292.811203) (xy 191.741059 -292.777972)
			(xy 191.704807 -292.738901) (xy 191.674783 -292.694864) (xy 191.651657 -292.646843) (xy 191.635947 -292.595913)
			(xy 191.628004 -292.543209) (xy 177.251624 -292.543209) (xy 177.243681 -292.595913) (xy 177.227971 -292.646843)
			(xy 177.204845 -292.694864) (xy 177.174821 -292.738901) (xy 177.138569 -292.777972) (xy 177.096898 -292.811203)
			(xy 177.05074 -292.837852) (xy 177.001126 -292.857324) (xy 176.949164 -292.869184) (xy 176.896014 -292.873168)
			(xy 176.842864 -292.869184) (xy 176.790902 -292.857324) (xy 176.741288 -292.837852) (xy 176.69513 -292.811203)
			(xy 176.653459 -292.777972) (xy 176.617207 -292.738901) (xy 176.587183 -292.694864) (xy 176.564057 -292.646843)
			(xy 176.548347 -292.595913) (xy 176.540404 -292.543209) (xy 158.88716 -292.543209) (xy 158.88716 -293.393347)
			(xy 172.440336 -293.393347) (xy 172.440336 -293.340049) (xy 172.448279 -293.287345) (xy 172.463989 -293.236415)
			(xy 172.487115 -293.188394) (xy 172.517139 -293.144357) (xy 172.553391 -293.105286) (xy 172.595062 -293.072055)
			(xy 172.64122 -293.045406) (xy 172.690834 -293.025934) (xy 172.742796 -293.014074) (xy 172.795946 -293.010091)
			(xy 172.849096 -293.014074) (xy 172.901058 -293.025934) (xy 172.950672 -293.045406) (xy 172.99683 -293.072055)
			(xy 173.038501 -293.105286) (xy 173.074753 -293.144357) (xy 173.104777 -293.188394) (xy 173.127903 -293.236415)
			(xy 173.143613 -293.287345) (xy 173.151556 -293.340049) (xy 173.152054 -293.366698) (xy 173.151556 -293.393347)
			(xy 176.540404 -293.393347) (xy 176.540404 -293.340049) (xy 176.548347 -293.287345) (xy 176.564057 -293.236415)
			(xy 176.587183 -293.188394) (xy 176.617207 -293.144357) (xy 176.653459 -293.105286) (xy 176.69513 -293.072055)
			(xy 176.741288 -293.045406) (xy 176.790902 -293.025934) (xy 176.842864 -293.014074) (xy 176.896014 -293.010091)
			(xy 176.949164 -293.014074) (xy 177.001126 -293.025934) (xy 177.05074 -293.045406) (xy 177.096898 -293.072055)
			(xy 177.138569 -293.105286) (xy 177.174821 -293.144357) (xy 177.204845 -293.188394) (xy 177.227971 -293.236415)
			(xy 177.243681 -293.287345) (xy 177.251624 -293.340049) (xy 177.252122 -293.366698) (xy 177.251624 -293.393347)
			(xy 187.527936 -293.393347) (xy 187.527936 -293.340049) (xy 187.535879 -293.287345) (xy 187.551589 -293.236415)
			(xy 187.574715 -293.188394) (xy 187.604739 -293.144357) (xy 187.640991 -293.105286) (xy 187.682662 -293.072055)
			(xy 187.72882 -293.045406) (xy 187.778434 -293.025934) (xy 187.830396 -293.014074) (xy 187.883546 -293.010091)
			(xy 187.936696 -293.014074) (xy 187.988658 -293.025934) (xy 188.038272 -293.045406) (xy 188.08443 -293.072055)
			(xy 188.126101 -293.105286) (xy 188.162353 -293.144357) (xy 188.192377 -293.188394) (xy 188.215503 -293.236415)
			(xy 188.231213 -293.287345) (xy 188.239156 -293.340049) (xy 188.239654 -293.366698) (xy 188.239156 -293.393347)
			(xy 191.628004 -293.393347) (xy 191.628004 -293.340049) (xy 191.635947 -293.287345) (xy 191.651657 -293.236415)
			(xy 191.674783 -293.188394) (xy 191.704807 -293.144357) (xy 191.741059 -293.105286) (xy 191.78273 -293.072055)
			(xy 191.828888 -293.045406) (xy 191.878502 -293.025934) (xy 191.930464 -293.014074) (xy 191.983614 -293.010091)
			(xy 192.036764 -293.014074) (xy 192.088726 -293.025934) (xy 192.13834 -293.045406) (xy 192.184498 -293.072055)
			(xy 192.226169 -293.105286) (xy 192.262421 -293.144357) (xy 192.292445 -293.188394) (xy 192.315571 -293.236415)
			(xy 192.331281 -293.287345) (xy 192.339224 -293.340049) (xy 192.339722 -293.366698) (xy 192.339224 -293.393347)
			(xy 202.615536 -293.393347) (xy 202.615536 -293.340049) (xy 202.623479 -293.287345) (xy 202.639189 -293.236415)
			(xy 202.662315 -293.188394) (xy 202.692339 -293.144357) (xy 202.728591 -293.105286) (xy 202.770262 -293.072055)
			(xy 202.81642 -293.045406) (xy 202.866034 -293.025934) (xy 202.917996 -293.014074) (xy 202.971146 -293.010091)
			(xy 203.024296 -293.014074) (xy 203.076258 -293.025934) (xy 203.125872 -293.045406) (xy 203.17203 -293.072055)
			(xy 203.213701 -293.105286) (xy 203.249953 -293.144357) (xy 203.279977 -293.188394) (xy 203.303103 -293.236415)
			(xy 203.318813 -293.287345) (xy 203.326756 -293.340049) (xy 203.327254 -293.366698) (xy 203.326756 -293.393347)
			(xy 206.715604 -293.393347) (xy 206.715604 -293.340049) (xy 206.723547 -293.287345) (xy 206.739257 -293.236415)
			(xy 206.762383 -293.188394) (xy 206.792407 -293.144357) (xy 206.828659 -293.105286) (xy 206.87033 -293.072055)
			(xy 206.916488 -293.045406) (xy 206.966102 -293.025934) (xy 207.018064 -293.014074) (xy 207.071214 -293.010091)
			(xy 207.124364 -293.014074) (xy 207.176326 -293.025934) (xy 207.22594 -293.045406) (xy 207.272098 -293.072055)
			(xy 207.313769 -293.105286) (xy 207.350021 -293.144357) (xy 207.380045 -293.188394) (xy 207.403171 -293.236415)
			(xy 207.418881 -293.287345) (xy 207.426824 -293.340049) (xy 207.427322 -293.366698) (xy 207.426824 -293.393347)
			(xy 207.418881 -293.446051) (xy 207.403171 -293.496981) (xy 207.380045 -293.545002) (xy 207.350021 -293.589039)
			(xy 207.313769 -293.62811) (xy 207.272098 -293.661341) (xy 207.22594 -293.68799) (xy 207.176326 -293.707462)
			(xy 207.124364 -293.719322) (xy 207.071214 -293.723306) (xy 207.018064 -293.719322) (xy 206.966102 -293.707462)
			(xy 206.916488 -293.68799) (xy 206.87033 -293.661341) (xy 206.828659 -293.62811) (xy 206.792407 -293.589039)
			(xy 206.762383 -293.545002) (xy 206.739257 -293.496981) (xy 206.723547 -293.446051) (xy 206.715604 -293.393347)
			(xy 203.326756 -293.393347) (xy 203.318813 -293.446051) (xy 203.303103 -293.496981) (xy 203.279977 -293.545002)
			(xy 203.249953 -293.589039) (xy 203.213701 -293.62811) (xy 203.17203 -293.661341) (xy 203.125872 -293.68799)
			(xy 203.076258 -293.707462) (xy 203.024296 -293.719322) (xy 202.971146 -293.723306) (xy 202.917996 -293.719322)
			(xy 202.866034 -293.707462) (xy 202.81642 -293.68799) (xy 202.770262 -293.661341) (xy 202.728591 -293.62811)
			(xy 202.692339 -293.589039) (xy 202.662315 -293.545002) (xy 202.639189 -293.496981) (xy 202.623479 -293.446051)
			(xy 202.615536 -293.393347) (xy 192.339224 -293.393347) (xy 192.331281 -293.446051) (xy 192.315571 -293.496981)
			(xy 192.292445 -293.545002) (xy 192.262421 -293.589039) (xy 192.226169 -293.62811) (xy 192.184498 -293.661341)
			(xy 192.13834 -293.68799) (xy 192.088726 -293.707462) (xy 192.036764 -293.719322) (xy 191.983614 -293.723306)
			(xy 191.930464 -293.719322) (xy 191.878502 -293.707462) (xy 191.828888 -293.68799) (xy 191.78273 -293.661341)
			(xy 191.741059 -293.62811) (xy 191.704807 -293.589039) (xy 191.674783 -293.545002) (xy 191.651657 -293.496981)
			(xy 191.635947 -293.446051) (xy 191.628004 -293.393347) (xy 188.239156 -293.393347) (xy 188.231213 -293.446051)
			(xy 188.215503 -293.496981) (xy 188.192377 -293.545002) (xy 188.162353 -293.589039) (xy 188.126101 -293.62811)
			(xy 188.08443 -293.661341) (xy 188.038272 -293.68799) (xy 187.988658 -293.707462) (xy 187.936696 -293.719322)
			(xy 187.883546 -293.723306) (xy 187.830396 -293.719322) (xy 187.778434 -293.707462) (xy 187.72882 -293.68799)
			(xy 187.682662 -293.661341) (xy 187.640991 -293.62811) (xy 187.604739 -293.589039) (xy 187.574715 -293.545002)
			(xy 187.551589 -293.496981) (xy 187.535879 -293.446051) (xy 187.527936 -293.393347) (xy 177.251624 -293.393347)
			(xy 177.243681 -293.446051) (xy 177.227971 -293.496981) (xy 177.204845 -293.545002) (xy 177.174821 -293.589039)
			(xy 177.138569 -293.62811) (xy 177.096898 -293.661341) (xy 177.05074 -293.68799) (xy 177.001126 -293.707462)
			(xy 176.949164 -293.719322) (xy 176.896014 -293.723306) (xy 176.842864 -293.719322) (xy 176.790902 -293.707462)
			(xy 176.741288 -293.68799) (xy 176.69513 -293.661341) (xy 176.653459 -293.62811) (xy 176.617207 -293.589039)
			(xy 176.587183 -293.545002) (xy 176.564057 -293.496981) (xy 176.548347 -293.446051) (xy 176.540404 -293.393347)
			(xy 173.151556 -293.393347) (xy 173.143613 -293.446051) (xy 173.127903 -293.496981) (xy 173.104777 -293.545002)
			(xy 173.074753 -293.589039) (xy 173.038501 -293.62811) (xy 172.99683 -293.661341) (xy 172.950672 -293.68799)
			(xy 172.901058 -293.707462) (xy 172.849096 -293.719322) (xy 172.795946 -293.723306) (xy 172.742796 -293.719322)
			(xy 172.690834 -293.707462) (xy 172.64122 -293.68799) (xy 172.595062 -293.661341) (xy 172.553391 -293.62811)
			(xy 172.517139 -293.589039) (xy 172.487115 -293.545002) (xy 172.463989 -293.496981) (xy 172.448279 -293.446051)
			(xy 172.440336 -293.393347) (xy 158.88716 -293.393347) (xy 158.88716 -294.243231) (xy 172.440336 -294.243231)
			(xy 172.440336 -294.189933) (xy 172.448279 -294.137229) (xy 172.463989 -294.086299) (xy 172.487115 -294.038278)
			(xy 172.517139 -293.994241) (xy 172.553391 -293.95517) (xy 172.595062 -293.921939) (xy 172.64122 -293.89529)
			(xy 172.690834 -293.875818) (xy 172.742796 -293.863958) (xy 172.795946 -293.859975) (xy 172.849096 -293.863958)
			(xy 172.901058 -293.875818) (xy 172.950672 -293.89529) (xy 172.99683 -293.921939) (xy 173.038501 -293.95517)
			(xy 173.074753 -293.994241) (xy 173.104777 -294.038278) (xy 173.127903 -294.086299) (xy 173.143613 -294.137229)
			(xy 173.151556 -294.189933) (xy 173.152054 -294.216582) (xy 173.151556 -294.243231) (xy 187.527936 -294.243231)
			(xy 187.527936 -294.189933) (xy 187.535879 -294.137229) (xy 187.551589 -294.086299) (xy 187.574715 -294.038278)
			(xy 187.604739 -293.994241) (xy 187.640991 -293.95517) (xy 187.682662 -293.921939) (xy 187.72882 -293.89529)
			(xy 187.778434 -293.875818) (xy 187.830396 -293.863958) (xy 187.883546 -293.859975) (xy 187.936696 -293.863958)
			(xy 187.988658 -293.875818) (xy 188.038272 -293.89529) (xy 188.08443 -293.921939) (xy 188.126101 -293.95517)
			(xy 188.162353 -293.994241) (xy 188.192377 -294.038278) (xy 188.215503 -294.086299) (xy 188.231213 -294.137229)
			(xy 188.239156 -294.189933) (xy 188.239654 -294.216582) (xy 188.239156 -294.243231) (xy 202.615536 -294.243231)
			(xy 202.615536 -294.189933) (xy 202.623479 -294.137229) (xy 202.639189 -294.086299) (xy 202.662315 -294.038278)
			(xy 202.692339 -293.994241) (xy 202.728591 -293.95517) (xy 202.770262 -293.921939) (xy 202.81642 -293.89529)
			(xy 202.866034 -293.875818) (xy 202.917996 -293.863958) (xy 202.971146 -293.859975) (xy 203.024296 -293.863958)
			(xy 203.076258 -293.875818) (xy 203.125872 -293.89529) (xy 203.17203 -293.921939) (xy 203.213701 -293.95517)
			(xy 203.249953 -293.994241) (xy 203.279977 -294.038278) (xy 203.303103 -294.086299) (xy 203.318813 -294.137229)
			(xy 203.326756 -294.189933) (xy 203.327254 -294.216582) (xy 203.326756 -294.243231) (xy 203.318813 -294.295935)
			(xy 203.303103 -294.346865) (xy 203.279977 -294.394886) (xy 203.249953 -294.438923) (xy 203.213701 -294.477994)
			(xy 203.17203 -294.511225) (xy 203.125872 -294.537874) (xy 203.076258 -294.557346) (xy 203.024296 -294.569206)
			(xy 202.971146 -294.57319) (xy 202.917996 -294.569206) (xy 202.866034 -294.557346) (xy 202.81642 -294.537874)
			(xy 202.770262 -294.511225) (xy 202.728591 -294.477994) (xy 202.692339 -294.438923) (xy 202.662315 -294.394886)
			(xy 202.639189 -294.346865) (xy 202.623479 -294.295935) (xy 202.615536 -294.243231) (xy 188.239156 -294.243231)
			(xy 188.231213 -294.295935) (xy 188.215503 -294.346865) (xy 188.192377 -294.394886) (xy 188.162353 -294.438923)
			(xy 188.126101 -294.477994) (xy 188.08443 -294.511225) (xy 188.038272 -294.537874) (xy 187.988658 -294.557346)
			(xy 187.936696 -294.569206) (xy 187.883546 -294.57319) (xy 187.830396 -294.569206) (xy 187.778434 -294.557346)
			(xy 187.72882 -294.537874) (xy 187.682662 -294.511225) (xy 187.640991 -294.477994) (xy 187.604739 -294.438923)
			(xy 187.574715 -294.394886) (xy 187.551589 -294.346865) (xy 187.535879 -294.295935) (xy 187.527936 -294.243231)
			(xy 173.151556 -294.243231) (xy 173.143613 -294.295935) (xy 173.127903 -294.346865) (xy 173.104777 -294.394886)
			(xy 173.074753 -294.438923) (xy 173.038501 -294.477994) (xy 172.99683 -294.511225) (xy 172.950672 -294.537874)
			(xy 172.901058 -294.557346) (xy 172.849096 -294.569206) (xy 172.795946 -294.57319) (xy 172.742796 -294.569206)
			(xy 172.690834 -294.557346) (xy 172.64122 -294.537874) (xy 172.595062 -294.511225) (xy 172.553391 -294.477994)
			(xy 172.517139 -294.438923) (xy 172.487115 -294.394886) (xy 172.463989 -294.346865) (xy 172.448279 -294.295935)
			(xy 172.440336 -294.243231) (xy 158.88716 -294.243231) (xy 158.88716 -295.093369) (xy 176.540404 -295.093369)
			(xy 176.540404 -295.040071) (xy 176.548347 -294.987367) (xy 176.564057 -294.936437) (xy 176.587183 -294.888416)
			(xy 176.617207 -294.844379) (xy 176.653459 -294.805308) (xy 176.69513 -294.772077) (xy 176.741288 -294.745428)
			(xy 176.790902 -294.725956) (xy 176.842864 -294.714096) (xy 176.896014 -294.710113) (xy 176.949164 -294.714096)
			(xy 177.001126 -294.725956) (xy 177.05074 -294.745428) (xy 177.096898 -294.772077) (xy 177.138569 -294.805308)
			(xy 177.174821 -294.844379) (xy 177.204845 -294.888416) (xy 177.227971 -294.936437) (xy 177.243681 -294.987367)
			(xy 177.251624 -295.040071) (xy 177.252122 -295.06672) (xy 177.251624 -295.093369) (xy 191.628004 -295.093369)
			(xy 191.628004 -295.040071) (xy 191.635947 -294.987367) (xy 191.651657 -294.936437) (xy 191.674783 -294.888416)
			(xy 191.704807 -294.844379) (xy 191.741059 -294.805308) (xy 191.78273 -294.772077) (xy 191.828888 -294.745428)
			(xy 191.878502 -294.725956) (xy 191.930464 -294.714096) (xy 191.983614 -294.710113) (xy 192.036764 -294.714096)
			(xy 192.088726 -294.725956) (xy 192.13834 -294.745428) (xy 192.184498 -294.772077) (xy 192.226169 -294.805308)
			(xy 192.262421 -294.844379) (xy 192.292445 -294.888416) (xy 192.315571 -294.936437) (xy 192.331281 -294.987367)
			(xy 192.339224 -295.040071) (xy 192.339722 -295.06672) (xy 192.339224 -295.093369) (xy 206.715604 -295.093369)
			(xy 206.715604 -295.040071) (xy 206.723547 -294.987367) (xy 206.739257 -294.936437) (xy 206.762383 -294.888416)
			(xy 206.792407 -294.844379) (xy 206.828659 -294.805308) (xy 206.87033 -294.772077) (xy 206.916488 -294.745428)
			(xy 206.966102 -294.725956) (xy 207.018064 -294.714096) (xy 207.071214 -294.710113) (xy 207.124364 -294.714096)
			(xy 207.176326 -294.725956) (xy 207.22594 -294.745428) (xy 207.272098 -294.772077) (xy 207.313769 -294.805308)
			(xy 207.350021 -294.844379) (xy 207.380045 -294.888416) (xy 207.403171 -294.936437) (xy 207.418881 -294.987367)
			(xy 207.426824 -295.040071) (xy 207.427322 -295.06672) (xy 207.426824 -295.093369) (xy 207.418881 -295.146073)
			(xy 207.403171 -295.197003) (xy 207.380045 -295.245024) (xy 207.350021 -295.289061) (xy 207.313769 -295.328132)
			(xy 207.272098 -295.361363) (xy 207.22594 -295.388012) (xy 207.176326 -295.407484) (xy 207.124364 -295.419344)
			(xy 207.071214 -295.423328) (xy 207.018064 -295.419344) (xy 206.966102 -295.407484) (xy 206.916488 -295.388012)
			(xy 206.87033 -295.361363) (xy 206.828659 -295.328132) (xy 206.792407 -295.289061) (xy 206.762383 -295.245024)
			(xy 206.739257 -295.197003) (xy 206.723547 -295.146073) (xy 206.715604 -295.093369) (xy 192.339224 -295.093369)
			(xy 192.331281 -295.146073) (xy 192.315571 -295.197003) (xy 192.292445 -295.245024) (xy 192.262421 -295.289061)
			(xy 192.226169 -295.328132) (xy 192.184498 -295.361363) (xy 192.13834 -295.388012) (xy 192.088726 -295.407484)
			(xy 192.036764 -295.419344) (xy 191.983614 -295.423328) (xy 191.930464 -295.419344) (xy 191.878502 -295.407484)
			(xy 191.828888 -295.388012) (xy 191.78273 -295.361363) (xy 191.741059 -295.328132) (xy 191.704807 -295.289061)
			(xy 191.674783 -295.245024) (xy 191.651657 -295.197003) (xy 191.635947 -295.146073) (xy 191.628004 -295.093369)
			(xy 177.251624 -295.093369) (xy 177.243681 -295.146073) (xy 177.227971 -295.197003) (xy 177.204845 -295.245024)
			(xy 177.174821 -295.289061) (xy 177.138569 -295.328132) (xy 177.096898 -295.361363) (xy 177.05074 -295.388012)
			(xy 177.001126 -295.407484) (xy 176.949164 -295.419344) (xy 176.896014 -295.423328) (xy 176.842864 -295.419344)
			(xy 176.790902 -295.407484) (xy 176.741288 -295.388012) (xy 176.69513 -295.361363) (xy 176.653459 -295.328132)
			(xy 176.617207 -295.289061) (xy 176.587183 -295.245024) (xy 176.564057 -295.197003) (xy 176.548347 -295.146073)
			(xy 176.540404 -295.093369) (xy 158.88716 -295.093369) (xy 158.88716 -295.943253) (xy 172.440336 -295.943253)
			(xy 172.440336 -295.889955) (xy 172.448279 -295.837251) (xy 172.463989 -295.786321) (xy 172.487115 -295.7383)
			(xy 172.517139 -295.694263) (xy 172.553391 -295.655192) (xy 172.595062 -295.621961) (xy 172.64122 -295.595312)
			(xy 172.690834 -295.57584) (xy 172.742796 -295.56398) (xy 172.795946 -295.559997) (xy 172.849096 -295.56398)
			(xy 172.901058 -295.57584) (xy 172.950672 -295.595312) (xy 172.99683 -295.621961) (xy 173.038501 -295.655192)
			(xy 173.074753 -295.694263) (xy 173.104777 -295.7383) (xy 173.127903 -295.786321) (xy 173.143613 -295.837251)
			(xy 173.151556 -295.889955) (xy 173.152054 -295.916604) (xy 173.151556 -295.943253) (xy 187.527936 -295.943253)
			(xy 187.527936 -295.889955) (xy 187.535879 -295.837251) (xy 187.551589 -295.786321) (xy 187.574715 -295.7383)
			(xy 187.604739 -295.694263) (xy 187.640991 -295.655192) (xy 187.682662 -295.621961) (xy 187.72882 -295.595312)
			(xy 187.778434 -295.57584) (xy 187.830396 -295.56398) (xy 187.883546 -295.559997) (xy 187.936696 -295.56398)
			(xy 187.988658 -295.57584) (xy 188.038272 -295.595312) (xy 188.08443 -295.621961) (xy 188.126101 -295.655192)
			(xy 188.162353 -295.694263) (xy 188.192377 -295.7383) (xy 188.215503 -295.786321) (xy 188.231213 -295.837251)
			(xy 188.239156 -295.889955) (xy 188.239654 -295.916604) (xy 188.239156 -295.943253) (xy 202.615536 -295.943253)
			(xy 202.615536 -295.889955) (xy 202.623479 -295.837251) (xy 202.639189 -295.786321) (xy 202.662315 -295.7383)
			(xy 202.692339 -295.694263) (xy 202.728591 -295.655192) (xy 202.770262 -295.621961) (xy 202.81642 -295.595312)
			(xy 202.866034 -295.57584) (xy 202.917996 -295.56398) (xy 202.971146 -295.559997) (xy 203.024296 -295.56398)
			(xy 203.076258 -295.57584) (xy 203.125872 -295.595312) (xy 203.17203 -295.621961) (xy 203.213701 -295.655192)
			(xy 203.249953 -295.694263) (xy 203.279977 -295.7383) (xy 203.303103 -295.786321) (xy 203.318813 -295.837251)
			(xy 203.326756 -295.889955) (xy 203.327254 -295.916604) (xy 203.326756 -295.943253) (xy 203.318813 -295.995957)
			(xy 203.303103 -296.046887) (xy 203.279977 -296.094908) (xy 203.249953 -296.138945) (xy 203.213701 -296.178016)
			(xy 203.17203 -296.211247) (xy 203.125872 -296.237896) (xy 203.076258 -296.257368) (xy 203.024296 -296.269228)
			(xy 202.971146 -296.273212) (xy 202.917996 -296.269228) (xy 202.866034 -296.257368) (xy 202.81642 -296.237896)
			(xy 202.770262 -296.211247) (xy 202.728591 -296.178016) (xy 202.692339 -296.138945) (xy 202.662315 -296.094908)
			(xy 202.639189 -296.046887) (xy 202.623479 -295.995957) (xy 202.615536 -295.943253) (xy 188.239156 -295.943253)
			(xy 188.231213 -295.995957) (xy 188.215503 -296.046887) (xy 188.192377 -296.094908) (xy 188.162353 -296.138945)
			(xy 188.126101 -296.178016) (xy 188.08443 -296.211247) (xy 188.038272 -296.237896) (xy 187.988658 -296.257368)
			(xy 187.936696 -296.269228) (xy 187.883546 -296.273212) (xy 187.830396 -296.269228) (xy 187.778434 -296.257368)
			(xy 187.72882 -296.237896) (xy 187.682662 -296.211247) (xy 187.640991 -296.178016) (xy 187.604739 -296.138945)
			(xy 187.574715 -296.094908) (xy 187.551589 -296.046887) (xy 187.535879 -295.995957) (xy 187.527936 -295.943253)
			(xy 173.151556 -295.943253) (xy 173.143613 -295.995957) (xy 173.127903 -296.046887) (xy 173.104777 -296.094908)
			(xy 173.074753 -296.138945) (xy 173.038501 -296.178016) (xy 172.99683 -296.211247) (xy 172.950672 -296.237896)
			(xy 172.901058 -296.257368) (xy 172.849096 -296.269228) (xy 172.795946 -296.273212) (xy 172.742796 -296.269228)
			(xy 172.690834 -296.257368) (xy 172.64122 -296.237896) (xy 172.595062 -296.211247) (xy 172.553391 -296.178016)
			(xy 172.517139 -296.138945) (xy 172.487115 -296.094908) (xy 172.463989 -296.046887) (xy 172.448279 -295.995957)
			(xy 172.440336 -295.943253) (xy 158.88716 -295.943253) (xy 158.88716 -296.793391) (xy 176.540404 -296.793391)
			(xy 176.540404 -296.740093) (xy 176.548347 -296.687389) (xy 176.564057 -296.636459) (xy 176.587183 -296.588438)
			(xy 176.617207 -296.544401) (xy 176.653459 -296.50533) (xy 176.69513 -296.472099) (xy 176.741288 -296.44545)
			(xy 176.790902 -296.425978) (xy 176.842864 -296.414118) (xy 176.896014 -296.410135) (xy 176.949164 -296.414118)
			(xy 177.001126 -296.425978) (xy 177.05074 -296.44545) (xy 177.096898 -296.472099) (xy 177.138569 -296.50533)
			(xy 177.174821 -296.544401) (xy 177.204845 -296.588438) (xy 177.227971 -296.636459) (xy 177.243681 -296.687389)
			(xy 177.251624 -296.740093) (xy 177.252122 -296.766742) (xy 177.251624 -296.793391) (xy 191.628004 -296.793391)
			(xy 191.628004 -296.740093) (xy 191.635947 -296.687389) (xy 191.651657 -296.636459) (xy 191.674783 -296.588438)
			(xy 191.704807 -296.544401) (xy 191.741059 -296.50533) (xy 191.78273 -296.472099) (xy 191.828888 -296.44545)
			(xy 191.878502 -296.425978) (xy 191.930464 -296.414118) (xy 191.983614 -296.410135) (xy 192.036764 -296.414118)
			(xy 192.088726 -296.425978) (xy 192.13834 -296.44545) (xy 192.184498 -296.472099) (xy 192.226169 -296.50533)
			(xy 192.262421 -296.544401) (xy 192.292445 -296.588438) (xy 192.315571 -296.636459) (xy 192.331281 -296.687389)
			(xy 192.339224 -296.740093) (xy 192.339722 -296.766742) (xy 192.339224 -296.793391) (xy 206.715604 -296.793391)
			(xy 206.715604 -296.740093) (xy 206.723547 -296.687389) (xy 206.739257 -296.636459) (xy 206.762383 -296.588438)
			(xy 206.792407 -296.544401) (xy 206.828659 -296.50533) (xy 206.87033 -296.472099) (xy 206.916488 -296.44545)
			(xy 206.966102 -296.425978) (xy 207.018064 -296.414118) (xy 207.071214 -296.410135) (xy 207.124364 -296.414118)
			(xy 207.176326 -296.425978) (xy 207.22594 -296.44545) (xy 207.272098 -296.472099) (xy 207.313769 -296.50533)
			(xy 207.350021 -296.544401) (xy 207.380045 -296.588438) (xy 207.403171 -296.636459) (xy 207.418881 -296.687389)
			(xy 207.426824 -296.740093) (xy 207.427322 -296.766742) (xy 207.426824 -296.793391) (xy 207.418881 -296.846095)
			(xy 207.403171 -296.897025) (xy 207.380045 -296.945046) (xy 207.350021 -296.989083) (xy 207.313769 -297.028154)
			(xy 207.272098 -297.061385) (xy 207.22594 -297.088034) (xy 207.176326 -297.107506) (xy 207.124364 -297.119366)
			(xy 207.071214 -297.12335) (xy 207.018064 -297.119366) (xy 206.966102 -297.107506) (xy 206.916488 -297.088034)
			(xy 206.87033 -297.061385) (xy 206.828659 -297.028154) (xy 206.792407 -296.989083) (xy 206.762383 -296.945046)
			(xy 206.739257 -296.897025) (xy 206.723547 -296.846095) (xy 206.715604 -296.793391) (xy 192.339224 -296.793391)
			(xy 192.331281 -296.846095) (xy 192.315571 -296.897025) (xy 192.292445 -296.945046) (xy 192.262421 -296.989083)
			(xy 192.226169 -297.028154) (xy 192.184498 -297.061385) (xy 192.13834 -297.088034) (xy 192.088726 -297.107506)
			(xy 192.036764 -297.119366) (xy 191.983614 -297.12335) (xy 191.930464 -297.119366) (xy 191.878502 -297.107506)
			(xy 191.828888 -297.088034) (xy 191.78273 -297.061385) (xy 191.741059 -297.028154) (xy 191.704807 -296.989083)
			(xy 191.674783 -296.945046) (xy 191.651657 -296.897025) (xy 191.635947 -296.846095) (xy 191.628004 -296.793391)
			(xy 177.251624 -296.793391) (xy 177.243681 -296.846095) (xy 177.227971 -296.897025) (xy 177.204845 -296.945046)
			(xy 177.174821 -296.989083) (xy 177.138569 -297.028154) (xy 177.096898 -297.061385) (xy 177.05074 -297.088034)
			(xy 177.001126 -297.107506) (xy 176.949164 -297.119366) (xy 176.896014 -297.12335) (xy 176.842864 -297.119366)
			(xy 176.790902 -297.107506) (xy 176.741288 -297.088034) (xy 176.69513 -297.061385) (xy 176.653459 -297.028154)
			(xy 176.617207 -296.989083) (xy 176.587183 -296.945046) (xy 176.564057 -296.897025) (xy 176.548347 -296.846095)
			(xy 176.540404 -296.793391) (xy 158.88716 -296.793391) (xy 158.88716 -297.643275) (xy 172.440336 -297.643275)
			(xy 172.440336 -297.589977) (xy 172.448279 -297.537273) (xy 172.463989 -297.486343) (xy 172.487115 -297.438322)
			(xy 172.517139 -297.394285) (xy 172.553391 -297.355214) (xy 172.595062 -297.321983) (xy 172.64122 -297.295334)
			(xy 172.690834 -297.275862) (xy 172.742796 -297.264002) (xy 172.795946 -297.260019) (xy 172.849096 -297.264002)
			(xy 172.901058 -297.275862) (xy 172.950672 -297.295334) (xy 172.99683 -297.321983) (xy 173.038501 -297.355214)
			(xy 173.074753 -297.394285) (xy 173.104777 -297.438322) (xy 173.127903 -297.486343) (xy 173.143613 -297.537273)
			(xy 173.151556 -297.589977) (xy 173.152054 -297.616626) (xy 173.151556 -297.643275) (xy 187.527936 -297.643275)
			(xy 187.527936 -297.589977) (xy 187.535879 -297.537273) (xy 187.551589 -297.486343) (xy 187.574715 -297.438322)
			(xy 187.604739 -297.394285) (xy 187.640991 -297.355214) (xy 187.682662 -297.321983) (xy 187.72882 -297.295334)
			(xy 187.778434 -297.275862) (xy 187.830396 -297.264002) (xy 187.883546 -297.260019) (xy 187.936696 -297.264002)
			(xy 187.988658 -297.275862) (xy 188.038272 -297.295334) (xy 188.08443 -297.321983) (xy 188.126101 -297.355214)
			(xy 188.162353 -297.394285) (xy 188.192377 -297.438322) (xy 188.215503 -297.486343) (xy 188.231213 -297.537273)
			(xy 188.239156 -297.589977) (xy 188.239654 -297.616626) (xy 188.239156 -297.643275) (xy 202.615536 -297.643275)
			(xy 202.615536 -297.589977) (xy 202.623479 -297.537273) (xy 202.639189 -297.486343) (xy 202.662315 -297.438322)
			(xy 202.692339 -297.394285) (xy 202.728591 -297.355214) (xy 202.770262 -297.321983) (xy 202.81642 -297.295334)
			(xy 202.866034 -297.275862) (xy 202.917996 -297.264002) (xy 202.971146 -297.260019) (xy 203.024296 -297.264002)
			(xy 203.076258 -297.275862) (xy 203.125872 -297.295334) (xy 203.17203 -297.321983) (xy 203.213701 -297.355214)
			(xy 203.249953 -297.394285) (xy 203.279977 -297.438322) (xy 203.303103 -297.486343) (xy 203.318813 -297.537273)
			(xy 203.326756 -297.589977) (xy 203.327254 -297.616626) (xy 203.326756 -297.643275) (xy 203.318813 -297.695979)
			(xy 203.303103 -297.746909) (xy 203.279977 -297.79493) (xy 203.249953 -297.838967) (xy 203.213701 -297.878038)
			(xy 203.17203 -297.911269) (xy 203.125872 -297.937918) (xy 203.076258 -297.95739) (xy 203.024296 -297.96925)
			(xy 202.971146 -297.973234) (xy 202.917996 -297.96925) (xy 202.866034 -297.95739) (xy 202.81642 -297.937918)
			(xy 202.770262 -297.911269) (xy 202.728591 -297.878038) (xy 202.692339 -297.838967) (xy 202.662315 -297.79493)
			(xy 202.639189 -297.746909) (xy 202.623479 -297.695979) (xy 202.615536 -297.643275) (xy 188.239156 -297.643275)
			(xy 188.231213 -297.695979) (xy 188.215503 -297.746909) (xy 188.192377 -297.79493) (xy 188.162353 -297.838967)
			(xy 188.126101 -297.878038) (xy 188.08443 -297.911269) (xy 188.038272 -297.937918) (xy 187.988658 -297.95739)
			(xy 187.936696 -297.96925) (xy 187.883546 -297.973234) (xy 187.830396 -297.96925) (xy 187.778434 -297.95739)
			(xy 187.72882 -297.937918) (xy 187.682662 -297.911269) (xy 187.640991 -297.878038) (xy 187.604739 -297.838967)
			(xy 187.574715 -297.79493) (xy 187.551589 -297.746909) (xy 187.535879 -297.695979) (xy 187.527936 -297.643275)
			(xy 173.151556 -297.643275) (xy 173.143613 -297.695979) (xy 173.127903 -297.746909) (xy 173.104777 -297.79493)
			(xy 173.074753 -297.838967) (xy 173.038501 -297.878038) (xy 172.99683 -297.911269) (xy 172.950672 -297.937918)
			(xy 172.901058 -297.95739) (xy 172.849096 -297.96925) (xy 172.795946 -297.973234) (xy 172.742796 -297.96925)
			(xy 172.690834 -297.95739) (xy 172.64122 -297.937918) (xy 172.595062 -297.911269) (xy 172.553391 -297.878038)
			(xy 172.517139 -297.838967) (xy 172.487115 -297.79493) (xy 172.463989 -297.746909) (xy 172.448279 -297.695979)
			(xy 172.440336 -297.643275) (xy 158.88716 -297.643275) (xy 158.88716 -298.493413) (xy 161.427404 -298.493413)
			(xy 161.427404 -298.440115) (xy 161.435347 -298.387411) (xy 161.451057 -298.336481) (xy 161.474183 -298.28846)
			(xy 161.504207 -298.244423) (xy 161.540459 -298.205352) (xy 161.58213 -298.172121) (xy 161.628288 -298.145472)
			(xy 161.677902 -298.126) (xy 161.729864 -298.11414) (xy 161.783014 -298.110157) (xy 161.836164 -298.11414)
			(xy 161.888126 -298.126) (xy 161.93774 -298.145472) (xy 161.983898 -298.172121) (xy 162.025569 -298.205352)
			(xy 162.061821 -298.244423) (xy 162.091845 -298.28846) (xy 162.114971 -298.336481) (xy 162.130681 -298.387411)
			(xy 162.138624 -298.440115) (xy 162.139122 -298.466764) (xy 162.138624 -298.493413) (xy 176.540404 -298.493413)
			(xy 176.540404 -298.440115) (xy 176.548347 -298.387411) (xy 176.564057 -298.336481) (xy 176.587183 -298.28846)
			(xy 176.617207 -298.244423) (xy 176.653459 -298.205352) (xy 176.69513 -298.172121) (xy 176.741288 -298.145472)
			(xy 176.790902 -298.126) (xy 176.842864 -298.11414) (xy 176.896014 -298.110157) (xy 176.949164 -298.11414)
			(xy 177.001126 -298.126) (xy 177.05074 -298.145472) (xy 177.096898 -298.172121) (xy 177.138569 -298.205352)
			(xy 177.174821 -298.244423) (xy 177.204845 -298.28846) (xy 177.227971 -298.336481) (xy 177.243681 -298.387411)
			(xy 177.251624 -298.440115) (xy 177.252122 -298.466764) (xy 177.251624 -298.493413) (xy 191.628004 -298.493413)
			(xy 191.628004 -298.440115) (xy 191.635947 -298.387411) (xy 191.651657 -298.336481) (xy 191.674783 -298.28846)
			(xy 191.704807 -298.244423) (xy 191.741059 -298.205352) (xy 191.78273 -298.172121) (xy 191.828888 -298.145472)
			(xy 191.878502 -298.126) (xy 191.930464 -298.11414) (xy 191.983614 -298.110157) (xy 192.036764 -298.11414)
			(xy 192.088726 -298.126) (xy 192.13834 -298.145472) (xy 192.184498 -298.172121) (xy 192.226169 -298.205352)
			(xy 192.262421 -298.244423) (xy 192.292445 -298.28846) (xy 192.315571 -298.336481) (xy 192.331281 -298.387411)
			(xy 192.339224 -298.440115) (xy 192.339722 -298.466764) (xy 192.339224 -298.493413) (xy 206.715604 -298.493413)
			(xy 206.715604 -298.440115) (xy 206.723547 -298.387411) (xy 206.739257 -298.336481) (xy 206.762383 -298.28846)
			(xy 206.792407 -298.244423) (xy 206.828659 -298.205352) (xy 206.87033 -298.172121) (xy 206.916488 -298.145472)
			(xy 206.966102 -298.126) (xy 207.018064 -298.11414) (xy 207.071214 -298.110157) (xy 207.124364 -298.11414)
			(xy 207.176326 -298.126) (xy 207.22594 -298.145472) (xy 207.272098 -298.172121) (xy 207.313769 -298.205352)
			(xy 207.350021 -298.244423) (xy 207.380045 -298.28846) (xy 207.403171 -298.336481) (xy 207.418881 -298.387411)
			(xy 207.426824 -298.440115) (xy 207.427322 -298.466764) (xy 207.426824 -298.493413) (xy 207.418881 -298.546117)
			(xy 207.403171 -298.597047) (xy 207.380045 -298.645068) (xy 207.350021 -298.689105) (xy 207.313769 -298.728176)
			(xy 207.272098 -298.761407) (xy 207.22594 -298.788056) (xy 207.176326 -298.807528) (xy 207.124364 -298.819388)
			(xy 207.071214 -298.823372) (xy 207.018064 -298.819388) (xy 206.966102 -298.807528) (xy 206.916488 -298.788056)
			(xy 206.87033 -298.761407) (xy 206.828659 -298.728176) (xy 206.792407 -298.689105) (xy 206.762383 -298.645068)
			(xy 206.739257 -298.597047) (xy 206.723547 -298.546117) (xy 206.715604 -298.493413) (xy 192.339224 -298.493413)
			(xy 192.331281 -298.546117) (xy 192.315571 -298.597047) (xy 192.292445 -298.645068) (xy 192.262421 -298.689105)
			(xy 192.226169 -298.728176) (xy 192.184498 -298.761407) (xy 192.13834 -298.788056) (xy 192.088726 -298.807528)
			(xy 192.036764 -298.819388) (xy 191.983614 -298.823372) (xy 191.930464 -298.819388) (xy 191.878502 -298.807528)
			(xy 191.828888 -298.788056) (xy 191.78273 -298.761407) (xy 191.741059 -298.728176) (xy 191.704807 -298.689105)
			(xy 191.674783 -298.645068) (xy 191.651657 -298.597047) (xy 191.635947 -298.546117) (xy 191.628004 -298.493413)
			(xy 177.251624 -298.493413) (xy 177.243681 -298.546117) (xy 177.227971 -298.597047) (xy 177.204845 -298.645068)
			(xy 177.174821 -298.689105) (xy 177.138569 -298.728176) (xy 177.096898 -298.761407) (xy 177.05074 -298.788056)
			(xy 177.001126 -298.807528) (xy 176.949164 -298.819388) (xy 176.896014 -298.823372) (xy 176.842864 -298.819388)
			(xy 176.790902 -298.807528) (xy 176.741288 -298.788056) (xy 176.69513 -298.761407) (xy 176.653459 -298.728176)
			(xy 176.617207 -298.689105) (xy 176.587183 -298.645068) (xy 176.564057 -298.597047) (xy 176.548347 -298.546117)
			(xy 176.540404 -298.493413) (xy 162.138624 -298.493413) (xy 162.130681 -298.546117) (xy 162.114971 -298.597047)
			(xy 162.091845 -298.645068) (xy 162.061821 -298.689105) (xy 162.025569 -298.728176) (xy 161.983898 -298.761407)
			(xy 161.93774 -298.788056) (xy 161.888126 -298.807528) (xy 161.836164 -298.819388) (xy 161.783014 -298.823372)
			(xy 161.729864 -298.819388) (xy 161.677902 -298.807528) (xy 161.628288 -298.788056) (xy 161.58213 -298.761407)
			(xy 161.540459 -298.728176) (xy 161.504207 -298.689105) (xy 161.474183 -298.645068) (xy 161.451057 -298.597047)
			(xy 161.435347 -298.546117) (xy 161.427404 -298.493413) (xy 158.88716 -298.493413) (xy 158.88716 -299.343297)
			(xy 172.440336 -299.343297) (xy 172.440336 -299.289999) (xy 172.448279 -299.237295) (xy 172.463989 -299.186365)
			(xy 172.487115 -299.138344) (xy 172.517139 -299.094307) (xy 172.553391 -299.055236) (xy 172.595062 -299.022005)
			(xy 172.64122 -298.995356) (xy 172.690834 -298.975884) (xy 172.742796 -298.964024) (xy 172.795946 -298.960041)
			(xy 172.849096 -298.964024) (xy 172.901058 -298.975884) (xy 172.950672 -298.995356) (xy 172.99683 -299.022005)
			(xy 173.038501 -299.055236) (xy 173.074753 -299.094307) (xy 173.104777 -299.138344) (xy 173.127903 -299.186365)
			(xy 173.143613 -299.237295) (xy 173.151556 -299.289999) (xy 173.152054 -299.316648) (xy 173.151556 -299.343297)
			(xy 187.527936 -299.343297) (xy 187.527936 -299.289999) (xy 187.535879 -299.237295) (xy 187.551589 -299.186365)
			(xy 187.574715 -299.138344) (xy 187.604739 -299.094307) (xy 187.640991 -299.055236) (xy 187.682662 -299.022005)
			(xy 187.72882 -298.995356) (xy 187.778434 -298.975884) (xy 187.830396 -298.964024) (xy 187.883546 -298.960041)
			(xy 187.936696 -298.964024) (xy 187.988658 -298.975884) (xy 188.038272 -298.995356) (xy 188.08443 -299.022005)
			(xy 188.126101 -299.055236) (xy 188.162353 -299.094307) (xy 188.192377 -299.138344) (xy 188.215503 -299.186365)
			(xy 188.231213 -299.237295) (xy 188.239156 -299.289999) (xy 188.239654 -299.316648) (xy 188.239156 -299.343297)
			(xy 202.615536 -299.343297) (xy 202.615536 -299.289999) (xy 202.623479 -299.237295) (xy 202.639189 -299.186365)
			(xy 202.662315 -299.138344) (xy 202.692339 -299.094307) (xy 202.728591 -299.055236) (xy 202.770262 -299.022005)
			(xy 202.81642 -298.995356) (xy 202.866034 -298.975884) (xy 202.917996 -298.964024) (xy 202.971146 -298.960041)
			(xy 203.024296 -298.964024) (xy 203.076258 -298.975884) (xy 203.125872 -298.995356) (xy 203.17203 -299.022005)
			(xy 203.213701 -299.055236) (xy 203.249953 -299.094307) (xy 203.279977 -299.138344) (xy 203.303103 -299.186365)
			(xy 203.318813 -299.237295) (xy 203.326756 -299.289999) (xy 203.327254 -299.316648) (xy 203.326756 -299.343297)
			(xy 203.318813 -299.396001) (xy 203.303103 -299.446931) (xy 203.279977 -299.494952) (xy 203.249953 -299.538989)
			(xy 203.213701 -299.57806) (xy 203.17203 -299.611291) (xy 203.125872 -299.63794) (xy 203.076258 -299.657412)
			(xy 203.024296 -299.669272) (xy 202.971146 -299.673256) (xy 202.917996 -299.669272) (xy 202.866034 -299.657412)
			(xy 202.81642 -299.63794) (xy 202.770262 -299.611291) (xy 202.728591 -299.57806) (xy 202.692339 -299.538989)
			(xy 202.662315 -299.494952) (xy 202.639189 -299.446931) (xy 202.623479 -299.396001) (xy 202.615536 -299.343297)
			(xy 188.239156 -299.343297) (xy 188.231213 -299.396001) (xy 188.215503 -299.446931) (xy 188.192377 -299.494952)
			(xy 188.162353 -299.538989) (xy 188.126101 -299.57806) (xy 188.08443 -299.611291) (xy 188.038272 -299.63794)
			(xy 187.988658 -299.657412) (xy 187.936696 -299.669272) (xy 187.883546 -299.673256) (xy 187.830396 -299.669272)
			(xy 187.778434 -299.657412) (xy 187.72882 -299.63794) (xy 187.682662 -299.611291) (xy 187.640991 -299.57806)
			(xy 187.604739 -299.538989) (xy 187.574715 -299.494952) (xy 187.551589 -299.446931) (xy 187.535879 -299.396001)
			(xy 187.527936 -299.343297) (xy 173.151556 -299.343297) (xy 173.143613 -299.396001) (xy 173.127903 -299.446931)
			(xy 173.104777 -299.494952) (xy 173.074753 -299.538989) (xy 173.038501 -299.57806) (xy 172.99683 -299.611291)
			(xy 172.950672 -299.63794) (xy 172.901058 -299.657412) (xy 172.849096 -299.669272) (xy 172.795946 -299.673256)
			(xy 172.742796 -299.669272) (xy 172.690834 -299.657412) (xy 172.64122 -299.63794) (xy 172.595062 -299.611291)
			(xy 172.553391 -299.57806) (xy 172.517139 -299.538989) (xy 172.487115 -299.494952) (xy 172.463989 -299.446931)
			(xy 172.448279 -299.396001) (xy 172.440336 -299.343297) (xy 158.88716 -299.343297) (xy 158.88716 -300.193435)
			(xy 161.427404 -300.193435) (xy 161.427404 -300.140137) (xy 161.435347 -300.087433) (xy 161.451057 -300.036503)
			(xy 161.474183 -299.988482) (xy 161.504207 -299.944445) (xy 161.540459 -299.905374) (xy 161.58213 -299.872143)
			(xy 161.628288 -299.845494) (xy 161.677902 -299.826022) (xy 161.729864 -299.814162) (xy 161.783014 -299.810179)
			(xy 161.836164 -299.814162) (xy 161.888126 -299.826022) (xy 161.93774 -299.845494) (xy 161.983898 -299.872143)
			(xy 162.025569 -299.905374) (xy 162.061821 -299.944445) (xy 162.091845 -299.988482) (xy 162.114971 -300.036503)
			(xy 162.130681 -300.087433) (xy 162.138624 -300.140137) (xy 162.139122 -300.166786) (xy 162.138629 -300.193181)
			(xy 176.540404 -300.193181) (xy 176.540404 -300.139883) (xy 176.548347 -300.087179) (xy 176.564057 -300.036249)
			(xy 176.587183 -299.988228) (xy 176.617207 -299.944191) (xy 176.653459 -299.90512) (xy 176.69513 -299.871889)
			(xy 176.741288 -299.84524) (xy 176.790902 -299.825768) (xy 176.842864 -299.813908) (xy 176.896014 -299.809925)
			(xy 176.949164 -299.813908) (xy 177.001126 -299.825768) (xy 177.05074 -299.84524) (xy 177.096898 -299.871889)
			(xy 177.138569 -299.90512) (xy 177.174821 -299.944191) (xy 177.204845 -299.988228) (xy 177.227971 -300.036249)
			(xy 177.243681 -300.087179) (xy 177.251624 -300.139883) (xy 177.252122 -300.166532) (xy 177.251624 -300.193181)
			(xy 177.251586 -300.193435) (xy 191.586094 -300.193435) (xy 191.586094 -300.140137) (xy 191.594037 -300.087433)
			(xy 191.609747 -300.036503) (xy 191.632873 -299.988482) (xy 191.662897 -299.944445) (xy 191.699149 -299.905374)
			(xy 191.74082 -299.872143) (xy 191.786978 -299.845494) (xy 191.836592 -299.826022) (xy 191.888554 -299.814162)
			(xy 191.941704 -299.810179) (xy 191.994854 -299.814162) (xy 192.046816 -299.826022) (xy 192.09643 -299.845494)
			(xy 192.142588 -299.872143) (xy 192.184259 -299.905374) (xy 192.220511 -299.944445) (xy 192.250535 -299.988482)
			(xy 192.273661 -300.036503) (xy 192.289371 -300.087433) (xy 192.297314 -300.140137) (xy 192.297812 -300.166786)
			(xy 192.297319 -300.193181) (xy 206.715604 -300.193181) (xy 206.715604 -300.139883) (xy 206.723547 -300.087179)
			(xy 206.739257 -300.036249) (xy 206.762383 -299.988228) (xy 206.792407 -299.944191) (xy 206.828659 -299.90512)
			(xy 206.87033 -299.871889) (xy 206.916488 -299.84524) (xy 206.966102 -299.825768) (xy 207.018064 -299.813908)
			(xy 207.071214 -299.809925) (xy 207.124364 -299.813908) (xy 207.176326 -299.825768) (xy 207.22594 -299.84524)
			(xy 207.272098 -299.871889) (xy 207.313769 -299.90512) (xy 207.350021 -299.944191) (xy 207.380045 -299.988228)
			(xy 207.403171 -300.036249) (xy 207.418881 -300.087179) (xy 207.426824 -300.139883) (xy 207.427322 -300.166532)
			(xy 207.426824 -300.193181) (xy 207.418881 -300.245885) (xy 207.403171 -300.296815) (xy 207.380045 -300.344836)
			(xy 207.350021 -300.388873) (xy 207.313769 -300.427944) (xy 207.272098 -300.461175) (xy 207.22594 -300.487824)
			(xy 207.176326 -300.507296) (xy 207.124364 -300.519156) (xy 207.071214 -300.52314) (xy 207.018064 -300.519156)
			(xy 206.966102 -300.507296) (xy 206.916488 -300.487824) (xy 206.87033 -300.461175) (xy 206.828659 -300.427944)
			(xy 206.792407 -300.388873) (xy 206.762383 -300.344836) (xy 206.739257 -300.296815) (xy 206.723547 -300.245885)
			(xy 206.715604 -300.193181) (xy 192.297319 -300.193181) (xy 192.297314 -300.193435) (xy 192.289371 -300.246139)
			(xy 192.273661 -300.297069) (xy 192.250535 -300.34509) (xy 192.220511 -300.389127) (xy 192.184259 -300.428198)
			(xy 192.142588 -300.461429) (xy 192.09643 -300.488078) (xy 192.046816 -300.50755) (xy 191.994854 -300.51941)
			(xy 191.941704 -300.523394) (xy 191.888554 -300.51941) (xy 191.836592 -300.50755) (xy 191.786978 -300.488078)
			(xy 191.74082 -300.461429) (xy 191.699149 -300.428198) (xy 191.662897 -300.389127) (xy 191.632873 -300.34509)
			(xy 191.609747 -300.297069) (xy 191.594037 -300.246139) (xy 191.586094 -300.193435) (xy 177.251586 -300.193435)
			(xy 177.243681 -300.245885) (xy 177.227971 -300.296815) (xy 177.204845 -300.344836) (xy 177.174821 -300.388873)
			(xy 177.138569 -300.427944) (xy 177.096898 -300.461175) (xy 177.05074 -300.487824) (xy 177.001126 -300.507296)
			(xy 176.949164 -300.519156) (xy 176.896014 -300.52314) (xy 176.842864 -300.519156) (xy 176.790902 -300.507296)
			(xy 176.741288 -300.487824) (xy 176.69513 -300.461175) (xy 176.653459 -300.427944) (xy 176.617207 -300.388873)
			(xy 176.587183 -300.344836) (xy 176.564057 -300.296815) (xy 176.548347 -300.245885) (xy 176.540404 -300.193181)
			(xy 162.138629 -300.193181) (xy 162.138624 -300.193435) (xy 162.130681 -300.246139) (xy 162.114971 -300.297069)
			(xy 162.091845 -300.34509) (xy 162.061821 -300.389127) (xy 162.025569 -300.428198) (xy 161.983898 -300.461429)
			(xy 161.93774 -300.488078) (xy 161.888126 -300.50755) (xy 161.836164 -300.51941) (xy 161.783014 -300.523394)
			(xy 161.729864 -300.51941) (xy 161.677902 -300.50755) (xy 161.628288 -300.488078) (xy 161.58213 -300.461429)
			(xy 161.540459 -300.428198) (xy 161.504207 -300.389127) (xy 161.474183 -300.34509) (xy 161.451057 -300.297069)
			(xy 161.435347 -300.246139) (xy 161.427404 -300.193435) (xy 158.88716 -300.193435) (xy 158.88716 -301.043319)
			(xy 172.440336 -301.043319) (xy 172.440336 -300.990021) (xy 172.448279 -300.937317) (xy 172.463989 -300.886387)
			(xy 172.487115 -300.838366) (xy 172.517139 -300.794329) (xy 172.553391 -300.755258) (xy 172.595062 -300.722027)
			(xy 172.64122 -300.695378) (xy 172.690834 -300.675906) (xy 172.742796 -300.664046) (xy 172.795946 -300.660063)
			(xy 172.849096 -300.664046) (xy 172.901058 -300.675906) (xy 172.950672 -300.695378) (xy 172.99683 -300.722027)
			(xy 173.038501 -300.755258) (xy 173.074753 -300.794329) (xy 173.104777 -300.838366) (xy 173.127903 -300.886387)
			(xy 173.143613 -300.937317) (xy 173.151556 -300.990021) (xy 173.152054 -301.01667) (xy 173.151556 -301.043319)
			(xy 187.527936 -301.043319) (xy 187.527936 -300.990021) (xy 187.535879 -300.937317) (xy 187.551589 -300.886387)
			(xy 187.574715 -300.838366) (xy 187.604739 -300.794329) (xy 187.640991 -300.755258) (xy 187.682662 -300.722027)
			(xy 187.72882 -300.695378) (xy 187.778434 -300.675906) (xy 187.830396 -300.664046) (xy 187.883546 -300.660063)
			(xy 187.936696 -300.664046) (xy 187.988658 -300.675906) (xy 188.038272 -300.695378) (xy 188.08443 -300.722027)
			(xy 188.126101 -300.755258) (xy 188.162353 -300.794329) (xy 188.192377 -300.838366) (xy 188.215503 -300.886387)
			(xy 188.231213 -300.937317) (xy 188.239156 -300.990021) (xy 188.239654 -301.01667) (xy 188.239156 -301.043319)
			(xy 202.615536 -301.043319) (xy 202.615536 -300.990021) (xy 202.623479 -300.937317) (xy 202.639189 -300.886387)
			(xy 202.662315 -300.838366) (xy 202.692339 -300.794329) (xy 202.728591 -300.755258) (xy 202.770262 -300.722027)
			(xy 202.81642 -300.695378) (xy 202.866034 -300.675906) (xy 202.917996 -300.664046) (xy 202.971146 -300.660063)
			(xy 203.024296 -300.664046) (xy 203.076258 -300.675906) (xy 203.125872 -300.695378) (xy 203.17203 -300.722027)
			(xy 203.213701 -300.755258) (xy 203.249953 -300.794329) (xy 203.279977 -300.838366) (xy 203.303103 -300.886387)
			(xy 203.318813 -300.937317) (xy 203.326756 -300.990021) (xy 203.327254 -301.01667) (xy 203.326756 -301.043319)
			(xy 203.318813 -301.096023) (xy 203.303103 -301.146953) (xy 203.279977 -301.194974) (xy 203.249953 -301.239011)
			(xy 203.213701 -301.278082) (xy 203.17203 -301.311313) (xy 203.125872 -301.337962) (xy 203.076258 -301.357434)
			(xy 203.024296 -301.369294) (xy 202.971146 -301.373278) (xy 202.917996 -301.369294) (xy 202.866034 -301.357434)
			(xy 202.81642 -301.337962) (xy 202.770262 -301.311313) (xy 202.728591 -301.278082) (xy 202.692339 -301.239011)
			(xy 202.662315 -301.194974) (xy 202.639189 -301.146953) (xy 202.623479 -301.096023) (xy 202.615536 -301.043319)
			(xy 188.239156 -301.043319) (xy 188.231213 -301.096023) (xy 188.215503 -301.146953) (xy 188.192377 -301.194974)
			(xy 188.162353 -301.239011) (xy 188.126101 -301.278082) (xy 188.08443 -301.311313) (xy 188.038272 -301.337962)
			(xy 187.988658 -301.357434) (xy 187.936696 -301.369294) (xy 187.883546 -301.373278) (xy 187.830396 -301.369294)
			(xy 187.778434 -301.357434) (xy 187.72882 -301.337962) (xy 187.682662 -301.311313) (xy 187.640991 -301.278082)
			(xy 187.604739 -301.239011) (xy 187.574715 -301.194974) (xy 187.551589 -301.146953) (xy 187.535879 -301.096023)
			(xy 187.527936 -301.043319) (xy 173.151556 -301.043319) (xy 173.143613 -301.096023) (xy 173.127903 -301.146953)
			(xy 173.104777 -301.194974) (xy 173.074753 -301.239011) (xy 173.038501 -301.278082) (xy 172.99683 -301.311313)
			(xy 172.950672 -301.337962) (xy 172.901058 -301.357434) (xy 172.849096 -301.369294) (xy 172.795946 -301.373278)
			(xy 172.742796 -301.369294) (xy 172.690834 -301.357434) (xy 172.64122 -301.337962) (xy 172.595062 -301.311313)
			(xy 172.553391 -301.278082) (xy 172.517139 -301.239011) (xy 172.487115 -301.194974) (xy 172.463989 -301.146953)
			(xy 172.448279 -301.096023) (xy 172.440336 -301.043319) (xy 158.88716 -301.043319) (xy 158.88716 -301.893203)
			(xy 161.427404 -301.893203) (xy 161.427404 -301.839905) (xy 161.435347 -301.787201) (xy 161.451057 -301.736271)
			(xy 161.474183 -301.68825) (xy 161.504207 -301.644213) (xy 161.540459 -301.605142) (xy 161.58213 -301.571911)
			(xy 161.628288 -301.545262) (xy 161.677902 -301.52579) (xy 161.729864 -301.51393) (xy 161.783014 -301.509947)
			(xy 161.836164 -301.51393) (xy 161.888126 -301.52579) (xy 161.93774 -301.545262) (xy 161.983898 -301.571911)
			(xy 162.025569 -301.605142) (xy 162.061821 -301.644213) (xy 162.091845 -301.68825) (xy 162.114971 -301.736271)
			(xy 162.130681 -301.787201) (xy 162.138624 -301.839905) (xy 162.139122 -301.866554) (xy 162.138624 -301.893203)
			(xy 176.540404 -301.893203) (xy 176.540404 -301.839905) (xy 176.548347 -301.787201) (xy 176.564057 -301.736271)
			(xy 176.587183 -301.68825) (xy 176.617207 -301.644213) (xy 176.653459 -301.605142) (xy 176.69513 -301.571911)
			(xy 176.741288 -301.545262) (xy 176.790902 -301.52579) (xy 176.842864 -301.51393) (xy 176.896014 -301.509947)
			(xy 176.949164 -301.51393) (xy 177.001126 -301.52579) (xy 177.05074 -301.545262) (xy 177.096898 -301.571911)
			(xy 177.138569 -301.605142) (xy 177.174821 -301.644213) (xy 177.204845 -301.68825) (xy 177.227971 -301.736271)
			(xy 177.243681 -301.787201) (xy 177.251624 -301.839905) (xy 177.252122 -301.866554) (xy 177.251624 -301.893203)
			(xy 177.251586 -301.893457) (xy 191.586094 -301.893457) (xy 191.586094 -301.840159) (xy 191.594037 -301.787455)
			(xy 191.609747 -301.736525) (xy 191.632873 -301.688504) (xy 191.662897 -301.644467) (xy 191.699149 -301.605396)
			(xy 191.74082 -301.572165) (xy 191.786978 -301.545516) (xy 191.836592 -301.526044) (xy 191.888554 -301.514184)
			(xy 191.941704 -301.510201) (xy 191.994854 -301.514184) (xy 192.046816 -301.526044) (xy 192.09643 -301.545516)
			(xy 192.142588 -301.572165) (xy 192.184259 -301.605396) (xy 192.220511 -301.644467) (xy 192.250535 -301.688504)
			(xy 192.273661 -301.736525) (xy 192.289371 -301.787455) (xy 192.297314 -301.840159) (xy 192.297812 -301.866808)
			(xy 192.297319 -301.893203) (xy 206.715604 -301.893203) (xy 206.715604 -301.839905) (xy 206.723547 -301.787201)
			(xy 206.739257 -301.736271) (xy 206.762383 -301.68825) (xy 206.792407 -301.644213) (xy 206.828659 -301.605142)
			(xy 206.87033 -301.571911) (xy 206.916488 -301.545262) (xy 206.966102 -301.52579) (xy 207.018064 -301.51393)
			(xy 207.071214 -301.509947) (xy 207.124364 -301.51393) (xy 207.176326 -301.52579) (xy 207.22594 -301.545262)
			(xy 207.272098 -301.571911) (xy 207.313769 -301.605142) (xy 207.350021 -301.644213) (xy 207.380045 -301.68825)
			(xy 207.403171 -301.736271) (xy 207.418881 -301.787201) (xy 207.426824 -301.839905) (xy 207.427322 -301.866554)
			(xy 207.426824 -301.893203) (xy 207.418881 -301.945907) (xy 207.403171 -301.996837) (xy 207.380045 -302.044858)
			(xy 207.350021 -302.088895) (xy 207.313769 -302.127966) (xy 207.272098 -302.161197) (xy 207.22594 -302.187846)
			(xy 207.176326 -302.207318) (xy 207.124364 -302.219178) (xy 207.071214 -302.223162) (xy 207.018064 -302.219178)
			(xy 206.966102 -302.207318) (xy 206.916488 -302.187846) (xy 206.87033 -302.161197) (xy 206.828659 -302.127966)
			(xy 206.792407 -302.088895) (xy 206.762383 -302.044858) (xy 206.739257 -301.996837) (xy 206.723547 -301.945907)
			(xy 206.715604 -301.893203) (xy 192.297319 -301.893203) (xy 192.297314 -301.893457) (xy 192.289371 -301.946161)
			(xy 192.273661 -301.997091) (xy 192.250535 -302.045112) (xy 192.220511 -302.089149) (xy 192.184259 -302.12822)
			(xy 192.142588 -302.161451) (xy 192.09643 -302.1881) (xy 192.046816 -302.207572) (xy 191.994854 -302.219432)
			(xy 191.941704 -302.223416) (xy 191.888554 -302.219432) (xy 191.836592 -302.207572) (xy 191.786978 -302.1881)
			(xy 191.74082 -302.161451) (xy 191.699149 -302.12822) (xy 191.662897 -302.089149) (xy 191.632873 -302.045112)
			(xy 191.609747 -301.997091) (xy 191.594037 -301.946161) (xy 191.586094 -301.893457) (xy 177.251586 -301.893457)
			(xy 177.243681 -301.945907) (xy 177.227971 -301.996837) (xy 177.204845 -302.044858) (xy 177.174821 -302.088895)
			(xy 177.138569 -302.127966) (xy 177.096898 -302.161197) (xy 177.05074 -302.187846) (xy 177.001126 -302.207318)
			(xy 176.949164 -302.219178) (xy 176.896014 -302.223162) (xy 176.842864 -302.219178) (xy 176.790902 -302.207318)
			(xy 176.741288 -302.187846) (xy 176.69513 -302.161197) (xy 176.653459 -302.127966) (xy 176.617207 -302.088895)
			(xy 176.587183 -302.044858) (xy 176.564057 -301.996837) (xy 176.548347 -301.945907) (xy 176.540404 -301.893203)
			(xy 162.138624 -301.893203) (xy 162.130681 -301.945907) (xy 162.114971 -301.996837) (xy 162.091845 -302.044858)
			(xy 162.061821 -302.088895) (xy 162.025569 -302.127966) (xy 161.983898 -302.161197) (xy 161.93774 -302.187846)
			(xy 161.888126 -302.207318) (xy 161.836164 -302.219178) (xy 161.783014 -302.223162) (xy 161.729864 -302.219178)
			(xy 161.677902 -302.207318) (xy 161.628288 -302.187846) (xy 161.58213 -302.161197) (xy 161.540459 -302.127966)
			(xy 161.504207 -302.088895) (xy 161.474183 -302.044858) (xy 161.451057 -301.996837) (xy 161.435347 -301.945907)
			(xy 161.427404 -301.893203) (xy 158.88716 -301.893203) (xy 158.88716 -302.743341) (xy 161.427404 -302.743341)
			(xy 161.427404 -302.690043) (xy 161.435347 -302.637339) (xy 161.451057 -302.586409) (xy 161.474183 -302.538388)
			(xy 161.504207 -302.494351) (xy 161.540459 -302.45528) (xy 161.58213 -302.422049) (xy 161.628288 -302.3954)
			(xy 161.677902 -302.375928) (xy 161.729864 -302.364068) (xy 161.783014 -302.360085) (xy 161.836164 -302.364068)
			(xy 161.888126 -302.375928) (xy 161.93774 -302.3954) (xy 161.983898 -302.422049) (xy 162.025569 -302.45528)
			(xy 162.061821 -302.494351) (xy 162.091845 -302.538388) (xy 162.114971 -302.586409) (xy 162.130681 -302.637339)
			(xy 162.138624 -302.690043) (xy 162.139122 -302.716692) (xy 162.138624 -302.743341) (xy 172.440336 -302.743341)
			(xy 172.440336 -302.690043) (xy 172.448279 -302.637339) (xy 172.463989 -302.586409) (xy 172.487115 -302.538388)
			(xy 172.517139 -302.494351) (xy 172.553391 -302.45528) (xy 172.595062 -302.422049) (xy 172.64122 -302.3954)
			(xy 172.690834 -302.375928) (xy 172.742796 -302.364068) (xy 172.795946 -302.360085) (xy 172.849096 -302.364068)
			(xy 172.901058 -302.375928) (xy 172.950672 -302.3954) (xy 172.99683 -302.422049) (xy 173.038501 -302.45528)
			(xy 173.074753 -302.494351) (xy 173.104777 -302.538388) (xy 173.127903 -302.586409) (xy 173.143613 -302.637339)
			(xy 173.151556 -302.690043) (xy 173.152054 -302.716692) (xy 173.151556 -302.743341) (xy 176.540404 -302.743341)
			(xy 176.540404 -302.690043) (xy 176.548347 -302.637339) (xy 176.564057 -302.586409) (xy 176.587183 -302.538388)
			(xy 176.617207 -302.494351) (xy 176.653459 -302.45528) (xy 176.69513 -302.422049) (xy 176.741288 -302.3954)
			(xy 176.790902 -302.375928) (xy 176.842864 -302.364068) (xy 176.896014 -302.360085) (xy 176.949164 -302.364068)
			(xy 177.001126 -302.375928) (xy 177.05074 -302.3954) (xy 177.096898 -302.422049) (xy 177.138569 -302.45528)
			(xy 177.174821 -302.494351) (xy 177.204845 -302.538388) (xy 177.227971 -302.586409) (xy 177.243681 -302.637339)
			(xy 177.251624 -302.690043) (xy 177.252122 -302.716692) (xy 177.251624 -302.743341) (xy 187.527936 -302.743341)
			(xy 187.527936 -302.690043) (xy 187.535879 -302.637339) (xy 187.551589 -302.586409) (xy 187.574715 -302.538388)
			(xy 187.604739 -302.494351) (xy 187.640991 -302.45528) (xy 187.682662 -302.422049) (xy 187.72882 -302.3954)
			(xy 187.778434 -302.375928) (xy 187.830396 -302.364068) (xy 187.883546 -302.360085) (xy 187.936696 -302.364068)
			(xy 187.988658 -302.375928) (xy 188.038272 -302.3954) (xy 188.08443 -302.422049) (xy 188.126101 -302.45528)
			(xy 188.162353 -302.494351) (xy 188.192377 -302.538388) (xy 188.215503 -302.586409) (xy 188.231213 -302.637339)
			(xy 188.239156 -302.690043) (xy 188.239654 -302.716692) (xy 188.239156 -302.743341) (xy 191.628004 -302.743341)
			(xy 191.628004 -302.690043) (xy 191.635947 -302.637339) (xy 191.651657 -302.586409) (xy 191.674783 -302.538388)
			(xy 191.704807 -302.494351) (xy 191.741059 -302.45528) (xy 191.78273 -302.422049) (xy 191.828888 -302.3954)
			(xy 191.878502 -302.375928) (xy 191.930464 -302.364068) (xy 191.983614 -302.360085) (xy 192.036764 -302.364068)
			(xy 192.088726 -302.375928) (xy 192.13834 -302.3954) (xy 192.184498 -302.422049) (xy 192.226169 -302.45528)
			(xy 192.262421 -302.494351) (xy 192.292445 -302.538388) (xy 192.315571 -302.586409) (xy 192.331281 -302.637339)
			(xy 192.339224 -302.690043) (xy 192.339722 -302.716692) (xy 192.339224 -302.743341) (xy 202.615536 -302.743341)
			(xy 202.615536 -302.690043) (xy 202.623479 -302.637339) (xy 202.639189 -302.586409) (xy 202.662315 -302.538388)
			(xy 202.692339 -302.494351) (xy 202.728591 -302.45528) (xy 202.770262 -302.422049) (xy 202.81642 -302.3954)
			(xy 202.866034 -302.375928) (xy 202.917996 -302.364068) (xy 202.971146 -302.360085) (xy 203.024296 -302.364068)
			(xy 203.076258 -302.375928) (xy 203.125872 -302.3954) (xy 203.17203 -302.422049) (xy 203.213701 -302.45528)
			(xy 203.249953 -302.494351) (xy 203.279977 -302.538388) (xy 203.303103 -302.586409) (xy 203.318813 -302.637339)
			(xy 203.326756 -302.690043) (xy 203.327254 -302.716692) (xy 203.326756 -302.743341) (xy 206.715604 -302.743341)
			(xy 206.715604 -302.690043) (xy 206.723547 -302.637339) (xy 206.739257 -302.586409) (xy 206.762383 -302.538388)
			(xy 206.792407 -302.494351) (xy 206.828659 -302.45528) (xy 206.87033 -302.422049) (xy 206.916488 -302.3954)
			(xy 206.966102 -302.375928) (xy 207.018064 -302.364068) (xy 207.071214 -302.360085) (xy 207.124364 -302.364068)
			(xy 207.176326 -302.375928) (xy 207.22594 -302.3954) (xy 207.272098 -302.422049) (xy 207.313769 -302.45528)
			(xy 207.350021 -302.494351) (xy 207.380045 -302.538388) (xy 207.403171 -302.586409) (xy 207.418881 -302.637339)
			(xy 207.426824 -302.690043) (xy 207.427322 -302.716692) (xy 207.426824 -302.743341) (xy 207.418881 -302.796045)
			(xy 207.403171 -302.846975) (xy 207.380045 -302.894996) (xy 207.350021 -302.939033) (xy 207.313769 -302.978104)
			(xy 207.272098 -303.011335) (xy 207.22594 -303.037984) (xy 207.176326 -303.057456) (xy 207.124364 -303.069316)
			(xy 207.071214 -303.0733) (xy 207.018064 -303.069316) (xy 206.966102 -303.057456) (xy 206.916488 -303.037984)
			(xy 206.87033 -303.011335) (xy 206.828659 -302.978104) (xy 206.792407 -302.939033) (xy 206.762383 -302.894996)
			(xy 206.739257 -302.846975) (xy 206.723547 -302.796045) (xy 206.715604 -302.743341) (xy 203.326756 -302.743341)
			(xy 203.318813 -302.796045) (xy 203.303103 -302.846975) (xy 203.279977 -302.894996) (xy 203.249953 -302.939033)
			(xy 203.213701 -302.978104) (xy 203.17203 -303.011335) (xy 203.125872 -303.037984) (xy 203.076258 -303.057456)
			(xy 203.024296 -303.069316) (xy 202.971146 -303.0733) (xy 202.917996 -303.069316) (xy 202.866034 -303.057456)
			(xy 202.81642 -303.037984) (xy 202.770262 -303.011335) (xy 202.728591 -302.978104) (xy 202.692339 -302.939033)
			(xy 202.662315 -302.894996) (xy 202.639189 -302.846975) (xy 202.623479 -302.796045) (xy 202.615536 -302.743341)
			(xy 192.339224 -302.743341) (xy 192.331281 -302.796045) (xy 192.315571 -302.846975) (xy 192.292445 -302.894996)
			(xy 192.262421 -302.939033) (xy 192.226169 -302.978104) (xy 192.184498 -303.011335) (xy 192.13834 -303.037984)
			(xy 192.088726 -303.057456) (xy 192.036764 -303.069316) (xy 191.983614 -303.0733) (xy 191.930464 -303.069316)
			(xy 191.878502 -303.057456) (xy 191.828888 -303.037984) (xy 191.78273 -303.011335) (xy 191.741059 -302.978104)
			(xy 191.704807 -302.939033) (xy 191.674783 -302.894996) (xy 191.651657 -302.846975) (xy 191.635947 -302.796045)
			(xy 191.628004 -302.743341) (xy 188.239156 -302.743341) (xy 188.231213 -302.796045) (xy 188.215503 -302.846975)
			(xy 188.192377 -302.894996) (xy 188.162353 -302.939033) (xy 188.126101 -302.978104) (xy 188.08443 -303.011335)
			(xy 188.038272 -303.037984) (xy 187.988658 -303.057456) (xy 187.936696 -303.069316) (xy 187.883546 -303.0733)
			(xy 187.830396 -303.069316) (xy 187.778434 -303.057456) (xy 187.72882 -303.037984) (xy 187.682662 -303.011335)
			(xy 187.640991 -302.978104) (xy 187.604739 -302.939033) (xy 187.574715 -302.894996) (xy 187.551589 -302.846975)
			(xy 187.535879 -302.796045) (xy 187.527936 -302.743341) (xy 177.251624 -302.743341) (xy 177.243681 -302.796045)
			(xy 177.227971 -302.846975) (xy 177.204845 -302.894996) (xy 177.174821 -302.939033) (xy 177.138569 -302.978104)
			(xy 177.096898 -303.011335) (xy 177.05074 -303.037984) (xy 177.001126 -303.057456) (xy 176.949164 -303.069316)
			(xy 176.896014 -303.0733) (xy 176.842864 -303.069316) (xy 176.790902 -303.057456) (xy 176.741288 -303.037984)
			(xy 176.69513 -303.011335) (xy 176.653459 -302.978104) (xy 176.617207 -302.939033) (xy 176.587183 -302.894996)
			(xy 176.564057 -302.846975) (xy 176.548347 -302.796045) (xy 176.540404 -302.743341) (xy 173.151556 -302.743341)
			(xy 173.143613 -302.796045) (xy 173.127903 -302.846975) (xy 173.104777 -302.894996) (xy 173.074753 -302.939033)
			(xy 173.038501 -302.978104) (xy 172.99683 -303.011335) (xy 172.950672 -303.037984) (xy 172.901058 -303.057456)
			(xy 172.849096 -303.069316) (xy 172.795946 -303.0733) (xy 172.742796 -303.069316) (xy 172.690834 -303.057456)
			(xy 172.64122 -303.037984) (xy 172.595062 -303.011335) (xy 172.553391 -302.978104) (xy 172.517139 -302.939033)
			(xy 172.487115 -302.894996) (xy 172.463989 -302.846975) (xy 172.448279 -302.796045) (xy 172.440336 -302.743341)
			(xy 162.138624 -302.743341) (xy 162.130681 -302.796045) (xy 162.114971 -302.846975) (xy 162.091845 -302.894996)
			(xy 162.061821 -302.939033) (xy 162.025569 -302.978104) (xy 161.983898 -303.011335) (xy 161.93774 -303.037984)
			(xy 161.888126 -303.057456) (xy 161.836164 -303.069316) (xy 161.783014 -303.0733) (xy 161.729864 -303.069316)
			(xy 161.677902 -303.057456) (xy 161.628288 -303.037984) (xy 161.58213 -303.011335) (xy 161.540459 -302.978104)
			(xy 161.504207 -302.939033) (xy 161.474183 -302.894996) (xy 161.451057 -302.846975) (xy 161.435347 -302.796045)
			(xy 161.427404 -302.743341) (xy 158.88716 -302.743341) (xy 158.88716 -303.593225) (xy 172.440336 -303.593225)
			(xy 172.440336 -303.539927) (xy 172.448279 -303.487223) (xy 172.463989 -303.436293) (xy 172.487115 -303.388272)
			(xy 172.517139 -303.344235) (xy 172.553391 -303.305164) (xy 172.595062 -303.271933) (xy 172.64122 -303.245284)
			(xy 172.690834 -303.225812) (xy 172.742796 -303.213952) (xy 172.795946 -303.209969) (xy 172.849096 -303.213952)
			(xy 172.901058 -303.225812) (xy 172.950672 -303.245284) (xy 172.99683 -303.271933) (xy 173.038501 -303.305164)
			(xy 173.074753 -303.344235) (xy 173.104777 -303.388272) (xy 173.127903 -303.436293) (xy 173.143613 -303.487223)
			(xy 173.151556 -303.539927) (xy 173.152054 -303.566576) (xy 173.151556 -303.593225) (xy 187.527936 -303.593225)
			(xy 187.527936 -303.539927) (xy 187.535879 -303.487223) (xy 187.551589 -303.436293) (xy 187.574715 -303.388272)
			(xy 187.604739 -303.344235) (xy 187.640991 -303.305164) (xy 187.682662 -303.271933) (xy 187.72882 -303.245284)
			(xy 187.778434 -303.225812) (xy 187.830396 -303.213952) (xy 187.883546 -303.209969) (xy 187.936696 -303.213952)
			(xy 187.988658 -303.225812) (xy 188.038272 -303.245284) (xy 188.08443 -303.271933) (xy 188.126101 -303.305164)
			(xy 188.162353 -303.344235) (xy 188.192377 -303.388272) (xy 188.215503 -303.436293) (xy 188.231213 -303.487223)
			(xy 188.239156 -303.539927) (xy 188.239654 -303.566576) (xy 188.239156 -303.593225) (xy 202.615536 -303.593225)
			(xy 202.615536 -303.539927) (xy 202.623479 -303.487223) (xy 202.639189 -303.436293) (xy 202.662315 -303.388272)
			(xy 202.692339 -303.344235) (xy 202.728591 -303.305164) (xy 202.770262 -303.271933) (xy 202.81642 -303.245284)
			(xy 202.866034 -303.225812) (xy 202.917996 -303.213952) (xy 202.971146 -303.209969) (xy 203.024296 -303.213952)
			(xy 203.076258 -303.225812) (xy 203.125872 -303.245284) (xy 203.17203 -303.271933) (xy 203.213701 -303.305164)
			(xy 203.249953 -303.344235) (xy 203.279977 -303.388272) (xy 203.303103 -303.436293) (xy 203.318813 -303.487223)
			(xy 203.326756 -303.539927) (xy 203.327254 -303.566576) (xy 203.326756 -303.593225) (xy 203.318813 -303.645929)
			(xy 203.303103 -303.696859) (xy 203.279977 -303.74488) (xy 203.249953 -303.788917) (xy 203.213701 -303.827988)
			(xy 203.17203 -303.861219) (xy 203.125872 -303.887868) (xy 203.076258 -303.90734) (xy 203.024296 -303.9192)
			(xy 202.971146 -303.923184) (xy 202.917996 -303.9192) (xy 202.866034 -303.90734) (xy 202.81642 -303.887868)
			(xy 202.770262 -303.861219) (xy 202.728591 -303.827988) (xy 202.692339 -303.788917) (xy 202.662315 -303.74488)
			(xy 202.639189 -303.696859) (xy 202.623479 -303.645929) (xy 202.615536 -303.593225) (xy 188.239156 -303.593225)
			(xy 188.231213 -303.645929) (xy 188.215503 -303.696859) (xy 188.192377 -303.74488) (xy 188.162353 -303.788917)
			(xy 188.126101 -303.827988) (xy 188.08443 -303.861219) (xy 188.038272 -303.887868) (xy 187.988658 -303.90734)
			(xy 187.936696 -303.9192) (xy 187.883546 -303.923184) (xy 187.830396 -303.9192) (xy 187.778434 -303.90734)
			(xy 187.72882 -303.887868) (xy 187.682662 -303.861219) (xy 187.640991 -303.827988) (xy 187.604739 -303.788917)
			(xy 187.574715 -303.74488) (xy 187.551589 -303.696859) (xy 187.535879 -303.645929) (xy 187.527936 -303.593225)
			(xy 173.151556 -303.593225) (xy 173.143613 -303.645929) (xy 173.127903 -303.696859) (xy 173.104777 -303.74488)
			(xy 173.074753 -303.788917) (xy 173.038501 -303.827988) (xy 172.99683 -303.861219) (xy 172.950672 -303.887868)
			(xy 172.901058 -303.90734) (xy 172.849096 -303.9192) (xy 172.795946 -303.923184) (xy 172.742796 -303.9192)
			(xy 172.690834 -303.90734) (xy 172.64122 -303.887868) (xy 172.595062 -303.861219) (xy 172.553391 -303.827988)
			(xy 172.517139 -303.788917) (xy 172.487115 -303.74488) (xy 172.463989 -303.696859) (xy 172.448279 -303.645929)
			(xy 172.440336 -303.593225) (xy 158.88716 -303.593225) (xy 158.88716 -304.443363) (xy 161.427404 -304.443363)
			(xy 161.427404 -304.390065) (xy 161.435347 -304.337361) (xy 161.451057 -304.286431) (xy 161.474183 -304.23841)
			(xy 161.504207 -304.194373) (xy 161.540459 -304.155302) (xy 161.58213 -304.122071) (xy 161.628288 -304.095422)
			(xy 161.677902 -304.07595) (xy 161.729864 -304.06409) (xy 161.783014 -304.060107) (xy 161.836164 -304.06409)
			(xy 161.888126 -304.07595) (xy 161.93774 -304.095422) (xy 161.983898 -304.122071) (xy 162.025569 -304.155302)
			(xy 162.061821 -304.194373) (xy 162.091845 -304.23841) (xy 162.114971 -304.286431) (xy 162.130681 -304.337361)
			(xy 162.138624 -304.390065) (xy 162.139122 -304.416714) (xy 162.138624 -304.443363) (xy 176.540404 -304.443363)
			(xy 176.540404 -304.390065) (xy 176.548347 -304.337361) (xy 176.564057 -304.286431) (xy 176.587183 -304.23841)
			(xy 176.617207 -304.194373) (xy 176.653459 -304.155302) (xy 176.69513 -304.122071) (xy 176.741288 -304.095422)
			(xy 176.790902 -304.07595) (xy 176.842864 -304.06409) (xy 176.896014 -304.060107) (xy 176.949164 -304.06409)
			(xy 177.001126 -304.07595) (xy 177.05074 -304.095422) (xy 177.096898 -304.122071) (xy 177.138569 -304.155302)
			(xy 177.174821 -304.194373) (xy 177.204845 -304.23841) (xy 177.227971 -304.286431) (xy 177.243681 -304.337361)
			(xy 177.251624 -304.390065) (xy 177.252122 -304.416714) (xy 177.251624 -304.443363) (xy 191.628004 -304.443363)
			(xy 191.628004 -304.390065) (xy 191.635947 -304.337361) (xy 191.651657 -304.286431) (xy 191.674783 -304.23841)
			(xy 191.704807 -304.194373) (xy 191.741059 -304.155302) (xy 191.78273 -304.122071) (xy 191.828888 -304.095422)
			(xy 191.878502 -304.07595) (xy 191.930464 -304.06409) (xy 191.983614 -304.060107) (xy 192.036764 -304.06409)
			(xy 192.088726 -304.07595) (xy 192.13834 -304.095422) (xy 192.184498 -304.122071) (xy 192.226169 -304.155302)
			(xy 192.262421 -304.194373) (xy 192.292445 -304.23841) (xy 192.315571 -304.286431) (xy 192.331281 -304.337361)
			(xy 192.339224 -304.390065) (xy 192.339722 -304.416714) (xy 192.339224 -304.443363) (xy 206.715604 -304.443363)
			(xy 206.715604 -304.390065) (xy 206.723547 -304.337361) (xy 206.739257 -304.286431) (xy 206.762383 -304.23841)
			(xy 206.792407 -304.194373) (xy 206.828659 -304.155302) (xy 206.87033 -304.122071) (xy 206.916488 -304.095422)
			(xy 206.966102 -304.07595) (xy 207.018064 -304.06409) (xy 207.071214 -304.060107) (xy 207.124364 -304.06409)
			(xy 207.176326 -304.07595) (xy 207.22594 -304.095422) (xy 207.272098 -304.122071) (xy 207.313769 -304.155302)
			(xy 207.350021 -304.194373) (xy 207.380045 -304.23841) (xy 207.403171 -304.286431) (xy 207.418881 -304.337361)
			(xy 207.426824 -304.390065) (xy 207.427322 -304.416714) (xy 207.426824 -304.443363) (xy 207.418881 -304.496067)
			(xy 207.403171 -304.546997) (xy 207.380045 -304.595018) (xy 207.350021 -304.639055) (xy 207.313769 -304.678126)
			(xy 207.272098 -304.711357) (xy 207.22594 -304.738006) (xy 207.176326 -304.757478) (xy 207.124364 -304.769338)
			(xy 207.071214 -304.773322) (xy 207.018064 -304.769338) (xy 206.966102 -304.757478) (xy 206.916488 -304.738006)
			(xy 206.87033 -304.711357) (xy 206.828659 -304.678126) (xy 206.792407 -304.639055) (xy 206.762383 -304.595018)
			(xy 206.739257 -304.546997) (xy 206.723547 -304.496067) (xy 206.715604 -304.443363) (xy 192.339224 -304.443363)
			(xy 192.331281 -304.496067) (xy 192.315571 -304.546997) (xy 192.292445 -304.595018) (xy 192.262421 -304.639055)
			(xy 192.226169 -304.678126) (xy 192.184498 -304.711357) (xy 192.13834 -304.738006) (xy 192.088726 -304.757478)
			(xy 192.036764 -304.769338) (xy 191.983614 -304.773322) (xy 191.930464 -304.769338) (xy 191.878502 -304.757478)
			(xy 191.828888 -304.738006) (xy 191.78273 -304.711357) (xy 191.741059 -304.678126) (xy 191.704807 -304.639055)
			(xy 191.674783 -304.595018) (xy 191.651657 -304.546997) (xy 191.635947 -304.496067) (xy 191.628004 -304.443363)
			(xy 177.251624 -304.443363) (xy 177.243681 -304.496067) (xy 177.227971 -304.546997) (xy 177.204845 -304.595018)
			(xy 177.174821 -304.639055) (xy 177.138569 -304.678126) (xy 177.096898 -304.711357) (xy 177.05074 -304.738006)
			(xy 177.001126 -304.757478) (xy 176.949164 -304.769338) (xy 176.896014 -304.773322) (xy 176.842864 -304.769338)
			(xy 176.790902 -304.757478) (xy 176.741288 -304.738006) (xy 176.69513 -304.711357) (xy 176.653459 -304.678126)
			(xy 176.617207 -304.639055) (xy 176.587183 -304.595018) (xy 176.564057 -304.546997) (xy 176.548347 -304.496067)
			(xy 176.540404 -304.443363) (xy 162.138624 -304.443363) (xy 162.130681 -304.496067) (xy 162.114971 -304.546997)
			(xy 162.091845 -304.595018) (xy 162.061821 -304.639055) (xy 162.025569 -304.678126) (xy 161.983898 -304.711357)
			(xy 161.93774 -304.738006) (xy 161.888126 -304.757478) (xy 161.836164 -304.769338) (xy 161.783014 -304.773322)
			(xy 161.729864 -304.769338) (xy 161.677902 -304.757478) (xy 161.628288 -304.738006) (xy 161.58213 -304.711357)
			(xy 161.540459 -304.678126) (xy 161.504207 -304.639055) (xy 161.474183 -304.595018) (xy 161.451057 -304.546997)
			(xy 161.435347 -304.496067) (xy 161.427404 -304.443363) (xy 158.88716 -304.443363) (xy 158.88716 -305.293247)
			(xy 172.440336 -305.293247) (xy 172.440336 -305.239949) (xy 172.448279 -305.187245) (xy 172.463989 -305.136315)
			(xy 172.487115 -305.088294) (xy 172.517139 -305.044257) (xy 172.553391 -305.005186) (xy 172.595062 -304.971955)
			(xy 172.64122 -304.945306) (xy 172.690834 -304.925834) (xy 172.742796 -304.913974) (xy 172.795946 -304.909991)
			(xy 172.849096 -304.913974) (xy 172.901058 -304.925834) (xy 172.950672 -304.945306) (xy 172.99683 -304.971955)
			(xy 173.038501 -305.005186) (xy 173.074753 -305.044257) (xy 173.104777 -305.088294) (xy 173.127903 -305.136315)
			(xy 173.143613 -305.187245) (xy 173.151556 -305.239949) (xy 173.152054 -305.266598) (xy 173.151556 -305.293247)
			(xy 187.527936 -305.293247) (xy 187.527936 -305.239949) (xy 187.535879 -305.187245) (xy 187.551589 -305.136315)
			(xy 187.574715 -305.088294) (xy 187.604739 -305.044257) (xy 187.640991 -305.005186) (xy 187.682662 -304.971955)
			(xy 187.72882 -304.945306) (xy 187.778434 -304.925834) (xy 187.830396 -304.913974) (xy 187.883546 -304.909991)
			(xy 187.936696 -304.913974) (xy 187.988658 -304.925834) (xy 188.038272 -304.945306) (xy 188.08443 -304.971955)
			(xy 188.126101 -305.005186) (xy 188.162353 -305.044257) (xy 188.192377 -305.088294) (xy 188.215503 -305.136315)
			(xy 188.231213 -305.187245) (xy 188.239156 -305.239949) (xy 188.239654 -305.266598) (xy 188.239156 -305.293247)
			(xy 202.615536 -305.293247) (xy 202.615536 -305.239949) (xy 202.623479 -305.187245) (xy 202.639189 -305.136315)
			(xy 202.662315 -305.088294) (xy 202.692339 -305.044257) (xy 202.728591 -305.005186) (xy 202.770262 -304.971955)
			(xy 202.81642 -304.945306) (xy 202.866034 -304.925834) (xy 202.917996 -304.913974) (xy 202.971146 -304.909991)
			(xy 203.024296 -304.913974) (xy 203.076258 -304.925834) (xy 203.125872 -304.945306) (xy 203.17203 -304.971955)
			(xy 203.213701 -305.005186) (xy 203.249953 -305.044257) (xy 203.279977 -305.088294) (xy 203.303103 -305.136315)
			(xy 203.318813 -305.187245) (xy 203.326756 -305.239949) (xy 203.327254 -305.266598) (xy 203.326756 -305.293247)
			(xy 203.318813 -305.345951) (xy 203.303103 -305.396881) (xy 203.279977 -305.444902) (xy 203.249953 -305.488939)
			(xy 203.213701 -305.52801) (xy 203.17203 -305.561241) (xy 203.125872 -305.58789) (xy 203.076258 -305.607362)
			(xy 203.024296 -305.619222) (xy 202.971146 -305.623206) (xy 202.917996 -305.619222) (xy 202.866034 -305.607362)
			(xy 202.81642 -305.58789) (xy 202.770262 -305.561241) (xy 202.728591 -305.52801) (xy 202.692339 -305.488939)
			(xy 202.662315 -305.444902) (xy 202.639189 -305.396881) (xy 202.623479 -305.345951) (xy 202.615536 -305.293247)
			(xy 188.239156 -305.293247) (xy 188.231213 -305.345951) (xy 188.215503 -305.396881) (xy 188.192377 -305.444902)
			(xy 188.162353 -305.488939) (xy 188.126101 -305.52801) (xy 188.08443 -305.561241) (xy 188.038272 -305.58789)
			(xy 187.988658 -305.607362) (xy 187.936696 -305.619222) (xy 187.883546 -305.623206) (xy 187.830396 -305.619222)
			(xy 187.778434 -305.607362) (xy 187.72882 -305.58789) (xy 187.682662 -305.561241) (xy 187.640991 -305.52801)
			(xy 187.604739 -305.488939) (xy 187.574715 -305.444902) (xy 187.551589 -305.396881) (xy 187.535879 -305.345951)
			(xy 187.527936 -305.293247) (xy 173.151556 -305.293247) (xy 173.143613 -305.345951) (xy 173.127903 -305.396881)
			(xy 173.104777 -305.444902) (xy 173.074753 -305.488939) (xy 173.038501 -305.52801) (xy 172.99683 -305.561241)
			(xy 172.950672 -305.58789) (xy 172.901058 -305.607362) (xy 172.849096 -305.619222) (xy 172.795946 -305.623206)
			(xy 172.742796 -305.619222) (xy 172.690834 -305.607362) (xy 172.64122 -305.58789) (xy 172.595062 -305.561241)
			(xy 172.553391 -305.52801) (xy 172.517139 -305.488939) (xy 172.487115 -305.444902) (xy 172.463989 -305.396881)
			(xy 172.448279 -305.345951) (xy 172.440336 -305.293247) (xy 158.88716 -305.293247) (xy 158.88716 -306.143385)
			(xy 161.427404 -306.143385) (xy 161.427404 -306.090087) (xy 161.435347 -306.037383) (xy 161.451057 -305.986453)
			(xy 161.474183 -305.938432) (xy 161.504207 -305.894395) (xy 161.540459 -305.855324) (xy 161.58213 -305.822093)
			(xy 161.628288 -305.795444) (xy 161.677902 -305.775972) (xy 161.729864 -305.764112) (xy 161.783014 -305.760129)
			(xy 161.836164 -305.764112) (xy 161.888126 -305.775972) (xy 161.93774 -305.795444) (xy 161.983898 -305.822093)
			(xy 162.025569 -305.855324) (xy 162.061821 -305.894395) (xy 162.091845 -305.938432) (xy 162.114971 -305.986453)
			(xy 162.130681 -306.037383) (xy 162.138624 -306.090087) (xy 162.139122 -306.116736) (xy 162.138624 -306.143385)
			(xy 176.540404 -306.143385) (xy 176.540404 -306.090087) (xy 176.548347 -306.037383) (xy 176.564057 -305.986453)
			(xy 176.587183 -305.938432) (xy 176.617207 -305.894395) (xy 176.653459 -305.855324) (xy 176.69513 -305.822093)
			(xy 176.741288 -305.795444) (xy 176.790902 -305.775972) (xy 176.842864 -305.764112) (xy 176.896014 -305.760129)
			(xy 176.949164 -305.764112) (xy 177.001126 -305.775972) (xy 177.05074 -305.795444) (xy 177.096898 -305.822093)
			(xy 177.138569 -305.855324) (xy 177.174821 -305.894395) (xy 177.204845 -305.938432) (xy 177.227971 -305.986453)
			(xy 177.243681 -306.037383) (xy 177.251624 -306.090087) (xy 177.252122 -306.116736) (xy 177.251624 -306.143385)
			(xy 191.628004 -306.143385) (xy 191.628004 -306.090087) (xy 191.635947 -306.037383) (xy 191.651657 -305.986453)
			(xy 191.674783 -305.938432) (xy 191.704807 -305.894395) (xy 191.741059 -305.855324) (xy 191.78273 -305.822093)
			(xy 191.828888 -305.795444) (xy 191.878502 -305.775972) (xy 191.930464 -305.764112) (xy 191.983614 -305.760129)
			(xy 192.036764 -305.764112) (xy 192.088726 -305.775972) (xy 192.13834 -305.795444) (xy 192.184498 -305.822093)
			(xy 192.226169 -305.855324) (xy 192.262421 -305.894395) (xy 192.292445 -305.938432) (xy 192.315571 -305.986453)
			(xy 192.331281 -306.037383) (xy 192.339224 -306.090087) (xy 192.339722 -306.116736) (xy 192.339224 -306.143385)
			(xy 206.715604 -306.143385) (xy 206.715604 -306.090087) (xy 206.723547 -306.037383) (xy 206.739257 -305.986453)
			(xy 206.762383 -305.938432) (xy 206.792407 -305.894395) (xy 206.828659 -305.855324) (xy 206.87033 -305.822093)
			(xy 206.916488 -305.795444) (xy 206.966102 -305.775972) (xy 207.018064 -305.764112) (xy 207.071214 -305.760129)
			(xy 207.124364 -305.764112) (xy 207.176326 -305.775972) (xy 207.22594 -305.795444) (xy 207.272098 -305.822093)
			(xy 207.313769 -305.855324) (xy 207.350021 -305.894395) (xy 207.380045 -305.938432) (xy 207.403171 -305.986453)
			(xy 207.418881 -306.037383) (xy 207.426824 -306.090087) (xy 207.427322 -306.116736) (xy 207.426824 -306.143385)
			(xy 207.418881 -306.196089) (xy 207.403171 -306.247019) (xy 207.380045 -306.29504) (xy 207.350021 -306.339077)
			(xy 207.313769 -306.378148) (xy 207.272098 -306.411379) (xy 207.22594 -306.438028) (xy 207.176326 -306.4575)
			(xy 207.124364 -306.46936) (xy 207.071214 -306.473344) (xy 207.018064 -306.46936) (xy 206.966102 -306.4575)
			(xy 206.916488 -306.438028) (xy 206.87033 -306.411379) (xy 206.828659 -306.378148) (xy 206.792407 -306.339077)
			(xy 206.762383 -306.29504) (xy 206.739257 -306.247019) (xy 206.723547 -306.196089) (xy 206.715604 -306.143385)
			(xy 192.339224 -306.143385) (xy 192.331281 -306.196089) (xy 192.315571 -306.247019) (xy 192.292445 -306.29504)
			(xy 192.262421 -306.339077) (xy 192.226169 -306.378148) (xy 192.184498 -306.411379) (xy 192.13834 -306.438028)
			(xy 192.088726 -306.4575) (xy 192.036764 -306.46936) (xy 191.983614 -306.473344) (xy 191.930464 -306.46936)
			(xy 191.878502 -306.4575) (xy 191.828888 -306.438028) (xy 191.78273 -306.411379) (xy 191.741059 -306.378148)
			(xy 191.704807 -306.339077) (xy 191.674783 -306.29504) (xy 191.651657 -306.247019) (xy 191.635947 -306.196089)
			(xy 191.628004 -306.143385) (xy 177.251624 -306.143385) (xy 177.243681 -306.196089) (xy 177.227971 -306.247019)
			(xy 177.204845 -306.29504) (xy 177.174821 -306.339077) (xy 177.138569 -306.378148) (xy 177.096898 -306.411379)
			(xy 177.05074 -306.438028) (xy 177.001126 -306.4575) (xy 176.949164 -306.46936) (xy 176.896014 -306.473344)
			(xy 176.842864 -306.46936) (xy 176.790902 -306.4575) (xy 176.741288 -306.438028) (xy 176.69513 -306.411379)
			(xy 176.653459 -306.378148) (xy 176.617207 -306.339077) (xy 176.587183 -306.29504) (xy 176.564057 -306.247019)
			(xy 176.548347 -306.196089) (xy 176.540404 -306.143385) (xy 162.138624 -306.143385) (xy 162.130681 -306.196089)
			(xy 162.114971 -306.247019) (xy 162.091845 -306.29504) (xy 162.061821 -306.339077) (xy 162.025569 -306.378148)
			(xy 161.983898 -306.411379) (xy 161.93774 -306.438028) (xy 161.888126 -306.4575) (xy 161.836164 -306.46936)
			(xy 161.783014 -306.473344) (xy 161.729864 -306.46936) (xy 161.677902 -306.4575) (xy 161.628288 -306.438028)
			(xy 161.58213 -306.411379) (xy 161.540459 -306.378148) (xy 161.504207 -306.339077) (xy 161.474183 -306.29504)
			(xy 161.451057 -306.247019) (xy 161.435347 -306.196089) (xy 161.427404 -306.143385) (xy 158.88716 -306.143385)
			(xy 158.88716 -306.993269) (xy 172.440336 -306.993269) (xy 172.440336 -306.939971) (xy 172.448279 -306.887267)
			(xy 172.463989 -306.836337) (xy 172.487115 -306.788316) (xy 172.517139 -306.744279) (xy 172.553391 -306.705208)
			(xy 172.595062 -306.671977) (xy 172.64122 -306.645328) (xy 172.690834 -306.625856) (xy 172.742796 -306.613996)
			(xy 172.795946 -306.610013) (xy 172.849096 -306.613996) (xy 172.901058 -306.625856) (xy 172.950672 -306.645328)
			(xy 172.99683 -306.671977) (xy 173.038501 -306.705208) (xy 173.074753 -306.744279) (xy 173.104777 -306.788316)
			(xy 173.127903 -306.836337) (xy 173.143613 -306.887267) (xy 173.151556 -306.939971) (xy 173.152054 -306.96662)
			(xy 173.151556 -306.993269) (xy 187.527936 -306.993269) (xy 187.527936 -306.939971) (xy 187.535879 -306.887267)
			(xy 187.551589 -306.836337) (xy 187.574715 -306.788316) (xy 187.604739 -306.744279) (xy 187.640991 -306.705208)
			(xy 187.682662 -306.671977) (xy 187.72882 -306.645328) (xy 187.778434 -306.625856) (xy 187.830396 -306.613996)
			(xy 187.883546 -306.610013) (xy 187.936696 -306.613996) (xy 187.988658 -306.625856) (xy 188.038272 -306.645328)
			(xy 188.08443 -306.671977) (xy 188.126101 -306.705208) (xy 188.162353 -306.744279) (xy 188.192377 -306.788316)
			(xy 188.215503 -306.836337) (xy 188.231213 -306.887267) (xy 188.239156 -306.939971) (xy 188.239654 -306.96662)
			(xy 188.239156 -306.993269) (xy 202.615536 -306.993269) (xy 202.615536 -306.939971) (xy 202.623479 -306.887267)
			(xy 202.639189 -306.836337) (xy 202.662315 -306.788316) (xy 202.692339 -306.744279) (xy 202.728591 -306.705208)
			(xy 202.770262 -306.671977) (xy 202.81642 -306.645328) (xy 202.866034 -306.625856) (xy 202.917996 -306.613996)
			(xy 202.971146 -306.610013) (xy 203.024296 -306.613996) (xy 203.076258 -306.625856) (xy 203.125872 -306.645328)
			(xy 203.17203 -306.671977) (xy 203.213701 -306.705208) (xy 203.249953 -306.744279) (xy 203.279977 -306.788316)
			(xy 203.303103 -306.836337) (xy 203.318813 -306.887267) (xy 203.326756 -306.939971) (xy 203.327254 -306.96662)
			(xy 203.326756 -306.993269) (xy 203.318813 -307.045973) (xy 203.303103 -307.096903) (xy 203.279977 -307.144924)
			(xy 203.249953 -307.188961) (xy 203.213701 -307.228032) (xy 203.17203 -307.261263) (xy 203.125872 -307.287912)
			(xy 203.076258 -307.307384) (xy 203.024296 -307.319244) (xy 202.971146 -307.323228) (xy 202.917996 -307.319244)
			(xy 202.866034 -307.307384) (xy 202.81642 -307.287912) (xy 202.770262 -307.261263) (xy 202.728591 -307.228032)
			(xy 202.692339 -307.188961) (xy 202.662315 -307.144924) (xy 202.639189 -307.096903) (xy 202.623479 -307.045973)
			(xy 202.615536 -306.993269) (xy 188.239156 -306.993269) (xy 188.231213 -307.045973) (xy 188.215503 -307.096903)
			(xy 188.192377 -307.144924) (xy 188.162353 -307.188961) (xy 188.126101 -307.228032) (xy 188.08443 -307.261263)
			(xy 188.038272 -307.287912) (xy 187.988658 -307.307384) (xy 187.936696 -307.319244) (xy 187.883546 -307.323228)
			(xy 187.830396 -307.319244) (xy 187.778434 -307.307384) (xy 187.72882 -307.287912) (xy 187.682662 -307.261263)
			(xy 187.640991 -307.228032) (xy 187.604739 -307.188961) (xy 187.574715 -307.144924) (xy 187.551589 -307.096903)
			(xy 187.535879 -307.045973) (xy 187.527936 -306.993269) (xy 173.151556 -306.993269) (xy 173.143613 -307.045973)
			(xy 173.127903 -307.096903) (xy 173.104777 -307.144924) (xy 173.074753 -307.188961) (xy 173.038501 -307.228032)
			(xy 172.99683 -307.261263) (xy 172.950672 -307.287912) (xy 172.901058 -307.307384) (xy 172.849096 -307.319244)
			(xy 172.795946 -307.323228) (xy 172.742796 -307.319244) (xy 172.690834 -307.307384) (xy 172.64122 -307.287912)
			(xy 172.595062 -307.261263) (xy 172.553391 -307.228032) (xy 172.517139 -307.188961) (xy 172.487115 -307.144924)
			(xy 172.463989 -307.096903) (xy 172.448279 -307.045973) (xy 172.440336 -306.993269) (xy 158.88716 -306.993269)
			(xy 158.88716 -307.843407) (xy 176.540404 -307.843407) (xy 176.540404 -307.790109) (xy 176.548347 -307.737405)
			(xy 176.564057 -307.686475) (xy 176.587183 -307.638454) (xy 176.617207 -307.594417) (xy 176.653459 -307.555346)
			(xy 176.69513 -307.522115) (xy 176.741288 -307.495466) (xy 176.790902 -307.475994) (xy 176.842864 -307.464134)
			(xy 176.896014 -307.460151) (xy 176.949164 -307.464134) (xy 177.001126 -307.475994) (xy 177.05074 -307.495466)
			(xy 177.096898 -307.522115) (xy 177.138569 -307.555346) (xy 177.174821 -307.594417) (xy 177.204845 -307.638454)
			(xy 177.227971 -307.686475) (xy 177.243681 -307.737405) (xy 177.251624 -307.790109) (xy 177.252122 -307.816758)
			(xy 177.251624 -307.843407) (xy 191.628004 -307.843407) (xy 191.628004 -307.790109) (xy 191.635947 -307.737405)
			(xy 191.651657 -307.686475) (xy 191.674783 -307.638454) (xy 191.704807 -307.594417) (xy 191.741059 -307.555346)
			(xy 191.78273 -307.522115) (xy 191.828888 -307.495466) (xy 191.878502 -307.475994) (xy 191.930464 -307.464134)
			(xy 191.983614 -307.460151) (xy 192.036764 -307.464134) (xy 192.088726 -307.475994) (xy 192.13834 -307.495466)
			(xy 192.184498 -307.522115) (xy 192.226169 -307.555346) (xy 192.262421 -307.594417) (xy 192.292445 -307.638454)
			(xy 192.315571 -307.686475) (xy 192.331281 -307.737405) (xy 192.339224 -307.790109) (xy 192.339722 -307.816758)
			(xy 192.339224 -307.843407) (xy 206.715604 -307.843407) (xy 206.715604 -307.790109) (xy 206.723547 -307.737405)
			(xy 206.739257 -307.686475) (xy 206.762383 -307.638454) (xy 206.792407 -307.594417) (xy 206.828659 -307.555346)
			(xy 206.87033 -307.522115) (xy 206.916488 -307.495466) (xy 206.966102 -307.475994) (xy 207.018064 -307.464134)
			(xy 207.071214 -307.460151) (xy 207.124364 -307.464134) (xy 207.176326 -307.475994) (xy 207.22594 -307.495466)
			(xy 207.272098 -307.522115) (xy 207.313769 -307.555346) (xy 207.350021 -307.594417) (xy 207.380045 -307.638454)
			(xy 207.403171 -307.686475) (xy 207.418881 -307.737405) (xy 207.426824 -307.790109) (xy 207.427322 -307.816758)
			(xy 207.426824 -307.843407) (xy 207.418881 -307.896111) (xy 207.403171 -307.947041) (xy 207.380045 -307.995062)
			(xy 207.350021 -308.039099) (xy 207.313769 -308.07817) (xy 207.272098 -308.111401) (xy 207.22594 -308.13805)
			(xy 207.176326 -308.157522) (xy 207.124364 -308.169382) (xy 207.071214 -308.173366) (xy 207.018064 -308.169382)
			(xy 206.966102 -308.157522) (xy 206.916488 -308.13805) (xy 206.87033 -308.111401) (xy 206.828659 -308.07817)
			(xy 206.792407 -308.039099) (xy 206.762383 -307.995062) (xy 206.739257 -307.947041) (xy 206.723547 -307.896111)
			(xy 206.715604 -307.843407) (xy 192.339224 -307.843407) (xy 192.331281 -307.896111) (xy 192.315571 -307.947041)
			(xy 192.292445 -307.995062) (xy 192.262421 -308.039099) (xy 192.226169 -308.07817) (xy 192.184498 -308.111401)
			(xy 192.13834 -308.13805) (xy 192.088726 -308.157522) (xy 192.036764 -308.169382) (xy 191.983614 -308.173366)
			(xy 191.930464 -308.169382) (xy 191.878502 -308.157522) (xy 191.828888 -308.13805) (xy 191.78273 -308.111401)
			(xy 191.741059 -308.07817) (xy 191.704807 -308.039099) (xy 191.674783 -307.995062) (xy 191.651657 -307.947041)
			(xy 191.635947 -307.896111) (xy 191.628004 -307.843407) (xy 177.251624 -307.843407) (xy 177.243681 -307.896111)
			(xy 177.227971 -307.947041) (xy 177.204845 -307.995062) (xy 177.174821 -308.039099) (xy 177.138569 -308.07817)
			(xy 177.096898 -308.111401) (xy 177.05074 -308.13805) (xy 177.001126 -308.157522) (xy 176.949164 -308.169382)
			(xy 176.896014 -308.173366) (xy 176.842864 -308.169382) (xy 176.790902 -308.157522) (xy 176.741288 -308.13805)
			(xy 176.69513 -308.111401) (xy 176.653459 -308.07817) (xy 176.617207 -308.039099) (xy 176.587183 -307.995062)
			(xy 176.564057 -307.947041) (xy 176.548347 -307.896111) (xy 176.540404 -307.843407) (xy 158.88716 -307.843407)
			(xy 158.88716 -308.693291) (xy 172.440336 -308.693291) (xy 172.440336 -308.639993) (xy 172.448279 -308.587289)
			(xy 172.463989 -308.536359) (xy 172.487115 -308.488338) (xy 172.517139 -308.444301) (xy 172.553391 -308.40523)
			(xy 172.595062 -308.371999) (xy 172.64122 -308.34535) (xy 172.690834 -308.325878) (xy 172.742796 -308.314018)
			(xy 172.795946 -308.310035) (xy 172.849096 -308.314018) (xy 172.901058 -308.325878) (xy 172.950672 -308.34535)
			(xy 172.99683 -308.371999) (xy 173.038501 -308.40523) (xy 173.074753 -308.444301) (xy 173.104777 -308.488338)
			(xy 173.127903 -308.536359) (xy 173.143613 -308.587289) (xy 173.151556 -308.639993) (xy 173.152054 -308.666642)
			(xy 173.151556 -308.693291) (xy 187.527936 -308.693291) (xy 187.527936 -308.639993) (xy 187.535879 -308.587289)
			(xy 187.551589 -308.536359) (xy 187.574715 -308.488338) (xy 187.604739 -308.444301) (xy 187.640991 -308.40523)
			(xy 187.682662 -308.371999) (xy 187.72882 -308.34535) (xy 187.778434 -308.325878) (xy 187.830396 -308.314018)
			(xy 187.883546 -308.310035) (xy 187.936696 -308.314018) (xy 187.988658 -308.325878) (xy 188.038272 -308.34535)
			(xy 188.08443 -308.371999) (xy 188.126101 -308.40523) (xy 188.162353 -308.444301) (xy 188.192377 -308.488338)
			(xy 188.215503 -308.536359) (xy 188.231213 -308.587289) (xy 188.239156 -308.639993) (xy 188.239654 -308.666642)
			(xy 188.239156 -308.693291) (xy 202.615536 -308.693291) (xy 202.615536 -308.639993) (xy 202.623479 -308.587289)
			(xy 202.639189 -308.536359) (xy 202.662315 -308.488338) (xy 202.692339 -308.444301) (xy 202.728591 -308.40523)
			(xy 202.770262 -308.371999) (xy 202.81642 -308.34535) (xy 202.866034 -308.325878) (xy 202.917996 -308.314018)
			(xy 202.971146 -308.310035) (xy 203.024296 -308.314018) (xy 203.076258 -308.325878) (xy 203.125872 -308.34535)
			(xy 203.17203 -308.371999) (xy 203.213701 -308.40523) (xy 203.249953 -308.444301) (xy 203.279977 -308.488338)
			(xy 203.303103 -308.536359) (xy 203.318813 -308.587289) (xy 203.326756 -308.639993) (xy 203.327254 -308.666642)
			(xy 203.326756 -308.693291) (xy 203.318813 -308.745995) (xy 203.303103 -308.796925) (xy 203.279977 -308.844946)
			(xy 203.249953 -308.888983) (xy 203.213701 -308.928054) (xy 203.17203 -308.961285) (xy 203.125872 -308.987934)
			(xy 203.076258 -309.007406) (xy 203.024296 -309.019266) (xy 202.971146 -309.02325) (xy 202.917996 -309.019266)
			(xy 202.866034 -309.007406) (xy 202.81642 -308.987934) (xy 202.770262 -308.961285) (xy 202.728591 -308.928054)
			(xy 202.692339 -308.888983) (xy 202.662315 -308.844946) (xy 202.639189 -308.796925) (xy 202.623479 -308.745995)
			(xy 202.615536 -308.693291) (xy 188.239156 -308.693291) (xy 188.231213 -308.745995) (xy 188.215503 -308.796925)
			(xy 188.192377 -308.844946) (xy 188.162353 -308.888983) (xy 188.126101 -308.928054) (xy 188.08443 -308.961285)
			(xy 188.038272 -308.987934) (xy 187.988658 -309.007406) (xy 187.936696 -309.019266) (xy 187.883546 -309.02325)
			(xy 187.830396 -309.019266) (xy 187.778434 -309.007406) (xy 187.72882 -308.987934) (xy 187.682662 -308.961285)
			(xy 187.640991 -308.928054) (xy 187.604739 -308.888983) (xy 187.574715 -308.844946) (xy 187.551589 -308.796925)
			(xy 187.535879 -308.745995) (xy 187.527936 -308.693291) (xy 173.151556 -308.693291) (xy 173.143613 -308.745995)
			(xy 173.127903 -308.796925) (xy 173.104777 -308.844946) (xy 173.074753 -308.888983) (xy 173.038501 -308.928054)
			(xy 172.99683 -308.961285) (xy 172.950672 -308.987934) (xy 172.901058 -309.007406) (xy 172.849096 -309.019266)
			(xy 172.795946 -309.02325) (xy 172.742796 -309.019266) (xy 172.690834 -309.007406) (xy 172.64122 -308.987934)
			(xy 172.595062 -308.961285) (xy 172.553391 -308.928054) (xy 172.517139 -308.888983) (xy 172.487115 -308.844946)
			(xy 172.463989 -308.796925) (xy 172.448279 -308.745995) (xy 172.440336 -308.693291) (xy 158.88716 -308.693291)
			(xy 158.88716 -309.543175) (xy 176.540404 -309.543175) (xy 176.540404 -309.489877) (xy 176.548347 -309.437173)
			(xy 176.564057 -309.386243) (xy 176.587183 -309.338222) (xy 176.617207 -309.294185) (xy 176.653459 -309.255114)
			(xy 176.69513 -309.221883) (xy 176.741288 -309.195234) (xy 176.790902 -309.175762) (xy 176.842864 -309.163902)
			(xy 176.896014 -309.159919) (xy 176.949164 -309.163902) (xy 177.001126 -309.175762) (xy 177.05074 -309.195234)
			(xy 177.096898 -309.221883) (xy 177.138569 -309.255114) (xy 177.174821 -309.294185) (xy 177.204845 -309.338222)
			(xy 177.227971 -309.386243) (xy 177.243681 -309.437173) (xy 177.251624 -309.489877) (xy 177.252122 -309.516526)
			(xy 177.251624 -309.543175) (xy 191.628004 -309.543175) (xy 191.628004 -309.489877) (xy 191.635947 -309.437173)
			(xy 191.651657 -309.386243) (xy 191.674783 -309.338222) (xy 191.704807 -309.294185) (xy 191.741059 -309.255114)
			(xy 191.78273 -309.221883) (xy 191.828888 -309.195234) (xy 191.878502 -309.175762) (xy 191.930464 -309.163902)
			(xy 191.983614 -309.159919) (xy 192.036764 -309.163902) (xy 192.088726 -309.175762) (xy 192.13834 -309.195234)
			(xy 192.184498 -309.221883) (xy 192.226169 -309.255114) (xy 192.262421 -309.294185) (xy 192.292445 -309.338222)
			(xy 192.315571 -309.386243) (xy 192.331281 -309.437173) (xy 192.339224 -309.489877) (xy 192.339722 -309.516526)
			(xy 192.339224 -309.543175) (xy 192.339186 -309.543429) (xy 206.715604 -309.543429) (xy 206.715604 -309.490131)
			(xy 206.723547 -309.437427) (xy 206.739257 -309.386497) (xy 206.762383 -309.338476) (xy 206.792407 -309.294439)
			(xy 206.828659 -309.255368) (xy 206.87033 -309.222137) (xy 206.916488 -309.195488) (xy 206.966102 -309.176016)
			(xy 207.018064 -309.164156) (xy 207.071214 -309.160173) (xy 207.124364 -309.164156) (xy 207.176326 -309.176016)
			(xy 207.22594 -309.195488) (xy 207.272098 -309.222137) (xy 207.313769 -309.255368) (xy 207.350021 -309.294439)
			(xy 207.380045 -309.338476) (xy 207.403171 -309.386497) (xy 207.418881 -309.437427) (xy 207.426824 -309.490131)
			(xy 207.427322 -309.51678) (xy 207.426824 -309.543429) (xy 207.418881 -309.596133) (xy 207.403171 -309.647063)
			(xy 207.380045 -309.695084) (xy 207.350021 -309.739121) (xy 207.313769 -309.778192) (xy 207.272098 -309.811423)
			(xy 207.22594 -309.838072) (xy 207.176326 -309.857544) (xy 207.124364 -309.869404) (xy 207.071214 -309.873388)
			(xy 207.018064 -309.869404) (xy 206.966102 -309.857544) (xy 206.916488 -309.838072) (xy 206.87033 -309.811423)
			(xy 206.828659 -309.778192) (xy 206.792407 -309.739121) (xy 206.762383 -309.695084) (xy 206.739257 -309.647063)
			(xy 206.723547 -309.596133) (xy 206.715604 -309.543429) (xy 192.339186 -309.543429) (xy 192.331281 -309.595879)
			(xy 192.315571 -309.646809) (xy 192.292445 -309.69483) (xy 192.262421 -309.738867) (xy 192.226169 -309.777938)
			(xy 192.184498 -309.811169) (xy 192.13834 -309.837818) (xy 192.088726 -309.85729) (xy 192.036764 -309.86915)
			(xy 191.983614 -309.873134) (xy 191.930464 -309.86915) (xy 191.878502 -309.85729) (xy 191.828888 -309.837818)
			(xy 191.78273 -309.811169) (xy 191.741059 -309.777938) (xy 191.704807 -309.738867) (xy 191.674783 -309.69483)
			(xy 191.651657 -309.646809) (xy 191.635947 -309.595879) (xy 191.628004 -309.543175) (xy 177.251624 -309.543175)
			(xy 177.243681 -309.595879) (xy 177.227971 -309.646809) (xy 177.204845 -309.69483) (xy 177.174821 -309.738867)
			(xy 177.138569 -309.777938) (xy 177.096898 -309.811169) (xy 177.05074 -309.837818) (xy 177.001126 -309.85729)
			(xy 176.949164 -309.86915) (xy 176.896014 -309.873134) (xy 176.842864 -309.86915) (xy 176.790902 -309.85729)
			(xy 176.741288 -309.837818) (xy 176.69513 -309.811169) (xy 176.653459 -309.777938) (xy 176.617207 -309.738867)
			(xy 176.587183 -309.69483) (xy 176.564057 -309.646809) (xy 176.548347 -309.595879) (xy 176.540404 -309.543175)
			(xy 158.88716 -309.543175) (xy 158.88716 -310.393313) (xy 172.440336 -310.393313) (xy 172.440336 -310.340015)
			(xy 172.448279 -310.287311) (xy 172.463989 -310.236381) (xy 172.487115 -310.18836) (xy 172.517139 -310.144323)
			(xy 172.553391 -310.105252) (xy 172.595062 -310.072021) (xy 172.64122 -310.045372) (xy 172.690834 -310.0259)
			(xy 172.742796 -310.01404) (xy 172.795946 -310.010057) (xy 172.849096 -310.01404) (xy 172.901058 -310.0259)
			(xy 172.950672 -310.045372) (xy 172.99683 -310.072021) (xy 173.038501 -310.105252) (xy 173.074753 -310.144323)
			(xy 173.104777 -310.18836) (xy 173.127903 -310.236381) (xy 173.143613 -310.287311) (xy 173.151556 -310.340015)
			(xy 173.152054 -310.366664) (xy 173.151556 -310.393313) (xy 187.527936 -310.393313) (xy 187.527936 -310.340015)
			(xy 187.535879 -310.287311) (xy 187.551589 -310.236381) (xy 187.574715 -310.18836) (xy 187.604739 -310.144323)
			(xy 187.640991 -310.105252) (xy 187.682662 -310.072021) (xy 187.72882 -310.045372) (xy 187.778434 -310.0259)
			(xy 187.830396 -310.01404) (xy 187.883546 -310.010057) (xy 187.936696 -310.01404) (xy 187.988658 -310.0259)
			(xy 188.038272 -310.045372) (xy 188.08443 -310.072021) (xy 188.126101 -310.105252) (xy 188.162353 -310.144323)
			(xy 188.192377 -310.18836) (xy 188.215503 -310.236381) (xy 188.231213 -310.287311) (xy 188.239156 -310.340015)
			(xy 188.239654 -310.366664) (xy 188.239156 -310.393313) (xy 202.615536 -310.393313) (xy 202.615536 -310.340015)
			(xy 202.623479 -310.287311) (xy 202.639189 -310.236381) (xy 202.662315 -310.18836) (xy 202.692339 -310.144323)
			(xy 202.728591 -310.105252) (xy 202.770262 -310.072021) (xy 202.81642 -310.045372) (xy 202.866034 -310.0259)
			(xy 202.917996 -310.01404) (xy 202.971146 -310.010057) (xy 203.024296 -310.01404) (xy 203.076258 -310.0259)
			(xy 203.125872 -310.045372) (xy 203.17203 -310.072021) (xy 203.213701 -310.105252) (xy 203.249953 -310.144323)
			(xy 203.279977 -310.18836) (xy 203.303103 -310.236381) (xy 203.318813 -310.287311) (xy 203.326756 -310.340015)
			(xy 203.327254 -310.366664) (xy 203.326756 -310.393313) (xy 203.318813 -310.446017) (xy 203.303103 -310.496947)
			(xy 203.279977 -310.544968) (xy 203.249953 -310.589005) (xy 203.213701 -310.628076) (xy 203.17203 -310.661307)
			(xy 203.125872 -310.687956) (xy 203.076258 -310.707428) (xy 203.024296 -310.719288) (xy 202.971146 -310.723272)
			(xy 202.917996 -310.719288) (xy 202.866034 -310.707428) (xy 202.81642 -310.687956) (xy 202.770262 -310.661307)
			(xy 202.728591 -310.628076) (xy 202.692339 -310.589005) (xy 202.662315 -310.544968) (xy 202.639189 -310.496947)
			(xy 202.623479 -310.446017) (xy 202.615536 -310.393313) (xy 188.239156 -310.393313) (xy 188.231213 -310.446017)
			(xy 188.215503 -310.496947) (xy 188.192377 -310.544968) (xy 188.162353 -310.589005) (xy 188.126101 -310.628076)
			(xy 188.08443 -310.661307) (xy 188.038272 -310.687956) (xy 187.988658 -310.707428) (xy 187.936696 -310.719288)
			(xy 187.883546 -310.723272) (xy 187.830396 -310.719288) (xy 187.778434 -310.707428) (xy 187.72882 -310.687956)
			(xy 187.682662 -310.661307) (xy 187.640991 -310.628076) (xy 187.604739 -310.589005) (xy 187.574715 -310.544968)
			(xy 187.551589 -310.496947) (xy 187.535879 -310.446017) (xy 187.527936 -310.393313) (xy 173.151556 -310.393313)
			(xy 173.143613 -310.446017) (xy 173.127903 -310.496947) (xy 173.104777 -310.544968) (xy 173.074753 -310.589005)
			(xy 173.038501 -310.628076) (xy 172.99683 -310.661307) (xy 172.950672 -310.687956) (xy 172.901058 -310.707428)
			(xy 172.849096 -310.719288) (xy 172.795946 -310.723272) (xy 172.742796 -310.719288) (xy 172.690834 -310.707428)
			(xy 172.64122 -310.687956) (xy 172.595062 -310.661307) (xy 172.553391 -310.628076) (xy 172.517139 -310.589005)
			(xy 172.487115 -310.544968) (xy 172.463989 -310.496947) (xy 172.448279 -310.446017) (xy 172.440336 -310.393313)
			(xy 158.88716 -310.393313) (xy 158.88716 -311.243197) (xy 176.540404 -311.243197) (xy 176.540404 -311.189899)
			(xy 176.548347 -311.137195) (xy 176.564057 -311.086265) (xy 176.587183 -311.038244) (xy 176.617207 -310.994207)
			(xy 176.653459 -310.955136) (xy 176.69513 -310.921905) (xy 176.741288 -310.895256) (xy 176.790902 -310.875784)
			(xy 176.842864 -310.863924) (xy 176.896014 -310.859941) (xy 176.949164 -310.863924) (xy 177.001126 -310.875784)
			(xy 177.05074 -310.895256) (xy 177.096898 -310.921905) (xy 177.138569 -310.955136) (xy 177.174821 -310.994207)
			(xy 177.204845 -311.038244) (xy 177.227971 -311.086265) (xy 177.243681 -311.137195) (xy 177.251624 -311.189899)
			(xy 177.252122 -311.216548) (xy 177.251624 -311.243197) (xy 191.628004 -311.243197) (xy 191.628004 -311.189899)
			(xy 191.635947 -311.137195) (xy 191.651657 -311.086265) (xy 191.674783 -311.038244) (xy 191.704807 -310.994207)
			(xy 191.741059 -310.955136) (xy 191.78273 -310.921905) (xy 191.828888 -310.895256) (xy 191.878502 -310.875784)
			(xy 191.930464 -310.863924) (xy 191.983614 -310.859941) (xy 192.036764 -310.863924) (xy 192.088726 -310.875784)
			(xy 192.13834 -310.895256) (xy 192.184498 -310.921905) (xy 192.226169 -310.955136) (xy 192.262421 -310.994207)
			(xy 192.292445 -311.038244) (xy 192.315571 -311.086265) (xy 192.331281 -311.137195) (xy 192.339224 -311.189899)
			(xy 192.339722 -311.216548) (xy 192.339224 -311.243197) (xy 192.339186 -311.243451) (xy 206.715604 -311.243451)
			(xy 206.715604 -311.190153) (xy 206.723547 -311.137449) (xy 206.739257 -311.086519) (xy 206.762383 -311.038498)
			(xy 206.792407 -310.994461) (xy 206.828659 -310.95539) (xy 206.87033 -310.922159) (xy 206.916488 -310.89551)
			(xy 206.966102 -310.876038) (xy 207.018064 -310.864178) (xy 207.071214 -310.860195) (xy 207.124364 -310.864178)
			(xy 207.176326 -310.876038) (xy 207.22594 -310.89551) (xy 207.272098 -310.922159) (xy 207.313769 -310.95539)
			(xy 207.350021 -310.994461) (xy 207.380045 -311.038498) (xy 207.403171 -311.086519) (xy 207.418881 -311.137449)
			(xy 207.426824 -311.190153) (xy 207.427322 -311.216802) (xy 207.426824 -311.243451) (xy 207.418881 -311.296155)
			(xy 207.403171 -311.347085) (xy 207.380045 -311.395106) (xy 207.350021 -311.439143) (xy 207.313769 -311.478214)
			(xy 207.272098 -311.511445) (xy 207.22594 -311.538094) (xy 207.176326 -311.557566) (xy 207.124364 -311.569426)
			(xy 207.071214 -311.57341) (xy 207.018064 -311.569426) (xy 206.966102 -311.557566) (xy 206.916488 -311.538094)
			(xy 206.87033 -311.511445) (xy 206.828659 -311.478214) (xy 206.792407 -311.439143) (xy 206.762383 -311.395106)
			(xy 206.739257 -311.347085) (xy 206.723547 -311.296155) (xy 206.715604 -311.243451) (xy 192.339186 -311.243451)
			(xy 192.331281 -311.295901) (xy 192.315571 -311.346831) (xy 192.292445 -311.394852) (xy 192.262421 -311.438889)
			(xy 192.226169 -311.47796) (xy 192.184498 -311.511191) (xy 192.13834 -311.53784) (xy 192.088726 -311.557312)
			(xy 192.036764 -311.569172) (xy 191.983614 -311.573156) (xy 191.930464 -311.569172) (xy 191.878502 -311.557312)
			(xy 191.828888 -311.53784) (xy 191.78273 -311.511191) (xy 191.741059 -311.47796) (xy 191.704807 -311.438889)
			(xy 191.674783 -311.394852) (xy 191.651657 -311.346831) (xy 191.635947 -311.295901) (xy 191.628004 -311.243197)
			(xy 177.251624 -311.243197) (xy 177.243681 -311.295901) (xy 177.227971 -311.346831) (xy 177.204845 -311.394852)
			(xy 177.174821 -311.438889) (xy 177.138569 -311.47796) (xy 177.096898 -311.511191) (xy 177.05074 -311.53784)
			(xy 177.001126 -311.557312) (xy 176.949164 -311.569172) (xy 176.896014 -311.573156) (xy 176.842864 -311.569172)
			(xy 176.790902 -311.557312) (xy 176.741288 -311.53784) (xy 176.69513 -311.511191) (xy 176.653459 -311.47796)
			(xy 176.617207 -311.438889) (xy 176.587183 -311.394852) (xy 176.564057 -311.346831) (xy 176.548347 -311.295901)
			(xy 176.540404 -311.243197) (xy 158.88716 -311.243197) (xy 158.88716 -312.093335) (xy 172.440336 -312.093335)
			(xy 172.440336 -312.040037) (xy 172.448279 -311.987333) (xy 172.463989 -311.936403) (xy 172.487115 -311.888382)
			(xy 172.517139 -311.844345) (xy 172.553391 -311.805274) (xy 172.595062 -311.772043) (xy 172.64122 -311.745394)
			(xy 172.690834 -311.725922) (xy 172.742796 -311.714062) (xy 172.795946 -311.710079) (xy 172.849096 -311.714062)
			(xy 172.901058 -311.725922) (xy 172.950672 -311.745394) (xy 172.99683 -311.772043) (xy 173.038501 -311.805274)
			(xy 173.074753 -311.844345) (xy 173.104777 -311.888382) (xy 173.127903 -311.936403) (xy 173.143613 -311.987333)
			(xy 173.151556 -312.040037) (xy 173.152054 -312.066686) (xy 173.151556 -312.093335) (xy 176.540404 -312.093335)
			(xy 176.540404 -312.040037) (xy 176.548347 -311.987333) (xy 176.564057 -311.936403) (xy 176.587183 -311.888382)
			(xy 176.617207 -311.844345) (xy 176.653459 -311.805274) (xy 176.69513 -311.772043) (xy 176.741288 -311.745394)
			(xy 176.790902 -311.725922) (xy 176.842864 -311.714062) (xy 176.896014 -311.710079) (xy 176.949164 -311.714062)
			(xy 177.001126 -311.725922) (xy 177.05074 -311.745394) (xy 177.096898 -311.772043) (xy 177.138569 -311.805274)
			(xy 177.174821 -311.844345) (xy 177.204845 -311.888382) (xy 177.227971 -311.936403) (xy 177.243681 -311.987333)
			(xy 177.251624 -312.040037) (xy 177.252122 -312.066686) (xy 177.251624 -312.093335) (xy 187.527936 -312.093335)
			(xy 187.527936 -312.040037) (xy 187.535879 -311.987333) (xy 187.551589 -311.936403) (xy 187.574715 -311.888382)
			(xy 187.604739 -311.844345) (xy 187.640991 -311.805274) (xy 187.682662 -311.772043) (xy 187.72882 -311.745394)
			(xy 187.778434 -311.725922) (xy 187.830396 -311.714062) (xy 187.883546 -311.710079) (xy 187.936696 -311.714062)
			(xy 187.988658 -311.725922) (xy 188.038272 -311.745394) (xy 188.08443 -311.772043) (xy 188.126101 -311.805274)
			(xy 188.162353 -311.844345) (xy 188.192377 -311.888382) (xy 188.215503 -311.936403) (xy 188.231213 -311.987333)
			(xy 188.239156 -312.040037) (xy 188.239654 -312.066686) (xy 188.239156 -312.093335) (xy 191.628004 -312.093335)
			(xy 191.628004 -312.040037) (xy 191.635947 -311.987333) (xy 191.651657 -311.936403) (xy 191.674783 -311.888382)
			(xy 191.704807 -311.844345) (xy 191.741059 -311.805274) (xy 191.78273 -311.772043) (xy 191.828888 -311.745394)
			(xy 191.878502 -311.725922) (xy 191.930464 -311.714062) (xy 191.983614 -311.710079) (xy 192.036764 -311.714062)
			(xy 192.088726 -311.725922) (xy 192.13834 -311.745394) (xy 192.184498 -311.772043) (xy 192.226169 -311.805274)
			(xy 192.262421 -311.844345) (xy 192.292445 -311.888382) (xy 192.315571 -311.936403) (xy 192.331281 -311.987333)
			(xy 192.339224 -312.040037) (xy 192.339722 -312.066686) (xy 192.339224 -312.093335) (xy 202.615536 -312.093335)
			(xy 202.615536 -312.040037) (xy 202.623479 -311.987333) (xy 202.639189 -311.936403) (xy 202.662315 -311.888382)
			(xy 202.692339 -311.844345) (xy 202.728591 -311.805274) (xy 202.770262 -311.772043) (xy 202.81642 -311.745394)
			(xy 202.866034 -311.725922) (xy 202.917996 -311.714062) (xy 202.971146 -311.710079) (xy 203.024296 -311.714062)
			(xy 203.076258 -311.725922) (xy 203.125872 -311.745394) (xy 203.17203 -311.772043) (xy 203.213701 -311.805274)
			(xy 203.249953 -311.844345) (xy 203.279977 -311.888382) (xy 203.303103 -311.936403) (xy 203.318813 -311.987333)
			(xy 203.326756 -312.040037) (xy 203.327254 -312.066686) (xy 203.326756 -312.093335) (xy 206.715604 -312.093335)
			(xy 206.715604 -312.040037) (xy 206.723547 -311.987333) (xy 206.739257 -311.936403) (xy 206.762383 -311.888382)
			(xy 206.792407 -311.844345) (xy 206.828659 -311.805274) (xy 206.87033 -311.772043) (xy 206.916488 -311.745394)
			(xy 206.966102 -311.725922) (xy 207.018064 -311.714062) (xy 207.071214 -311.710079) (xy 207.124364 -311.714062)
			(xy 207.176326 -311.725922) (xy 207.22594 -311.745394) (xy 207.272098 -311.772043) (xy 207.313769 -311.805274)
			(xy 207.350021 -311.844345) (xy 207.380045 -311.888382) (xy 207.403171 -311.936403) (xy 207.418881 -311.987333)
			(xy 207.426824 -312.040037) (xy 207.427322 -312.066686) (xy 207.426824 -312.093335) (xy 207.418881 -312.146039)
			(xy 207.403171 -312.196969) (xy 207.380045 -312.24499) (xy 207.350021 -312.289027) (xy 207.313769 -312.328098)
			(xy 207.272098 -312.361329) (xy 207.22594 -312.387978) (xy 207.176326 -312.40745) (xy 207.124364 -312.41931)
			(xy 207.071214 -312.423294) (xy 207.018064 -312.41931) (xy 206.966102 -312.40745) (xy 206.916488 -312.387978)
			(xy 206.87033 -312.361329) (xy 206.828659 -312.328098) (xy 206.792407 -312.289027) (xy 206.762383 -312.24499)
			(xy 206.739257 -312.196969) (xy 206.723547 -312.146039) (xy 206.715604 -312.093335) (xy 203.326756 -312.093335)
			(xy 203.318813 -312.146039) (xy 203.303103 -312.196969) (xy 203.279977 -312.24499) (xy 203.249953 -312.289027)
			(xy 203.213701 -312.328098) (xy 203.17203 -312.361329) (xy 203.125872 -312.387978) (xy 203.076258 -312.40745)
			(xy 203.024296 -312.41931) (xy 202.971146 -312.423294) (xy 202.917996 -312.41931) (xy 202.866034 -312.40745)
			(xy 202.81642 -312.387978) (xy 202.770262 -312.361329) (xy 202.728591 -312.328098) (xy 202.692339 -312.289027)
			(xy 202.662315 -312.24499) (xy 202.639189 -312.196969) (xy 202.623479 -312.146039) (xy 202.615536 -312.093335)
			(xy 192.339224 -312.093335) (xy 192.331281 -312.146039) (xy 192.315571 -312.196969) (xy 192.292445 -312.24499)
			(xy 192.262421 -312.289027) (xy 192.226169 -312.328098) (xy 192.184498 -312.361329) (xy 192.13834 -312.387978)
			(xy 192.088726 -312.40745) (xy 192.036764 -312.41931) (xy 191.983614 -312.423294) (xy 191.930464 -312.41931)
			(xy 191.878502 -312.40745) (xy 191.828888 -312.387978) (xy 191.78273 -312.361329) (xy 191.741059 -312.328098)
			(xy 191.704807 -312.289027) (xy 191.674783 -312.24499) (xy 191.651657 -312.196969) (xy 191.635947 -312.146039)
			(xy 191.628004 -312.093335) (xy 188.239156 -312.093335) (xy 188.231213 -312.146039) (xy 188.215503 -312.196969)
			(xy 188.192377 -312.24499) (xy 188.162353 -312.289027) (xy 188.126101 -312.328098) (xy 188.08443 -312.361329)
			(xy 188.038272 -312.387978) (xy 187.988658 -312.40745) (xy 187.936696 -312.41931) (xy 187.883546 -312.423294)
			(xy 187.830396 -312.41931) (xy 187.778434 -312.40745) (xy 187.72882 -312.387978) (xy 187.682662 -312.361329)
			(xy 187.640991 -312.328098) (xy 187.604739 -312.289027) (xy 187.574715 -312.24499) (xy 187.551589 -312.196969)
			(xy 187.535879 -312.146039) (xy 187.527936 -312.093335) (xy 177.251624 -312.093335) (xy 177.243681 -312.146039)
			(xy 177.227971 -312.196969) (xy 177.204845 -312.24499) (xy 177.174821 -312.289027) (xy 177.138569 -312.328098)
			(xy 177.096898 -312.361329) (xy 177.05074 -312.387978) (xy 177.001126 -312.40745) (xy 176.949164 -312.41931)
			(xy 176.896014 -312.423294) (xy 176.842864 -312.41931) (xy 176.790902 -312.40745) (xy 176.741288 -312.387978)
			(xy 176.69513 -312.361329) (xy 176.653459 -312.328098) (xy 176.617207 -312.289027) (xy 176.587183 -312.24499)
			(xy 176.564057 -312.196969) (xy 176.548347 -312.146039) (xy 176.540404 -312.093335) (xy 173.151556 -312.093335)
			(xy 173.143613 -312.146039) (xy 173.127903 -312.196969) (xy 173.104777 -312.24499) (xy 173.074753 -312.289027)
			(xy 173.038501 -312.328098) (xy 172.99683 -312.361329) (xy 172.950672 -312.387978) (xy 172.901058 -312.40745)
			(xy 172.849096 -312.41931) (xy 172.795946 -312.423294) (xy 172.742796 -312.41931) (xy 172.690834 -312.40745)
			(xy 172.64122 -312.387978) (xy 172.595062 -312.361329) (xy 172.553391 -312.328098) (xy 172.517139 -312.289027)
			(xy 172.487115 -312.24499) (xy 172.463989 -312.196969) (xy 172.448279 -312.146039) (xy 172.440336 -312.093335)
			(xy 158.88716 -312.093335) (xy 158.88716 -312.943219) (xy 172.440336 -312.943219) (xy 172.440336 -312.889921)
			(xy 172.448279 -312.837217) (xy 172.463989 -312.786287) (xy 172.487115 -312.738266) (xy 172.517139 -312.694229)
			(xy 172.553391 -312.655158) (xy 172.595062 -312.621927) (xy 172.64122 -312.595278) (xy 172.690834 -312.575806)
			(xy 172.742796 -312.563946) (xy 172.795946 -312.559963) (xy 172.849096 -312.563946) (xy 172.901058 -312.575806)
			(xy 172.950672 -312.595278) (xy 172.99683 -312.621927) (xy 173.038501 -312.655158) (xy 173.074753 -312.694229)
			(xy 173.104777 -312.738266) (xy 173.127903 -312.786287) (xy 173.143613 -312.837217) (xy 173.151556 -312.889921)
			(xy 173.152054 -312.91657) (xy 173.151556 -312.943219) (xy 187.527936 -312.943219) (xy 187.527936 -312.889921)
			(xy 187.535879 -312.837217) (xy 187.551589 -312.786287) (xy 187.574715 -312.738266) (xy 187.604739 -312.694229)
			(xy 187.640991 -312.655158) (xy 187.682662 -312.621927) (xy 187.72882 -312.595278) (xy 187.778434 -312.575806)
			(xy 187.830396 -312.563946) (xy 187.883546 -312.559963) (xy 187.936696 -312.563946) (xy 187.988658 -312.575806)
			(xy 188.038272 -312.595278) (xy 188.08443 -312.621927) (xy 188.126101 -312.655158) (xy 188.162353 -312.694229)
			(xy 188.192377 -312.738266) (xy 188.215503 -312.786287) (xy 188.231213 -312.837217) (xy 188.239156 -312.889921)
			(xy 188.239654 -312.91657) (xy 188.239156 -312.943219) (xy 202.615536 -312.943219) (xy 202.615536 -312.889921)
			(xy 202.623479 -312.837217) (xy 202.639189 -312.786287) (xy 202.662315 -312.738266) (xy 202.692339 -312.694229)
			(xy 202.728591 -312.655158) (xy 202.770262 -312.621927) (xy 202.81642 -312.595278) (xy 202.866034 -312.575806)
			(xy 202.917996 -312.563946) (xy 202.971146 -312.559963) (xy 203.024296 -312.563946) (xy 203.076258 -312.575806)
			(xy 203.125872 -312.595278) (xy 203.17203 -312.621927) (xy 203.213701 -312.655158) (xy 203.249953 -312.694229)
			(xy 203.279977 -312.738266) (xy 203.303103 -312.786287) (xy 203.318813 -312.837217) (xy 203.326756 -312.889921)
			(xy 203.327254 -312.91657) (xy 203.326756 -312.943219) (xy 203.318813 -312.995923) (xy 203.305918 -313.037728)
			(xy 212.475062 -313.037728) (xy 212.479133 -312.982106) (xy 212.491259 -312.927669) (xy 212.511182 -312.875578)
			(xy 212.538478 -312.826943) (xy 212.572564 -312.7828) (xy 212.612713 -312.744091) (xy 212.658071 -312.71164)
			(xy 212.707671 -312.686139) (xy 212.760455 -312.668132) (xy 212.815298 -312.658002) (xy 212.871032 -312.655965)
			(xy 212.926469 -312.662065) (xy 212.980426 -312.676171) (xy 213.031755 -312.697983) (xy 213.079361 -312.727037)
			(xy 213.122229 -312.762712) (xy 213.159446 -312.804249) (xy 213.190219 -312.850762) (xy 213.213891 -312.901259)
			(xy 213.229959 -312.954666) (xy 213.238079 -313.009842) (xy 213.238588 -313.037728) (xy 213.238079 -313.065614)
			(xy 213.229959 -313.12079) (xy 213.213891 -313.174197) (xy 213.190219 -313.224694) (xy 213.159446 -313.271207)
			(xy 213.122229 -313.312744) (xy 213.079361 -313.348419) (xy 213.031755 -313.377473) (xy 212.980426 -313.399285)
			(xy 212.926469 -313.413391) (xy 212.871032 -313.419491) (xy 212.815298 -313.417454) (xy 212.760455 -313.407324)
			(xy 212.707671 -313.389317) (xy 212.658071 -313.363816) (xy 212.612713 -313.331365) (xy 212.572564 -313.292656)
			(xy 212.538478 -313.248513) (xy 212.511182 -313.199878) (xy 212.491259 -313.147787) (xy 212.479133 -313.09335)
			(xy 212.475062 -313.037728) (xy 203.305918 -313.037728) (xy 203.303103 -313.046853) (xy 203.279977 -313.094874)
			(xy 203.249953 -313.138911) (xy 203.213701 -313.177982) (xy 203.17203 -313.211213) (xy 203.125872 -313.237862)
			(xy 203.076258 -313.257334) (xy 203.024296 -313.269194) (xy 202.971146 -313.273178) (xy 202.917996 -313.269194)
			(xy 202.866034 -313.257334) (xy 202.81642 -313.237862) (xy 202.770262 -313.211213) (xy 202.728591 -313.177982)
			(xy 202.692339 -313.138911) (xy 202.662315 -313.094874) (xy 202.639189 -313.046853) (xy 202.623479 -312.995923)
			(xy 202.615536 -312.943219) (xy 188.239156 -312.943219) (xy 188.231213 -312.995923) (xy 188.215503 -313.046853)
			(xy 188.192377 -313.094874) (xy 188.162353 -313.138911) (xy 188.126101 -313.177982) (xy 188.08443 -313.211213)
			(xy 188.038272 -313.237862) (xy 187.988658 -313.257334) (xy 187.936696 -313.269194) (xy 187.883546 -313.273178)
			(xy 187.830396 -313.269194) (xy 187.778434 -313.257334) (xy 187.72882 -313.237862) (xy 187.682662 -313.211213)
			(xy 187.640991 -313.177982) (xy 187.604739 -313.138911) (xy 187.574715 -313.094874) (xy 187.551589 -313.046853)
			(xy 187.535879 -312.995923) (xy 187.527936 -312.943219) (xy 173.151556 -312.943219) (xy 173.143613 -312.995923)
			(xy 173.127903 -313.046853) (xy 173.104777 -313.094874) (xy 173.074753 -313.138911) (xy 173.038501 -313.177982)
			(xy 172.99683 -313.211213) (xy 172.950672 -313.237862) (xy 172.901058 -313.257334) (xy 172.849096 -313.269194)
			(xy 172.795946 -313.273178) (xy 172.742796 -313.269194) (xy 172.690834 -313.257334) (xy 172.64122 -313.237862)
			(xy 172.595062 -313.211213) (xy 172.553391 -313.177982) (xy 172.517139 -313.138911) (xy 172.487115 -313.094874)
			(xy 172.463989 -313.046853) (xy 172.448279 -312.995923) (xy 172.440336 -312.943219) (xy 158.88716 -312.943219)
			(xy 158.88716 -313.793357) (xy 176.540404 -313.793357) (xy 176.540404 -313.740059) (xy 176.548347 -313.687355)
			(xy 176.564057 -313.636425) (xy 176.587183 -313.588404) (xy 176.617207 -313.544367) (xy 176.653459 -313.505296)
			(xy 176.69513 -313.472065) (xy 176.741288 -313.445416) (xy 176.790902 -313.425944) (xy 176.842864 -313.414084)
			(xy 176.896014 -313.410101) (xy 176.949164 -313.414084) (xy 177.001126 -313.425944) (xy 177.05074 -313.445416)
			(xy 177.096898 -313.472065) (xy 177.138569 -313.505296) (xy 177.174821 -313.544367) (xy 177.204845 -313.588404)
			(xy 177.227971 -313.636425) (xy 177.243681 -313.687355) (xy 177.251624 -313.740059) (xy 177.252122 -313.766708)
			(xy 177.251624 -313.793357) (xy 191.628004 -313.793357) (xy 191.628004 -313.740059) (xy 191.635947 -313.687355)
			(xy 191.651657 -313.636425) (xy 191.674783 -313.588404) (xy 191.704807 -313.544367) (xy 191.741059 -313.505296)
			(xy 191.78273 -313.472065) (xy 191.828888 -313.445416) (xy 191.878502 -313.425944) (xy 191.930464 -313.414084)
			(xy 191.983614 -313.410101) (xy 192.036764 -313.414084) (xy 192.088726 -313.425944) (xy 192.13834 -313.445416)
			(xy 192.184498 -313.472065) (xy 192.226169 -313.505296) (xy 192.262421 -313.544367) (xy 192.292445 -313.588404)
			(xy 192.315571 -313.636425) (xy 192.331281 -313.687355) (xy 192.339224 -313.740059) (xy 192.339722 -313.766708)
			(xy 192.339224 -313.793357) (xy 206.715604 -313.793357) (xy 206.715604 -313.740059) (xy 206.723547 -313.687355)
			(xy 206.739257 -313.636425) (xy 206.762383 -313.588404) (xy 206.792407 -313.544367) (xy 206.828659 -313.505296)
			(xy 206.87033 -313.472065) (xy 206.916488 -313.445416) (xy 206.966102 -313.425944) (xy 207.018064 -313.414084)
			(xy 207.071214 -313.410101) (xy 207.124364 -313.414084) (xy 207.176326 -313.425944) (xy 207.22594 -313.445416)
			(xy 207.272098 -313.472065) (xy 207.313769 -313.505296) (xy 207.350021 -313.544367) (xy 207.380045 -313.588404)
			(xy 207.403171 -313.636425) (xy 207.418881 -313.687355) (xy 207.426824 -313.740059) (xy 207.427322 -313.766708)
			(xy 207.426824 -313.793357) (xy 207.418881 -313.846061) (xy 207.403171 -313.896991) (xy 207.380045 -313.945012)
			(xy 207.350021 -313.989049) (xy 207.313769 -314.02812) (xy 207.272098 -314.061351) (xy 207.22594 -314.088)
			(xy 207.176326 -314.107472) (xy 207.124364 -314.119332) (xy 207.071214 -314.123316) (xy 207.018064 -314.119332)
			(xy 206.966102 -314.107472) (xy 206.916488 -314.088) (xy 206.87033 -314.061351) (xy 206.828659 -314.02812)
			(xy 206.792407 -313.989049) (xy 206.762383 -313.945012) (xy 206.739257 -313.896991) (xy 206.723547 -313.846061)
			(xy 206.715604 -313.793357) (xy 192.339224 -313.793357) (xy 192.331281 -313.846061) (xy 192.315571 -313.896991)
			(xy 192.292445 -313.945012) (xy 192.262421 -313.989049) (xy 192.226169 -314.02812) (xy 192.184498 -314.061351)
			(xy 192.13834 -314.088) (xy 192.088726 -314.107472) (xy 192.036764 -314.119332) (xy 191.983614 -314.123316)
			(xy 191.930464 -314.119332) (xy 191.878502 -314.107472) (xy 191.828888 -314.088) (xy 191.78273 -314.061351)
			(xy 191.741059 -314.02812) (xy 191.704807 -313.989049) (xy 191.674783 -313.945012) (xy 191.651657 -313.896991)
			(xy 191.635947 -313.846061) (xy 191.628004 -313.793357) (xy 177.251624 -313.793357) (xy 177.243681 -313.846061)
			(xy 177.227971 -313.896991) (xy 177.204845 -313.945012) (xy 177.174821 -313.989049) (xy 177.138569 -314.02812)
			(xy 177.096898 -314.061351) (xy 177.05074 -314.088) (xy 177.001126 -314.107472) (xy 176.949164 -314.119332)
			(xy 176.896014 -314.123316) (xy 176.842864 -314.119332) (xy 176.790902 -314.107472) (xy 176.741288 -314.088)
			(xy 176.69513 -314.061351) (xy 176.653459 -314.02812) (xy 176.617207 -313.989049) (xy 176.587183 -313.945012)
			(xy 176.564057 -313.896991) (xy 176.548347 -313.846061) (xy 176.540404 -313.793357) (xy 158.88716 -313.793357)
			(xy 158.88716 -314.643241) (xy 172.440336 -314.643241) (xy 172.440336 -314.589943) (xy 172.448279 -314.537239)
			(xy 172.463989 -314.486309) (xy 172.487115 -314.438288) (xy 172.517139 -314.394251) (xy 172.553391 -314.35518)
			(xy 172.595062 -314.321949) (xy 172.64122 -314.2953) (xy 172.690834 -314.275828) (xy 172.742796 -314.263968)
			(xy 172.795946 -314.259985) (xy 172.849096 -314.263968) (xy 172.901058 -314.275828) (xy 172.950672 -314.2953)
			(xy 172.99683 -314.321949) (xy 173.038501 -314.35518) (xy 173.074753 -314.394251) (xy 173.104777 -314.438288)
			(xy 173.127903 -314.486309) (xy 173.143613 -314.537239) (xy 173.151556 -314.589943) (xy 173.152054 -314.616592)
			(xy 173.151556 -314.643241) (xy 187.527936 -314.643241) (xy 187.527936 -314.589943) (xy 187.535879 -314.537239)
			(xy 187.551589 -314.486309) (xy 187.574715 -314.438288) (xy 187.604739 -314.394251) (xy 187.640991 -314.35518)
			(xy 187.682662 -314.321949) (xy 187.72882 -314.2953) (xy 187.778434 -314.275828) (xy 187.830396 -314.263968)
			(xy 187.883546 -314.259985) (xy 187.936696 -314.263968) (xy 187.988658 -314.275828) (xy 188.038272 -314.2953)
			(xy 188.08443 -314.321949) (xy 188.126101 -314.35518) (xy 188.162353 -314.394251) (xy 188.192377 -314.438288)
			(xy 188.215503 -314.486309) (xy 188.231213 -314.537239) (xy 188.239156 -314.589943) (xy 188.239654 -314.616592)
			(xy 188.239156 -314.643241) (xy 202.615536 -314.643241) (xy 202.615536 -314.589943) (xy 202.623479 -314.537239)
			(xy 202.639189 -314.486309) (xy 202.662315 -314.438288) (xy 202.692339 -314.394251) (xy 202.728591 -314.35518)
			(xy 202.770262 -314.321949) (xy 202.81642 -314.2953) (xy 202.866034 -314.275828) (xy 202.917996 -314.263968)
			(xy 202.971146 -314.259985) (xy 203.024296 -314.263968) (xy 203.076258 -314.275828) (xy 203.125872 -314.2953)
			(xy 203.17203 -314.321949) (xy 203.213701 -314.35518) (xy 203.249953 -314.394251) (xy 203.279977 -314.438288)
			(xy 203.303103 -314.486309) (xy 203.318813 -314.537239) (xy 203.326756 -314.589943) (xy 203.327254 -314.616592)
			(xy 203.326756 -314.643241) (xy 203.318813 -314.695945) (xy 203.303103 -314.746875) (xy 203.279977 -314.794896)
			(xy 203.249953 -314.838933) (xy 203.213701 -314.878004) (xy 203.17203 -314.911235) (xy 203.125872 -314.937884)
			(xy 203.076258 -314.957356) (xy 203.024296 -314.969216) (xy 202.971146 -314.9732) (xy 202.917996 -314.969216)
			(xy 202.866034 -314.957356) (xy 202.81642 -314.937884) (xy 202.770262 -314.911235) (xy 202.728591 -314.878004)
			(xy 202.692339 -314.838933) (xy 202.662315 -314.794896) (xy 202.639189 -314.746875) (xy 202.623479 -314.695945)
			(xy 202.615536 -314.643241) (xy 188.239156 -314.643241) (xy 188.231213 -314.695945) (xy 188.215503 -314.746875)
			(xy 188.192377 -314.794896) (xy 188.162353 -314.838933) (xy 188.126101 -314.878004) (xy 188.08443 -314.911235)
			(xy 188.038272 -314.937884) (xy 187.988658 -314.957356) (xy 187.936696 -314.969216) (xy 187.883546 -314.9732)
			(xy 187.830396 -314.969216) (xy 187.778434 -314.957356) (xy 187.72882 -314.937884) (xy 187.682662 -314.911235)
			(xy 187.640991 -314.878004) (xy 187.604739 -314.838933) (xy 187.574715 -314.794896) (xy 187.551589 -314.746875)
			(xy 187.535879 -314.695945) (xy 187.527936 -314.643241) (xy 173.151556 -314.643241) (xy 173.143613 -314.695945)
			(xy 173.127903 -314.746875) (xy 173.104777 -314.794896) (xy 173.074753 -314.838933) (xy 173.038501 -314.878004)
			(xy 172.99683 -314.911235) (xy 172.950672 -314.937884) (xy 172.901058 -314.957356) (xy 172.849096 -314.969216)
			(xy 172.795946 -314.9732) (xy 172.742796 -314.969216) (xy 172.690834 -314.957356) (xy 172.64122 -314.937884)
			(xy 172.595062 -314.911235) (xy 172.553391 -314.878004) (xy 172.517139 -314.838933) (xy 172.487115 -314.794896)
			(xy 172.463989 -314.746875) (xy 172.448279 -314.695945) (xy 172.440336 -314.643241) (xy 158.88716 -314.643241)
			(xy 158.88716 -315.493379) (xy 176.540404 -315.493379) (xy 176.540404 -315.440081) (xy 176.548347 -315.387377)
			(xy 176.564057 -315.336447) (xy 176.587183 -315.288426) (xy 176.617207 -315.244389) (xy 176.653459 -315.205318)
			(xy 176.69513 -315.172087) (xy 176.741288 -315.145438) (xy 176.790902 -315.125966) (xy 176.842864 -315.114106)
			(xy 176.896014 -315.110123) (xy 176.949164 -315.114106) (xy 177.001126 -315.125966) (xy 177.05074 -315.145438)
			(xy 177.096898 -315.172087) (xy 177.138569 -315.205318) (xy 177.174821 -315.244389) (xy 177.204845 -315.288426)
			(xy 177.227971 -315.336447) (xy 177.243681 -315.387377) (xy 177.251624 -315.440081) (xy 177.252122 -315.46673)
			(xy 177.251624 -315.493379) (xy 191.628004 -315.493379) (xy 191.628004 -315.440081) (xy 191.635947 -315.387377)
			(xy 191.651657 -315.336447) (xy 191.674783 -315.288426) (xy 191.704807 -315.244389) (xy 191.741059 -315.205318)
			(xy 191.78273 -315.172087) (xy 191.828888 -315.145438) (xy 191.878502 -315.125966) (xy 191.930464 -315.114106)
			(xy 191.983614 -315.110123) (xy 192.036764 -315.114106) (xy 192.088726 -315.125966) (xy 192.13834 -315.145438)
			(xy 192.184498 -315.172087) (xy 192.226169 -315.205318) (xy 192.262421 -315.244389) (xy 192.292445 -315.288426)
			(xy 192.315571 -315.336447) (xy 192.331281 -315.387377) (xy 192.339224 -315.440081) (xy 192.339722 -315.46673)
			(xy 192.339224 -315.493379) (xy 206.715604 -315.493379) (xy 206.715604 -315.440081) (xy 206.723547 -315.387377)
			(xy 206.739257 -315.336447) (xy 206.762383 -315.288426) (xy 206.792407 -315.244389) (xy 206.828659 -315.205318)
			(xy 206.87033 -315.172087) (xy 206.916488 -315.145438) (xy 206.966102 -315.125966) (xy 207.018064 -315.114106)
			(xy 207.071214 -315.110123) (xy 207.124364 -315.114106) (xy 207.176326 -315.125966) (xy 207.22594 -315.145438)
			(xy 207.272098 -315.172087) (xy 207.313769 -315.205318) (xy 207.350021 -315.244389) (xy 207.380045 -315.288426)
			(xy 207.403171 -315.336447) (xy 207.418881 -315.387377) (xy 207.426824 -315.440081) (xy 207.427322 -315.46673)
			(xy 207.426824 -315.493379) (xy 207.425864 -315.49975) (xy 216.691462 -315.49975) (xy 216.695533 -315.444128)
			(xy 216.707659 -315.389691) (xy 216.727582 -315.3376) (xy 216.754878 -315.288965) (xy 216.788964 -315.244822)
			(xy 216.829113 -315.206113) (xy 216.874471 -315.173662) (xy 216.924071 -315.148161) (xy 216.976855 -315.130154)
			(xy 217.031698 -315.120024) (xy 217.087432 -315.117987) (xy 217.142869 -315.124087) (xy 217.196826 -315.138193)
			(xy 217.248155 -315.160005) (xy 217.295761 -315.189059) (xy 217.338629 -315.224734) (xy 217.375846 -315.266271)
			(xy 217.406619 -315.312784) (xy 217.430291 -315.363281) (xy 217.446359 -315.416688) (xy 217.454479 -315.471864)
			(xy 217.454988 -315.49975) (xy 217.454479 -315.527636) (xy 217.446359 -315.582812) (xy 217.430291 -315.636219)
			(xy 217.406619 -315.686716) (xy 217.375846 -315.733229) (xy 217.338629 -315.774766) (xy 217.295761 -315.810441)
			(xy 217.248155 -315.839495) (xy 217.196826 -315.861307) (xy 217.142869 -315.875413) (xy 217.087432 -315.881513)
			(xy 217.031698 -315.879476) (xy 216.976855 -315.869346) (xy 216.924071 -315.851339) (xy 216.874471 -315.825838)
			(xy 216.829113 -315.793387) (xy 216.788964 -315.754678) (xy 216.754878 -315.710535) (xy 216.727582 -315.6619)
			(xy 216.707659 -315.609809) (xy 216.695533 -315.555372) (xy 216.691462 -315.49975) (xy 207.425864 -315.49975)
			(xy 207.418881 -315.546083) (xy 207.403171 -315.597013) (xy 207.380045 -315.645034) (xy 207.350021 -315.689071)
			(xy 207.313769 -315.728142) (xy 207.272098 -315.761373) (xy 207.22594 -315.788022) (xy 207.176326 -315.807494)
			(xy 207.124364 -315.819354) (xy 207.071214 -315.823338) (xy 207.018064 -315.819354) (xy 206.966102 -315.807494)
			(xy 206.916488 -315.788022) (xy 206.87033 -315.761373) (xy 206.828659 -315.728142) (xy 206.792407 -315.689071)
			(xy 206.762383 -315.645034) (xy 206.739257 -315.597013) (xy 206.723547 -315.546083) (xy 206.715604 -315.493379)
			(xy 192.339224 -315.493379) (xy 192.331281 -315.546083) (xy 192.315571 -315.597013) (xy 192.292445 -315.645034)
			(xy 192.262421 -315.689071) (xy 192.226169 -315.728142) (xy 192.184498 -315.761373) (xy 192.13834 -315.788022)
			(xy 192.088726 -315.807494) (xy 192.036764 -315.819354) (xy 191.983614 -315.823338) (xy 191.930464 -315.819354)
			(xy 191.878502 -315.807494) (xy 191.828888 -315.788022) (xy 191.78273 -315.761373) (xy 191.741059 -315.728142)
			(xy 191.704807 -315.689071) (xy 191.674783 -315.645034) (xy 191.651657 -315.597013) (xy 191.635947 -315.546083)
			(xy 191.628004 -315.493379) (xy 177.251624 -315.493379) (xy 177.243681 -315.546083) (xy 177.227971 -315.597013)
			(xy 177.204845 -315.645034) (xy 177.174821 -315.689071) (xy 177.138569 -315.728142) (xy 177.096898 -315.761373)
			(xy 177.05074 -315.788022) (xy 177.001126 -315.807494) (xy 176.949164 -315.819354) (xy 176.896014 -315.823338)
			(xy 176.842864 -315.819354) (xy 176.790902 -315.807494) (xy 176.741288 -315.788022) (xy 176.69513 -315.761373)
			(xy 176.653459 -315.728142) (xy 176.617207 -315.689071) (xy 176.587183 -315.645034) (xy 176.564057 -315.597013)
			(xy 176.548347 -315.546083) (xy 176.540404 -315.493379) (xy 158.88716 -315.493379) (xy 158.88716 -316.343263)
			(xy 172.440336 -316.343263) (xy 172.440336 -316.289965) (xy 172.448279 -316.237261) (xy 172.463989 -316.186331)
			(xy 172.487115 -316.13831) (xy 172.517139 -316.094273) (xy 172.553391 -316.055202) (xy 172.595062 -316.021971)
			(xy 172.64122 -315.995322) (xy 172.690834 -315.97585) (xy 172.742796 -315.96399) (xy 172.795946 -315.960007)
			(xy 172.849096 -315.96399) (xy 172.901058 -315.97585) (xy 172.950672 -315.995322) (xy 172.99683 -316.021971)
			(xy 173.038501 -316.055202) (xy 173.074753 -316.094273) (xy 173.104777 -316.13831) (xy 173.127903 -316.186331)
			(xy 173.143613 -316.237261) (xy 173.151556 -316.289965) (xy 173.152054 -316.316614) (xy 173.151556 -316.343263)
			(xy 173.144433 -316.390528) (xy 183.376822 -316.390528) (xy 183.380893 -316.334906) (xy 183.393019 -316.280469)
			(xy 183.412942 -316.228378) (xy 183.440238 -316.179743) (xy 183.474324 -316.1356) (xy 183.514473 -316.096891)
			(xy 183.559831 -316.06444) (xy 183.609431 -316.038939) (xy 183.662215 -316.020932) (xy 183.717058 -316.010802)
			(xy 183.772792 -316.008765) (xy 183.828229 -316.014865) (xy 183.882186 -316.028971) (xy 183.933515 -316.050783)
			(xy 183.981121 -316.079837) (xy 184.023989 -316.115512) (xy 184.061206 -316.157049) (xy 184.091979 -316.203562)
			(xy 184.115651 -316.254059) (xy 184.131719 -316.307466) (xy 184.136987 -316.343263) (xy 187.527936 -316.343263)
			(xy 187.527936 -316.289965) (xy 187.535879 -316.237261) (xy 187.551589 -316.186331) (xy 187.574715 -316.13831)
			(xy 187.604739 -316.094273) (xy 187.640991 -316.055202) (xy 187.682662 -316.021971) (xy 187.72882 -315.995322)
			(xy 187.778434 -315.97585) (xy 187.830396 -315.96399) (xy 187.883546 -315.960007) (xy 187.936696 -315.96399)
			(xy 187.988658 -315.97585) (xy 188.038272 -315.995322) (xy 188.08443 -316.021971) (xy 188.126101 -316.055202)
			(xy 188.162353 -316.094273) (xy 188.192377 -316.13831) (xy 188.215503 -316.186331) (xy 188.231213 -316.237261)
			(xy 188.239156 -316.289965) (xy 188.239654 -316.316614) (xy 188.239156 -316.343263) (xy 202.615536 -316.343263)
			(xy 202.615536 -316.289965) (xy 202.623479 -316.237261) (xy 202.639189 -316.186331) (xy 202.662315 -316.13831)
			(xy 202.692339 -316.094273) (xy 202.728591 -316.055202) (xy 202.770262 -316.021971) (xy 202.81642 -315.995322)
			(xy 202.866034 -315.97585) (xy 202.917996 -315.96399) (xy 202.971146 -315.960007) (xy 203.024296 -315.96399)
			(xy 203.076258 -315.97585) (xy 203.125872 -315.995322) (xy 203.17203 -316.021971) (xy 203.213701 -316.055202)
			(xy 203.249953 -316.094273) (xy 203.279977 -316.13831) (xy 203.303103 -316.186331) (xy 203.318813 -316.237261)
			(xy 203.326756 -316.289965) (xy 203.327254 -316.316614) (xy 203.326756 -316.343263) (xy 203.318813 -316.395967)
			(xy 203.303103 -316.446897) (xy 203.279977 -316.494918) (xy 203.249953 -316.538955) (xy 203.213701 -316.578026)
			(xy 203.17203 -316.611257) (xy 203.125872 -316.637906) (xy 203.076258 -316.657378) (xy 203.024296 -316.669238)
			(xy 202.971146 -316.673222) (xy 202.917996 -316.669238) (xy 202.866034 -316.657378) (xy 202.81642 -316.637906)
			(xy 202.770262 -316.611257) (xy 202.728591 -316.578026) (xy 202.692339 -316.538955) (xy 202.662315 -316.494918)
			(xy 202.639189 -316.446897) (xy 202.623479 -316.395967) (xy 202.615536 -316.343263) (xy 188.239156 -316.343263)
			(xy 188.231213 -316.395967) (xy 188.215503 -316.446897) (xy 188.192377 -316.494918) (xy 188.162353 -316.538955)
			(xy 188.126101 -316.578026) (xy 188.08443 -316.611257) (xy 188.038272 -316.637906) (xy 187.988658 -316.657378)
			(xy 187.936696 -316.669238) (xy 187.883546 -316.673222) (xy 187.830396 -316.669238) (xy 187.778434 -316.657378)
			(xy 187.72882 -316.637906) (xy 187.682662 -316.611257) (xy 187.640991 -316.578026) (xy 187.604739 -316.538955)
			(xy 187.574715 -316.494918) (xy 187.551589 -316.446897) (xy 187.535879 -316.395967) (xy 187.527936 -316.343263)
			(xy 184.136987 -316.343263) (xy 184.139839 -316.362642) (xy 184.140348 -316.390528) (xy 184.139839 -316.418414)
			(xy 184.131719 -316.47359) (xy 184.115651 -316.526997) (xy 184.091979 -316.577494) (xy 184.061206 -316.624007)
			(xy 184.023989 -316.665544) (xy 183.981121 -316.701219) (xy 183.933515 -316.730273) (xy 183.882186 -316.752085)
			(xy 183.828229 -316.766191) (xy 183.772792 -316.772291) (xy 183.717058 -316.770254) (xy 183.662215 -316.760124)
			(xy 183.609431 -316.742117) (xy 183.559831 -316.716616) (xy 183.514473 -316.684165) (xy 183.474324 -316.645456)
			(xy 183.440238 -316.601313) (xy 183.412942 -316.552678) (xy 183.393019 -316.500587) (xy 183.380893 -316.44615)
			(xy 183.376822 -316.390528) (xy 173.144433 -316.390528) (xy 173.143613 -316.395967) (xy 173.127903 -316.446897)
			(xy 173.104777 -316.494918) (xy 173.074753 -316.538955) (xy 173.038501 -316.578026) (xy 172.99683 -316.611257)
			(xy 172.950672 -316.637906) (xy 172.901058 -316.657378) (xy 172.849096 -316.669238) (xy 172.795946 -316.673222)
			(xy 172.742796 -316.669238) (xy 172.690834 -316.657378) (xy 172.64122 -316.637906) (xy 172.595062 -316.611257)
			(xy 172.553391 -316.578026) (xy 172.517139 -316.538955) (xy 172.487115 -316.494918) (xy 172.463989 -316.446897)
			(xy 172.448279 -316.395967) (xy 172.440336 -316.343263) (xy 158.88716 -316.343263) (xy 158.88716 -317.218039)
			(xy 163.702228 -317.218039) (xy 163.702228 -317.164741) (xy 163.710171 -317.112037) (xy 163.725881 -317.061107)
			(xy 163.749007 -317.013086) (xy 163.779031 -316.969049) (xy 163.815283 -316.929978) (xy 163.856954 -316.896747)
			(xy 163.903112 -316.870098) (xy 163.952726 -316.850626) (xy 164.004688 -316.838766) (xy 164.057838 -316.834783)
			(xy 164.110988 -316.838766) (xy 164.16295 -316.850626) (xy 164.212564 -316.870098) (xy 164.258722 -316.896747)
			(xy 164.300393 -316.929978) (xy 164.336645 -316.969049) (xy 164.366669 -317.013086) (xy 164.389795 -317.061107)
			(xy 164.405505 -317.112037) (xy 164.413448 -317.164741) (xy 164.413946 -317.19139) (xy 164.413448 -317.218039)
			(xy 164.40962 -317.243439) (xy 171.230788 -317.243439) (xy 171.230788 -317.190141) (xy 171.238731 -317.137437)
			(xy 171.254441 -317.086507) (xy 171.277567 -317.038486) (xy 171.307591 -316.994449) (xy 171.343843 -316.955378)
			(xy 171.385514 -316.922147) (xy 171.431672 -316.895498) (xy 171.481286 -316.876026) (xy 171.533248 -316.864166)
			(xy 171.586398 -316.860183) (xy 171.639548 -316.864166) (xy 171.69151 -316.876026) (xy 171.741124 -316.895498)
			(xy 171.787282 -316.922147) (xy 171.828953 -316.955378) (xy 171.865205 -316.994449) (xy 171.895229 -317.038486)
			(xy 171.918355 -317.086507) (xy 171.934065 -317.137437) (xy 171.942008 -317.190141) (xy 171.942069 -317.193401)
			(xy 176.540404 -317.193401) (xy 176.540404 -317.140103) (xy 176.548347 -317.087399) (xy 176.564057 -317.036469)
			(xy 176.587183 -316.988448) (xy 176.617207 -316.944411) (xy 176.653459 -316.90534) (xy 176.69513 -316.872109)
			(xy 176.741288 -316.84546) (xy 176.790902 -316.825988) (xy 176.842864 -316.814128) (xy 176.896014 -316.810145)
			(xy 176.949164 -316.814128) (xy 177.001126 -316.825988) (xy 177.05074 -316.84546) (xy 177.096898 -316.872109)
			(xy 177.138569 -316.90534) (xy 177.174821 -316.944411) (xy 177.204845 -316.988448) (xy 177.227971 -317.036469)
			(xy 177.243681 -317.087399) (xy 177.251624 -317.140103) (xy 177.252122 -317.166752) (xy 177.251624 -317.193401)
			(xy 184.084204 -317.193401) (xy 184.084204 -317.140103) (xy 184.092147 -317.087399) (xy 184.107857 -317.036469)
			(xy 184.130983 -316.988448) (xy 184.161007 -316.944411) (xy 184.197259 -316.90534) (xy 184.23893 -316.872109)
			(xy 184.285088 -316.84546) (xy 184.334702 -316.825988) (xy 184.386664 -316.814128) (xy 184.439814 -316.810145)
			(xy 184.492964 -316.814128) (xy 184.544926 -316.825988) (xy 184.59454 -316.84546) (xy 184.640698 -316.872109)
			(xy 184.682369 -316.90534) (xy 184.718621 -316.944411) (xy 184.748645 -316.988448) (xy 184.771771 -317.036469)
			(xy 184.787481 -317.087399) (xy 184.795424 -317.140103) (xy 184.795528 -317.145649) (xy 190.37045 -317.145649)
			(xy 190.37045 -317.092351) (xy 190.378393 -317.039647) (xy 190.394103 -316.988717) (xy 190.417229 -316.940696)
			(xy 190.447253 -316.896659) (xy 190.483505 -316.857588) (xy 190.525176 -316.824357) (xy 190.571334 -316.797708)
			(xy 190.620948 -316.778236) (xy 190.67291 -316.766376) (xy 190.72606 -316.762393) (xy 190.77921 -316.766376)
			(xy 190.831172 -316.778236) (xy 190.880786 -316.797708) (xy 190.926944 -316.824357) (xy 190.968615 -316.857588)
			(xy 191.004867 -316.896659) (xy 191.034891 -316.940696) (xy 191.058017 -316.988717) (xy 191.073727 -317.039647)
			(xy 191.08167 -317.092351) (xy 191.082168 -317.119) (xy 191.08167 -317.145649) (xy 191.074473 -317.193401)
			(xy 191.628004 -317.193401) (xy 191.628004 -317.140103) (xy 191.635947 -317.087399) (xy 191.651657 -317.036469)
			(xy 191.674783 -316.988448) (xy 191.704807 -316.944411) (xy 191.741059 -316.90534) (xy 191.78273 -316.872109)
			(xy 191.828888 -316.84546) (xy 191.878502 -316.825988) (xy 191.930464 -316.814128) (xy 191.983614 -316.810145)
			(xy 192.036764 -316.814128) (xy 192.088726 -316.825988) (xy 192.13834 -316.84546) (xy 192.184498 -316.872109)
			(xy 192.226169 -316.90534) (xy 192.262421 -316.944411) (xy 192.292445 -316.988448) (xy 192.315571 -317.036469)
			(xy 192.331281 -317.087399) (xy 192.339224 -317.140103) (xy 192.339722 -317.166752) (xy 192.339224 -317.193401)
			(xy 199.171804 -317.193401) (xy 199.171804 -317.140103) (xy 199.179747 -317.087399) (xy 199.195457 -317.036469)
			(xy 199.218583 -316.988448) (xy 199.248607 -316.944411) (xy 199.284859 -316.90534) (xy 199.32653 -316.872109)
			(xy 199.372688 -316.84546) (xy 199.422302 -316.825988) (xy 199.474264 -316.814128) (xy 199.527414 -316.810145)
			(xy 199.580564 -316.814128) (xy 199.632526 -316.825988) (xy 199.68214 -316.84546) (xy 199.728298 -316.872109)
			(xy 199.769969 -316.90534) (xy 199.806221 -316.944411) (xy 199.836245 -316.988448) (xy 199.859371 -317.036469)
			(xy 199.875081 -317.087399) (xy 199.883024 -317.140103) (xy 199.883522 -317.166752) (xy 199.883024 -317.193401)
			(xy 206.715604 -317.193401) (xy 206.715604 -317.140103) (xy 206.723547 -317.087399) (xy 206.739257 -317.036469)
			(xy 206.762383 -316.988448) (xy 206.792407 -316.944411) (xy 206.828659 -316.90534) (xy 206.87033 -316.872109)
			(xy 206.916488 -316.84546) (xy 206.966102 -316.825988) (xy 207.018064 -316.814128) (xy 207.071214 -316.810145)
			(xy 207.124364 -316.814128) (xy 207.176326 -316.825988) (xy 207.22594 -316.84546) (xy 207.272098 -316.872109)
			(xy 207.313769 -316.90534) (xy 207.350021 -316.944411) (xy 207.380045 -316.988448) (xy 207.403171 -317.036469)
			(xy 207.409818 -317.058019) (xy 214.273628 -317.058019) (xy 214.273628 -317.004721) (xy 214.281571 -316.952017)
			(xy 214.297281 -316.901087) (xy 214.320407 -316.853066) (xy 214.350431 -316.809029) (xy 214.386683 -316.769958)
			(xy 214.428354 -316.736727) (xy 214.474512 -316.710078) (xy 214.524126 -316.690606) (xy 214.576088 -316.678746)
			(xy 214.629238 -316.674763) (xy 214.682388 -316.678746) (xy 214.73435 -316.690606) (xy 214.783964 -316.710078)
			(xy 214.830122 -316.736727) (xy 214.871793 -316.769958) (xy 214.908045 -316.809029) (xy 214.938069 -316.853066)
			(xy 214.961195 -316.901087) (xy 214.976905 -316.952017) (xy 214.984848 -317.004721) (xy 214.985346 -317.03137)
			(xy 214.984848 -317.058019) (xy 214.976905 -317.110723) (xy 214.961195 -317.161653) (xy 214.938069 -317.209674)
			(xy 214.908045 -317.253711) (xy 214.871793 -317.292782) (xy 214.830122 -317.326013) (xy 214.783964 -317.352662)
			(xy 214.73435 -317.372134) (xy 214.682388 -317.383994) (xy 214.629238 -317.387978) (xy 214.576088 -317.383994)
			(xy 214.524126 -317.372134) (xy 214.474512 -317.352662) (xy 214.428354 -317.326013) (xy 214.386683 -317.292782)
			(xy 214.350431 -317.253711) (xy 214.320407 -317.209674) (xy 214.297281 -317.161653) (xy 214.281571 -317.110723)
			(xy 214.273628 -317.058019) (xy 207.409818 -317.058019) (xy 207.418881 -317.087399) (xy 207.426824 -317.140103)
			(xy 207.427322 -317.166752) (xy 207.426824 -317.193401) (xy 207.418881 -317.246105) (xy 207.403171 -317.297035)
			(xy 207.380045 -317.345056) (xy 207.350021 -317.389093) (xy 207.313769 -317.428164) (xy 207.272098 -317.461395)
			(xy 207.22594 -317.488044) (xy 207.176326 -317.507516) (xy 207.124364 -317.519376) (xy 207.071214 -317.52336)
			(xy 207.018064 -317.519376) (xy 206.966102 -317.507516) (xy 206.916488 -317.488044) (xy 206.87033 -317.461395)
			(xy 206.828659 -317.428164) (xy 206.792407 -317.389093) (xy 206.762383 -317.345056) (xy 206.739257 -317.297035)
			(xy 206.723547 -317.246105) (xy 206.715604 -317.193401) (xy 199.883024 -317.193401) (xy 199.875081 -317.246105)
			(xy 199.859371 -317.297035) (xy 199.836245 -317.345056) (xy 199.806221 -317.389093) (xy 199.769969 -317.428164)
			(xy 199.728298 -317.461395) (xy 199.68214 -317.488044) (xy 199.632526 -317.507516) (xy 199.580564 -317.519376)
			(xy 199.527414 -317.52336) (xy 199.474264 -317.519376) (xy 199.422302 -317.507516) (xy 199.372688 -317.488044)
			(xy 199.32653 -317.461395) (xy 199.284859 -317.428164) (xy 199.248607 -317.389093) (xy 199.218583 -317.345056)
			(xy 199.195457 -317.297035) (xy 199.179747 -317.246105) (xy 199.171804 -317.193401) (xy 192.339224 -317.193401)
			(xy 192.331281 -317.246105) (xy 192.315571 -317.297035) (xy 192.292445 -317.345056) (xy 192.262421 -317.389093)
			(xy 192.226169 -317.428164) (xy 192.184498 -317.461395) (xy 192.13834 -317.488044) (xy 192.088726 -317.507516)
			(xy 192.036764 -317.519376) (xy 191.983614 -317.52336) (xy 191.930464 -317.519376) (xy 191.878502 -317.507516)
			(xy 191.828888 -317.488044) (xy 191.78273 -317.461395) (xy 191.741059 -317.428164) (xy 191.704807 -317.389093)
			(xy 191.674783 -317.345056) (xy 191.651657 -317.297035) (xy 191.635947 -317.246105) (xy 191.628004 -317.193401)
			(xy 191.074473 -317.193401) (xy 191.073727 -317.198353) (xy 191.058017 -317.249283) (xy 191.034891 -317.297304)
			(xy 191.004867 -317.341341) (xy 190.968615 -317.380412) (xy 190.926944 -317.413643) (xy 190.880786 -317.440292)
			(xy 190.831172 -317.459764) (xy 190.77921 -317.471624) (xy 190.72606 -317.475608) (xy 190.67291 -317.471624)
			(xy 190.620948 -317.459764) (xy 190.571334 -317.440292) (xy 190.525176 -317.413643) (xy 190.483505 -317.380412)
			(xy 190.447253 -317.341341) (xy 190.417229 -317.297304) (xy 190.394103 -317.249283) (xy 190.378393 -317.198353)
			(xy 190.37045 -317.145649) (xy 184.795528 -317.145649) (xy 184.795922 -317.166752) (xy 184.795424 -317.193401)
			(xy 184.787481 -317.246105) (xy 184.771771 -317.297035) (xy 184.748645 -317.345056) (xy 184.718621 -317.389093)
			(xy 184.682369 -317.428164) (xy 184.640698 -317.461395) (xy 184.59454 -317.488044) (xy 184.544926 -317.507516)
			(xy 184.492964 -317.519376) (xy 184.439814 -317.52336) (xy 184.386664 -317.519376) (xy 184.334702 -317.507516)
			(xy 184.285088 -317.488044) (xy 184.23893 -317.461395) (xy 184.197259 -317.428164) (xy 184.161007 -317.389093)
			(xy 184.130983 -317.345056) (xy 184.107857 -317.297035) (xy 184.092147 -317.246105) (xy 184.084204 -317.193401)
			(xy 177.251624 -317.193401) (xy 177.243681 -317.246105) (xy 177.227971 -317.297035) (xy 177.204845 -317.345056)
			(xy 177.174821 -317.389093) (xy 177.138569 -317.428164) (xy 177.096898 -317.461395) (xy 177.05074 -317.488044)
			(xy 177.001126 -317.507516) (xy 176.949164 -317.519376) (xy 176.896014 -317.52336) (xy 176.842864 -317.519376)
			(xy 176.790902 -317.507516) (xy 176.741288 -317.488044) (xy 176.69513 -317.461395) (xy 176.653459 -317.428164)
			(xy 176.617207 -317.389093) (xy 176.587183 -317.345056) (xy 176.564057 -317.297035) (xy 176.548347 -317.246105)
			(xy 176.540404 -317.193401) (xy 171.942069 -317.193401) (xy 171.942506 -317.21679) (xy 171.942008 -317.243439)
			(xy 171.934065 -317.296143) (xy 171.918355 -317.347073) (xy 171.895229 -317.395094) (xy 171.865205 -317.439131)
			(xy 171.828953 -317.478202) (xy 171.787282 -317.511433) (xy 171.741124 -317.538082) (xy 171.69151 -317.557554)
			(xy 171.639548 -317.569414) (xy 171.586398 -317.573398) (xy 171.533248 -317.569414) (xy 171.481286 -317.557554)
			(xy 171.431672 -317.538082) (xy 171.385514 -317.511433) (xy 171.343843 -317.478202) (xy 171.307591 -317.439131)
			(xy 171.277567 -317.395094) (xy 171.254441 -317.347073) (xy 171.238731 -317.296143) (xy 171.230788 -317.243439)
			(xy 164.40962 -317.243439) (xy 164.405505 -317.270743) (xy 164.389795 -317.321673) (xy 164.366669 -317.369694)
			(xy 164.336645 -317.413731) (xy 164.300393 -317.452802) (xy 164.258722 -317.486033) (xy 164.212564 -317.512682)
			(xy 164.16295 -317.532154) (xy 164.110988 -317.544014) (xy 164.057838 -317.547998) (xy 164.004688 -317.544014)
			(xy 163.952726 -317.532154) (xy 163.903112 -317.512682) (xy 163.856954 -317.486033) (xy 163.815283 -317.452802)
			(xy 163.779031 -317.413731) (xy 163.749007 -317.369694) (xy 163.725881 -317.321673) (xy 163.710171 -317.270743)
			(xy 163.702228 -317.218039) (xy 158.88716 -317.218039) (xy 158.88716 -317.590932) (xy 216.59418 -317.590932)
			(xy 216.598251 -317.53531) (xy 216.610377 -317.480873) (xy 216.6303 -317.428782) (xy 216.657596 -317.380147)
			(xy 216.691682 -317.336004) (xy 216.731831 -317.297295) (xy 216.777189 -317.264844) (xy 216.826789 -317.239343)
			(xy 216.879573 -317.221336) (xy 216.934416 -317.211206) (xy 216.99015 -317.209169) (xy 217.045587 -317.215269)
			(xy 217.099544 -317.229375) (xy 217.150873 -317.251187) (xy 217.198479 -317.280241) (xy 217.241347 -317.315916)
			(xy 217.278564 -317.357453) (xy 217.309337 -317.403966) (xy 217.333009 -317.454463) (xy 217.349077 -317.50787)
			(xy 217.357197 -317.563046) (xy 217.357706 -317.590932) (xy 217.357197 -317.618818) (xy 217.349077 -317.673994)
			(xy 217.333009 -317.727401) (xy 217.309337 -317.777898) (xy 217.278564 -317.824411) (xy 217.241347 -317.865948)
			(xy 217.198479 -317.901623) (xy 217.150873 -317.930677) (xy 217.099544 -317.952489) (xy 217.045587 -317.966595)
			(xy 216.99015 -317.972695) (xy 216.934416 -317.970658) (xy 216.879573 -317.960528) (xy 216.826789 -317.942521)
			(xy 216.777189 -317.91702) (xy 216.731831 -317.884569) (xy 216.691682 -317.84586) (xy 216.657596 -317.801717)
			(xy 216.6303 -317.753082) (xy 216.610377 -317.700991) (xy 216.598251 -317.646554) (xy 216.59418 -317.590932)
			(xy 158.88716 -317.590932) (xy 158.88716 -318.043285) (xy 161.452804 -318.043285) (xy 161.452804 -317.989987)
			(xy 161.460747 -317.937283) (xy 161.476457 -317.886353) (xy 161.499583 -317.838332) (xy 161.529607 -317.794295)
			(xy 161.565859 -317.755224) (xy 161.60753 -317.721993) (xy 161.653688 -317.695344) (xy 161.703302 -317.675872)
			(xy 161.755264 -317.664012) (xy 161.808414 -317.660029) (xy 161.861564 -317.664012) (xy 161.913526 -317.675872)
			(xy 161.96314 -317.695344) (xy 162.009298 -317.721993) (xy 162.050969 -317.755224) (xy 162.087221 -317.794295)
			(xy 162.117245 -317.838332) (xy 162.140371 -317.886353) (xy 162.156081 -317.937283) (xy 162.164024 -317.989987)
			(xy 162.164522 -318.016636) (xy 162.164024 -318.043285) (xy 168.996604 -318.043285) (xy 168.996604 -317.989987)
			(xy 169.004547 -317.937283) (xy 169.020257 -317.886353) (xy 169.043383 -317.838332) (xy 169.073407 -317.794295)
			(xy 169.109659 -317.755224) (xy 169.15133 -317.721993) (xy 169.197488 -317.695344) (xy 169.247102 -317.675872)
			(xy 169.299064 -317.664012) (xy 169.352214 -317.660029) (xy 169.405364 -317.664012) (xy 169.457326 -317.675872)
			(xy 169.50694 -317.695344) (xy 169.553098 -317.721993) (xy 169.594769 -317.755224) (xy 169.631021 -317.794295)
			(xy 169.661045 -317.838332) (xy 169.684171 -317.886353) (xy 169.699881 -317.937283) (xy 169.707824 -317.989987)
			(xy 169.708322 -318.016636) (xy 169.707824 -318.043285) (xy 169.699881 -318.095989) (xy 169.684171 -318.146919)
			(xy 169.679524 -318.156569) (xy 175.471572 -318.156569) (xy 175.471572 -318.103271) (xy 175.479515 -318.050567)
			(xy 175.495225 -317.999637) (xy 175.518351 -317.951616) (xy 175.548375 -317.907579) (xy 175.584627 -317.868508)
			(xy 175.626298 -317.835277) (xy 175.672456 -317.808628) (xy 175.72207 -317.789156) (xy 175.774032 -317.777296)
			(xy 175.827182 -317.773313) (xy 175.880332 -317.777296) (xy 175.932294 -317.789156) (xy 175.981908 -317.808628)
			(xy 176.028066 -317.835277) (xy 176.069737 -317.868508) (xy 176.105989 -317.907579) (xy 176.136013 -317.951616)
			(xy 176.159139 -317.999637) (xy 176.172603 -318.043285) (xy 178.723788 -318.043285) (xy 178.723788 -317.989987)
			(xy 178.731731 -317.937283) (xy 178.747441 -317.886353) (xy 178.770567 -317.838332) (xy 178.800591 -317.794295)
			(xy 178.836843 -317.755224) (xy 178.878514 -317.721993) (xy 178.924672 -317.695344) (xy 178.974286 -317.675872)
			(xy 179.026248 -317.664012) (xy 179.079398 -317.660029) (xy 179.132548 -317.664012) (xy 179.18451 -317.675872)
			(xy 179.234124 -317.695344) (xy 179.280282 -317.721993) (xy 179.321953 -317.755224) (xy 179.358205 -317.794295)
			(xy 179.388229 -317.838332) (xy 179.411355 -317.886353) (xy 179.427065 -317.937283) (xy 179.435008 -317.989987)
			(xy 179.435506 -318.016636) (xy 179.435008 -318.043285) (xy 186.326008 -318.043285) (xy 186.326008 -317.989987)
			(xy 186.333951 -317.937283) (xy 186.349661 -317.886353) (xy 186.372787 -317.838332) (xy 186.402811 -317.794295)
			(xy 186.439063 -317.755224) (xy 186.480734 -317.721993) (xy 186.526892 -317.695344) (xy 186.576506 -317.675872)
			(xy 186.628468 -317.664012) (xy 186.681618 -317.660029) (xy 186.734768 -317.664012) (xy 186.78673 -317.675872)
			(xy 186.836344 -317.695344) (xy 186.882502 -317.721993) (xy 186.924173 -317.755224) (xy 186.960425 -317.794295)
			(xy 186.990449 -317.838332) (xy 187.013575 -317.886353) (xy 187.029285 -317.937283) (xy 187.037228 -317.989987)
			(xy 187.037726 -318.016636) (xy 187.037228 -318.043285) (xy 191.628004 -318.043285) (xy 191.628004 -317.989987)
			(xy 191.635947 -317.937283) (xy 191.651657 -317.886353) (xy 191.674783 -317.838332) (xy 191.704807 -317.794295)
			(xy 191.741059 -317.755224) (xy 191.78273 -317.721993) (xy 191.828888 -317.695344) (xy 191.878502 -317.675872)
			(xy 191.930464 -317.664012) (xy 191.983614 -317.660029) (xy 192.036764 -317.664012) (xy 192.088726 -317.675872)
			(xy 192.13834 -317.695344) (xy 192.184498 -317.721993) (xy 192.226169 -317.755224) (xy 192.262421 -317.794295)
			(xy 192.292445 -317.838332) (xy 192.315571 -317.886353) (xy 192.331281 -317.937283) (xy 192.339224 -317.989987)
			(xy 192.339552 -318.007539) (xy 201.359405 -318.007539) (xy 201.364888 -317.95366) (xy 201.378467 -317.901233)
			(xy 201.399828 -317.851466) (xy 201.428479 -317.805508) (xy 201.463759 -317.764418) (xy 201.504854 -317.729145)
			(xy 201.550817 -317.700501) (xy 201.600588 -317.679148) (xy 201.653017 -317.665578) (xy 201.706897 -317.660104)
			(xy 201.760985 -317.662851) (xy 201.814033 -317.673758) (xy 201.864818 -317.692572) (xy 201.912168 -317.718859)
			(xy 201.954991 -317.752013) (xy 201.9923 -317.79127) (xy 202.023234 -317.835723) (xy 202.04708 -317.884348)
			(xy 202.063288 -317.936023) (xy 202.071483 -317.989557) (xy 202.071986 -318.016636) (xy 202.07145 -318.043285)
			(xy 208.909148 -318.043285) (xy 208.909148 -317.989987) (xy 208.917091 -317.937283) (xy 208.932801 -317.886353)
			(xy 208.955927 -317.838332) (xy 208.985951 -317.794295) (xy 209.022203 -317.755224) (xy 209.063874 -317.721993)
			(xy 209.110032 -317.695344) (xy 209.159646 -317.675872) (xy 209.211608 -317.664012) (xy 209.264758 -317.660029)
			(xy 209.317908 -317.664012) (xy 209.36987 -317.675872) (xy 209.419484 -317.695344) (xy 209.465642 -317.721993)
			(xy 209.507313 -317.755224) (xy 209.543565 -317.794295) (xy 209.573589 -317.838332) (xy 209.596715 -317.886353)
			(xy 209.612425 -317.937283) (xy 209.620368 -317.989987) (xy 209.620866 -318.016636) (xy 209.620368 -318.043285)
			(xy 214.259404 -318.043285) (xy 214.259404 -317.989987) (xy 214.267347 -317.937283) (xy 214.283057 -317.886353)
			(xy 214.306183 -317.838332) (xy 214.336207 -317.794295) (xy 214.372459 -317.755224) (xy 214.41413 -317.721993)
			(xy 214.460288 -317.695344) (xy 214.509902 -317.675872) (xy 214.561864 -317.664012) (xy 214.615014 -317.660029)
			(xy 214.668164 -317.664012) (xy 214.720126 -317.675872) (xy 214.76974 -317.695344) (xy 214.815898 -317.721993)
			(xy 214.857569 -317.755224) (xy 214.893821 -317.794295) (xy 214.923845 -317.838332) (xy 214.946971 -317.886353)
			(xy 214.962681 -317.937283) (xy 214.970624 -317.989987) (xy 214.971122 -318.016636) (xy 214.970624 -318.043285)
			(xy 214.962681 -318.095989) (xy 214.946971 -318.146919) (xy 214.923845 -318.19494) (xy 214.893821 -318.238977)
			(xy 214.857569 -318.278048) (xy 214.815898 -318.311279) (xy 214.76974 -318.337928) (xy 214.720126 -318.3574)
			(xy 214.668164 -318.36926) (xy 214.615014 -318.373244) (xy 214.561864 -318.36926) (xy 214.509902 -318.3574)
			(xy 214.460288 -318.337928) (xy 214.41413 -318.311279) (xy 214.372459 -318.278048) (xy 214.336207 -318.238977)
			(xy 214.306183 -318.19494) (xy 214.283057 -318.146919) (xy 214.267347 -318.095989) (xy 214.259404 -318.043285)
			(xy 209.620368 -318.043285) (xy 209.612425 -318.095989) (xy 209.596715 -318.146919) (xy 209.573589 -318.19494)
			(xy 209.543565 -318.238977) (xy 209.507313 -318.278048) (xy 209.465642 -318.311279) (xy 209.419484 -318.337928)
			(xy 209.36987 -318.3574) (xy 209.317908 -318.36926) (xy 209.264758 -318.373244) (xy 209.211608 -318.36926)
			(xy 209.159646 -318.3574) (xy 209.110032 -318.337928) (xy 209.063874 -318.311279) (xy 209.022203 -318.278048)
			(xy 208.985951 -318.238977) (xy 208.955927 -318.19494) (xy 208.932801 -318.146919) (xy 208.917091 -318.095989)
			(xy 208.909148 -318.043285) (xy 202.07145 -318.043285) (xy 202.071359 -318.047836) (xy 202.060495 -318.109283)
			(xy 202.050396 -318.13881) (xy 202.046157 -318.151897) (xy 202.043956 -318.179301) (xy 202.049146 -318.2063)
			(xy 202.061353 -318.230934) (xy 202.07969 -318.251419) (xy 202.102828 -318.266268) (xy 202.129089 -318.274404)
			(xy 202.156569 -318.275239) (xy 202.17003 -318.272414) (xy 202.190969 -318.267569) (xy 202.233631 -318.262353)
			(xy 202.25512 -318.262) (xy 202.282198 -318.262519) (xy 202.33573 -318.270723) (xy 202.387402 -318.286938)
			(xy 202.436022 -318.31079) (xy 202.48047 -318.34173) (xy 202.519721 -318.379044) (xy 202.552869 -318.421871)
			(xy 202.579149 -318.469223) (xy 202.597956 -318.520009) (xy 202.608856 -318.573057) (xy 202.611597 -318.627144)
			(xy 202.606117 -318.681023) (xy 202.592541 -318.73345) (xy 202.571183 -318.783217) (xy 202.542535 -318.829176)
			(xy 202.507259 -318.870267) (xy 202.480284 -318.893423) (xy 206.715604 -318.893423) (xy 206.715604 -318.840125)
			(xy 206.723547 -318.787421) (xy 206.739257 -318.736491) (xy 206.762383 -318.68847) (xy 206.792407 -318.644433)
			(xy 206.828659 -318.605362) (xy 206.87033 -318.572131) (xy 206.916488 -318.545482) (xy 206.966102 -318.52601)
			(xy 207.018064 -318.51415) (xy 207.071214 -318.510167) (xy 207.124364 -318.51415) (xy 207.176326 -318.52601)
			(xy 207.22594 -318.545482) (xy 207.272098 -318.572131) (xy 207.313769 -318.605362) (xy 207.350021 -318.644433)
			(xy 207.376391 -318.683111) (xy 209.575644 -318.683111) (xy 209.575644 -318.629813) (xy 209.583587 -318.577109)
			(xy 209.599297 -318.526179) (xy 209.622423 -318.478158) (xy 209.652447 -318.434121) (xy 209.688699 -318.39505)
			(xy 209.73037 -318.361819) (xy 209.776528 -318.33517) (xy 209.826142 -318.315698) (xy 209.878104 -318.303838)
			(xy 209.931254 -318.299855) (xy 209.984404 -318.303838) (xy 210.036366 -318.315698) (xy 210.08598 -318.33517)
			(xy 210.132138 -318.361819) (xy 210.173809 -318.39505) (xy 210.210061 -318.434121) (xy 210.240085 -318.478158)
			(xy 210.263211 -318.526179) (xy 210.278921 -318.577109) (xy 210.286864 -318.629813) (xy 210.287362 -318.656462)
			(xy 210.286864 -318.683111) (xy 210.278921 -318.735815) (xy 210.263211 -318.786745) (xy 210.240085 -318.834766)
			(xy 210.210061 -318.878803) (xy 210.173809 -318.917874) (xy 210.132138 -318.951105) (xy 210.08598 -318.977754)
			(xy 210.036366 -318.997226) (xy 209.984404 -319.009086) (xy 209.931254 -319.01307) (xy 209.878104 -319.009086)
			(xy 209.826142 -318.997226) (xy 209.776528 -318.977754) (xy 209.73037 -318.951105) (xy 209.688699 -318.917874)
			(xy 209.652447 -318.878803) (xy 209.622423 -318.834766) (xy 209.599297 -318.786745) (xy 209.583587 -318.735815)
			(xy 209.575644 -318.683111) (xy 207.376391 -318.683111) (xy 207.380045 -318.68847) (xy 207.403171 -318.736491)
			(xy 207.418881 -318.787421) (xy 207.426824 -318.840125) (xy 207.427322 -318.866774) (xy 207.426824 -318.893423)
			(xy 207.418881 -318.946127) (xy 207.403171 -318.997057) (xy 207.380045 -319.045078) (xy 207.350021 -319.089115)
			(xy 207.313769 -319.128186) (xy 207.272098 -319.161417) (xy 207.22594 -319.188066) (xy 207.176326 -319.207538)
			(xy 207.124364 -319.219398) (xy 207.071214 -319.223382) (xy 207.018064 -319.219398) (xy 206.966102 -319.207538)
			(xy 206.916488 -319.188066) (xy 206.87033 -319.161417) (xy 206.828659 -319.128186) (xy 206.792407 -319.089115)
			(xy 206.762383 -319.045078) (xy 206.739257 -318.997057) (xy 206.723547 -318.946127) (xy 206.715604 -318.893423)
			(xy 202.480284 -318.893423) (xy 202.466166 -318.905542) (xy 202.420206 -318.934189) (xy 202.370439 -318.955545)
			(xy 202.318011 -318.969119) (xy 202.264132 -318.974598) (xy 202.210046 -318.971854) (xy 202.156998 -318.960953)
			(xy 202.106212 -318.942144) (xy 202.058861 -318.915862) (xy 202.016035 -318.882713) (xy 201.978723 -318.843461)
			(xy 201.947784 -318.799012) (xy 201.923933 -318.75039) (xy 201.90772 -318.698718) (xy 201.899518 -318.645186)
			(xy 201.899012 -318.618108) (xy 201.899651 -318.586908) (xy 201.910506 -318.525462) (xy 201.920602 -318.495934)
			(xy 201.924907 -318.482868) (xy 201.927097 -318.455456) (xy 201.921896 -318.428452) (xy 201.909679 -318.403815)
			(xy 201.891334 -318.383328) (xy 201.868188 -318.368479) (xy 201.84192 -318.360341) (xy 201.814432 -318.359505)
			(xy 201.800968 -318.36233) (xy 201.780029 -318.367174) (xy 201.737367 -318.372391) (xy 201.715878 -318.372744)
			(xy 201.688799 -318.372179) (xy 201.635267 -318.363974) (xy 201.583594 -318.347758) (xy 201.534973 -318.323905)
			(xy 201.490524 -318.292963) (xy 201.451274 -318.255648) (xy 201.418127 -318.212819) (xy 201.391848 -318.165465)
			(xy 201.373042 -318.114677) (xy 201.362144 -318.061627) (xy 201.359405 -318.007539) (xy 192.339552 -318.007539)
			(xy 192.339722 -318.016636) (xy 192.339224 -318.043285) (xy 192.331281 -318.095989) (xy 192.315571 -318.146919)
			(xy 192.292445 -318.19494) (xy 192.262421 -318.238977) (xy 192.226169 -318.278048) (xy 192.184498 -318.311279)
			(xy 192.13834 -318.337928) (xy 192.088726 -318.3574) (xy 192.036764 -318.36926) (xy 191.983614 -318.373244)
			(xy 191.930464 -318.36926) (xy 191.878502 -318.3574) (xy 191.828888 -318.337928) (xy 191.78273 -318.311279)
			(xy 191.741059 -318.278048) (xy 191.704807 -318.238977) (xy 191.674783 -318.19494) (xy 191.651657 -318.146919)
			(xy 191.635947 -318.095989) (xy 191.628004 -318.043285) (xy 187.037228 -318.043285) (xy 187.029285 -318.095989)
			(xy 187.013575 -318.146919) (xy 186.990449 -318.19494) (xy 186.960425 -318.238977) (xy 186.924173 -318.278048)
			(xy 186.882502 -318.311279) (xy 186.836344 -318.337928) (xy 186.78673 -318.3574) (xy 186.734768 -318.36926)
			(xy 186.681618 -318.373244) (xy 186.628468 -318.36926) (xy 186.576506 -318.3574) (xy 186.526892 -318.337928)
			(xy 186.480734 -318.311279) (xy 186.439063 -318.278048) (xy 186.402811 -318.238977) (xy 186.372787 -318.19494)
			(xy 186.349661 -318.146919) (xy 186.333951 -318.095989) (xy 186.326008 -318.043285) (xy 179.435008 -318.043285)
			(xy 179.427065 -318.095989) (xy 179.411355 -318.146919) (xy 179.388229 -318.19494) (xy 179.358205 -318.238977)
			(xy 179.321953 -318.278048) (xy 179.280282 -318.311279) (xy 179.234124 -318.337928) (xy 179.18451 -318.3574)
			(xy 179.132548 -318.36926) (xy 179.079398 -318.373244) (xy 179.026248 -318.36926) (xy 178.974286 -318.3574)
			(xy 178.924672 -318.337928) (xy 178.878514 -318.311279) (xy 178.836843 -318.278048) (xy 178.800591 -318.238977)
			(xy 178.770567 -318.19494) (xy 178.747441 -318.146919) (xy 178.731731 -318.095989) (xy 178.723788 -318.043285)
			(xy 176.172603 -318.043285) (xy 176.174849 -318.050567) (xy 176.182792 -318.103271) (xy 176.18329 -318.12992)
			(xy 176.182792 -318.156569) (xy 176.174849 -318.209273) (xy 176.159139 -318.260203) (xy 176.136013 -318.308224)
			(xy 176.105989 -318.352261) (xy 176.069737 -318.391332) (xy 176.028066 -318.424563) (xy 175.981908 -318.451212)
			(xy 175.932294 -318.470684) (xy 175.880332 -318.482544) (xy 175.827182 -318.486528) (xy 175.774032 -318.482544)
			(xy 175.72207 -318.470684) (xy 175.672456 -318.451212) (xy 175.626298 -318.424563) (xy 175.584627 -318.391332)
			(xy 175.548375 -318.352261) (xy 175.518351 -318.308224) (xy 175.495225 -318.260203) (xy 175.479515 -318.209273)
			(xy 175.471572 -318.156569) (xy 169.679524 -318.156569) (xy 169.661045 -318.19494) (xy 169.631021 -318.238977)
			(xy 169.594769 -318.278048) (xy 169.553098 -318.311279) (xy 169.50694 -318.337928) (xy 169.457326 -318.3574)
			(xy 169.405364 -318.36926) (xy 169.352214 -318.373244) (xy 169.299064 -318.36926) (xy 169.247102 -318.3574)
			(xy 169.197488 -318.337928) (xy 169.15133 -318.311279) (xy 169.109659 -318.278048) (xy 169.073407 -318.238977)
			(xy 169.043383 -318.19494) (xy 169.020257 -318.146919) (xy 169.004547 -318.095989) (xy 168.996604 -318.043285)
			(xy 162.164024 -318.043285) (xy 162.156081 -318.095989) (xy 162.140371 -318.146919) (xy 162.117245 -318.19494)
			(xy 162.087221 -318.238977) (xy 162.050969 -318.278048) (xy 162.009298 -318.311279) (xy 161.96314 -318.337928)
			(xy 161.913526 -318.3574) (xy 161.861564 -318.36926) (xy 161.808414 -318.373244) (xy 161.755264 -318.36926)
			(xy 161.703302 -318.3574) (xy 161.653688 -318.337928) (xy 161.60753 -318.311279) (xy 161.565859 -318.278048)
			(xy 161.529607 -318.238977) (xy 161.499583 -318.19494) (xy 161.476457 -318.146919) (xy 161.460747 -318.095989)
			(xy 161.452804 -318.043285) (xy 158.88716 -318.043285) (xy 158.88716 -318.893423) (xy 159.587936 -318.893423)
			(xy 159.587936 -318.840125) (xy 159.595879 -318.787421) (xy 159.611589 -318.736491) (xy 159.634715 -318.68847)
			(xy 159.664739 -318.644433) (xy 159.700991 -318.605362) (xy 159.742662 -318.572131) (xy 159.78882 -318.545482)
			(xy 159.838434 -318.52601) (xy 159.890396 -318.51415) (xy 159.943546 -318.510167) (xy 159.996696 -318.51415)
			(xy 160.048658 -318.52601) (xy 160.098272 -318.545482) (xy 160.126801 -318.561953) (xy 164.205148 -318.561953)
			(xy 164.205148 -318.508655) (xy 164.213091 -318.455951) (xy 164.228801 -318.405021) (xy 164.251927 -318.357)
			(xy 164.281951 -318.312963) (xy 164.318203 -318.273892) (xy 164.359874 -318.240661) (xy 164.406032 -318.214012)
			(xy 164.455646 -318.19454) (xy 164.507608 -318.18268) (xy 164.560758 -318.178697) (xy 164.613908 -318.18268)
			(xy 164.66587 -318.19454) (xy 164.715484 -318.214012) (xy 164.761642 -318.240661) (xy 164.803313 -318.273892)
			(xy 164.839565 -318.312963) (xy 164.869589 -318.357) (xy 164.892715 -318.405021) (xy 164.908425 -318.455951)
			(xy 164.916368 -318.508655) (xy 164.916866 -318.535304) (xy 164.916368 -318.561953) (xy 164.908425 -318.614657)
			(xy 164.892715 -318.665587) (xy 164.869589 -318.713608) (xy 164.839565 -318.757645) (xy 164.803313 -318.796716)
			(xy 164.761642 -318.829947) (xy 164.715484 -318.856596) (xy 164.66587 -318.876068) (xy 164.613908 -318.887928)
			(xy 164.560758 -318.891912) (xy 164.507608 -318.887928) (xy 164.455646 -318.876068) (xy 164.406032 -318.856596)
			(xy 164.359874 -318.829947) (xy 164.318203 -318.796716) (xy 164.281951 -318.757645) (xy 164.251927 -318.713608)
			(xy 164.228801 -318.665587) (xy 164.213091 -318.614657) (xy 164.205148 -318.561953) (xy 160.126801 -318.561953)
			(xy 160.14443 -318.572131) (xy 160.186101 -318.605362) (xy 160.222353 -318.644433) (xy 160.252377 -318.68847)
			(xy 160.275503 -318.736491) (xy 160.291213 -318.787421) (xy 160.299156 -318.840125) (xy 160.299654 -318.866774)
			(xy 160.299156 -318.893423) (xy 168.996604 -318.893423) (xy 168.996604 -318.840125) (xy 169.004547 -318.787421)
			(xy 169.020257 -318.736491) (xy 169.043383 -318.68847) (xy 169.073407 -318.644433) (xy 169.109659 -318.605362)
			(xy 169.15133 -318.572131) (xy 169.197488 -318.545482) (xy 169.247102 -318.52601) (xy 169.299064 -318.51415)
			(xy 169.352214 -318.510167) (xy 169.405364 -318.51415) (xy 169.457326 -318.52601) (xy 169.50694 -318.545482)
			(xy 169.553098 -318.572131) (xy 169.594769 -318.605362) (xy 169.631021 -318.644433) (xy 169.661045 -318.68847)
			(xy 169.684171 -318.736491) (xy 169.699881 -318.787421) (xy 169.707824 -318.840125) (xy 169.708322 -318.866774)
			(xy 169.707824 -318.893423) (xy 176.540404 -318.893423) (xy 176.540404 -318.840125) (xy 176.548347 -318.787421)
			(xy 176.564057 -318.736491) (xy 176.587183 -318.68847) (xy 176.617207 -318.644433) (xy 176.653459 -318.605362)
			(xy 176.69513 -318.572131) (xy 176.741288 -318.545482) (xy 176.790902 -318.52601) (xy 176.842864 -318.51415)
			(xy 176.896014 -318.510167) (xy 176.949164 -318.51415) (xy 177.001126 -318.52601) (xy 177.05074 -318.545482)
			(xy 177.096898 -318.572131) (xy 177.138569 -318.605362) (xy 177.174821 -318.644433) (xy 177.204845 -318.68847)
			(xy 177.227971 -318.736491) (xy 177.243681 -318.787421) (xy 177.251624 -318.840125) (xy 177.252122 -318.866774)
			(xy 177.251624 -318.893423) (xy 177.243681 -318.946127) (xy 177.227971 -318.997057) (xy 177.204845 -319.045078)
			(xy 177.174821 -319.089115) (xy 177.138569 -319.128186) (xy 177.096898 -319.161417) (xy 177.05074 -319.188066)
			(xy 177.03651 -319.193651) (xy 179.093612 -319.193651) (xy 179.093612 -319.140353) (xy 179.101555 -319.087649)
			(xy 179.117265 -319.036719) (xy 179.140391 -318.988698) (xy 179.170415 -318.944661) (xy 179.206667 -318.90559)
			(xy 179.248338 -318.872359) (xy 179.294496 -318.84571) (xy 179.34411 -318.826238) (xy 179.396072 -318.814378)
			(xy 179.449222 -318.810395) (xy 179.502372 -318.814378) (xy 179.554334 -318.826238) (xy 179.603948 -318.84571)
			(xy 179.650106 -318.872359) (xy 179.67652 -318.893423) (xy 184.084204 -318.893423) (xy 184.084204 -318.840125)
			(xy 184.092147 -318.787421) (xy 184.107857 -318.736491) (xy 184.130983 -318.68847) (xy 184.161007 -318.644433)
			(xy 184.197259 -318.605362) (xy 184.23893 -318.572131) (xy 184.285088 -318.545482) (xy 184.334702 -318.52601)
			(xy 184.386664 -318.51415) (xy 184.439814 -318.510167) (xy 184.492964 -318.51415) (xy 184.544926 -318.52601)
			(xy 184.59454 -318.545482) (xy 184.640698 -318.572131) (xy 184.660742 -318.588115) (xy 190.15455 -318.588115)
			(xy 190.15455 -318.534817) (xy 190.162493 -318.482113) (xy 190.178203 -318.431183) (xy 190.201329 -318.383162)
			(xy 190.231353 -318.339125) (xy 190.267605 -318.300054) (xy 190.309276 -318.266823) (xy 190.355434 -318.240174)
			(xy 190.405048 -318.220702) (xy 190.45701 -318.208842) (xy 190.51016 -318.204859) (xy 190.56331 -318.208842)
			(xy 190.615272 -318.220702) (xy 190.664886 -318.240174) (xy 190.711044 -318.266823) (xy 190.752715 -318.300054)
			(xy 190.788967 -318.339125) (xy 190.818991 -318.383162) (xy 190.842117 -318.431183) (xy 190.857827 -318.482113)
			(xy 190.86577 -318.534817) (xy 190.866268 -318.561466) (xy 190.86577 -318.588115) (xy 190.857827 -318.640819)
			(xy 190.842117 -318.691749) (xy 190.818991 -318.73977) (xy 190.788967 -318.783807) (xy 190.752715 -318.822878)
			(xy 190.711044 -318.856109) (xy 190.664886 -318.882758) (xy 190.637712 -318.893423) (xy 191.64045 -318.893423)
			(xy 191.64045 -318.840125) (xy 191.648393 -318.787421) (xy 191.664103 -318.736491) (xy 191.687229 -318.68847)
			(xy 191.717253 -318.644433) (xy 191.753505 -318.605362) (xy 191.795176 -318.572131) (xy 191.841334 -318.545482)
			(xy 191.890948 -318.52601) (xy 191.94291 -318.51415) (xy 191.99606 -318.510167) (xy 192.04921 -318.51415)
			(xy 192.101172 -318.52601) (xy 192.150786 -318.545482) (xy 192.196944 -318.572131) (xy 192.238615 -318.605362)
			(xy 192.274867 -318.644433) (xy 192.304891 -318.68847) (xy 192.328017 -318.736491) (xy 192.343727 -318.787421)
			(xy 192.35167 -318.840125) (xy 192.352168 -318.866774) (xy 192.35167 -318.893423) (xy 192.343727 -318.946127)
			(xy 192.328017 -318.997057) (xy 192.316642 -319.020677) (xy 194.245982 -319.020677) (xy 194.245982 -318.967379)
			(xy 194.253925 -318.914675) (xy 194.269635 -318.863745) (xy 194.292761 -318.815724) (xy 194.322785 -318.771687)
			(xy 194.359037 -318.732616) (xy 194.400708 -318.699385) (xy 194.446866 -318.672736) (xy 194.49648 -318.653264)
			(xy 194.548442 -318.641404) (xy 194.601592 -318.637421) (xy 194.654742 -318.641404) (xy 194.706704 -318.653264)
			(xy 194.756318 -318.672736) (xy 194.802476 -318.699385) (xy 194.844147 -318.732616) (xy 194.880399 -318.771687)
			(xy 194.910423 -318.815724) (xy 194.933549 -318.863745) (xy 194.942704 -318.893423) (xy 199.171804 -318.893423)
			(xy 199.171804 -318.840125) (xy 199.179747 -318.787421) (xy 199.195457 -318.736491) (xy 199.218583 -318.68847)
			(xy 199.248607 -318.644433) (xy 199.284859 -318.605362) (xy 199.32653 -318.572131) (xy 199.372688 -318.545482)
			(xy 199.422302 -318.52601) (xy 199.474264 -318.51415) (xy 199.527414 -318.510167) (xy 199.580564 -318.51415)
			(xy 199.632526 -318.52601) (xy 199.68214 -318.545482) (xy 199.728298 -318.572131) (xy 199.769969 -318.605362)
			(xy 199.806221 -318.644433) (xy 199.836245 -318.68847) (xy 199.859371 -318.736491) (xy 199.875081 -318.787421)
			(xy 199.883024 -318.840125) (xy 199.883522 -318.866774) (xy 199.883024 -318.893423) (xy 199.875081 -318.946127)
			(xy 199.859371 -318.997057) (xy 199.836245 -319.045078) (xy 199.806221 -319.089115) (xy 199.769969 -319.128186)
			(xy 199.728298 -319.161417) (xy 199.68214 -319.188066) (xy 199.632526 -319.207538) (xy 199.580564 -319.219398)
			(xy 199.527414 -319.223382) (xy 199.474264 -319.219398) (xy 199.422302 -319.207538) (xy 199.372688 -319.188066)
			(xy 199.32653 -319.161417) (xy 199.284859 -319.128186) (xy 199.248607 -319.089115) (xy 199.218583 -319.045078)
			(xy 199.195457 -318.997057) (xy 199.179747 -318.946127) (xy 199.171804 -318.893423) (xy 194.942704 -318.893423)
			(xy 194.949259 -318.914675) (xy 194.957202 -318.967379) (xy 194.9577 -318.994028) (xy 194.957202 -319.020677)
			(xy 194.949259 -319.073381) (xy 194.933549 -319.124311) (xy 194.910423 -319.172332) (xy 194.880399 -319.216369)
			(xy 194.852384 -319.246562) (xy 213.671463 -319.246562) (xy 213.676943 -319.192674) (xy 213.690521 -319.140238)
			(xy 213.711882 -319.090463) (xy 213.740535 -319.044496) (xy 213.775819 -319.003399) (xy 213.816919 -318.968119)
			(xy 213.862888 -318.939469) (xy 213.912665 -318.918112) (xy 213.965102 -318.904538) (xy 214.01899 -318.899062)
			(xy 214.073086 -318.901809) (xy 214.126142 -318.912717) (xy 214.176934 -318.931533) (xy 214.224291 -318.957824)
			(xy 214.267121 -318.990983) (xy 214.304435 -319.030246) (xy 214.335373 -319.074707) (xy 214.359222 -319.12334)
			(xy 214.375431 -319.175023) (xy 214.383626 -319.228565) (xy 214.384128 -319.255648) (xy 214.38362 -319.27292)
			(xy 214.383405 -319.286782) (xy 214.389588 -319.313797) (xy 214.402801 -319.338158) (xy 214.422074 -319.358073)
			(xy 214.445989 -319.372078) (xy 214.472787 -319.379143) (xy 214.500498 -319.378748) (xy 214.513922 -319.375282)
			(xy 214.538626 -319.368399) (xy 214.589373 -319.361011) (xy 214.615014 -319.36055) (xy 214.642094 -319.361113)
			(xy 214.695628 -319.369316) (xy 214.747302 -319.385532) (xy 214.795926 -319.409385) (xy 214.840376 -319.440327)
			(xy 214.879628 -319.477643) (xy 214.912777 -319.520472) (xy 214.939058 -319.567828) (xy 214.957864 -319.618617)
			(xy 214.968763 -319.671668) (xy 214.971503 -319.725758) (xy 214.96602 -319.779639) (xy 214.952441 -319.832068)
			(xy 214.93108 -319.881836) (xy 214.902428 -319.927796) (xy 214.867147 -319.968887) (xy 214.826051 -320.004161)
			(xy 214.780086 -320.032806) (xy 214.730315 -320.05416) (xy 214.677883 -320.06773) (xy 214.624002 -320.073204)
			(xy 214.569912 -320.070456) (xy 214.516863 -320.059549) (xy 214.466077 -320.040734) (xy 214.418726 -320.014446)
			(xy 214.375901 -319.981291) (xy 214.338591 -319.942032) (xy 214.307657 -319.897577) (xy 214.283811 -319.84895)
			(xy 214.267603 -319.797273) (xy 214.259408 -319.743738) (xy 214.258906 -319.716658) (xy 214.259414 -319.699386)
			(xy 214.25958 -319.685526) (xy 214.253401 -319.658518) (xy 214.240194 -319.634162) (xy 214.22093 -319.61425)
			(xy 214.197025 -319.600245) (xy 214.170237 -319.593176) (xy 214.142534 -319.593563) (xy 214.129112 -319.597024)
			(xy 214.104406 -319.6039) (xy 214.05366 -319.611292) (xy 214.02802 -319.611756) (xy 214.000937 -319.611224)
			(xy 213.947396 -319.603024) (xy 213.895714 -319.586811) (xy 213.847083 -319.562959) (xy 213.802624 -319.532017)
			(xy 213.763365 -319.4947) (xy 213.730209 -319.451868) (xy 213.703922 -319.404509) (xy 213.685109 -319.353715)
			(xy 213.674206 -319.300658) (xy 213.671463 -319.246562) (xy 194.852384 -319.246562) (xy 194.844147 -319.25544)
			(xy 194.802476 -319.288671) (xy 194.756318 -319.31532) (xy 194.706704 -319.334792) (xy 194.654742 -319.346652)
			(xy 194.601592 -319.350636) (xy 194.548442 -319.346652) (xy 194.49648 -319.334792) (xy 194.446866 -319.31532)
			(xy 194.400708 -319.288671) (xy 194.359037 -319.25544) (xy 194.322785 -319.216369) (xy 194.292761 -319.172332)
			(xy 194.269635 -319.124311) (xy 194.253925 -319.073381) (xy 194.245982 -319.020677) (xy 192.316642 -319.020677)
			(xy 192.304891 -319.045078) (xy 192.274867 -319.089115) (xy 192.238615 -319.128186) (xy 192.196944 -319.161417)
			(xy 192.150786 -319.188066) (xy 192.101172 -319.207538) (xy 192.04921 -319.219398) (xy 191.99606 -319.223382)
			(xy 191.94291 -319.219398) (xy 191.890948 -319.207538) (xy 191.841334 -319.188066) (xy 191.795176 -319.161417)
			(xy 191.753505 -319.128186) (xy 191.717253 -319.089115) (xy 191.687229 -319.045078) (xy 191.664103 -318.997057)
			(xy 191.648393 -318.946127) (xy 191.64045 -318.893423) (xy 190.637712 -318.893423) (xy 190.615272 -318.90223)
			(xy 190.56331 -318.91409) (xy 190.51016 -318.918074) (xy 190.45701 -318.91409) (xy 190.405048 -318.90223)
			(xy 190.355434 -318.882758) (xy 190.309276 -318.856109) (xy 190.267605 -318.822878) (xy 190.231353 -318.783807)
			(xy 190.201329 -318.73977) (xy 190.178203 -318.691749) (xy 190.162493 -318.640819) (xy 190.15455 -318.588115)
			(xy 184.660742 -318.588115) (xy 184.682369 -318.605362) (xy 184.718621 -318.644433) (xy 184.748645 -318.68847)
			(xy 184.771771 -318.736491) (xy 184.787481 -318.787421) (xy 184.795424 -318.840125) (xy 184.795922 -318.866774)
			(xy 184.795424 -318.893423) (xy 184.787481 -318.946127) (xy 184.771771 -318.997057) (xy 184.748645 -319.045078)
			(xy 184.718621 -319.089115) (xy 184.682369 -319.128186) (xy 184.640698 -319.161417) (xy 184.59454 -319.188066)
			(xy 184.544926 -319.207538) (xy 184.492964 -319.219398) (xy 184.439814 -319.223382) (xy 184.386664 -319.219398)
			(xy 184.334702 -319.207538) (xy 184.285088 -319.188066) (xy 184.23893 -319.161417) (xy 184.197259 -319.128186)
			(xy 184.161007 -319.089115) (xy 184.130983 -319.045078) (xy 184.107857 -318.997057) (xy 184.092147 -318.946127)
			(xy 184.084204 -318.893423) (xy 179.67652 -318.893423) (xy 179.691777 -318.90559) (xy 179.728029 -318.944661)
			(xy 179.758053 -318.988698) (xy 179.781179 -319.036719) (xy 179.796889 -319.087649) (xy 179.804832 -319.140353)
			(xy 179.80533 -319.167002) (xy 179.804832 -319.193651) (xy 179.796889 -319.246355) (xy 179.781179 -319.297285)
			(xy 179.758053 -319.345306) (xy 179.728029 -319.389343) (xy 179.691777 -319.428414) (xy 179.650106 -319.461645)
			(xy 179.603948 -319.488294) (xy 179.554334 -319.507766) (xy 179.502372 -319.519626) (xy 179.449222 -319.52361)
			(xy 179.396072 -319.519626) (xy 179.34411 -319.507766) (xy 179.294496 -319.488294) (xy 179.248338 -319.461645)
			(xy 179.206667 -319.428414) (xy 179.170415 -319.389343) (xy 179.140391 -319.345306) (xy 179.117265 -319.297285)
			(xy 179.101555 -319.246355) (xy 179.093612 -319.193651) (xy 177.03651 -319.193651) (xy 177.001126 -319.207538)
			(xy 176.949164 -319.219398) (xy 176.896014 -319.223382) (xy 176.842864 -319.219398) (xy 176.790902 -319.207538)
			(xy 176.741288 -319.188066) (xy 176.69513 -319.161417) (xy 176.653459 -319.128186) (xy 176.617207 -319.089115)
			(xy 176.587183 -319.045078) (xy 176.564057 -318.997057) (xy 176.548347 -318.946127) (xy 176.540404 -318.893423)
			(xy 169.707824 -318.893423) (xy 169.699881 -318.946127) (xy 169.684171 -318.997057) (xy 169.661045 -319.045078)
			(xy 169.631021 -319.089115) (xy 169.594769 -319.128186) (xy 169.553098 -319.161417) (xy 169.50694 -319.188066)
			(xy 169.457326 -319.207538) (xy 169.405364 -319.219398) (xy 169.352214 -319.223382) (xy 169.299064 -319.219398)
			(xy 169.247102 -319.207538) (xy 169.197488 -319.188066) (xy 169.15133 -319.161417) (xy 169.109659 -319.128186)
			(xy 169.073407 -319.089115) (xy 169.043383 -319.045078) (xy 169.020257 -318.997057) (xy 169.004547 -318.946127)
			(xy 168.996604 -318.893423) (xy 160.299156 -318.893423) (xy 160.291213 -318.946127) (xy 160.275503 -318.997057)
			(xy 160.252377 -319.045078) (xy 160.222353 -319.089115) (xy 160.186101 -319.128186) (xy 160.14443 -319.161417)
			(xy 160.098272 -319.188066) (xy 160.048658 -319.207538) (xy 159.996696 -319.219398) (xy 159.943546 -319.223382)
			(xy 159.890396 -319.219398) (xy 159.838434 -319.207538) (xy 159.78882 -319.188066) (xy 159.742662 -319.161417)
			(xy 159.700991 -319.128186) (xy 159.664739 -319.089115) (xy 159.634715 -319.045078) (xy 159.611589 -318.997057)
			(xy 159.595879 -318.946127) (xy 159.587936 -318.893423) (xy 158.88716 -318.893423) (xy 158.88716 -319.743307)
			(xy 159.646864 -319.743307) (xy 159.646864 -319.690009) (xy 159.654807 -319.637305) (xy 159.670517 -319.586375)
			(xy 159.693643 -319.538354) (xy 159.723667 -319.494317) (xy 159.759919 -319.455246) (xy 159.80159 -319.422015)
			(xy 159.847748 -319.395366) (xy 159.897362 -319.375894) (xy 159.949324 -319.364034) (xy 160.002474 -319.360051)
			(xy 160.055624 -319.364034) (xy 160.107586 -319.375894) (xy 160.1572 -319.395366) (xy 160.203358 -319.422015)
			(xy 160.245029 -319.455246) (xy 160.281281 -319.494317) (xy 160.311305 -319.538354) (xy 160.334431 -319.586375)
			(xy 160.350141 -319.637305) (xy 160.358084 -319.690009) (xy 160.358582 -319.716658) (xy 160.358084 -319.743307)
			(xy 160.350141 -319.796011) (xy 160.334431 -319.846941) (xy 160.311305 -319.894962) (xy 160.281281 -319.938999)
			(xy 160.245029 -319.97807) (xy 160.203358 -320.011301) (xy 160.1572 -320.03795) (xy 160.107586 -320.057422)
			(xy 160.055624 -320.069282) (xy 160.002474 -320.073266) (xy 159.949324 -320.069282) (xy 159.897362 -320.057422)
			(xy 159.847748 -320.03795) (xy 159.80159 -320.011301) (xy 159.759919 -319.97807) (xy 159.723667 -319.938999)
			(xy 159.693643 -319.894962) (xy 159.670517 -319.846941) (xy 159.654807 -319.796011) (xy 159.646864 -319.743307)
			(xy 158.88716 -319.743307) (xy 158.88716 -320.711068) (xy 159.47136 -321.295268) (xy 159.986472 -321.295268)
			(xy 159.986973 -321.26746) (xy 159.99561 -321.212518) (xy 160.012684 -321.159588) (xy 160.037781 -321.109956)
			(xy 160.070289 -321.06483) (xy 160.109418 -321.025307) (xy 160.154217 -320.992349) (xy 160.203595 -320.966757)
			(xy 160.229804 -320.957448) (xy 160.243099 -320.952538) (xy 160.266478 -320.936533) (xy 160.284565 -320.914726)
			(xy 160.295972 -320.888791) (xy 160.299822 -320.860722) (xy 160.295819 -320.832674) (xy 160.284272 -320.806802)
			(xy 160.275524 -320.79565) (xy 160.259866 -320.776326) (xy 160.233501 -320.734154) (xy 160.213264 -320.688722)
			(xy 160.19955 -320.640915) (xy 160.192626 -320.591664) (xy 160.192212 -320.566796) (xy 160.19271 -320.540147)
			(xy 160.200653 -320.487443) (xy 160.216363 -320.436513) (xy 160.239489 -320.388492) (xy 160.269513 -320.344455)
			(xy 160.305765 -320.305384) (xy 160.347436 -320.272153) (xy 160.393594 -320.245504) (xy 160.443208 -320.226032)
			(xy 160.49517 -320.214172) (xy 160.54832 -320.210189) (xy 160.60147 -320.214172) (xy 160.653432 -320.226032)
			(xy 160.703046 -320.245504) (xy 160.749204 -320.272153) (xy 160.790875 -320.305384) (xy 160.827127 -320.344455)
			(xy 160.833423 -320.35369) (xy 161.41065 -320.35369) (xy 161.411198 -320.326256) (xy 161.419621 -320.272037)
			(xy 161.436252 -320.21975) (xy 161.460697 -320.170627) (xy 161.49238 -320.12583) (xy 161.530552 -320.086416)
			(xy 161.552128 -320.069464) (xy 161.563948 -320.059796) (xy 161.581779 -320.035031) (xy 161.591498 -320.006104)
			(xy 161.592238 -319.975596) (xy 161.583933 -319.946231) (xy 161.567324 -319.92063) (xy 161.555938 -319.91046)
			(xy 161.536314 -319.893441) (xy 161.501725 -319.854689) (xy 161.473129 -319.811326) (xy 161.451132 -319.76427)
			(xy 161.4362 -319.714519) (xy 161.42865 -319.663128) (xy 161.428176 -319.637156) (xy 161.428674 -319.610507)
			(xy 161.436617 -319.557803) (xy 161.452327 -319.506873) (xy 161.475453 -319.458852) (xy 161.505477 -319.414815)
			(xy 161.541729 -319.375744) (xy 161.5834 -319.342513) (xy 161.629558 -319.315864) (xy 161.679172 -319.296392)
			(xy 161.731134 -319.284532) (xy 161.784284 -319.280549) (xy 161.837434 -319.284532) (xy 161.889396 -319.296392)
			(xy 161.93901 -319.315864) (xy 161.985168 -319.342513) (xy 162.026839 -319.375744) (xy 162.063091 -319.414815)
			(xy 162.093115 -319.458852) (xy 162.116241 -319.506873) (xy 162.131951 -319.557803) (xy 162.139894 -319.610507)
			(xy 162.140392 -319.637156) (xy 162.1399 -319.664593) (xy 162.131468 -319.718815) (xy 162.123674 -319.743307)
			(xy 164.896536 -319.743307) (xy 164.896536 -319.690009) (xy 164.904479 -319.637305) (xy 164.920189 -319.586375)
			(xy 164.943315 -319.538354) (xy 164.973339 -319.494317) (xy 165.009591 -319.455246) (xy 165.051262 -319.422015)
			(xy 165.09742 -319.395366) (xy 165.147034 -319.375894) (xy 165.198996 -319.364034) (xy 165.252146 -319.360051)
			(xy 165.305296 -319.364034) (xy 165.357258 -319.375894) (xy 165.406872 -319.395366) (xy 165.45303 -319.422015)
			(xy 165.494701 -319.455246) (xy 165.530953 -319.494317) (xy 165.560977 -319.538354) (xy 165.584103 -319.586375)
			(xy 165.599813 -319.637305) (xy 165.607756 -319.690009) (xy 165.608254 -319.716658) (xy 165.607756 -319.743307)
			(xy 165.599813 -319.796011) (xy 165.584103 -319.846941) (xy 165.560977 -319.894962) (xy 165.540554 -319.924917)
			(xy 168.46041 -319.924917) (xy 168.46041 -319.871619) (xy 168.468353 -319.818915) (xy 168.484063 -319.767985)
			(xy 168.507189 -319.719964) (xy 168.537213 -319.675927) (xy 168.573465 -319.636856) (xy 168.615136 -319.603625)
			(xy 168.661294 -319.576976) (xy 168.710908 -319.557504) (xy 168.76287 -319.545644) (xy 168.81602 -319.541661)
			(xy 168.86917 -319.545644) (xy 168.921132 -319.557504) (xy 168.970746 -319.576976) (xy 169.016904 -319.603625)
			(xy 169.058575 -319.636856) (xy 169.094827 -319.675927) (xy 169.124851 -319.719964) (xy 169.136093 -319.743307)
			(xy 172.440336 -319.743307) (xy 172.440336 -319.690009) (xy 172.448279 -319.637305) (xy 172.463989 -319.586375)
			(xy 172.487115 -319.538354) (xy 172.517139 -319.494317) (xy 172.553391 -319.455246) (xy 172.595062 -319.422015)
			(xy 172.64122 -319.395366) (xy 172.690834 -319.375894) (xy 172.742796 -319.364034) (xy 172.795946 -319.360051)
			(xy 172.849096 -319.364034) (xy 172.901058 -319.375894) (xy 172.950672 -319.395366) (xy 172.99683 -319.422015)
			(xy 173.038501 -319.455246) (xy 173.074753 -319.494317) (xy 173.104777 -319.538354) (xy 173.127903 -319.586375)
			(xy 173.143613 -319.637305) (xy 173.151556 -319.690009) (xy 173.152054 -319.716658) (xy 173.151556 -319.743307)
			(xy 179.984136 -319.743307) (xy 179.984136 -319.690009) (xy 179.992079 -319.637305) (xy 180.007789 -319.586375)
			(xy 180.030915 -319.538354) (xy 180.060939 -319.494317) (xy 180.097191 -319.455246) (xy 180.138862 -319.422015)
			(xy 180.18502 -319.395366) (xy 180.234634 -319.375894) (xy 180.286596 -319.364034) (xy 180.339746 -319.360051)
			(xy 180.392896 -319.364034) (xy 180.444858 -319.375894) (xy 180.494472 -319.395366) (xy 180.54063 -319.422015)
			(xy 180.582301 -319.455246) (xy 180.618553 -319.494317) (xy 180.648577 -319.538354) (xy 180.671703 -319.586375)
			(xy 180.687413 -319.637305) (xy 180.695356 -319.690009) (xy 180.695854 -319.716658) (xy 180.695356 -319.743307)
			(xy 183.46419 -319.743307) (xy 183.46419 -319.690009) (xy 183.472133 -319.637305) (xy 183.487843 -319.586375)
			(xy 183.510969 -319.538354) (xy 183.540993 -319.494317) (xy 183.577245 -319.455246) (xy 183.618916 -319.422015)
			(xy 183.665074 -319.395366) (xy 183.714688 -319.375894) (xy 183.76665 -319.364034) (xy 183.8198 -319.360051)
			(xy 183.87295 -319.364034) (xy 183.924912 -319.375894) (xy 183.974526 -319.395366) (xy 184.020684 -319.422015)
			(xy 184.062355 -319.455246) (xy 184.098607 -319.494317) (xy 184.128631 -319.538354) (xy 184.151757 -319.586375)
			(xy 184.167467 -319.637305) (xy 184.17541 -319.690009) (xy 184.175908 -319.716658) (xy 184.17541 -319.743307)
			(xy 187.527936 -319.743307) (xy 187.527936 -319.690009) (xy 187.535879 -319.637305) (xy 187.551589 -319.586375)
			(xy 187.574715 -319.538354) (xy 187.604739 -319.494317) (xy 187.640991 -319.455246) (xy 187.682662 -319.422015)
			(xy 187.72882 -319.395366) (xy 187.778434 -319.375894) (xy 187.830396 -319.364034) (xy 187.883546 -319.360051)
			(xy 187.936696 -319.364034) (xy 187.988658 -319.375894) (xy 188.038272 -319.395366) (xy 188.08443 -319.422015)
			(xy 188.126101 -319.455246) (xy 188.162353 -319.494317) (xy 188.192377 -319.538354) (xy 188.215503 -319.586375)
			(xy 188.231213 -319.637305) (xy 188.239156 -319.690009) (xy 188.239654 -319.716658) (xy 188.239156 -319.743307)
			(xy 195.071736 -319.743307) (xy 195.071736 -319.690009) (xy 195.079679 -319.637305) (xy 195.095389 -319.586375)
			(xy 195.118515 -319.538354) (xy 195.148539 -319.494317) (xy 195.184791 -319.455246) (xy 195.226462 -319.422015)
			(xy 195.27262 -319.395366) (xy 195.322234 -319.375894) (xy 195.374196 -319.364034) (xy 195.427346 -319.360051)
			(xy 195.480496 -319.364034) (xy 195.532458 -319.375894) (xy 195.582072 -319.395366) (xy 195.62823 -319.422015)
			(xy 195.669901 -319.455246) (xy 195.706153 -319.494317) (xy 195.736177 -319.538354) (xy 195.759303 -319.586375)
			(xy 195.775013 -319.637305) (xy 195.782956 -319.690009) (xy 195.783454 -319.716658) (xy 195.782956 -319.743307)
			(xy 195.775013 -319.796011) (xy 195.759303 -319.846941) (xy 195.736177 -319.894962) (xy 195.727876 -319.907137)
			(xy 198.55941 -319.907137) (xy 198.55941 -319.853839) (xy 198.567353 -319.801135) (xy 198.583063 -319.750205)
			(xy 198.606189 -319.702184) (xy 198.636213 -319.658147) (xy 198.672465 -319.619076) (xy 198.714136 -319.585845)
			(xy 198.760294 -319.559196) (xy 198.809908 -319.539724) (xy 198.86187 -319.527864) (xy 198.91502 -319.523881)
			(xy 198.96817 -319.527864) (xy 199.020132 -319.539724) (xy 199.069746 -319.559196) (xy 199.115904 -319.585845)
			(xy 199.157575 -319.619076) (xy 199.193827 -319.658147) (xy 199.223851 -319.702184) (xy 199.243655 -319.743307)
			(xy 202.615536 -319.743307) (xy 202.615536 -319.690009) (xy 202.623479 -319.637305) (xy 202.639189 -319.586375)
			(xy 202.662315 -319.538354) (xy 202.692339 -319.494317) (xy 202.728591 -319.455246) (xy 202.770262 -319.422015)
			(xy 202.81642 -319.395366) (xy 202.866034 -319.375894) (xy 202.917996 -319.364034) (xy 202.971146 -319.360051)
			(xy 203.024296 -319.364034) (xy 203.076258 -319.375894) (xy 203.125872 -319.395366) (xy 203.17203 -319.422015)
			(xy 203.213701 -319.455246) (xy 203.249953 -319.494317) (xy 203.279977 -319.538354) (xy 203.303103 -319.586375)
			(xy 203.318813 -319.637305) (xy 203.326756 -319.690009) (xy 203.327254 -319.716658) (xy 203.326756 -319.743307)
			(xy 206.00415 -319.743307) (xy 206.00415 -319.690009) (xy 206.012093 -319.637305) (xy 206.027803 -319.586375)
			(xy 206.050929 -319.538354) (xy 206.080953 -319.494317) (xy 206.117205 -319.455246) (xy 206.158876 -319.422015)
			(xy 206.205034 -319.395366) (xy 206.254648 -319.375894) (xy 206.30661 -319.364034) (xy 206.35976 -319.360051)
			(xy 206.41291 -319.364034) (xy 206.464872 -319.375894) (xy 206.514486 -319.395366) (xy 206.560644 -319.422015)
			(xy 206.602315 -319.455246) (xy 206.638567 -319.494317) (xy 206.668591 -319.538354) (xy 206.691717 -319.586375)
			(xy 206.707427 -319.637305) (xy 206.71537 -319.690009) (xy 206.715868 -319.716658) (xy 206.71537 -319.743307)
			(xy 210.159336 -319.743307) (xy 210.159336 -319.690009) (xy 210.167279 -319.637305) (xy 210.182989 -319.586375)
			(xy 210.206115 -319.538354) (xy 210.236139 -319.494317) (xy 210.272391 -319.455246) (xy 210.314062 -319.422015)
			(xy 210.36022 -319.395366) (xy 210.409834 -319.375894) (xy 210.461796 -319.364034) (xy 210.514946 -319.360051)
			(xy 210.568096 -319.364034) (xy 210.620058 -319.375894) (xy 210.669672 -319.395366) (xy 210.71583 -319.422015)
			(xy 210.757501 -319.455246) (xy 210.793753 -319.494317) (xy 210.823777 -319.538354) (xy 210.846903 -319.586375)
			(xy 210.862613 -319.637305) (xy 210.870556 -319.690009) (xy 210.871054 -319.716658) (xy 210.870556 -319.743307)
			(xy 210.862613 -319.796011) (xy 210.846903 -319.846941) (xy 210.823777 -319.894962) (xy 210.793753 -319.938999)
			(xy 210.757501 -319.97807) (xy 210.71583 -320.011301) (xy 210.669672 -320.03795) (xy 210.620058 -320.057422)
			(xy 210.568096 -320.069282) (xy 210.514946 -320.073266) (xy 210.461796 -320.069282) (xy 210.409834 -320.057422)
			(xy 210.36022 -320.03795) (xy 210.314062 -320.011301) (xy 210.272391 -319.97807) (xy 210.236139 -319.938999)
			(xy 210.206115 -319.894962) (xy 210.182989 -319.846941) (xy 210.167279 -319.796011) (xy 210.159336 -319.743307)
			(xy 206.71537 -319.743307) (xy 206.707427 -319.796011) (xy 206.691717 -319.846941) (xy 206.668591 -319.894962)
			(xy 206.638567 -319.938999) (xy 206.602315 -319.97807) (xy 206.560644 -320.011301) (xy 206.514486 -320.03795)
			(xy 206.464872 -320.057422) (xy 206.41291 -320.069282) (xy 206.35976 -320.073266) (xy 206.30661 -320.069282)
			(xy 206.254648 -320.057422) (xy 206.205034 -320.03795) (xy 206.158876 -320.011301) (xy 206.117205 -319.97807)
			(xy 206.080953 -319.938999) (xy 206.050929 -319.894962) (xy 206.027803 -319.846941) (xy 206.012093 -319.796011)
			(xy 206.00415 -319.743307) (xy 203.326756 -319.743307) (xy 203.318813 -319.796011) (xy 203.303103 -319.846941)
			(xy 203.279977 -319.894962) (xy 203.249953 -319.938999) (xy 203.213701 -319.97807) (xy 203.17203 -320.011301)
			(xy 203.125872 -320.03795) (xy 203.076258 -320.057422) (xy 203.024296 -320.069282) (xy 202.971146 -320.073266)
			(xy 202.917996 -320.069282) (xy 202.866034 -320.057422) (xy 202.81642 -320.03795) (xy 202.770262 -320.011301)
			(xy 202.728591 -319.97807) (xy 202.692339 -319.938999) (xy 202.662315 -319.894962) (xy 202.639189 -319.846941)
			(xy 202.623479 -319.796011) (xy 202.615536 -319.743307) (xy 199.243655 -319.743307) (xy 199.246977 -319.750205)
			(xy 199.262687 -319.801135) (xy 199.27063 -319.853839) (xy 199.271128 -319.880488) (xy 199.27063 -319.907137)
			(xy 199.262687 -319.959841) (xy 199.246977 -320.010771) (xy 199.223851 -320.058792) (xy 199.193827 -320.102829)
			(xy 199.157575 -320.1419) (xy 199.115904 -320.175131) (xy 199.069746 -320.20178) (xy 199.020132 -320.221252)
			(xy 198.96817 -320.233112) (xy 198.91502 -320.237096) (xy 198.86187 -320.233112) (xy 198.809908 -320.221252)
			(xy 198.760294 -320.20178) (xy 198.714136 -320.175131) (xy 198.672465 -320.1419) (xy 198.636213 -320.102829)
			(xy 198.606189 -320.058792) (xy 198.583063 -320.010771) (xy 198.567353 -319.959841) (xy 198.55941 -319.907137)
			(xy 195.727876 -319.907137) (xy 195.706153 -319.938999) (xy 195.669901 -319.97807) (xy 195.62823 -320.011301)
			(xy 195.582072 -320.03795) (xy 195.532458 -320.057422) (xy 195.480496 -320.069282) (xy 195.427346 -320.073266)
			(xy 195.374196 -320.069282) (xy 195.322234 -320.057422) (xy 195.27262 -320.03795) (xy 195.226462 -320.011301)
			(xy 195.184791 -319.97807) (xy 195.148539 -319.938999) (xy 195.118515 -319.894962) (xy 195.095389 -319.846941)
			(xy 195.079679 -319.796011) (xy 195.071736 -319.743307) (xy 188.239156 -319.743307) (xy 188.231213 -319.796011)
			(xy 188.215503 -319.846941) (xy 188.192377 -319.894962) (xy 188.162353 -319.938999) (xy 188.126101 -319.97807)
			(xy 188.08443 -320.011301) (xy 188.038272 -320.03795) (xy 187.988658 -320.057422) (xy 187.936696 -320.069282)
			(xy 187.883546 -320.073266) (xy 187.830396 -320.069282) (xy 187.778434 -320.057422) (xy 187.72882 -320.03795)
			(xy 187.682662 -320.011301) (xy 187.640991 -319.97807) (xy 187.604739 -319.938999) (xy 187.574715 -319.894962)
			(xy 187.551589 -319.846941) (xy 187.535879 -319.796011) (xy 187.527936 -319.743307) (xy 184.17541 -319.743307)
			(xy 184.167467 -319.796011) (xy 184.151757 -319.846941) (xy 184.128631 -319.894962) (xy 184.098607 -319.938999)
			(xy 184.062355 -319.97807) (xy 184.020684 -320.011301) (xy 183.974526 -320.03795) (xy 183.924912 -320.057422)
			(xy 183.87295 -320.069282) (xy 183.8198 -320.073266) (xy 183.76665 -320.069282) (xy 183.714688 -320.057422)
			(xy 183.665074 -320.03795) (xy 183.618916 -320.011301) (xy 183.577245 -319.97807) (xy 183.540993 -319.938999)
			(xy 183.510969 -319.894962) (xy 183.487843 -319.846941) (xy 183.472133 -319.796011) (xy 183.46419 -319.743307)
			(xy 180.695356 -319.743307) (xy 180.687413 -319.796011) (xy 180.671703 -319.846941) (xy 180.648577 -319.894962)
			(xy 180.618553 -319.938999) (xy 180.582301 -319.97807) (xy 180.54063 -320.011301) (xy 180.494472 -320.03795)
			(xy 180.444858 -320.057422) (xy 180.392896 -320.069282) (xy 180.339746 -320.073266) (xy 180.286596 -320.069282)
			(xy 180.234634 -320.057422) (xy 180.18502 -320.03795) (xy 180.138862 -320.011301) (xy 180.097191 -319.97807)
			(xy 180.060939 -319.938999) (xy 180.030915 -319.894962) (xy 180.007789 -319.846941) (xy 179.992079 -319.796011)
			(xy 179.984136 -319.743307) (xy 173.151556 -319.743307) (xy 173.143613 -319.796011) (xy 173.127903 -319.846941)
			(xy 173.104777 -319.894962) (xy 173.074753 -319.938999) (xy 173.038501 -319.97807) (xy 172.99683 -320.011301)
			(xy 172.950672 -320.03795) (xy 172.901058 -320.057422) (xy 172.849096 -320.069282) (xy 172.795946 -320.073266)
			(xy 172.742796 -320.069282) (xy 172.690834 -320.057422) (xy 172.64122 -320.03795) (xy 172.595062 -320.011301)
			(xy 172.553391 -319.97807) (xy 172.517139 -319.938999) (xy 172.487115 -319.894962) (xy 172.463989 -319.846941)
			(xy 172.448279 -319.796011) (xy 172.440336 -319.743307) (xy 169.136093 -319.743307) (xy 169.147977 -319.767985)
			(xy 169.163687 -319.818915) (xy 169.17163 -319.871619) (xy 169.172128 -319.898268) (xy 169.17163 -319.924917)
			(xy 169.163687 -319.977621) (xy 169.147977 -320.028551) (xy 169.124851 -320.076572) (xy 169.094827 -320.120609)
			(xy 169.058575 -320.15968) (xy 169.016904 -320.192911) (xy 168.970746 -320.21956) (xy 168.921132 -320.239032)
			(xy 168.86917 -320.250892) (xy 168.81602 -320.254876) (xy 168.76287 -320.250892) (xy 168.710908 -320.239032)
			(xy 168.661294 -320.21956) (xy 168.615136 -320.192911) (xy 168.573465 -320.15968) (xy 168.537213 -320.120609)
			(xy 168.507189 -320.076572) (xy 168.484063 -320.028551) (xy 168.468353 -319.977621) (xy 168.46041 -319.924917)
			(xy 165.540554 -319.924917) (xy 165.530953 -319.938999) (xy 165.494701 -319.97807) (xy 165.45303 -320.011301)
			(xy 165.406872 -320.03795) (xy 165.357258 -320.057422) (xy 165.305296 -320.069282) (xy 165.252146 -320.073266)
			(xy 165.198996 -320.069282) (xy 165.147034 -320.057422) (xy 165.09742 -320.03795) (xy 165.051262 -320.011301)
			(xy 165.009591 -319.97807) (xy 164.973339 -319.938999) (xy 164.943315 -319.894962) (xy 164.920189 -319.846941)
			(xy 164.904479 -319.796011) (xy 164.896536 -319.743307) (xy 162.123674 -319.743307) (xy 162.114828 -319.771104)
			(xy 162.090372 -319.820227) (xy 162.058678 -319.865022) (xy 162.020495 -319.904432) (xy 161.998914 -319.921382)
			(xy 161.987053 -319.931001) (xy 161.969233 -319.955782) (xy 161.959524 -319.98472) (xy 161.958792 -320.015235)
			(xy 161.967103 -320.044606) (xy 161.983716 -320.070212) (xy 161.995104 -320.080386) (xy 162.014738 -320.097394)
			(xy 162.049329 -320.136147) (xy 162.077926 -320.179512) (xy 162.099921 -320.22657) (xy 162.113822 -320.272897)
			(xy 164.15765 -320.272897) (xy 164.15765 -320.219599) (xy 164.165593 -320.166895) (xy 164.181303 -320.115965)
			(xy 164.204429 -320.067944) (xy 164.234453 -320.023907) (xy 164.270705 -319.984836) (xy 164.312376 -319.951605)
			(xy 164.358534 -319.924956) (xy 164.408148 -319.905484) (xy 164.46011 -319.893624) (xy 164.51326 -319.889641)
			(xy 164.56641 -319.893624) (xy 164.618372 -319.905484) (xy 164.667986 -319.924956) (xy 164.714144 -319.951605)
			(xy 164.755815 -319.984836) (xy 164.792067 -320.023907) (xy 164.822091 -320.067944) (xy 164.845217 -320.115965)
			(xy 164.860927 -320.166895) (xy 164.86887 -320.219599) (xy 164.869368 -320.246248) (xy 164.86887 -320.272897)
			(xy 164.860927 -320.325601) (xy 164.845217 -320.376531) (xy 164.822091 -320.424552) (xy 164.792067 -320.468589)
			(xy 164.755815 -320.50766) (xy 164.714144 -320.540891) (xy 164.667986 -320.56754) (xy 164.618372 -320.587012)
			(xy 164.56641 -320.598872) (xy 164.51326 -320.602856) (xy 164.46011 -320.598872) (xy 164.408148 -320.587012)
			(xy 164.358534 -320.56754) (xy 164.312376 -320.540891) (xy 164.270705 -320.50766) (xy 164.234453 -320.468589)
			(xy 164.204429 -320.424552) (xy 164.181303 -320.376531) (xy 164.165593 -320.325601) (xy 164.15765 -320.272897)
			(xy 162.113822 -320.272897) (xy 162.11485 -320.276323) (xy 162.122395 -320.327718) (xy 162.122866 -320.35369)
			(xy 162.122368 -320.380339) (xy 162.114425 -320.433043) (xy 162.098715 -320.483973) (xy 162.075589 -320.531994)
			(xy 162.045565 -320.576031) (xy 162.009313 -320.615102) (xy 161.967642 -320.648333) (xy 161.921484 -320.674982)
			(xy 161.87187 -320.694454) (xy 161.819908 -320.706314) (xy 161.766758 -320.710298) (xy 161.713608 -320.706314)
			(xy 161.661646 -320.694454) (xy 161.612032 -320.674982) (xy 161.565874 -320.648333) (xy 161.524203 -320.615102)
			(xy 161.487951 -320.576031) (xy 161.457927 -320.531994) (xy 161.434801 -320.483973) (xy 161.419091 -320.433043)
			(xy 161.411148 -320.380339) (xy 161.41065 -320.35369) (xy 160.833423 -320.35369) (xy 160.857151 -320.388492)
			(xy 160.880277 -320.436513) (xy 160.895987 -320.487443) (xy 160.90393 -320.540147) (xy 160.904428 -320.566796)
			(xy 160.903896 -320.594603) (xy 160.895264 -320.649543) (xy 160.878195 -320.702473) (xy 160.853103 -320.752104)
			(xy 160.820599 -320.797231) (xy 160.781474 -320.836754) (xy 160.736679 -320.869713) (xy 160.687304 -320.895306)
			(xy 160.661096 -320.904616) (xy 160.647822 -320.909577) (xy 160.624449 -320.925574) (xy 160.606363 -320.947372)
			(xy 160.600262 -320.961237) (xy 167.63999 -320.961237) (xy 167.63999 -320.907939) (xy 167.647933 -320.855235)
			(xy 167.663643 -320.804305) (xy 167.686769 -320.756284) (xy 167.716793 -320.712247) (xy 167.753045 -320.673176)
			(xy 167.794716 -320.639945) (xy 167.840874 -320.613296) (xy 167.890488 -320.593824) (xy 167.94245 -320.581964)
			(xy 167.9956 -320.577981) (xy 168.04875 -320.581964) (xy 168.100712 -320.593824) (xy 168.150326 -320.613296)
			(xy 168.196484 -320.639945) (xy 168.238155 -320.673176) (xy 168.274407 -320.712247) (xy 168.304431 -320.756284)
			(xy 168.327557 -320.804305) (xy 168.343267 -320.855235) (xy 168.35121 -320.907939) (xy 168.351708 -320.934588)
			(xy 168.35121 -320.961237) (xy 168.343267 -321.013941) (xy 168.327557 -321.064871) (xy 168.304431 -321.112892)
			(xy 168.274407 -321.156929) (xy 168.258701 -321.173856) (xy 168.971976 -321.173856) (xy 168.97251 -321.146594)
			(xy 168.98082 -321.092708) (xy 168.997254 -321.04072) (xy 169.021427 -320.991848) (xy 169.052773 -320.947237)
			(xy 169.07129 -320.927222) (xy 169.081209 -320.916226) (xy 169.09478 -320.88992) (xy 169.100227 -320.860826)
			(xy 169.097091 -320.831392) (xy 169.085637 -320.804098) (xy 169.076624 -320.792348) (xy 169.061457 -320.773185)
			(xy 169.035972 -320.731484) (xy 169.016427 -320.68669) (xy 169.00319 -320.639645) (xy 168.996509 -320.591232)
			(xy 168.996106 -320.566796) (xy 168.996604 -320.540147) (xy 169.004547 -320.487443) (xy 169.020257 -320.436513)
			(xy 169.043383 -320.388492) (xy 169.073407 -320.344455) (xy 169.109659 -320.305384) (xy 169.15133 -320.272153)
			(xy 169.197488 -320.245504) (xy 169.247102 -320.226032) (xy 169.299064 -320.214172) (xy 169.352214 -320.210189)
			(xy 169.405364 -320.214172) (xy 169.457326 -320.226032) (xy 169.50694 -320.245504) (xy 169.553098 -320.272153)
			(xy 169.594769 -320.305384) (xy 169.631021 -320.344455) (xy 169.661045 -320.388492) (xy 169.684171 -320.436513)
			(xy 169.699881 -320.487443) (xy 169.707824 -320.540147) (xy 169.708322 -320.566796) (xy 169.707831 -320.593445)
			(xy 171.85131 -320.593445) (xy 171.85131 -320.540147) (xy 171.859253 -320.487443) (xy 171.874963 -320.436513)
			(xy 171.898089 -320.388492) (xy 171.928113 -320.344455) (xy 171.964365 -320.305384) (xy 172.006036 -320.272153)
			(xy 172.052194 -320.245504) (xy 172.101808 -320.226032) (xy 172.15377 -320.214172) (xy 172.20692 -320.210189)
			(xy 172.26007 -320.214172) (xy 172.312032 -320.226032) (xy 172.361646 -320.245504) (xy 172.407804 -320.272153)
			(xy 172.449475 -320.305384) (xy 172.485727 -320.344455) (xy 172.515751 -320.388492) (xy 172.534608 -320.427649)
			(xy 175.944883 -320.427649) (xy 175.950365 -320.373766) (xy 175.963943 -320.321333) (xy 175.985305 -320.271562)
			(xy 176.013958 -320.2256) (xy 176.04924 -320.184506) (xy 176.090338 -320.149229) (xy 176.136305 -320.120583)
			(xy 176.186079 -320.099228) (xy 176.238513 -320.085656) (xy 176.292397 -320.080182) (xy 176.346489 -320.08293)
			(xy 176.399542 -320.093838) (xy 176.45033 -320.112653) (xy 176.497684 -320.138943) (xy 176.54051 -320.172101)
			(xy 176.577821 -320.211361) (xy 176.608757 -320.255819) (xy 176.632604 -320.304449) (xy 176.648811 -320.356129)
			(xy 176.657006 -320.409667) (xy 176.657508 -320.436748) (xy 176.657214 -320.457191) (xy 176.6525 -320.497805)
			(xy 176.64811 -320.517774) (xy 176.64542 -320.531376) (xy 176.646629 -320.559064) (xy 176.649155 -320.5668)
			(xy 178.755764 -320.5668) (xy 178.759748 -320.513644) (xy 178.771609 -320.461676) (xy 178.791084 -320.412057)
			(xy 178.817737 -320.365894) (xy 178.850973 -320.32422) (xy 178.890049 -320.287964) (xy 178.934092 -320.257938)
			(xy 178.982119 -320.234812) (xy 179.033056 -320.219102) (xy 179.085766 -320.21116) (xy 179.112418 -320.210688)
			(xy 179.140505 -320.211212) (xy 179.195981 -320.220047) (xy 179.249383 -320.237479) (xy 179.299386 -320.263077)
			(xy 179.344753 -320.296206) (xy 179.384357 -320.336044) (xy 179.401216 -320.358516) (xy 179.409643 -320.369387)
			(xy 179.43112 -320.386554) (xy 179.456394 -320.397377) (xy 179.483639 -320.401074) (xy 179.510884 -320.397377)
			(xy 179.536158 -320.386554) (xy 179.557635 -320.369387) (xy 179.566062 -320.358516) (xy 179.582909 -320.336033)
			(xy 179.622506 -320.296183) (xy 179.667872 -320.263048) (xy 179.71788 -320.237451) (xy 179.771289 -320.220029)
			(xy 179.826771 -320.211213) (xy 179.85486 -320.210688) (xy 179.881513 -320.211166) (xy 179.934224 -320.219106)
			(xy 179.985162 -320.234813) (xy 180.033191 -320.257938) (xy 180.077236 -320.287963) (xy 180.116314 -320.324217)
			(xy 180.149551 -320.365892) (xy 180.176206 -320.412055) (xy 180.195682 -320.461675) (xy 180.207544 -320.513644)
			(xy 180.211528 -320.5668) (xy 180.209531 -320.593445) (xy 184.084204 -320.593445) (xy 184.084204 -320.540147)
			(xy 184.092147 -320.487443) (xy 184.107857 -320.436513) (xy 184.130983 -320.388492) (xy 184.161007 -320.344455)
			(xy 184.197259 -320.305384) (xy 184.23893 -320.272153) (xy 184.285088 -320.245504) (xy 184.334702 -320.226032)
			(xy 184.386664 -320.214172) (xy 184.439814 -320.210189) (xy 184.492964 -320.214172) (xy 184.544926 -320.226032)
			(xy 184.59454 -320.245504) (xy 184.640698 -320.272153) (xy 184.682369 -320.305384) (xy 184.718621 -320.344455)
			(xy 184.748645 -320.388492) (xy 184.771771 -320.436513) (xy 184.787481 -320.487443) (xy 184.795424 -320.540147)
			(xy 184.795922 -320.566796) (xy 184.795424 -320.593445) (xy 186.98971 -320.593445) (xy 186.98971 -320.540147)
			(xy 186.997653 -320.487443) (xy 187.013363 -320.436513) (xy 187.036489 -320.388492) (xy 187.066513 -320.344455)
			(xy 187.102765 -320.305384) (xy 187.144436 -320.272153) (xy 187.190594 -320.245504) (xy 187.240208 -320.226032)
			(xy 187.29217 -320.214172) (xy 187.34532 -320.210189) (xy 187.39847 -320.214172) (xy 187.450432 -320.226032)
			(xy 187.500046 -320.245504) (xy 187.546204 -320.272153) (xy 187.587875 -320.305384) (xy 187.624127 -320.344455)
			(xy 187.650679 -320.3834) (xy 190.905401 -320.3834) (xy 190.909383 -320.330252) (xy 190.921243 -320.27829)
			(xy 190.940715 -320.228677) (xy 190.967364 -320.18252) (xy 191.000594 -320.140851) (xy 191.039664 -320.104599)
			(xy 191.0837 -320.074576) (xy 191.13172 -320.051451) (xy 191.182649 -320.035741) (xy 191.235351 -320.027798)
			(xy 191.262 -320.0273) (xy 191.28869 -320.027759) (xy 191.341473 -320.035726) (xy 191.392475 -320.051483)
			(xy 191.440554 -320.074674) (xy 191.484633 -320.104783) (xy 191.523724 -320.141133) (xy 191.556952 -320.18291)
			(xy 191.583572 -320.229179) (xy 191.593724 -320.253868) (xy 191.599213 -320.266562) (xy 191.615757 -320.288704)
			(xy 191.637635 -320.305595) (xy 191.663243 -320.315997) (xy 191.690702 -320.319148) (xy 191.718 -320.314816)
			(xy 191.743135 -320.303318) (xy 191.753998 -320.294762) (xy 191.773344 -320.278968) (xy 191.81563 -320.252395)
			(xy 191.861211 -320.231986) (xy 191.909196 -320.21814) (xy 191.958643 -320.211128) (xy 191.983614 -320.210688)
			(xy 192.010262 -320.211195) (xy 192.062963 -320.21914) (xy 192.113892 -320.234851) (xy 192.16191 -320.257977)
			(xy 192.205945 -320.288001) (xy 192.245013 -320.324253) (xy 192.278243 -320.365923) (xy 192.30489 -320.412079)
			(xy 192.324361 -320.461692) (xy 192.336221 -320.513652) (xy 192.340204 -320.5668) (xy 192.338207 -320.593445)
			(xy 194.48271 -320.593445) (xy 194.48271 -320.540147) (xy 194.490653 -320.487443) (xy 194.506363 -320.436513)
			(xy 194.529489 -320.388492) (xy 194.559513 -320.344455) (xy 194.595765 -320.305384) (xy 194.637436 -320.272153)
			(xy 194.683594 -320.245504) (xy 194.733208 -320.226032) (xy 194.78517 -320.214172) (xy 194.83832 -320.210189)
			(xy 194.89147 -320.214172) (xy 194.943432 -320.226032) (xy 194.993046 -320.245504) (xy 195.039204 -320.272153)
			(xy 195.080875 -320.305384) (xy 195.117127 -320.344455) (xy 195.147151 -320.388492) (xy 195.170277 -320.436513)
			(xy 195.185987 -320.487443) (xy 195.19393 -320.540147) (xy 195.194428 -320.566796) (xy 195.19393 -320.593445)
			(xy 199.171804 -320.593445) (xy 199.171804 -320.540147) (xy 199.179747 -320.487443) (xy 199.195457 -320.436513)
			(xy 199.218583 -320.388492) (xy 199.248607 -320.344455) (xy 199.284859 -320.305384) (xy 199.32653 -320.272153)
			(xy 199.372688 -320.245504) (xy 199.422302 -320.226032) (xy 199.474264 -320.214172) (xy 199.527414 -320.210189)
			(xy 199.580564 -320.214172) (xy 199.632526 -320.226032) (xy 199.68214 -320.245504) (xy 199.728298 -320.272153)
			(xy 199.769969 -320.305384) (xy 199.806221 -320.344455) (xy 199.836245 -320.388492) (xy 199.859371 -320.436513)
			(xy 199.875081 -320.487443) (xy 199.883024 -320.540147) (xy 199.883522 -320.566796) (xy 199.883024 -320.593445)
			(xy 202.05191 -320.593445) (xy 202.05191 -320.540147) (xy 202.059853 -320.487443) (xy 202.075563 -320.436513)
			(xy 202.098689 -320.388492) (xy 202.128713 -320.344455) (xy 202.164965 -320.305384) (xy 202.206636 -320.272153)
			(xy 202.252794 -320.245504) (xy 202.302408 -320.226032) (xy 202.35437 -320.214172) (xy 202.40752 -320.210189)
			(xy 202.46067 -320.214172) (xy 202.512632 -320.226032) (xy 202.562246 -320.245504) (xy 202.608404 -320.272153)
			(xy 202.650075 -320.305384) (xy 202.686327 -320.344455) (xy 202.716351 -320.388492) (xy 202.739477 -320.436513)
			(xy 202.755187 -320.487443) (xy 202.76313 -320.540147) (xy 202.763628 -320.566796) (xy 202.76313 -320.593445)
			(xy 206.715604 -320.593445) (xy 206.715604 -320.540147) (xy 206.723547 -320.487443) (xy 206.739257 -320.436513)
			(xy 206.762383 -320.388492) (xy 206.792407 -320.344455) (xy 206.828659 -320.305384) (xy 206.87033 -320.272153)
			(xy 206.916488 -320.245504) (xy 206.966102 -320.226032) (xy 207.018064 -320.214172) (xy 207.071214 -320.210189)
			(xy 207.124364 -320.214172) (xy 207.176326 -320.226032) (xy 207.22594 -320.245504) (xy 207.272098 -320.272153)
			(xy 207.313769 -320.305384) (xy 207.350021 -320.344455) (xy 207.380045 -320.388492) (xy 207.403171 -320.436513)
			(xy 207.418881 -320.487443) (xy 207.426824 -320.540147) (xy 207.427322 -320.566796) (xy 207.426824 -320.593445)
			(xy 209.63889 -320.593445) (xy 209.63889 -320.540147) (xy 209.646833 -320.487443) (xy 209.662543 -320.436513)
			(xy 209.685669 -320.388492) (xy 209.715693 -320.344455) (xy 209.751945 -320.305384) (xy 209.793616 -320.272153)
			(xy 209.839774 -320.245504) (xy 209.889388 -320.226032) (xy 209.94135 -320.214172) (xy 209.9945 -320.210189)
			(xy 210.04765 -320.214172) (xy 210.099612 -320.226032) (xy 210.149226 -320.245504) (xy 210.195384 -320.272153)
			(xy 210.237055 -320.305384) (xy 210.273307 -320.344455) (xy 210.303331 -320.388492) (xy 210.326457 -320.436513)
			(xy 210.342167 -320.487443) (xy 210.35011 -320.540147) (xy 210.350608 -320.566796) (xy 210.35011 -320.593445)
			(xy 214.259404 -320.593445) (xy 214.259404 -320.540147) (xy 214.267347 -320.487443) (xy 214.283057 -320.436513)
			(xy 214.306183 -320.388492) (xy 214.336207 -320.344455) (xy 214.372459 -320.305384) (xy 214.41413 -320.272153)
			(xy 214.460288 -320.245504) (xy 214.509902 -320.226032) (xy 214.561864 -320.214172) (xy 214.615014 -320.210189)
			(xy 214.668164 -320.214172) (xy 214.720126 -320.226032) (xy 214.76974 -320.245504) (xy 214.815898 -320.272153)
			(xy 214.857569 -320.305384) (xy 214.893821 -320.344455) (xy 214.923845 -320.388492) (xy 214.946971 -320.436513)
			(xy 214.962681 -320.487443) (xy 214.970624 -320.540147) (xy 214.971122 -320.566796) (xy 214.970624 -320.593445)
			(xy 214.962681 -320.646149) (xy 214.946971 -320.697079) (xy 214.923845 -320.7451) (xy 214.893821 -320.789137)
			(xy 214.857569 -320.828208) (xy 214.815898 -320.861439) (xy 214.76974 -320.888088) (xy 214.720126 -320.90756)
			(xy 214.668164 -320.91942) (xy 214.615014 -320.923404) (xy 214.561864 -320.91942) (xy 214.509902 -320.90756)
			(xy 214.460288 -320.888088) (xy 214.41413 -320.861439) (xy 214.372459 -320.828208) (xy 214.336207 -320.789137)
			(xy 214.306183 -320.7451) (xy 214.283057 -320.697079) (xy 214.267347 -320.646149) (xy 214.259404 -320.593445)
			(xy 210.35011 -320.593445) (xy 210.342167 -320.646149) (xy 210.326457 -320.697079) (xy 210.303331 -320.7451)
			(xy 210.273307 -320.789137) (xy 210.237055 -320.828208) (xy 210.195384 -320.861439) (xy 210.149226 -320.888088)
			(xy 210.099612 -320.90756) (xy 210.04765 -320.91942) (xy 209.9945 -320.923404) (xy 209.94135 -320.91942)
			(xy 209.889388 -320.90756) (xy 209.839774 -320.888088) (xy 209.793616 -320.861439) (xy 209.751945 -320.828208)
			(xy 209.715693 -320.789137) (xy 209.685669 -320.7451) (xy 209.662543 -320.697079) (xy 209.646833 -320.646149)
			(xy 209.63889 -320.593445) (xy 207.426824 -320.593445) (xy 207.418881 -320.646149) (xy 207.403171 -320.697079)
			(xy 207.380045 -320.7451) (xy 207.350021 -320.789137) (xy 207.313769 -320.828208) (xy 207.272098 -320.861439)
			(xy 207.22594 -320.888088) (xy 207.176326 -320.90756) (xy 207.124364 -320.91942) (xy 207.071214 -320.923404)
			(xy 207.018064 -320.91942) (xy 206.966102 -320.90756) (xy 206.916488 -320.888088) (xy 206.87033 -320.861439)
			(xy 206.828659 -320.828208) (xy 206.792407 -320.789137) (xy 206.762383 -320.7451) (xy 206.739257 -320.697079)
			(xy 206.723547 -320.646149) (xy 206.715604 -320.593445) (xy 202.76313 -320.593445) (xy 202.755187 -320.646149)
			(xy 202.739477 -320.697079) (xy 202.716351 -320.7451) (xy 202.686327 -320.789137) (xy 202.650075 -320.828208)
			(xy 202.608404 -320.861439) (xy 202.562246 -320.888088) (xy 202.512632 -320.90756) (xy 202.46067 -320.91942)
			(xy 202.40752 -320.923404) (xy 202.35437 -320.91942) (xy 202.302408 -320.90756) (xy 202.252794 -320.888088)
			(xy 202.206636 -320.861439) (xy 202.164965 -320.828208) (xy 202.128713 -320.789137) (xy 202.098689 -320.7451)
			(xy 202.075563 -320.697079) (xy 202.059853 -320.646149) (xy 202.05191 -320.593445) (xy 199.883024 -320.593445)
			(xy 199.875081 -320.646149) (xy 199.859371 -320.697079) (xy 199.836245 -320.7451) (xy 199.806221 -320.789137)
			(xy 199.769969 -320.828208) (xy 199.728298 -320.861439) (xy 199.68214 -320.888088) (xy 199.632526 -320.90756)
			(xy 199.580564 -320.91942) (xy 199.527414 -320.923404) (xy 199.474264 -320.91942) (xy 199.422302 -320.90756)
			(xy 199.372688 -320.888088) (xy 199.32653 -320.861439) (xy 199.284859 -320.828208) (xy 199.248607 -320.789137)
			(xy 199.218583 -320.7451) (xy 199.195457 -320.697079) (xy 199.179747 -320.646149) (xy 199.171804 -320.593445)
			(xy 195.19393 -320.593445) (xy 195.185987 -320.646149) (xy 195.170277 -320.697079) (xy 195.147151 -320.7451)
			(xy 195.117127 -320.789137) (xy 195.080875 -320.828208) (xy 195.039204 -320.861439) (xy 194.993046 -320.888088)
			(xy 194.943432 -320.90756) (xy 194.89147 -320.91942) (xy 194.83832 -320.923404) (xy 194.78517 -320.91942)
			(xy 194.733208 -320.90756) (xy 194.683594 -320.888088) (xy 194.637436 -320.861439) (xy 194.595765 -320.828208)
			(xy 194.559513 -320.789137) (xy 194.529489 -320.7451) (xy 194.506363 -320.697079) (xy 194.490653 -320.646149)
			(xy 194.48271 -320.593445) (xy 192.338207 -320.593445) (xy 192.336221 -320.619948) (xy 192.324361 -320.671908)
			(xy 192.30489 -320.721521) (xy 192.278243 -320.767677) (xy 192.245013 -320.809347) (xy 192.205945 -320.845599)
			(xy 192.16191 -320.875623) (xy 192.113892 -320.898749) (xy 192.062963 -320.91446) (xy 192.010262 -320.922405)
			(xy 191.983614 -320.922904) (xy 191.956924 -320.92243) (xy 191.904143 -320.914465) (xy 191.853141 -320.898711)
			(xy 191.805062 -320.875521) (xy 191.760983 -320.845415) (xy 191.721892 -320.809067) (xy 191.688663 -320.767291)
			(xy 191.662042 -320.721024) (xy 191.65189 -320.696336) (xy 191.646381 -320.683652) (xy 191.62984 -320.661511)
			(xy 191.607966 -320.64462) (xy 191.582363 -320.634216) (xy 191.554906 -320.631064) (xy 191.527611 -320.635394)
			(xy 191.502478 -320.646888) (xy 191.491616 -320.655442) (xy 191.472266 -320.67123) (xy 191.429981 -320.697804)
			(xy 191.3844 -320.718214) (xy 191.336417 -320.732062) (xy 191.28697 -320.739075) (xy 191.262 -320.739516)
			(xy 191.235351 -320.739002) (xy 191.182649 -320.731059) (xy 191.13172 -320.715349) (xy 191.0837 -320.692224)
			(xy 191.039664 -320.662201) (xy 191.000594 -320.625949) (xy 190.967364 -320.58428) (xy 190.940715 -320.538123)
			(xy 190.921243 -320.48851) (xy 190.909383 -320.436548) (xy 190.905401 -320.3834) (xy 187.650679 -320.3834)
			(xy 187.654151 -320.388492) (xy 187.677277 -320.436513) (xy 187.692987 -320.487443) (xy 187.70093 -320.540147)
			(xy 187.701428 -320.566796) (xy 187.70093 -320.593445) (xy 187.692987 -320.646149) (xy 187.677277 -320.697079)
			(xy 187.654151 -320.7451) (xy 187.624127 -320.789137) (xy 187.587875 -320.828208) (xy 187.546204 -320.861439)
			(xy 187.500046 -320.888088) (xy 187.450432 -320.90756) (xy 187.39847 -320.91942) (xy 187.34532 -320.923404)
			(xy 187.29217 -320.91942) (xy 187.240208 -320.90756) (xy 187.190594 -320.888088) (xy 187.144436 -320.861439)
			(xy 187.102765 -320.828208) (xy 187.066513 -320.789137) (xy 187.036489 -320.7451) (xy 187.013363 -320.697079)
			(xy 186.997653 -320.646149) (xy 186.98971 -320.593445) (xy 184.795424 -320.593445) (xy 184.787481 -320.646149)
			(xy 184.771771 -320.697079) (xy 184.748645 -320.7451) (xy 184.718621 -320.789137) (xy 184.682369 -320.828208)
			(xy 184.640698 -320.861439) (xy 184.59454 -320.888088) (xy 184.544926 -320.90756) (xy 184.492964 -320.91942)
			(xy 184.439814 -320.923404) (xy 184.386664 -320.91942) (xy 184.334702 -320.90756) (xy 184.285088 -320.888088)
			(xy 184.23893 -320.861439) (xy 184.197259 -320.828208) (xy 184.161007 -320.789137) (xy 184.130983 -320.7451)
			(xy 184.107857 -320.697079) (xy 184.092147 -320.646149) (xy 184.084204 -320.593445) (xy 180.209531 -320.593445)
			(xy 180.207544 -320.619956) (xy 180.195682 -320.671925) (xy 180.176206 -320.721545) (xy 180.149551 -320.767708)
			(xy 180.116314 -320.809383) (xy 180.077236 -320.845637) (xy 180.033191 -320.875662) (xy 179.985162 -320.898787)
			(xy 179.934224 -320.914494) (xy 179.881513 -320.922434) (xy 179.85486 -320.922904) (xy 179.826772 -320.922399)
			(xy 179.771295 -320.913561) (xy 179.717893 -320.896125) (xy 179.667889 -320.870523) (xy 179.622523 -320.837391)
			(xy 179.58292 -320.797549) (xy 179.566062 -320.775076) (xy 179.557662 -320.764161) (xy 179.536206 -320.746911)
			(xy 179.510917 -320.736031) (xy 179.483639 -320.732314) (xy 179.456361 -320.736031) (xy 179.431072 -320.746911)
			(xy 179.409616 -320.764161) (xy 179.401216 -320.775076) (xy 179.38438 -320.797567) (xy 179.344781 -320.837418)
			(xy 179.299413 -320.870552) (xy 179.249402 -320.896147) (xy 179.195992 -320.913568) (xy 179.140508 -320.922381)
			(xy 179.112418 -320.922904) (xy 179.085766 -320.92244) (xy 179.033056 -320.914498) (xy 178.982119 -320.898788)
			(xy 178.934092 -320.875662) (xy 178.890049 -320.845636) (xy 178.850973 -320.80938) (xy 178.817737 -320.767706)
			(xy 178.791084 -320.721543) (xy 178.771609 -320.671924) (xy 178.759748 -320.619956) (xy 178.755764 -320.5668)
			(xy 176.649155 -320.5668) (xy 176.655233 -320.58541) (xy 176.670598 -320.608477) (xy 176.691594 -320.626567)
			(xy 176.716679 -320.638353) (xy 176.744008 -320.642966) (xy 176.757838 -320.64198) (xy 176.795684 -320.639948)
			(xy 176.822766 -320.640481) (xy 176.876307 -320.64868) (xy 176.927988 -320.664894) (xy 176.976618 -320.688746)
			(xy 177.021075 -320.719688) (xy 177.060334 -320.757005) (xy 177.093489 -320.799836) (xy 177.119776 -320.847195)
			(xy 177.138587 -320.897988) (xy 177.149491 -320.951044) (xy 177.152233 -321.005139) (xy 177.146753 -321.059026)
			(xy 177.133175 -321.111461) (xy 177.111814 -321.161236) (xy 177.083161 -321.207202) (xy 177.047878 -321.248298)
			(xy 177.006779 -321.283578) (xy 176.960811 -321.312227) (xy 176.912771 -321.332839) (xy 179.978548 -321.332839)
			(xy 179.978548 -321.279541) (xy 179.986491 -321.226837) (xy 180.002201 -321.175907) (xy 180.025327 -321.127886)
			(xy 180.055351 -321.083849) (xy 180.091603 -321.044778) (xy 180.133274 -321.011547) (xy 180.179432 -320.984898)
			(xy 180.229046 -320.965426) (xy 180.281008 -320.953566) (xy 180.334158 -320.949583) (xy 180.387308 -320.953566)
			(xy 180.43927 -320.965426) (xy 180.488884 -320.984898) (xy 180.535042 -321.011547) (xy 180.576713 -321.044778)
			(xy 180.612965 -321.083849) (xy 180.642989 -321.127886) (xy 180.666115 -321.175907) (xy 180.681825 -321.226837)
			(xy 180.689768 -321.279541) (xy 180.690266 -321.30619) (xy 180.689768 -321.332839) (xy 180.681825 -321.385543)
			(xy 180.666115 -321.436473) (xy 180.662813 -321.443329) (xy 184.075568 -321.443329) (xy 184.075568 -321.390031)
			(xy 184.083511 -321.337327) (xy 184.099221 -321.286397) (xy 184.122347 -321.238376) (xy 184.152371 -321.194339)
			(xy 184.188623 -321.155268) (xy 184.230294 -321.122037) (xy 184.276452 -321.095388) (xy 184.326066 -321.075916)
			(xy 184.378028 -321.064056) (xy 184.431178 -321.060073) (xy 184.484328 -321.064056) (xy 184.53629 -321.075916)
			(xy 184.585904 -321.095388) (xy 184.632062 -321.122037) (xy 184.673733 -321.155268) (xy 184.709985 -321.194339)
			(xy 184.740009 -321.238376) (xy 184.763135 -321.286397) (xy 184.778845 -321.337327) (xy 184.786788 -321.390031)
			(xy 184.787286 -321.41668) (xy 184.786788 -321.443329) (xy 187.527428 -321.443329) (xy 187.527428 -321.390031)
			(xy 187.535371 -321.337327) (xy 187.551081 -321.286397) (xy 187.574207 -321.238376) (xy 187.604231 -321.194339)
			(xy 187.640483 -321.155268) (xy 187.682154 -321.122037) (xy 187.728312 -321.095388) (xy 187.777926 -321.075916)
			(xy 187.829888 -321.064056) (xy 187.883038 -321.060073) (xy 187.936188 -321.064056) (xy 187.98815 -321.075916)
			(xy 188.037764 -321.095388) (xy 188.083922 -321.122037) (xy 188.125593 -321.155268) (xy 188.161845 -321.194339)
			(xy 188.191869 -321.238376) (xy 188.214995 -321.286397) (xy 188.230705 -321.337327) (xy 188.238648 -321.390031)
			(xy 188.239146 -321.41668) (xy 188.238648 -321.443329) (xy 191.616828 -321.443329) (xy 191.616828 -321.390031)
			(xy 191.624771 -321.337327) (xy 191.640481 -321.286397) (xy 191.663607 -321.238376) (xy 191.693631 -321.194339)
			(xy 191.729883 -321.155268) (xy 191.771554 -321.122037) (xy 191.817712 -321.095388) (xy 191.867326 -321.075916)
			(xy 191.919288 -321.064056) (xy 191.972438 -321.060073) (xy 192.025588 -321.064056) (xy 192.07755 -321.075916)
			(xy 192.127164 -321.095388) (xy 192.173322 -321.122037) (xy 192.214993 -321.155268) (xy 192.251245 -321.194339)
			(xy 192.281269 -321.238376) (xy 192.304395 -321.286397) (xy 192.320105 -321.337327) (xy 192.328048 -321.390031)
			(xy 192.328546 -321.41668) (xy 192.328048 -321.443329) (xy 195.071736 -321.443329) (xy 195.071736 -321.390031)
			(xy 195.079679 -321.337327) (xy 195.095389 -321.286397) (xy 195.118515 -321.238376) (xy 195.148539 -321.194339)
			(xy 195.184791 -321.155268) (xy 195.226462 -321.122037) (xy 195.27262 -321.095388) (xy 195.322234 -321.075916)
			(xy 195.374196 -321.064056) (xy 195.427346 -321.060073) (xy 195.480496 -321.064056) (xy 195.532458 -321.075916)
			(xy 195.582072 -321.095388) (xy 195.62823 -321.122037) (xy 195.669901 -321.155268) (xy 195.706153 -321.194339)
			(xy 195.736177 -321.238376) (xy 195.759303 -321.286397) (xy 195.775013 -321.337327) (xy 195.782956 -321.390031)
			(xy 195.783454 -321.41668) (xy 195.782956 -321.443329) (xy 199.171804 -321.443329) (xy 199.171804 -321.390031)
			(xy 199.179747 -321.337327) (xy 199.195457 -321.286397) (xy 199.218583 -321.238376) (xy 199.248607 -321.194339)
			(xy 199.284859 -321.155268) (xy 199.32653 -321.122037) (xy 199.372688 -321.095388) (xy 199.422302 -321.075916)
			(xy 199.474264 -321.064056) (xy 199.527414 -321.060073) (xy 199.580564 -321.064056) (xy 199.632526 -321.075916)
			(xy 199.68214 -321.095388) (xy 199.728298 -321.122037) (xy 199.769969 -321.155268) (xy 199.806221 -321.194339)
			(xy 199.836245 -321.238376) (xy 199.859371 -321.286397) (xy 199.875081 -321.337327) (xy 199.883024 -321.390031)
			(xy 199.883522 -321.41668) (xy 199.883024 -321.443329) (xy 202.615536 -321.443329) (xy 202.615536 -321.390031)
			(xy 202.623479 -321.337327) (xy 202.639189 -321.286397) (xy 202.662315 -321.238376) (xy 202.692339 -321.194339)
			(xy 202.728591 -321.155268) (xy 202.770262 -321.122037) (xy 202.81642 -321.095388) (xy 202.866034 -321.075916)
			(xy 202.917996 -321.064056) (xy 202.971146 -321.060073) (xy 203.024296 -321.064056) (xy 203.076258 -321.075916)
			(xy 203.125872 -321.095388) (xy 203.17203 -321.122037) (xy 203.213701 -321.155268) (xy 203.249953 -321.194339)
			(xy 203.279977 -321.238376) (xy 203.303103 -321.286397) (xy 203.318813 -321.337327) (xy 203.326756 -321.390031)
			(xy 203.327254 -321.41668) (xy 203.326756 -321.443329) (xy 206.715604 -321.443329) (xy 206.715604 -321.390031)
			(xy 206.723547 -321.337327) (xy 206.739257 -321.286397) (xy 206.762383 -321.238376) (xy 206.792407 -321.194339)
			(xy 206.828659 -321.155268) (xy 206.87033 -321.122037) (xy 206.916488 -321.095388) (xy 206.966102 -321.075916)
			(xy 207.018064 -321.064056) (xy 207.071214 -321.060073) (xy 207.124364 -321.064056) (xy 207.176326 -321.075916)
			(xy 207.22594 -321.095388) (xy 207.272098 -321.122037) (xy 207.313769 -321.155268) (xy 207.350021 -321.194339)
			(xy 207.380045 -321.238376) (xy 207.403171 -321.286397) (xy 207.418881 -321.337327) (xy 207.426824 -321.390031)
			(xy 207.427322 -321.41668) (xy 207.426824 -321.443329) (xy 210.159336 -321.443329) (xy 210.159336 -321.390031)
			(xy 210.167279 -321.337327) (xy 210.182989 -321.286397) (xy 210.206115 -321.238376) (xy 210.236139 -321.194339)
			(xy 210.272391 -321.155268) (xy 210.314062 -321.122037) (xy 210.36022 -321.095388) (xy 210.409834 -321.075916)
			(xy 210.461796 -321.064056) (xy 210.514946 -321.060073) (xy 210.568096 -321.064056) (xy 210.620058 -321.075916)
			(xy 210.669672 -321.095388) (xy 210.71583 -321.122037) (xy 210.757501 -321.155268) (xy 210.793753 -321.194339)
			(xy 210.823777 -321.238376) (xy 210.846903 -321.286397) (xy 210.862613 -321.337327) (xy 210.870556 -321.390031)
			(xy 210.871054 -321.41668) (xy 210.870556 -321.443329) (xy 214.259404 -321.443329) (xy 214.259404 -321.390031)
			(xy 214.267347 -321.337327) (xy 214.283057 -321.286397) (xy 214.306183 -321.238376) (xy 214.336207 -321.194339)
			(xy 214.372459 -321.155268) (xy 214.41413 -321.122037) (xy 214.460288 -321.095388) (xy 214.509902 -321.075916)
			(xy 214.561864 -321.064056) (xy 214.615014 -321.060073) (xy 214.668164 -321.064056) (xy 214.720126 -321.075916)
			(xy 214.76974 -321.095388) (xy 214.815898 -321.122037) (xy 214.857569 -321.155268) (xy 214.893821 -321.194339)
			(xy 214.923845 -321.238376) (xy 214.946971 -321.286397) (xy 214.962681 -321.337327) (xy 214.970624 -321.390031)
			(xy 214.971122 -321.41668) (xy 214.970624 -321.443329) (xy 214.962681 -321.496033) (xy 214.946971 -321.546963)
			(xy 214.923845 -321.594984) (xy 214.893821 -321.639021) (xy 214.857569 -321.678092) (xy 214.815898 -321.711323)
			(xy 214.76974 -321.737972) (xy 214.720126 -321.757444) (xy 214.668164 -321.769304) (xy 214.615014 -321.773288)
			(xy 214.561864 -321.769304) (xy 214.509902 -321.757444) (xy 214.460288 -321.737972) (xy 214.41413 -321.711323)
			(xy 214.372459 -321.678092) (xy 214.336207 -321.639021) (xy 214.306183 -321.594984) (xy 214.283057 -321.546963)
			(xy 214.267347 -321.496033) (xy 214.259404 -321.443329) (xy 210.870556 -321.443329) (xy 210.862613 -321.496033)
			(xy 210.846903 -321.546963) (xy 210.823777 -321.594984) (xy 210.793753 -321.639021) (xy 210.757501 -321.678092)
			(xy 210.71583 -321.711323) (xy 210.669672 -321.737972) (xy 210.620058 -321.757444) (xy 210.568096 -321.769304)
			(xy 210.514946 -321.773288) (xy 210.461796 -321.769304) (xy 210.409834 -321.757444) (xy 210.36022 -321.737972)
			(xy 210.314062 -321.711323) (xy 210.272391 -321.678092) (xy 210.236139 -321.639021) (xy 210.206115 -321.594984)
			(xy 210.182989 -321.546963) (xy 210.167279 -321.496033) (xy 210.159336 -321.443329) (xy 207.426824 -321.443329)
			(xy 207.418881 -321.496033) (xy 207.403171 -321.546963) (xy 207.380045 -321.594984) (xy 207.350021 -321.639021)
			(xy 207.313769 -321.678092) (xy 207.272098 -321.711323) (xy 207.22594 -321.737972) (xy 207.176326 -321.757444)
			(xy 207.124364 -321.769304) (xy 207.071214 -321.773288) (xy 207.018064 -321.769304) (xy 206.966102 -321.757444)
			(xy 206.916488 -321.737972) (xy 206.87033 -321.711323) (xy 206.828659 -321.678092) (xy 206.792407 -321.639021)
			(xy 206.762383 -321.594984) (xy 206.739257 -321.546963) (xy 206.723547 -321.496033) (xy 206.715604 -321.443329)
			(xy 203.326756 -321.443329) (xy 203.318813 -321.496033) (xy 203.303103 -321.546963) (xy 203.279977 -321.594984)
			(xy 203.249953 -321.639021) (xy 203.213701 -321.678092) (xy 203.17203 -321.711323) (xy 203.125872 -321.737972)
			(xy 203.076258 -321.757444) (xy 203.024296 -321.769304) (xy 202.971146 -321.773288) (xy 202.917996 -321.769304)
			(xy 202.866034 -321.757444) (xy 202.81642 -321.737972) (xy 202.770262 -321.711323) (xy 202.728591 -321.678092)
			(xy 202.692339 -321.639021) (xy 202.662315 -321.594984) (xy 202.639189 -321.546963) (xy 202.623479 -321.496033)
			(xy 202.615536 -321.443329) (xy 199.883024 -321.443329) (xy 199.875081 -321.496033) (xy 199.859371 -321.546963)
			(xy 199.836245 -321.594984) (xy 199.806221 -321.639021) (xy 199.769969 -321.678092) (xy 199.728298 -321.711323)
			(xy 199.68214 -321.737972) (xy 199.632526 -321.757444) (xy 199.580564 -321.769304) (xy 199.527414 -321.773288)
			(xy 199.474264 -321.769304) (xy 199.422302 -321.757444) (xy 199.372688 -321.737972) (xy 199.32653 -321.711323)
			(xy 199.284859 -321.678092) (xy 199.248607 -321.639021) (xy 199.218583 -321.594984) (xy 199.195457 -321.546963)
			(xy 199.179747 -321.496033) (xy 199.171804 -321.443329) (xy 195.782956 -321.443329) (xy 195.775013 -321.496033)
			(xy 195.759303 -321.546963) (xy 195.736177 -321.594984) (xy 195.706153 -321.639021) (xy 195.669901 -321.678092)
			(xy 195.62823 -321.711323) (xy 195.582072 -321.737972) (xy 195.532458 -321.757444) (xy 195.480496 -321.769304)
			(xy 195.427346 -321.773288) (xy 195.374196 -321.769304) (xy 195.322234 -321.757444) (xy 195.27262 -321.737972)
			(xy 195.226462 -321.711323) (xy 195.184791 -321.678092) (xy 195.148539 -321.639021) (xy 195.118515 -321.594984)
			(xy 195.095389 -321.546963) (xy 195.079679 -321.496033) (xy 195.071736 -321.443329) (xy 192.328048 -321.443329)
			(xy 192.320105 -321.496033) (xy 192.304395 -321.546963) (xy 192.281269 -321.594984) (xy 192.251245 -321.639021)
			(xy 192.214993 -321.678092) (xy 192.173322 -321.711323) (xy 192.127164 -321.737972) (xy 192.07755 -321.757444)
			(xy 192.025588 -321.769304) (xy 191.972438 -321.773288) (xy 191.919288 -321.769304) (xy 191.867326 -321.757444)
			(xy 191.817712 -321.737972) (xy 191.771554 -321.711323) (xy 191.729883 -321.678092) (xy 191.693631 -321.639021)
			(xy 191.663607 -321.594984) (xy 191.640481 -321.546963) (xy 191.624771 -321.496033) (xy 191.616828 -321.443329)
			(xy 188.238648 -321.443329) (xy 188.230705 -321.496033) (xy 188.214995 -321.546963) (xy 188.191869 -321.594984)
			(xy 188.161845 -321.639021) (xy 188.125593 -321.678092) (xy 188.083922 -321.711323) (xy 188.037764 -321.737972)
			(xy 187.98815 -321.757444) (xy 187.936188 -321.769304) (xy 187.883038 -321.773288) (xy 187.829888 -321.769304)
			(xy 187.777926 -321.757444) (xy 187.728312 -321.737972) (xy 187.682154 -321.711323) (xy 187.640483 -321.678092)
			(xy 187.604231 -321.639021) (xy 187.574207 -321.594984) (xy 187.551081 -321.546963) (xy 187.535371 -321.496033)
			(xy 187.527428 -321.443329) (xy 184.786788 -321.443329) (xy 184.778845 -321.496033) (xy 184.763135 -321.546963)
			(xy 184.740009 -321.594984) (xy 184.709985 -321.639021) (xy 184.673733 -321.678092) (xy 184.632062 -321.711323)
			(xy 184.585904 -321.737972) (xy 184.53629 -321.757444) (xy 184.484328 -321.769304) (xy 184.431178 -321.773288)
			(xy 184.378028 -321.769304) (xy 184.326066 -321.757444) (xy 184.276452 -321.737972) (xy 184.230294 -321.711323)
			(xy 184.188623 -321.678092) (xy 184.152371 -321.639021) (xy 184.122347 -321.594984) (xy 184.099221 -321.546963)
			(xy 184.083511 -321.496033) (xy 184.075568 -321.443329) (xy 180.662813 -321.443329) (xy 180.642989 -321.484494)
			(xy 180.612965 -321.528531) (xy 180.576713 -321.567602) (xy 180.535042 -321.600833) (xy 180.488884 -321.627482)
			(xy 180.43927 -321.646954) (xy 180.387308 -321.658814) (xy 180.334158 -321.662798) (xy 180.281008 -321.658814)
			(xy 180.229046 -321.646954) (xy 180.179432 -321.627482) (xy 180.133274 -321.600833) (xy 180.091603 -321.567602)
			(xy 180.055351 -321.528531) (xy 180.025327 -321.484494) (xy 180.002201 -321.436473) (xy 179.986491 -321.385543)
			(xy 179.978548 -321.332839) (xy 176.912771 -321.332839) (xy 176.911035 -321.333584) (xy 176.858598 -321.347158)
			(xy 176.804711 -321.352634) (xy 176.750616 -321.349887) (xy 176.697561 -321.33898) (xy 176.646769 -321.320164)
			(xy 176.599413 -321.293874) (xy 176.556584 -321.260715) (xy 176.51927 -321.221453) (xy 176.488332 -321.176994)
			(xy 176.464483 -321.128362) (xy 176.448274 -321.07668) (xy 176.440078 -321.023138) (xy 176.439576 -320.996056)
			(xy 176.439871 -320.975613) (xy 176.444584 -320.934999) (xy 176.448974 -320.91503) (xy 176.451677 -320.90143)
			(xy 176.450469 -320.873738) (xy 176.441865 -320.84739) (xy 176.426498 -320.824321) (xy 176.405498 -320.80623)
			(xy 176.380409 -320.794446) (xy 176.353078 -320.789836) (xy 176.339246 -320.790824) (xy 176.3014 -320.792856)
			(xy 176.274319 -320.792302) (xy 176.220782 -320.7841) (xy 176.169104 -320.767886) (xy 176.120477 -320.744033)
			(xy 176.076024 -320.713091) (xy 176.036768 -320.675774) (xy 176.003617 -320.632944) (xy 175.977333 -320.585587)
			(xy 175.958524 -320.534795) (xy 175.947624 -320.481742) (xy 175.944883 -320.427649) (xy 172.534608 -320.427649)
			(xy 172.538877 -320.436513) (xy 172.554587 -320.487443) (xy 172.56253 -320.540147) (xy 172.563028 -320.566796)
			(xy 172.56253 -320.593445) (xy 172.554587 -320.646149) (xy 172.538877 -320.697079) (xy 172.515751 -320.7451)
			(xy 172.485727 -320.789137) (xy 172.449475 -320.828208) (xy 172.407804 -320.861439) (xy 172.361646 -320.888088)
			(xy 172.312032 -320.90756) (xy 172.26007 -320.91942) (xy 172.20692 -320.923404) (xy 172.15377 -320.91942)
			(xy 172.101808 -320.90756) (xy 172.052194 -320.888088) (xy 172.006036 -320.861439) (xy 171.964365 -320.828208)
			(xy 171.928113 -320.789137) (xy 171.898089 -320.7451) (xy 171.874963 -320.697079) (xy 171.859253 -320.646149)
			(xy 171.85131 -320.593445) (xy 169.707831 -320.593445) (xy 169.70782 -320.594059) (xy 169.699503 -320.647947)
			(xy 169.683061 -320.699935) (xy 169.658881 -320.748806) (xy 169.627528 -320.793416) (xy 169.609008 -320.81343)
			(xy 169.599135 -320.824464) (xy 169.58556 -320.850756) (xy 169.580104 -320.87984) (xy 169.583228 -320.909265)
			(xy 169.594668 -320.936554) (xy 169.603674 -320.948304) (xy 169.618819 -320.967484) (xy 169.644307 -321.009181)
			(xy 169.663856 -321.05397) (xy 169.677099 -321.101011) (xy 169.683786 -321.149421) (xy 169.684192 -321.173856)
			(xy 169.683694 -321.200505) (xy 169.675751 -321.253209) (xy 169.660041 -321.304139) (xy 169.648788 -321.327505)
			(xy 172.376074 -321.327505) (xy 172.376074 -321.274207) (xy 172.384017 -321.221503) (xy 172.399727 -321.170573)
			(xy 172.422853 -321.122552) (xy 172.452877 -321.078515) (xy 172.489129 -321.039444) (xy 172.5308 -321.006213)
			(xy 172.576958 -320.979564) (xy 172.626572 -320.960092) (xy 172.678534 -320.948232) (xy 172.731684 -320.944249)
			(xy 172.784834 -320.948232) (xy 172.836796 -320.960092) (xy 172.88641 -320.979564) (xy 172.932568 -321.006213)
			(xy 172.974239 -321.039444) (xy 173.010491 -321.078515) (xy 173.040515 -321.122552) (xy 173.063641 -321.170573)
			(xy 173.079351 -321.221503) (xy 173.087294 -321.274207) (xy 173.087792 -321.300856) (xy 173.087294 -321.327505)
			(xy 173.079351 -321.380209) (xy 173.063641 -321.431139) (xy 173.040515 -321.47916) (xy 173.010491 -321.523197)
			(xy 172.974239 -321.562268) (xy 172.932568 -321.595499) (xy 172.88641 -321.622148) (xy 172.836796 -321.64162)
			(xy 172.784834 -321.65348) (xy 172.731684 -321.657464) (xy 172.678534 -321.65348) (xy 172.626572 -321.64162)
			(xy 172.576958 -321.622148) (xy 172.5308 -321.595499) (xy 172.489129 -321.562268) (xy 172.452877 -321.523197)
			(xy 172.422853 -321.47916) (xy 172.399727 -321.431139) (xy 172.384017 -321.380209) (xy 172.376074 -321.327505)
			(xy 169.648788 -321.327505) (xy 169.636915 -321.35216) (xy 169.606891 -321.396197) (xy 169.570639 -321.435268)
			(xy 169.528968 -321.468499) (xy 169.48281 -321.495148) (xy 169.433196 -321.51462) (xy 169.381234 -321.52648)
			(xy 169.328084 -321.530464) (xy 169.274934 -321.52648) (xy 169.222972 -321.51462) (xy 169.173358 -321.495148)
			(xy 169.1272 -321.468499) (xy 169.085529 -321.435268) (xy 169.049277 -321.396197) (xy 169.019253 -321.35216)
			(xy 168.996127 -321.304139) (xy 168.980417 -321.253209) (xy 168.972474 -321.200505) (xy 168.971976 -321.173856)
			(xy 168.258701 -321.173856) (xy 168.238155 -321.196) (xy 168.196484 -321.229231) (xy 168.150326 -321.25588)
			(xy 168.100712 -321.275352) (xy 168.04875 -321.287212) (xy 167.9956 -321.291196) (xy 167.94245 -321.287212)
			(xy 167.890488 -321.275352) (xy 167.840874 -321.25588) (xy 167.794716 -321.229231) (xy 167.753045 -321.196)
			(xy 167.716793 -321.156929) (xy 167.686769 -321.112892) (xy 167.663643 -321.064871) (xy 167.647933 -321.013941)
			(xy 167.63999 -320.961237) (xy 160.600262 -320.961237) (xy 160.594956 -320.973296) (xy 160.591101 -321.001356)
			(xy 160.595096 -321.029396) (xy 160.606634 -321.055263) (xy 160.615376 -321.066414) (xy 160.631064 -321.085715)
			(xy 160.657424 -321.127893) (xy 160.677655 -321.173331) (xy 160.691362 -321.221144) (xy 160.698278 -321.270399)
			(xy 160.698688 -321.295268) (xy 160.69819 -321.321917) (xy 160.690247 -321.374621) (xy 160.674537 -321.425551)
			(xy 160.651411 -321.473572) (xy 160.621387 -321.517609) (xy 160.585135 -321.55668) (xy 160.543464 -321.589911)
			(xy 160.497306 -321.61656) (xy 160.447692 -321.636032) (xy 160.39573 -321.647892) (xy 160.34258 -321.651876)
			(xy 160.28943 -321.647892) (xy 160.237468 -321.636032) (xy 160.187854 -321.61656) (xy 160.141696 -321.589911)
			(xy 160.100025 -321.55668) (xy 160.063773 -321.517609) (xy 160.033749 -321.473572) (xy 160.010623 -321.425551)
			(xy 159.994913 -321.374621) (xy 159.98697 -321.321917) (xy 159.986472 -321.295268) (xy 159.47136 -321.295268)
			(xy 159.589216 -321.413124) (xy 160.256523 -321.785213) (xy 164.639488 -321.785213) (xy 164.639488 -321.731915)
			(xy 164.647431 -321.679211) (xy 164.663141 -321.628281) (xy 164.686267 -321.58026) (xy 164.716291 -321.536223)
			(xy 164.752543 -321.497152) (xy 164.794214 -321.463921) (xy 164.840372 -321.437272) (xy 164.889986 -321.4178)
			(xy 164.941948 -321.40594) (xy 164.995098 -321.401957) (xy 165.048248 -321.40594) (xy 165.10021 -321.4178)
			(xy 165.149824 -321.437272) (xy 165.195982 -321.463921) (xy 165.237653 -321.497152) (xy 165.273905 -321.536223)
			(xy 165.303929 -321.58026) (xy 165.327055 -321.628281) (xy 165.342765 -321.679211) (xy 165.350708 -321.731915)
			(xy 165.351206 -321.758564) (xy 165.350708 -321.785213) (xy 165.342765 -321.837917) (xy 165.327055 -321.888847)
			(xy 165.303929 -321.936868) (xy 165.273905 -321.980905) (xy 165.237653 -322.019976) (xy 165.195982 -322.053207)
			(xy 165.149824 -322.079856) (xy 165.10021 -322.099328) (xy 165.048248 -322.111188) (xy 164.995098 -322.115172)
			(xy 164.941948 -322.111188) (xy 164.889986 -322.099328) (xy 164.840372 -322.079856) (xy 164.794214 -322.053207)
			(xy 164.752543 -322.019976) (xy 164.716291 -321.980905) (xy 164.686267 -321.936868) (xy 164.663141 -321.888847)
			(xy 164.647431 -321.837917) (xy 164.639488 -321.785213) (xy 160.256523 -321.785213) (xy 161.19221 -322.30695)
			(xy 161.2142 -322.319382) (xy 161.25702 -322.346192) (xy 161.277808 -322.360544) (xy 162.393122 -323.14134)
			(xy 162.416903 -323.129511) (xy 162.467301 -323.112758) (xy 162.519729 -323.10428) (xy 162.546284 -323.103748)
			(xy 162.572273 -323.104256) (xy 162.623612 -323.112385) (xy 162.673048 -323.128444) (xy 162.719363 -323.152038)
			(xy 162.761417 -323.182587) (xy 162.798174 -323.219338) (xy 162.828731 -323.261386) (xy 162.852333 -323.307697)
			(xy 162.868401 -323.357129) (xy 162.876539 -323.408467) (xy 162.876992 -323.434456) (xy 162.876926 -323.445409)
			(xy 162.875529 -323.467271) (xy 162.874198 -323.478144) (xy 163.679632 -324.042278) (xy 163.714718 -324.067403)
			(xy 163.780831 -324.122877) (xy 163.841855 -324.183904) (xy 163.897326 -324.25002) (xy 163.922456 -324.285102)
			(xy 164.916358 -325.704708) (xy 164.94071 -325.740299) (xy 164.983814 -325.815) (xy 165.020242 -325.893175)
			(xy 165.049714 -325.974228) (xy 165.072008 -326.057542) (xy 165.079934 -326.099932) (xy 165.205586 -326.812148)
			(xy 178.870862 -326.812148) (xy 178.874933 -326.756526) (xy 178.887059 -326.702089) (xy 178.906982 -326.649998)
			(xy 178.934278 -326.601363) (xy 178.968364 -326.55722) (xy 179.008513 -326.518511) (xy 179.053871 -326.48606)
			(xy 179.103471 -326.460559) (xy 179.156255 -326.442552) (xy 179.211098 -326.432422) (xy 179.266832 -326.430385)
			(xy 179.322269 -326.436485) (xy 179.376226 -326.450591) (xy 179.427555 -326.472403) (xy 179.475161 -326.501457)
			(xy 179.518029 -326.537132) (xy 179.555246 -326.578669) (xy 179.586019 -326.625182) (xy 179.609691 -326.675679)
			(xy 179.620723 -326.712347) (xy 180.395926 -326.712347) (xy 180.395926 -326.657853) (xy 180.403681 -326.603914)
			(xy 180.419033 -326.551627) (xy 180.44167 -326.502058) (xy 180.471131 -326.456214) (xy 180.506816 -326.41503)
			(xy 180.547998 -326.379343) (xy 180.59384 -326.34988) (xy 180.643409 -326.32724) (xy 180.695694 -326.311885)
			(xy 180.749633 -326.304128) (xy 180.77688 -326.30364) (xy 180.805797 -326.304158) (xy 180.862969 -326.312885)
			(xy 180.918169 -326.330142) (xy 180.970131 -326.355533) (xy 181.017664 -326.388478) (xy 181.05968 -326.42822)
			(xy 181.07787 -326.450706) (xy 181.087767 -326.462511) (xy 181.113091 -326.48003) (xy 181.142484 -326.489206)
			(xy 181.173276 -326.489206) (xy 181.202669 -326.48003) (xy 181.227993 -326.462511) (xy 181.23789 -326.450706)
			(xy 181.256088 -326.428229) (xy 181.298106 -326.388493) (xy 181.34564 -326.355553) (xy 181.3976 -326.330163)
			(xy 181.452796 -326.312906) (xy 181.509964 -326.304176) (xy 181.53888 -326.30364) (xy 181.566137 -326.304006)
			(xy 181.620097 -326.311761) (xy 181.672404 -326.327117) (xy 181.721993 -326.349762) (xy 181.767854 -326.379233)
			(xy 181.809055 -326.414931) (xy 181.844755 -326.45613) (xy 181.874229 -326.501989) (xy 181.896876 -326.551577)
			(xy 181.912235 -326.603883) (xy 181.919993 -326.657843) (xy 181.919993 -326.712357) (xy 181.912235 -326.766317)
			(xy 181.896876 -326.818623) (xy 181.874229 -326.868211) (xy 181.844755 -326.91407) (xy 181.809055 -326.955269)
			(xy 181.767854 -326.990967) (xy 181.721993 -327.020438) (xy 181.672404 -327.043083) (xy 181.620097 -327.058439)
			(xy 181.566137 -327.066194) (xy 181.53888 -327.066656) (xy 181.509964 -327.066097) (xy 181.452794 -327.057378)
			(xy 181.397596 -327.04013) (xy 181.345633 -327.014746) (xy 181.298099 -326.981809) (xy 181.256081 -326.942073)
			(xy 181.23789 -326.91959) (xy 181.227993 -326.907785) (xy 181.202669 -326.890266) (xy 181.173276 -326.88109)
			(xy 181.142484 -326.88109) (xy 181.113091 -326.890266) (xy 181.087767 -326.907785) (xy 181.07787 -326.91959)
			(xy 181.059693 -326.942086) (xy 181.017671 -326.981821) (xy 180.970133 -327.014759) (xy 180.918169 -327.040145)
			(xy 180.862969 -327.057398) (xy 180.805797 -327.066123) (xy 180.77688 -327.066656) (xy 180.749633 -327.066072)
			(xy 180.695694 -327.058315) (xy 180.643409 -327.04296) (xy 180.59384 -327.02032) (xy 180.547998 -326.990857)
			(xy 180.506816 -326.95517) (xy 180.471131 -326.913986) (xy 180.44167 -326.868142) (xy 180.419033 -326.818573)
			(xy 180.403681 -326.766286) (xy 180.395926 -326.712347) (xy 179.620723 -326.712347) (xy 179.625759 -326.729086)
			(xy 179.633879 -326.784262) (xy 179.634388 -326.812148) (xy 179.633879 -326.840034) (xy 179.625759 -326.89521)
			(xy 179.609691 -326.948617) (xy 179.586019 -326.999114) (xy 179.555246 -327.045627) (xy 179.518029 -327.087164)
			(xy 179.475161 -327.122839) (xy 179.427555 -327.151893) (xy 179.376226 -327.173705) (xy 179.322269 -327.187811)
			(xy 179.266832 -327.193911) (xy 179.211098 -327.191874) (xy 179.156255 -327.181744) (xy 179.103471 -327.163737)
			(xy 179.053871 -327.138236) (xy 179.008513 -327.105785) (xy 178.968364 -327.067076) (xy 178.934278 -327.022933)
			(xy 178.906982 -326.974298) (xy 178.887059 -326.922207) (xy 178.874933 -326.86777) (xy 178.870862 -326.812148)
			(xy 165.205586 -326.812148) (xy 165.252146 -327.076054) (xy 165.87724 -327.701148) (xy 179.378862 -327.701148)
			(xy 179.382933 -327.645526) (xy 179.395059 -327.591089) (xy 179.414982 -327.538998) (xy 179.442278 -327.490363)
			(xy 179.476364 -327.44622) (xy 179.516513 -327.407511) (xy 179.561871 -327.37506) (xy 179.611471 -327.349559)
			(xy 179.664255 -327.331552) (xy 179.719098 -327.321422) (xy 179.774832 -327.319385) (xy 179.830269 -327.325485)
			(xy 179.884226 -327.339591) (xy 179.935555 -327.361403) (xy 179.983161 -327.390457) (xy 180.026029 -327.426132)
			(xy 180.063246 -327.467669) (xy 180.094019 -327.514182) (xy 180.117691 -327.564679) (xy 180.133759 -327.618086)
			(xy 180.141879 -327.673262) (xy 180.142388 -327.701148) (xy 180.141879 -327.729034) (xy 180.133759 -327.78421)
			(xy 180.117691 -327.837617) (xy 180.094019 -327.888114) (xy 180.063246 -327.934627) (xy 180.026029 -327.976164)
			(xy 179.983161 -328.011839) (xy 179.935555 -328.040893) (xy 179.884226 -328.062705) (xy 179.830269 -328.076811)
			(xy 179.774832 -328.082911) (xy 179.719098 -328.080874) (xy 179.664255 -328.070744) (xy 179.611471 -328.052737)
			(xy 179.561871 -328.027236) (xy 179.516513 -327.994785) (xy 179.476364 -327.956076) (xy 179.442278 -327.911933)
			(xy 179.414982 -327.863298) (xy 179.395059 -327.811207) (xy 179.382933 -327.75677) (xy 179.378862 -327.701148)
			(xy 165.87724 -327.701148) (xy 166.5351 -328.359008) (xy 193.24066 -328.359008)
		)
		(stroke
			(width 0)
			(type solid)
		)
		(fill yes)
		(layer "In13.Cu")
		(net "GND")
	)
	(gr_poly
		(pts
			(xy 465.1502 -326.860408) (xy 465.1502 -321.357498) (xy 465.149761 -321.34394) (xy 465.142602 -321.317785)
			(xy 465.128815 -321.294434) (xy 465.109371 -321.275532) (xy 465.08564 -321.262411) (xy 465.059293 -321.255994)
			(xy 465.032186 -321.256733) (xy 465.006228 -321.264576) (xy 464.994498 -321.271392) (xy 464.973104 -321.284391)
			(xy 464.927442 -321.30491) (xy 464.879354 -321.318822) (xy 464.82979 -321.325851) (xy 464.80476 -321.326256)
			(xy 464.778109 -321.325755) (xy 464.725403 -321.317806) (xy 464.674471 -321.30209) (xy 464.626449 -321.278959)
			(xy 464.582411 -321.24893) (xy 464.54334 -321.212673) (xy 464.510109 -321.170999) (xy 464.48346 -321.124837)
			(xy 464.463987 -321.075219) (xy 464.452127 -321.023253) (xy 464.448144 -320.9701) (xy 464.452127 -320.916947)
			(xy 464.463987 -320.864981) (xy 464.48346 -320.815363) (xy 464.510109 -320.769201) (xy 464.54334 -320.727527)
			(xy 464.582411 -320.69127) (xy 464.626449 -320.661241) (xy 464.674471 -320.63811) (xy 464.725403 -320.622394)
			(xy 464.778109 -320.614445) (xy 464.80476 -320.61404) (xy 464.829786 -320.614488) (xy 464.879341 -320.621536)
			(xy 464.927423 -320.635443) (xy 464.973088 -320.655937) (xy 464.994498 -320.668904) (xy 465.006213 -320.675767)
			(xy 465.032183 -320.683654) (xy 465.059314 -320.684419) (xy 465.085687 -320.678008) (xy 465.109439 -320.664873)
			(xy 465.12889 -320.645944) (xy 465.142665 -320.622558) (xy 465.149791 -320.596369) (xy 465.1502 -320.582798)
			(xy 465.1502 -319.997836) (xy 465.149729 -319.984215) (xy 465.142454 -319.95796) (xy 465.128494 -319.934564)
			(xy 465.108842 -319.915694) (xy 465.084899 -319.902694) (xy 465.05837 -319.896491) (xy 465.031145 -319.897526)
			(xy 465.005164 -319.905725) (xy 464.993482 -319.912746) (xy 464.971735 -319.9263) (xy 464.925173 -319.947699)
			(xy 464.876023 -319.962195) (xy 464.825302 -319.969488) (xy 464.79968 -319.969896) (xy 464.773033 -319.969397)
			(xy 464.720333 -319.961451) (xy 464.669407 -319.94574) (xy 464.621391 -319.922614) (xy 464.577357 -319.89259)
			(xy 464.538291 -319.85634) (xy 464.505063 -319.814671) (xy 464.478416 -319.768516) (xy 464.458946 -319.718905)
			(xy 464.447087 -319.666946) (xy 464.443104 -319.6138) (xy 464.447087 -319.560654) (xy 464.458946 -319.508695)
			(xy 464.478416 -319.459084) (xy 464.505063 -319.412929) (xy 464.538291 -319.37126) (xy 464.577357 -319.33501)
			(xy 464.621391 -319.304986) (xy 464.669407 -319.28186) (xy 464.720333 -319.266149) (xy 464.773033 -319.258203)
			(xy 464.79968 -319.25768) (xy 464.8253 -319.258108) (xy 464.876018 -319.265412) (xy 464.925166 -319.279902)
			(xy 464.971735 -319.301279) (xy 464.993482 -319.31483) (xy 465.005161 -319.321855) (xy 465.031142 -319.330057)
			(xy 465.058367 -319.331093) (xy 465.084896 -319.324889) (xy 465.108838 -319.311888) (xy 465.128488 -319.293016)
			(xy 465.142446 -319.269618) (xy 465.149715 -319.243361) (xy 465.1502 -319.22974) (xy 465.1502 -318.029082)
			(xy 465.149772 -318.01552) (xy 465.14263 -317.989353) (xy 465.128856 -317.965987) (xy 465.109419 -317.947068)
			(xy 465.085689 -317.93393) (xy 465.059338 -317.927498) (xy 465.032224 -317.928227) (xy 465.019136 -317.9318)
			(xy 464.994017 -317.938921) (xy 464.942371 -317.946571) (xy 464.916266 -317.94704) (xy 464.889616 -317.94654)
			(xy 464.836912 -317.938591) (xy 464.785981 -317.922877) (xy 464.737961 -317.899748) (xy 464.693924 -317.86972)
			(xy 464.654854 -317.833465) (xy 464.621623 -317.791791) (xy 464.594975 -317.745631) (xy 464.575503 -317.696015)
			(xy 464.563643 -317.644051) (xy 464.55966 -317.5909) (xy 464.563643 -317.537749) (xy 464.575503 -317.485785)
			(xy 464.594975 -317.436169) (xy 464.621623 -317.390009) (xy 464.654854 -317.348335) (xy 464.693924 -317.31208)
			(xy 464.737961 -317.282052) (xy 464.785981 -317.258923) (xy 464.836912 -317.243209) (xy 464.889616 -317.23526)
			(xy 464.916266 -317.234824) (xy 464.94237 -317.235298) (xy 464.994017 -317.242943) (xy 465.019136 -317.250064)
			(xy 465.03224 -317.253587) (xy 465.059355 -317.254338) (xy 465.085711 -317.247924) (xy 465.109448 -317.234795)
			(xy 465.12889 -317.215881) (xy 465.142666 -317.192514) (xy 465.149804 -317.166345) (xy 465.1502 -317.152782)
			(xy 465.1502 -187.701428) (xy 464.61172 -187.162948) (xy 418.876734 -187.162948) (xy 418.861755 -187.163517)
			(xy 418.833104 -187.172278) (xy 418.808223 -187.188969) (xy 418.78925 -187.212157) (xy 418.777815 -187.23985)
			(xy 418.774899 -187.269668) (xy 418.780754 -187.299051) (xy 418.794876 -187.325475) (xy 418.805106 -187.33643)
			(xy 418.805614 -187.336938) (xy 421.830246 -190.36157) (xy 432.258722 -190.36157) (xy 432.262793 -190.305948)
			(xy 432.274919 -190.251511) (xy 432.294842 -190.19942) (xy 432.322138 -190.150785) (xy 432.356224 -190.106642)
			(xy 432.396373 -190.067933) (xy 432.441731 -190.035482) (xy 432.491331 -190.009981) (xy 432.544115 -189.991974)
			(xy 432.598958 -189.981844) (xy 432.654692 -189.979807) (xy 432.710129 -189.985907) (xy 432.764086 -190.000013)
			(xy 432.815415 -190.021825) (xy 432.863021 -190.050879) (xy 432.905889 -190.086554) (xy 432.943106 -190.128091)
			(xy 432.973879 -190.174604) (xy 432.997551 -190.225101) (xy 433.013619 -190.278508) (xy 433.021739 -190.333684)
			(xy 433.022248 -190.36157) (xy 433.021739 -190.389456) (xy 433.013619 -190.444632) (xy 432.997551 -190.498039)
			(xy 432.973879 -190.548536) (xy 432.943106 -190.595049) (xy 432.905889 -190.636586) (xy 432.863021 -190.672261)
			(xy 432.815415 -190.701315) (xy 432.764086 -190.723127) (xy 432.710129 -190.737233) (xy 432.654692 -190.743333)
			(xy 432.598958 -190.741296) (xy 432.544115 -190.731166) (xy 432.491331 -190.713159) (xy 432.441731 -190.687658)
			(xy 432.396373 -190.655207) (xy 432.356224 -190.616498) (xy 432.322138 -190.572355) (xy 432.294842 -190.52372)
			(xy 432.274919 -190.471629) (xy 432.262793 -190.417192) (xy 432.258722 -190.36157) (xy 421.830246 -190.36157)
			(xy 422.719246 -191.25057) (xy 426.797722 -191.25057) (xy 426.801793 -191.194948) (xy 426.813919 -191.140511)
			(xy 426.833842 -191.08842) (xy 426.861138 -191.039785) (xy 426.895224 -190.995642) (xy 426.935373 -190.956933)
			(xy 426.980731 -190.924482) (xy 427.030331 -190.898981) (xy 427.083115 -190.880974) (xy 427.137958 -190.870844)
			(xy 427.193692 -190.868807) (xy 427.249129 -190.874907) (xy 427.303086 -190.889013) (xy 427.354415 -190.910825)
			(xy 427.402021 -190.939879) (xy 427.444889 -190.975554) (xy 427.482106 -191.017091) (xy 427.512879 -191.063604)
			(xy 427.536551 -191.114101) (xy 427.552619 -191.167508) (xy 427.560739 -191.222684) (xy 427.561248 -191.25057)
			(xy 427.560951 -191.266826) (xy 432.681124 -191.266826) (xy 432.685195 -191.211204) (xy 432.697321 -191.156767)
			(xy 432.717244 -191.104676) (xy 432.74454 -191.056041) (xy 432.778626 -191.011898) (xy 432.818775 -190.973189)
			(xy 432.864133 -190.940738) (xy 432.913733 -190.915237) (xy 432.966517 -190.89723) (xy 433.02136 -190.8871)
			(xy 433.077094 -190.885063) (xy 433.132531 -190.891163) (xy 433.186488 -190.905269) (xy 433.237817 -190.927081)
			(xy 433.285423 -190.956135) (xy 433.328291 -190.99181) (xy 433.365508 -191.033347) (xy 433.396281 -191.07986)
			(xy 433.419953 -191.130357) (xy 433.436021 -191.183764) (xy 433.444141 -191.23894) (xy 433.44465 -191.266826)
			(xy 433.444141 -191.294712) (xy 433.436021 -191.349888) (xy 433.419953 -191.403295) (xy 433.396281 -191.453792)
			(xy 433.365508 -191.500305) (xy 433.328291 -191.541842) (xy 433.285423 -191.577517) (xy 433.237817 -191.606571)
			(xy 433.186488 -191.628383) (xy 433.132531 -191.642489) (xy 433.077094 -191.648589) (xy 433.02136 -191.646552)
			(xy 432.966517 -191.636422) (xy 432.913733 -191.618415) (xy 432.864133 -191.592914) (xy 432.818775 -191.560463)
			(xy 432.778626 -191.521754) (xy 432.74454 -191.477611) (xy 432.717244 -191.428976) (xy 432.697321 -191.376885)
			(xy 432.685195 -191.322448) (xy 432.681124 -191.266826) (xy 427.560951 -191.266826) (xy 427.560739 -191.278456)
			(xy 427.552619 -191.333632) (xy 427.536551 -191.387039) (xy 427.512879 -191.437536) (xy 427.482106 -191.484049)
			(xy 427.444889 -191.525586) (xy 427.402021 -191.561261) (xy 427.354415 -191.590315) (xy 427.303086 -191.612127)
			(xy 427.249129 -191.626233) (xy 427.193692 -191.632333) (xy 427.137958 -191.630296) (xy 427.083115 -191.620166)
			(xy 427.030331 -191.602159) (xy 426.980731 -191.576658) (xy 426.935373 -191.544207) (xy 426.895224 -191.505498)
			(xy 426.861138 -191.461355) (xy 426.833842 -191.41272) (xy 426.813919 -191.360629) (xy 426.801793 -191.306192)
			(xy 426.797722 -191.25057) (xy 422.719246 -191.25057) (xy 423.413428 -191.944752) (xy 423.427398 -191.948308)
			(xy 423.454806 -191.955405) (xy 423.507306 -191.976591) (xy 423.556095 -192.00531) (xy 423.6001 -192.04093)
			(xy 423.638353 -192.082666) (xy 423.670011 -192.129601) (xy 423.69438 -192.180702) (xy 423.710922 -192.234846)
			(xy 423.719274 -192.290841) (xy 423.719752 -192.319148) (xy 423.719263 -192.346398) (xy 423.711501 -192.400343)
			(xy 423.696142 -192.452635) (xy 423.673499 -192.502209) (xy 423.644032 -192.548056) (xy 423.608341 -192.589244)
			(xy 423.567153 -192.624935) (xy 423.521305 -192.654401) (xy 423.471731 -192.677044) (xy 423.419439 -192.692402)
			(xy 423.365494 -192.700163) (xy 423.338244 -192.700656) (xy 423.309942 -192.700137) (xy 423.253959 -192.691764)
			(xy 423.199829 -192.67521) (xy 423.148739 -192.650838) (xy 423.101812 -192.619184) (xy 423.060077 -192.580943)
			(xy 423.024453 -192.536954) (xy 422.995719 -192.488184) (xy 422.974509 -192.435703) (xy 422.967404 -192.408302)
			(xy 422.963848 -192.394332) (xy 418.449252 -187.879736) (xy 407.4668 -187.879736) (xy 407.4668 -191.944244)
			(xy 407.469594 -191.952118) (xy 407.478994 -191.981847) (xy 407.489084 -192.043372) (xy 407.48966 -192.074546)
			(xy 407.742134 -192.074546) (xy 407.746205 -192.018924) (xy 407.758331 -191.964487) (xy 407.778254 -191.912396)
			(xy 407.80555 -191.863761) (xy 407.839636 -191.819618) (xy 407.879785 -191.780909) (xy 407.925143 -191.748458)
			(xy 407.974743 -191.722957) (xy 408.027527 -191.70495) (xy 408.08237 -191.69482) (xy 408.138104 -191.692783)
			(xy 408.193541 -191.698883) (xy 408.247498 -191.712989) (xy 408.298827 -191.734801) (xy 408.346433 -191.763855)
			(xy 408.389301 -191.79953) (xy 408.426518 -191.841067) (xy 408.457291 -191.88758) (xy 408.480963 -191.938077)
			(xy 408.497031 -191.991484) (xy 408.505151 -192.04666) (xy 408.50566 -192.074546) (xy 408.758134 -192.074546)
			(xy 408.762205 -192.018924) (xy 408.774331 -191.964487) (xy 408.794254 -191.912396) (xy 408.82155 -191.863761)
			(xy 408.855636 -191.819618) (xy 408.895785 -191.780909) (xy 408.941143 -191.748458) (xy 408.990743 -191.722957)
			(xy 409.043527 -191.70495) (xy 409.09837 -191.69482) (xy 409.154104 -191.692783) (xy 409.209541 -191.698883)
			(xy 409.263498 -191.712989) (xy 409.314827 -191.734801) (xy 409.362433 -191.763855) (xy 409.405301 -191.79953)
			(xy 409.442518 -191.841067) (xy 409.473291 -191.88758) (xy 409.496963 -191.938077) (xy 409.513031 -191.991484)
			(xy 409.521151 -192.04666) (xy 409.52166 -192.074546) (xy 409.774134 -192.074546) (xy 409.778205 -192.018924)
			(xy 409.790331 -191.964487) (xy 409.810254 -191.912396) (xy 409.83755 -191.863761) (xy 409.871636 -191.819618)
			(xy 409.911785 -191.780909) (xy 409.957143 -191.748458) (xy 410.006743 -191.722957) (xy 410.059527 -191.70495)
			(xy 410.11437 -191.69482) (xy 410.170104 -191.692783) (xy 410.225541 -191.698883) (xy 410.279498 -191.712989)
			(xy 410.330827 -191.734801) (xy 410.378433 -191.763855) (xy 410.421301 -191.79953) (xy 410.458518 -191.841067)
			(xy 410.489291 -191.88758) (xy 410.512963 -191.938077) (xy 410.529031 -191.991484) (xy 410.537151 -192.04666)
			(xy 410.53766 -192.074546) (xy 410.790134 -192.074546) (xy 410.794205 -192.018924) (xy 410.806331 -191.964487)
			(xy 410.826254 -191.912396) (xy 410.85355 -191.863761) (xy 410.887636 -191.819618) (xy 410.927785 -191.780909)
			(xy 410.973143 -191.748458) (xy 411.022743 -191.722957) (xy 411.075527 -191.70495) (xy 411.13037 -191.69482)
			(xy 411.186104 -191.692783) (xy 411.241541 -191.698883) (xy 411.295498 -191.712989) (xy 411.346827 -191.734801)
			(xy 411.394433 -191.763855) (xy 411.437301 -191.79953) (xy 411.474518 -191.841067) (xy 411.505291 -191.88758)
			(xy 411.528963 -191.938077) (xy 411.545031 -191.991484) (xy 411.553151 -192.04666) (xy 411.55366 -192.074546)
			(xy 413.873694 -192.074546) (xy 413.877765 -192.018924) (xy 413.889891 -191.964487) (xy 413.909814 -191.912396)
			(xy 413.93711 -191.863761) (xy 413.971196 -191.819618) (xy 414.011345 -191.780909) (xy 414.056703 -191.748458)
			(xy 414.106303 -191.722957) (xy 414.159087 -191.70495) (xy 414.21393 -191.69482) (xy 414.269664 -191.692783)
			(xy 414.325101 -191.698883) (xy 414.379058 -191.712989) (xy 414.430387 -191.734801) (xy 414.477993 -191.763855)
			(xy 414.520861 -191.79953) (xy 414.558078 -191.841067) (xy 414.588851 -191.88758) (xy 414.612523 -191.938077)
			(xy 414.628591 -191.991484) (xy 414.636711 -192.04666) (xy 414.63722 -192.074546) (xy 414.889694 -192.074546)
			(xy 414.893765 -192.018924) (xy 414.905891 -191.964487) (xy 414.925814 -191.912396) (xy 414.95311 -191.863761)
			(xy 414.987196 -191.819618) (xy 415.027345 -191.780909) (xy 415.072703 -191.748458) (xy 415.122303 -191.722957)
			(xy 415.175087 -191.70495) (xy 415.22993 -191.69482) (xy 415.285664 -191.692783) (xy 415.341101 -191.698883)
			(xy 415.395058 -191.712989) (xy 415.446387 -191.734801) (xy 415.493993 -191.763855) (xy 415.536861 -191.79953)
			(xy 415.574078 -191.841067) (xy 415.604851 -191.88758) (xy 415.628523 -191.938077) (xy 415.644591 -191.991484)
			(xy 415.652711 -192.04666) (xy 415.65322 -192.074546) (xy 415.905694 -192.074546) (xy 415.909765 -192.018924)
			(xy 415.921891 -191.964487) (xy 415.941814 -191.912396) (xy 415.96911 -191.863761) (xy 416.003196 -191.819618)
			(xy 416.043345 -191.780909) (xy 416.088703 -191.748458) (xy 416.138303 -191.722957) (xy 416.191087 -191.70495)
			(xy 416.24593 -191.69482) (xy 416.301664 -191.692783) (xy 416.357101 -191.698883) (xy 416.411058 -191.712989)
			(xy 416.462387 -191.734801) (xy 416.509993 -191.763855) (xy 416.552861 -191.79953) (xy 416.590078 -191.841067)
			(xy 416.620851 -191.88758) (xy 416.644523 -191.938077) (xy 416.660591 -191.991484) (xy 416.668711 -192.04666)
			(xy 416.66922 -192.074546) (xy 416.668711 -192.102432) (xy 416.661863 -192.148968) (xy 419.101268 -192.148968)
			(xy 419.105339 -192.093346) (xy 419.117465 -192.038909) (xy 419.137388 -191.986818) (xy 419.164684 -191.938183)
			(xy 419.19877 -191.89404) (xy 419.238919 -191.855331) (xy 419.284277 -191.82288) (xy 419.333877 -191.797379)
			(xy 419.386661 -191.779372) (xy 419.441504 -191.769242) (xy 419.497238 -191.767205) (xy 419.552675 -191.773305)
			(xy 419.606632 -191.787411) (xy 419.657961 -191.809223) (xy 419.705567 -191.838277) (xy 419.748435 -191.873952)
			(xy 419.785652 -191.915489) (xy 419.816425 -191.962002) (xy 419.840097 -192.012499) (xy 419.856165 -192.065906)
			(xy 419.864285 -192.121082) (xy 419.864794 -192.148968) (xy 419.864285 -192.176854) (xy 419.856165 -192.23203)
			(xy 419.840097 -192.285437) (xy 419.816425 -192.335934) (xy 419.785652 -192.382447) (xy 419.748435 -192.423984)
			(xy 419.705567 -192.459659) (xy 419.657961 -192.488713) (xy 419.606632 -192.510525) (xy 419.552675 -192.524631)
			(xy 419.497238 -192.530731) (xy 419.441504 -192.528694) (xy 419.386661 -192.518564) (xy 419.333877 -192.500557)
			(xy 419.284277 -192.475056) (xy 419.238919 -192.442605) (xy 419.19877 -192.403896) (xy 419.164684 -192.359753)
			(xy 419.137388 -192.311118) (xy 419.117465 -192.259027) (xy 419.105339 -192.20459) (xy 419.101268 -192.148968)
			(xy 416.661863 -192.148968) (xy 416.660591 -192.157608) (xy 416.644523 -192.211015) (xy 416.620851 -192.261512)
			(xy 416.590078 -192.308025) (xy 416.552861 -192.349562) (xy 416.509993 -192.385237) (xy 416.462387 -192.414291)
			(xy 416.411058 -192.436103) (xy 416.357101 -192.450209) (xy 416.301664 -192.456309) (xy 416.24593 -192.454272)
			(xy 416.191087 -192.444142) (xy 416.138303 -192.426135) (xy 416.088703 -192.400634) (xy 416.043345 -192.368183)
			(xy 416.003196 -192.329474) (xy 415.96911 -192.285331) (xy 415.941814 -192.236696) (xy 415.921891 -192.184605)
			(xy 415.909765 -192.130168) (xy 415.905694 -192.074546) (xy 415.65322 -192.074546) (xy 415.652711 -192.102432)
			(xy 415.644591 -192.157608) (xy 415.628523 -192.211015) (xy 415.604851 -192.261512) (xy 415.574078 -192.308025)
			(xy 415.536861 -192.349562) (xy 415.493993 -192.385237) (xy 415.446387 -192.414291) (xy 415.395058 -192.436103)
			(xy 415.341101 -192.450209) (xy 415.285664 -192.456309) (xy 415.22993 -192.454272) (xy 415.175087 -192.444142)
			(xy 415.122303 -192.426135) (xy 415.072703 -192.400634) (xy 415.027345 -192.368183) (xy 414.987196 -192.329474)
			(xy 414.95311 -192.285331) (xy 414.925814 -192.236696) (xy 414.905891 -192.184605) (xy 414.893765 -192.130168)
			(xy 414.889694 -192.074546) (xy 414.63722 -192.074546) (xy 414.636711 -192.102432) (xy 414.628591 -192.157608)
			(xy 414.612523 -192.211015) (xy 414.588851 -192.261512) (xy 414.558078 -192.308025) (xy 414.520861 -192.349562)
			(xy 414.477993 -192.385237) (xy 414.430387 -192.414291) (xy 414.379058 -192.436103) (xy 414.325101 -192.450209)
			(xy 414.269664 -192.456309) (xy 414.21393 -192.454272) (xy 414.159087 -192.444142) (xy 414.106303 -192.426135)
			(xy 414.056703 -192.400634) (xy 414.011345 -192.368183) (xy 413.971196 -192.329474) (xy 413.93711 -192.285331)
			(xy 413.909814 -192.236696) (xy 413.889891 -192.184605) (xy 413.877765 -192.130168) (xy 413.873694 -192.074546)
			(xy 411.55366 -192.074546) (xy 411.553151 -192.102432) (xy 411.545031 -192.157608) (xy 411.528963 -192.211015)
			(xy 411.505291 -192.261512) (xy 411.474518 -192.308025) (xy 411.437301 -192.349562) (xy 411.394433 -192.385237)
			(xy 411.346827 -192.414291) (xy 411.295498 -192.436103) (xy 411.241541 -192.450209) (xy 411.186104 -192.456309)
			(xy 411.13037 -192.454272) (xy 411.075527 -192.444142) (xy 411.022743 -192.426135) (xy 410.973143 -192.400634)
			(xy 410.927785 -192.368183) (xy 410.887636 -192.329474) (xy 410.85355 -192.285331) (xy 410.826254 -192.236696)
			(xy 410.806331 -192.184605) (xy 410.794205 -192.130168) (xy 410.790134 -192.074546) (xy 410.53766 -192.074546)
			(xy 410.537151 -192.102432) (xy 410.529031 -192.157608) (xy 410.512963 -192.211015) (xy 410.489291 -192.261512)
			(xy 410.458518 -192.308025) (xy 410.421301 -192.349562) (xy 410.378433 -192.385237) (xy 410.330827 -192.414291)
			(xy 410.279498 -192.436103) (xy 410.225541 -192.450209) (xy 410.170104 -192.456309) (xy 410.11437 -192.454272)
			(xy 410.059527 -192.444142) (xy 410.006743 -192.426135) (xy 409.957143 -192.400634) (xy 409.911785 -192.368183)
			(xy 409.871636 -192.329474) (xy 409.83755 -192.285331) (xy 409.810254 -192.236696) (xy 409.790331 -192.184605)
			(xy 409.778205 -192.130168) (xy 409.774134 -192.074546) (xy 409.52166 -192.074546) (xy 409.521151 -192.102432)
			(xy 409.513031 -192.157608) (xy 409.496963 -192.211015) (xy 409.473291 -192.261512) (xy 409.442518 -192.308025)
			(xy 409.405301 -192.349562) (xy 409.362433 -192.385237) (xy 409.314827 -192.414291) (xy 409.263498 -192.436103)
			(xy 409.209541 -192.450209) (xy 409.154104 -192.456309) (xy 409.09837 -192.454272) (xy 409.043527 -192.444142)
			(xy 408.990743 -192.426135) (xy 408.941143 -192.400634) (xy 408.895785 -192.368183) (xy 408.855636 -192.329474)
			(xy 408.82155 -192.285331) (xy 408.794254 -192.236696) (xy 408.774331 -192.184605) (xy 408.762205 -192.130168)
			(xy 408.758134 -192.074546) (xy 408.50566 -192.074546) (xy 408.505151 -192.102432) (xy 408.497031 -192.157608)
			(xy 408.480963 -192.211015) (xy 408.457291 -192.261512) (xy 408.426518 -192.308025) (xy 408.389301 -192.349562)
			(xy 408.346433 -192.385237) (xy 408.298827 -192.414291) (xy 408.247498 -192.436103) (xy 408.193541 -192.450209)
			(xy 408.138104 -192.456309) (xy 408.08237 -192.454272) (xy 408.027527 -192.444142) (xy 407.974743 -192.426135)
			(xy 407.925143 -192.400634) (xy 407.879785 -192.368183) (xy 407.839636 -192.329474) (xy 407.80555 -192.285331)
			(xy 407.778254 -192.236696) (xy 407.758331 -192.184605) (xy 407.746205 -192.130168) (xy 407.742134 -192.074546)
			(xy 407.48966 -192.074546) (xy 407.489058 -192.105718) (xy 407.478971 -192.16724) (xy 407.469594 -192.196974)
			(xy 407.4668 -192.204848) (xy 407.4668 -193.218308) (xy 429.035462 -193.218308) (xy 429.039533 -193.162686)
			(xy 429.051659 -193.108249) (xy 429.071582 -193.056158) (xy 429.098878 -193.007523) (xy 429.132964 -192.96338)
			(xy 429.173113 -192.924671) (xy 429.218471 -192.89222) (xy 429.268071 -192.866719) (xy 429.320855 -192.848712)
			(xy 429.375698 -192.838582) (xy 429.431432 -192.836545) (xy 429.486869 -192.842645) (xy 429.540826 -192.856751)
			(xy 429.592155 -192.878563) (xy 429.639761 -192.907617) (xy 429.682629 -192.943292) (xy 429.719846 -192.984829)
			(xy 429.750619 -193.031342) (xy 429.774291 -193.081839) (xy 429.790359 -193.135246) (xy 429.798479 -193.190422)
			(xy 429.798988 -193.218308) (xy 429.798479 -193.246194) (xy 429.790359 -193.30137) (xy 429.774291 -193.354777)
			(xy 429.750619 -193.405274) (xy 429.719846 -193.451787) (xy 429.682629 -193.493324) (xy 429.639761 -193.528999)
			(xy 429.592155 -193.558053) (xy 429.540826 -193.579865) (xy 429.486869 -193.593971) (xy 429.431432 -193.600071)
			(xy 429.375698 -193.598034) (xy 429.320855 -193.587904) (xy 429.268071 -193.569897) (xy 429.218471 -193.544396)
			(xy 429.173113 -193.511945) (xy 429.132964 -193.473236) (xy 429.098878 -193.429093) (xy 429.071582 -193.380458)
			(xy 429.051659 -193.328367) (xy 429.039533 -193.27393) (xy 429.035462 -193.218308) (xy 407.4668 -193.218308)
			(xy 407.4668 -194.344036) (xy 407.467272 -194.358667) (xy 407.475556 -194.386731) (xy 407.491462 -194.411292)
			(xy 407.513682 -194.430331) (xy 407.540391 -194.442284) (xy 407.569394 -194.446167) (xy 407.598307 -194.441663)
			(xy 407.624754 -194.429141) (xy 407.635964 -194.419728) (xy 407.655657 -194.402793) (xy 407.699028 -194.374216)
			(xy 407.746088 -194.35224) (xy 407.79584 -194.33733) (xy 407.847231 -194.329802) (xy 407.8732 -194.329304)
			(xy 407.899848 -194.329802) (xy 407.95255 -194.337745) (xy 408.003479 -194.353455) (xy 408.051498 -194.376579)
			(xy 408.095534 -194.406602) (xy 408.134603 -194.442853) (xy 408.167833 -194.484523) (xy 408.194481 -194.530679)
			(xy 408.213953 -194.580292) (xy 408.225813 -194.632252) (xy 408.229796 -194.6854) (xy 408.225813 -194.738548)
			(xy 408.213953 -194.790508) (xy 408.212841 -194.793341) (xy 412.836604 -194.793341) (xy 412.836604 -194.740043)
			(xy 412.844547 -194.687339) (xy 412.860257 -194.636409) (xy 412.883383 -194.588388) (xy 412.913407 -194.544351)
			(xy 412.949659 -194.50528) (xy 412.99133 -194.472049) (xy 413.037488 -194.4454) (xy 413.087102 -194.425928)
			(xy 413.139064 -194.414068) (xy 413.192214 -194.410085) (xy 413.245364 -194.414068) (xy 413.297326 -194.425928)
			(xy 413.34694 -194.4454) (xy 413.393098 -194.472049) (xy 413.434769 -194.50528) (xy 413.471021 -194.544351)
			(xy 413.501045 -194.588388) (xy 413.524171 -194.636409) (xy 413.539881 -194.687339) (xy 413.547824 -194.740043)
			(xy 413.548322 -194.766692) (xy 413.547824 -194.793341) (xy 420.380404 -194.793341) (xy 420.380404 -194.740043)
			(xy 420.388347 -194.687339) (xy 420.404057 -194.636409) (xy 420.427183 -194.588388) (xy 420.457207 -194.544351)
			(xy 420.493459 -194.50528) (xy 420.53513 -194.472049) (xy 420.581288 -194.4454) (xy 420.630902 -194.425928)
			(xy 420.682864 -194.414068) (xy 420.736014 -194.410085) (xy 420.789164 -194.414068) (xy 420.841126 -194.425928)
			(xy 420.89074 -194.4454) (xy 420.936898 -194.472049) (xy 420.978569 -194.50528) (xy 421.014821 -194.544351)
			(xy 421.044845 -194.588388) (xy 421.067971 -194.636409) (xy 421.083681 -194.687339) (xy 421.091624 -194.740043)
			(xy 421.092122 -194.766692) (xy 421.091624 -194.793341) (xy 427.898804 -194.793341) (xy 427.898804 -194.740043)
			(xy 427.906747 -194.687339) (xy 427.922457 -194.636409) (xy 427.945583 -194.588388) (xy 427.975607 -194.544351)
			(xy 428.011859 -194.50528) (xy 428.05353 -194.472049) (xy 428.099688 -194.4454) (xy 428.149302 -194.425928)
			(xy 428.201264 -194.414068) (xy 428.254414 -194.410085) (xy 428.307564 -194.414068) (xy 428.359526 -194.425928)
			(xy 428.40914 -194.4454) (xy 428.455298 -194.472049) (xy 428.496969 -194.50528) (xy 428.533221 -194.544351)
			(xy 428.563245 -194.588388) (xy 428.586371 -194.636409) (xy 428.602081 -194.687339) (xy 428.610024 -194.740043)
			(xy 428.610522 -194.766692) (xy 428.610024 -194.793341) (xy 435.468004 -194.793341) (xy 435.468004 -194.740043)
			(xy 435.475947 -194.687339) (xy 435.491657 -194.636409) (xy 435.514783 -194.588388) (xy 435.544807 -194.544351)
			(xy 435.581059 -194.50528) (xy 435.62273 -194.472049) (xy 435.668888 -194.4454) (xy 435.718502 -194.425928)
			(xy 435.770464 -194.414068) (xy 435.823614 -194.410085) (xy 435.876764 -194.414068) (xy 435.928726 -194.425928)
			(xy 435.97834 -194.4454) (xy 436.024498 -194.472049) (xy 436.066169 -194.50528) (xy 436.102421 -194.544351)
			(xy 436.132445 -194.588388) (xy 436.155571 -194.636409) (xy 436.171281 -194.687339) (xy 436.179224 -194.740043)
			(xy 436.179722 -194.766692) (xy 436.179224 -194.793341) (xy 443.011804 -194.793341) (xy 443.011804 -194.740043)
			(xy 443.019747 -194.687339) (xy 443.035457 -194.636409) (xy 443.058583 -194.588388) (xy 443.088607 -194.544351)
			(xy 443.124859 -194.50528) (xy 443.16653 -194.472049) (xy 443.212688 -194.4454) (xy 443.262302 -194.425928)
			(xy 443.314264 -194.414068) (xy 443.367414 -194.410085) (xy 443.420564 -194.414068) (xy 443.472526 -194.425928)
			(xy 443.52214 -194.4454) (xy 443.568298 -194.472049) (xy 443.609969 -194.50528) (xy 443.646221 -194.544351)
			(xy 443.676245 -194.588388) (xy 443.699371 -194.636409) (xy 443.715081 -194.687339) (xy 443.723024 -194.740043)
			(xy 443.723522 -194.766692) (xy 443.723024 -194.793341) (xy 443.715081 -194.846045) (xy 443.699371 -194.896975)
			(xy 443.682369 -194.932279) (xy 450.128376 -194.932279) (xy 450.128376 -194.878981) (xy 450.136319 -194.826277)
			(xy 450.152029 -194.775347) (xy 450.175155 -194.727326) (xy 450.205179 -194.683289) (xy 450.241431 -194.644218)
			(xy 450.283102 -194.610987) (xy 450.32926 -194.584338) (xy 450.378874 -194.564866) (xy 450.430836 -194.553006)
			(xy 450.483986 -194.549023) (xy 450.537136 -194.553006) (xy 450.589098 -194.564866) (xy 450.638712 -194.584338)
			(xy 450.68487 -194.610987) (xy 450.726541 -194.644218) (xy 450.762793 -194.683289) (xy 450.792817 -194.727326)
			(xy 450.815943 -194.775347) (xy 450.821493 -194.793341) (xy 458.074004 -194.793341) (xy 458.074004 -194.740043)
			(xy 458.081947 -194.687339) (xy 458.097657 -194.636409) (xy 458.120783 -194.588388) (xy 458.150807 -194.544351)
			(xy 458.187059 -194.50528) (xy 458.22873 -194.472049) (xy 458.274888 -194.4454) (xy 458.324502 -194.425928)
			(xy 458.376464 -194.414068) (xy 458.429614 -194.410085) (xy 458.482764 -194.414068) (xy 458.534726 -194.425928)
			(xy 458.58434 -194.4454) (xy 458.630498 -194.472049) (xy 458.672169 -194.50528) (xy 458.708421 -194.544351)
			(xy 458.738445 -194.588388) (xy 458.761571 -194.636409) (xy 458.777281 -194.687339) (xy 458.785224 -194.740043)
			(xy 458.785722 -194.766692) (xy 458.785224 -194.793341) (xy 458.777281 -194.846045) (xy 458.761571 -194.896975)
			(xy 458.738445 -194.944996) (xy 458.708421 -194.989033) (xy 458.672169 -195.028104) (xy 458.630498 -195.061335)
			(xy 458.58434 -195.087984) (xy 458.534726 -195.107456) (xy 458.482764 -195.119316) (xy 458.429614 -195.1233)
			(xy 458.376464 -195.119316) (xy 458.324502 -195.107456) (xy 458.274888 -195.087984) (xy 458.22873 -195.061335)
			(xy 458.187059 -195.028104) (xy 458.150807 -194.989033) (xy 458.120783 -194.944996) (xy 458.097657 -194.896975)
			(xy 458.081947 -194.846045) (xy 458.074004 -194.793341) (xy 450.821493 -194.793341) (xy 450.831653 -194.826277)
			(xy 450.839596 -194.878981) (xy 450.840094 -194.90563) (xy 450.839596 -194.932279) (xy 450.831653 -194.984983)
			(xy 450.815943 -195.035913) (xy 450.792817 -195.083934) (xy 450.762793 -195.127971) (xy 450.726541 -195.167042)
			(xy 450.68487 -195.200273) (xy 450.638712 -195.226922) (xy 450.589098 -195.246394) (xy 450.537136 -195.258254)
			(xy 450.483986 -195.262238) (xy 450.430836 -195.258254) (xy 450.378874 -195.246394) (xy 450.32926 -195.226922)
			(xy 450.283102 -195.200273) (xy 450.241431 -195.167042) (xy 450.205179 -195.127971) (xy 450.175155 -195.083934)
			(xy 450.152029 -195.035913) (xy 450.136319 -194.984983) (xy 450.128376 -194.932279) (xy 443.682369 -194.932279)
			(xy 443.676245 -194.944996) (xy 443.646221 -194.989033) (xy 443.609969 -195.028104) (xy 443.568298 -195.061335)
			(xy 443.52214 -195.087984) (xy 443.472526 -195.107456) (xy 443.420564 -195.119316) (xy 443.367414 -195.1233)
			(xy 443.314264 -195.119316) (xy 443.262302 -195.107456) (xy 443.212688 -195.087984) (xy 443.16653 -195.061335)
			(xy 443.124859 -195.028104) (xy 443.088607 -194.989033) (xy 443.058583 -194.944996) (xy 443.035457 -194.896975)
			(xy 443.019747 -194.846045) (xy 443.011804 -194.793341) (xy 436.179224 -194.793341) (xy 436.171281 -194.846045)
			(xy 436.155571 -194.896975) (xy 436.132445 -194.944996) (xy 436.102421 -194.989033) (xy 436.066169 -195.028104)
			(xy 436.024498 -195.061335) (xy 435.97834 -195.087984) (xy 435.928726 -195.107456) (xy 435.876764 -195.119316)
			(xy 435.823614 -195.1233) (xy 435.770464 -195.119316) (xy 435.718502 -195.107456) (xy 435.668888 -195.087984)
			(xy 435.62273 -195.061335) (xy 435.581059 -195.028104) (xy 435.544807 -194.989033) (xy 435.514783 -194.944996)
			(xy 435.491657 -194.896975) (xy 435.475947 -194.846045) (xy 435.468004 -194.793341) (xy 428.610024 -194.793341)
			(xy 428.602081 -194.846045) (xy 428.586371 -194.896975) (xy 428.563245 -194.944996) (xy 428.533221 -194.989033)
			(xy 428.496969 -195.028104) (xy 428.455298 -195.061335) (xy 428.40914 -195.087984) (xy 428.359526 -195.107456)
			(xy 428.307564 -195.119316) (xy 428.254414 -195.1233) (xy 428.201264 -195.119316) (xy 428.149302 -195.107456)
			(xy 428.099688 -195.087984) (xy 428.05353 -195.061335) (xy 428.011859 -195.028104) (xy 427.975607 -194.989033)
			(xy 427.945583 -194.944996) (xy 427.922457 -194.896975) (xy 427.906747 -194.846045) (xy 427.898804 -194.793341)
			(xy 421.091624 -194.793341) (xy 421.083681 -194.846045) (xy 421.067971 -194.896975) (xy 421.044845 -194.944996)
			(xy 421.014821 -194.989033) (xy 420.978569 -195.028104) (xy 420.936898 -195.061335) (xy 420.89074 -195.087984)
			(xy 420.841126 -195.107456) (xy 420.789164 -195.119316) (xy 420.736014 -195.1233) (xy 420.682864 -195.119316)
			(xy 420.630902 -195.107456) (xy 420.581288 -195.087984) (xy 420.53513 -195.061335) (xy 420.493459 -195.028104)
			(xy 420.457207 -194.989033) (xy 420.427183 -194.944996) (xy 420.404057 -194.896975) (xy 420.388347 -194.846045)
			(xy 420.380404 -194.793341) (xy 413.547824 -194.793341) (xy 413.539881 -194.846045) (xy 413.524171 -194.896975)
			(xy 413.501045 -194.944996) (xy 413.471021 -194.989033) (xy 413.434769 -195.028104) (xy 413.393098 -195.061335)
			(xy 413.34694 -195.087984) (xy 413.297326 -195.107456) (xy 413.245364 -195.119316) (xy 413.192214 -195.1233)
			(xy 413.139064 -195.119316) (xy 413.087102 -195.107456) (xy 413.037488 -195.087984) (xy 412.99133 -195.061335)
			(xy 412.949659 -195.028104) (xy 412.913407 -194.989033) (xy 412.883383 -194.944996) (xy 412.860257 -194.896975)
			(xy 412.844547 -194.846045) (xy 412.836604 -194.793341) (xy 408.212841 -194.793341) (xy 408.194481 -194.840121)
			(xy 408.167833 -194.886277) (xy 408.134603 -194.927947) (xy 408.095534 -194.964198) (xy 408.051498 -194.994221)
			(xy 408.003479 -195.017345) (xy 407.95255 -195.033055) (xy 407.899848 -195.040998) (xy 407.8732 -195.04152)
			(xy 407.84723 -195.04105) (xy 407.79584 -195.033511) (xy 407.746088 -195.018593) (xy 407.699028 -194.996611)
			(xy 407.655658 -194.968032) (xy 407.635964 -194.951096) (xy 407.624736 -194.941729) (xy 407.598302 -194.929259)
			(xy 407.569417 -194.924788) (xy 407.540449 -194.928682) (xy 407.513771 -194.940623) (xy 407.491569 -194.959632)
			(xy 407.475661 -194.984152) (xy 407.46735 -195.012174) (xy 407.4668 -195.026788) (xy 407.4668 -195.643225)
			(xy 424.480472 -195.643225) (xy 424.480472 -195.589927) (xy 424.488415 -195.537223) (xy 424.504125 -195.486293)
			(xy 424.527251 -195.438272) (xy 424.557275 -195.394235) (xy 424.593527 -195.355164) (xy 424.635198 -195.321933)
			(xy 424.681356 -195.295284) (xy 424.73097 -195.275812) (xy 424.782932 -195.263952) (xy 424.836082 -195.259969)
			(xy 424.889232 -195.263952) (xy 424.941194 -195.275812) (xy 424.990808 -195.295284) (xy 425.036966 -195.321933)
			(xy 425.078637 -195.355164) (xy 425.114889 -195.394235) (xy 425.144913 -195.438272) (xy 425.168039 -195.486293)
			(xy 425.183749 -195.537223) (xy 425.191692 -195.589927) (xy 425.19219 -195.616576) (xy 425.191692 -195.643225)
			(xy 439.568072 -195.643225) (xy 439.568072 -195.589927) (xy 439.576015 -195.537223) (xy 439.591725 -195.486293)
			(xy 439.614851 -195.438272) (xy 439.644875 -195.394235) (xy 439.681127 -195.355164) (xy 439.722798 -195.321933)
			(xy 439.768956 -195.295284) (xy 439.81857 -195.275812) (xy 439.870532 -195.263952) (xy 439.923682 -195.259969)
			(xy 439.976832 -195.263952) (xy 440.028794 -195.275812) (xy 440.078408 -195.295284) (xy 440.124566 -195.321933)
			(xy 440.166237 -195.355164) (xy 440.202489 -195.394235) (xy 440.232513 -195.438272) (xy 440.255639 -195.486293)
			(xy 440.271349 -195.537223) (xy 440.279292 -195.589927) (xy 440.27979 -195.616576) (xy 440.279292 -195.643225)
			(xy 454.655672 -195.643225) (xy 454.655672 -195.589927) (xy 454.663615 -195.537223) (xy 454.679325 -195.486293)
			(xy 454.702451 -195.438272) (xy 454.732475 -195.394235) (xy 454.768727 -195.355164) (xy 454.810398 -195.321933)
			(xy 454.856556 -195.295284) (xy 454.90617 -195.275812) (xy 454.958132 -195.263952) (xy 455.011282 -195.259969)
			(xy 455.064432 -195.263952) (xy 455.116394 -195.275812) (xy 455.166008 -195.295284) (xy 455.212166 -195.321933)
			(xy 455.253837 -195.355164) (xy 455.290089 -195.394235) (xy 455.320113 -195.438272) (xy 455.343239 -195.486293)
			(xy 455.358949 -195.537223) (xy 455.366892 -195.589927) (xy 455.36739 -195.616576) (xy 455.366892 -195.643225)
			(xy 455.358949 -195.695929) (xy 455.343239 -195.746859) (xy 455.320113 -195.79488) (xy 455.290089 -195.838917)
			(xy 455.253837 -195.877988) (xy 455.212166 -195.911219) (xy 455.166008 -195.937868) (xy 455.116394 -195.95734)
			(xy 455.064432 -195.9692) (xy 455.011282 -195.973184) (xy 454.958132 -195.9692) (xy 454.90617 -195.95734)
			(xy 454.856556 -195.937868) (xy 454.810398 -195.911219) (xy 454.768727 -195.877988) (xy 454.732475 -195.838917)
			(xy 454.702451 -195.79488) (xy 454.679325 -195.746859) (xy 454.663615 -195.695929) (xy 454.655672 -195.643225)
			(xy 440.279292 -195.643225) (xy 440.271349 -195.695929) (xy 440.255639 -195.746859) (xy 440.232513 -195.79488)
			(xy 440.202489 -195.838917) (xy 440.166237 -195.877988) (xy 440.124566 -195.911219) (xy 440.078408 -195.937868)
			(xy 440.028794 -195.95734) (xy 439.976832 -195.9692) (xy 439.923682 -195.973184) (xy 439.870532 -195.9692)
			(xy 439.81857 -195.95734) (xy 439.768956 -195.937868) (xy 439.722798 -195.911219) (xy 439.681127 -195.877988)
			(xy 439.644875 -195.838917) (xy 439.614851 -195.79488) (xy 439.591725 -195.746859) (xy 439.576015 -195.695929)
			(xy 439.568072 -195.643225) (xy 425.191692 -195.643225) (xy 425.183749 -195.695929) (xy 425.168039 -195.746859)
			(xy 425.144913 -195.79488) (xy 425.114889 -195.838917) (xy 425.078637 -195.877988) (xy 425.036966 -195.911219)
			(xy 424.990808 -195.937868) (xy 424.941194 -195.95734) (xy 424.889232 -195.9692) (xy 424.836082 -195.973184)
			(xy 424.782932 -195.9692) (xy 424.73097 -195.95734) (xy 424.681356 -195.937868) (xy 424.635198 -195.911219)
			(xy 424.593527 -195.877988) (xy 424.557275 -195.838917) (xy 424.527251 -195.79488) (xy 424.504125 -195.746859)
			(xy 424.488415 -195.695929) (xy 424.480472 -195.643225) (xy 407.4668 -195.643225) (xy 407.4668 -196.493363)
			(xy 420.380404 -196.493363) (xy 420.380404 -196.440065) (xy 420.388347 -196.387361) (xy 420.404057 -196.336431)
			(xy 420.427183 -196.28841) (xy 420.457207 -196.244373) (xy 420.493459 -196.205302) (xy 420.53513 -196.172071)
			(xy 420.581288 -196.145422) (xy 420.630902 -196.12595) (xy 420.682864 -196.11409) (xy 420.736014 -196.110107)
			(xy 420.789164 -196.11409) (xy 420.841126 -196.12595) (xy 420.89074 -196.145422) (xy 420.936898 -196.172071)
			(xy 420.978569 -196.205302) (xy 421.014821 -196.244373) (xy 421.044845 -196.28841) (xy 421.067971 -196.336431)
			(xy 421.083681 -196.387361) (xy 421.091624 -196.440065) (xy 421.092122 -196.466714) (xy 421.091624 -196.493363)
			(xy 435.468004 -196.493363) (xy 435.468004 -196.440065) (xy 435.475947 -196.387361) (xy 435.491657 -196.336431)
			(xy 435.514783 -196.28841) (xy 435.544807 -196.244373) (xy 435.581059 -196.205302) (xy 435.62273 -196.172071)
			(xy 435.668888 -196.145422) (xy 435.718502 -196.12595) (xy 435.770464 -196.11409) (xy 435.823614 -196.110107)
			(xy 435.876764 -196.11409) (xy 435.928726 -196.12595) (xy 435.97834 -196.145422) (xy 436.024498 -196.172071)
			(xy 436.066169 -196.205302) (xy 436.102421 -196.244373) (xy 436.132445 -196.28841) (xy 436.155571 -196.336431)
			(xy 436.171281 -196.387361) (xy 436.179224 -196.440065) (xy 436.179722 -196.466714) (xy 436.179224 -196.493363)
			(xy 450.555604 -196.493363) (xy 450.555604 -196.440065) (xy 450.563547 -196.387361) (xy 450.579257 -196.336431)
			(xy 450.602383 -196.28841) (xy 450.632407 -196.244373) (xy 450.668659 -196.205302) (xy 450.71033 -196.172071)
			(xy 450.756488 -196.145422) (xy 450.806102 -196.12595) (xy 450.858064 -196.11409) (xy 450.911214 -196.110107)
			(xy 450.964364 -196.11409) (xy 451.016326 -196.12595) (xy 451.06594 -196.145422) (xy 451.112098 -196.172071)
			(xy 451.153769 -196.205302) (xy 451.190021 -196.244373) (xy 451.220045 -196.28841) (xy 451.243171 -196.336431)
			(xy 451.258881 -196.387361) (xy 451.266824 -196.440065) (xy 451.267322 -196.466714) (xy 451.266824 -196.493363)
			(xy 451.258881 -196.546067) (xy 451.243171 -196.596997) (xy 451.220045 -196.645018) (xy 451.190021 -196.689055)
			(xy 451.153769 -196.728126) (xy 451.112098 -196.761357) (xy 451.06594 -196.788006) (xy 451.016326 -196.807478)
			(xy 450.964364 -196.819338) (xy 450.911214 -196.823322) (xy 450.858064 -196.819338) (xy 450.806102 -196.807478)
			(xy 450.756488 -196.788006) (xy 450.71033 -196.761357) (xy 450.668659 -196.728126) (xy 450.632407 -196.689055)
			(xy 450.602383 -196.645018) (xy 450.579257 -196.596997) (xy 450.563547 -196.546067) (xy 450.555604 -196.493363)
			(xy 436.179224 -196.493363) (xy 436.171281 -196.546067) (xy 436.155571 -196.596997) (xy 436.132445 -196.645018)
			(xy 436.102421 -196.689055) (xy 436.066169 -196.728126) (xy 436.024498 -196.761357) (xy 435.97834 -196.788006)
			(xy 435.928726 -196.807478) (xy 435.876764 -196.819338) (xy 435.823614 -196.823322) (xy 435.770464 -196.819338)
			(xy 435.718502 -196.807478) (xy 435.668888 -196.788006) (xy 435.62273 -196.761357) (xy 435.581059 -196.728126)
			(xy 435.544807 -196.689055) (xy 435.514783 -196.645018) (xy 435.491657 -196.596997) (xy 435.475947 -196.546067)
			(xy 435.468004 -196.493363) (xy 421.091624 -196.493363) (xy 421.083681 -196.546067) (xy 421.067971 -196.596997)
			(xy 421.044845 -196.645018) (xy 421.014821 -196.689055) (xy 420.978569 -196.728126) (xy 420.936898 -196.761357)
			(xy 420.89074 -196.788006) (xy 420.841126 -196.807478) (xy 420.789164 -196.819338) (xy 420.736014 -196.823322)
			(xy 420.682864 -196.819338) (xy 420.630902 -196.807478) (xy 420.581288 -196.788006) (xy 420.53513 -196.761357)
			(xy 420.493459 -196.728126) (xy 420.457207 -196.689055) (xy 420.427183 -196.645018) (xy 420.404057 -196.596997)
			(xy 420.388347 -196.546067) (xy 420.380404 -196.493363) (xy 407.4668 -196.493363) (xy 407.4668 -197.343247)
			(xy 424.480472 -197.343247) (xy 424.480472 -197.289949) (xy 424.488415 -197.237245) (xy 424.504125 -197.186315)
			(xy 424.527251 -197.138294) (xy 424.557275 -197.094257) (xy 424.593527 -197.055186) (xy 424.635198 -197.021955)
			(xy 424.681356 -196.995306) (xy 424.73097 -196.975834) (xy 424.782932 -196.963974) (xy 424.836082 -196.959991)
			(xy 424.889232 -196.963974) (xy 424.941194 -196.975834) (xy 424.990808 -196.995306) (xy 425.036966 -197.021955)
			(xy 425.078637 -197.055186) (xy 425.114889 -197.094257) (xy 425.144913 -197.138294) (xy 425.168039 -197.186315)
			(xy 425.183749 -197.237245) (xy 425.191692 -197.289949) (xy 425.19219 -197.316598) (xy 425.191692 -197.343247)
			(xy 439.568072 -197.343247) (xy 439.568072 -197.289949) (xy 439.576015 -197.237245) (xy 439.591725 -197.186315)
			(xy 439.614851 -197.138294) (xy 439.644875 -197.094257) (xy 439.681127 -197.055186) (xy 439.722798 -197.021955)
			(xy 439.768956 -196.995306) (xy 439.81857 -196.975834) (xy 439.870532 -196.963974) (xy 439.923682 -196.959991)
			(xy 439.976832 -196.963974) (xy 440.028794 -196.975834) (xy 440.078408 -196.995306) (xy 440.124566 -197.021955)
			(xy 440.166237 -197.055186) (xy 440.202489 -197.094257) (xy 440.232513 -197.138294) (xy 440.255639 -197.186315)
			(xy 440.271349 -197.237245) (xy 440.279292 -197.289949) (xy 440.27979 -197.316598) (xy 440.279292 -197.343247)
			(xy 454.655672 -197.343247) (xy 454.655672 -197.289949) (xy 454.663615 -197.237245) (xy 454.679325 -197.186315)
			(xy 454.702451 -197.138294) (xy 454.732475 -197.094257) (xy 454.768727 -197.055186) (xy 454.810398 -197.021955)
			(xy 454.856556 -196.995306) (xy 454.90617 -196.975834) (xy 454.958132 -196.963974) (xy 455.011282 -196.959991)
			(xy 455.064432 -196.963974) (xy 455.116394 -196.975834) (xy 455.166008 -196.995306) (xy 455.212166 -197.021955)
			(xy 455.253837 -197.055186) (xy 455.290089 -197.094257) (xy 455.320113 -197.138294) (xy 455.343239 -197.186315)
			(xy 455.358949 -197.237245) (xy 455.366892 -197.289949) (xy 455.36739 -197.316598) (xy 455.366892 -197.343247)
			(xy 455.358949 -197.395951) (xy 455.343239 -197.446881) (xy 455.320113 -197.494902) (xy 455.290089 -197.538939)
			(xy 455.253837 -197.57801) (xy 455.212166 -197.611241) (xy 455.166008 -197.63789) (xy 455.116394 -197.657362)
			(xy 455.064432 -197.669222) (xy 455.011282 -197.673206) (xy 454.958132 -197.669222) (xy 454.90617 -197.657362)
			(xy 454.856556 -197.63789) (xy 454.810398 -197.611241) (xy 454.768727 -197.57801) (xy 454.732475 -197.538939)
			(xy 454.702451 -197.494902) (xy 454.679325 -197.446881) (xy 454.663615 -197.395951) (xy 454.655672 -197.343247)
			(xy 440.279292 -197.343247) (xy 440.271349 -197.395951) (xy 440.255639 -197.446881) (xy 440.232513 -197.494902)
			(xy 440.202489 -197.538939) (xy 440.166237 -197.57801) (xy 440.124566 -197.611241) (xy 440.078408 -197.63789)
			(xy 440.028794 -197.657362) (xy 439.976832 -197.669222) (xy 439.923682 -197.673206) (xy 439.870532 -197.669222)
			(xy 439.81857 -197.657362) (xy 439.768956 -197.63789) (xy 439.722798 -197.611241) (xy 439.681127 -197.57801)
			(xy 439.644875 -197.538939) (xy 439.614851 -197.494902) (xy 439.591725 -197.446881) (xy 439.576015 -197.395951)
			(xy 439.568072 -197.343247) (xy 425.191692 -197.343247) (xy 425.183749 -197.395951) (xy 425.168039 -197.446881)
			(xy 425.144913 -197.494902) (xy 425.114889 -197.538939) (xy 425.078637 -197.57801) (xy 425.036966 -197.611241)
			(xy 424.990808 -197.63789) (xy 424.941194 -197.657362) (xy 424.889232 -197.669222) (xy 424.836082 -197.673206)
			(xy 424.782932 -197.669222) (xy 424.73097 -197.657362) (xy 424.681356 -197.63789) (xy 424.635198 -197.611241)
			(xy 424.593527 -197.57801) (xy 424.557275 -197.538939) (xy 424.527251 -197.494902) (xy 424.504125 -197.446881)
			(xy 424.488415 -197.395951) (xy 424.480472 -197.343247) (xy 407.4668 -197.343247) (xy 407.4668 -198.193385)
			(xy 420.380404 -198.193385) (xy 420.380404 -198.140087) (xy 420.388347 -198.087383) (xy 420.404057 -198.036453)
			(xy 420.427183 -197.988432) (xy 420.457207 -197.944395) (xy 420.493459 -197.905324) (xy 420.53513 -197.872093)
			(xy 420.581288 -197.845444) (xy 420.630902 -197.825972) (xy 420.682864 -197.814112) (xy 420.736014 -197.810129)
			(xy 420.789164 -197.814112) (xy 420.841126 -197.825972) (xy 420.89074 -197.845444) (xy 420.936898 -197.872093)
			(xy 420.978569 -197.905324) (xy 421.014821 -197.944395) (xy 421.044845 -197.988432) (xy 421.067971 -198.036453)
			(xy 421.083681 -198.087383) (xy 421.091624 -198.140087) (xy 421.092122 -198.166736) (xy 421.091624 -198.193385)
			(xy 435.468004 -198.193385) (xy 435.468004 -198.140087) (xy 435.475947 -198.087383) (xy 435.491657 -198.036453)
			(xy 435.514783 -197.988432) (xy 435.544807 -197.944395) (xy 435.581059 -197.905324) (xy 435.62273 -197.872093)
			(xy 435.668888 -197.845444) (xy 435.718502 -197.825972) (xy 435.770464 -197.814112) (xy 435.823614 -197.810129)
			(xy 435.876764 -197.814112) (xy 435.928726 -197.825972) (xy 435.97834 -197.845444) (xy 436.024498 -197.872093)
			(xy 436.066169 -197.905324) (xy 436.102421 -197.944395) (xy 436.132445 -197.988432) (xy 436.155571 -198.036453)
			(xy 436.171281 -198.087383) (xy 436.179224 -198.140087) (xy 436.179722 -198.166736) (xy 436.179224 -198.193385)
			(xy 450.555604 -198.193385) (xy 450.555604 -198.140087) (xy 450.563547 -198.087383) (xy 450.579257 -198.036453)
			(xy 450.602383 -197.988432) (xy 450.632407 -197.944395) (xy 450.668659 -197.905324) (xy 450.71033 -197.872093)
			(xy 450.756488 -197.845444) (xy 450.806102 -197.825972) (xy 450.858064 -197.814112) (xy 450.911214 -197.810129)
			(xy 450.964364 -197.814112) (xy 451.016326 -197.825972) (xy 451.06594 -197.845444) (xy 451.112098 -197.872093)
			(xy 451.153769 -197.905324) (xy 451.190021 -197.944395) (xy 451.220045 -197.988432) (xy 451.243171 -198.036453)
			(xy 451.258881 -198.087383) (xy 451.266824 -198.140087) (xy 451.267322 -198.166736) (xy 451.266824 -198.193385)
			(xy 451.258881 -198.246089) (xy 451.243171 -198.297019) (xy 451.220045 -198.34504) (xy 451.190021 -198.389077)
			(xy 451.153769 -198.428148) (xy 451.112098 -198.461379) (xy 451.06594 -198.488028) (xy 451.016326 -198.5075)
			(xy 450.964364 -198.51936) (xy 450.911214 -198.523344) (xy 450.858064 -198.51936) (xy 450.806102 -198.5075)
			(xy 450.756488 -198.488028) (xy 450.71033 -198.461379) (xy 450.668659 -198.428148) (xy 450.632407 -198.389077)
			(xy 450.602383 -198.34504) (xy 450.579257 -198.297019) (xy 450.563547 -198.246089) (xy 450.555604 -198.193385)
			(xy 436.179224 -198.193385) (xy 436.171281 -198.246089) (xy 436.155571 -198.297019) (xy 436.132445 -198.34504)
			(xy 436.102421 -198.389077) (xy 436.066169 -198.428148) (xy 436.024498 -198.461379) (xy 435.97834 -198.488028)
			(xy 435.928726 -198.5075) (xy 435.876764 -198.51936) (xy 435.823614 -198.523344) (xy 435.770464 -198.51936)
			(xy 435.718502 -198.5075) (xy 435.668888 -198.488028) (xy 435.62273 -198.461379) (xy 435.581059 -198.428148)
			(xy 435.544807 -198.389077) (xy 435.514783 -198.34504) (xy 435.491657 -198.297019) (xy 435.475947 -198.246089)
			(xy 435.468004 -198.193385) (xy 421.091624 -198.193385) (xy 421.083681 -198.246089) (xy 421.067971 -198.297019)
			(xy 421.044845 -198.34504) (xy 421.014821 -198.389077) (xy 420.978569 -198.428148) (xy 420.936898 -198.461379)
			(xy 420.89074 -198.488028) (xy 420.841126 -198.5075) (xy 420.789164 -198.51936) (xy 420.736014 -198.523344)
			(xy 420.682864 -198.51936) (xy 420.630902 -198.5075) (xy 420.581288 -198.488028) (xy 420.53513 -198.461379)
			(xy 420.493459 -198.428148) (xy 420.457207 -198.389077) (xy 420.427183 -198.34504) (xy 420.404057 -198.297019)
			(xy 420.388347 -198.246089) (xy 420.380404 -198.193385) (xy 407.4668 -198.193385) (xy 407.4668 -199.043269)
			(xy 424.480472 -199.043269) (xy 424.480472 -198.989971) (xy 424.488415 -198.937267) (xy 424.504125 -198.886337)
			(xy 424.527251 -198.838316) (xy 424.557275 -198.794279) (xy 424.593527 -198.755208) (xy 424.635198 -198.721977)
			(xy 424.681356 -198.695328) (xy 424.73097 -198.675856) (xy 424.782932 -198.663996) (xy 424.836082 -198.660013)
			(xy 424.889232 -198.663996) (xy 424.941194 -198.675856) (xy 424.990808 -198.695328) (xy 425.036966 -198.721977)
			(xy 425.078637 -198.755208) (xy 425.114889 -198.794279) (xy 425.144913 -198.838316) (xy 425.168039 -198.886337)
			(xy 425.183749 -198.937267) (xy 425.191692 -198.989971) (xy 425.19219 -199.01662) (xy 425.191692 -199.043269)
			(xy 439.568072 -199.043269) (xy 439.568072 -198.989971) (xy 439.576015 -198.937267) (xy 439.591725 -198.886337)
			(xy 439.614851 -198.838316) (xy 439.644875 -198.794279) (xy 439.681127 -198.755208) (xy 439.722798 -198.721977)
			(xy 439.768956 -198.695328) (xy 439.81857 -198.675856) (xy 439.870532 -198.663996) (xy 439.923682 -198.660013)
			(xy 439.976832 -198.663996) (xy 440.028794 -198.675856) (xy 440.078408 -198.695328) (xy 440.124566 -198.721977)
			(xy 440.166237 -198.755208) (xy 440.202489 -198.794279) (xy 440.232513 -198.838316) (xy 440.255639 -198.886337)
			(xy 440.271349 -198.937267) (xy 440.279292 -198.989971) (xy 440.27979 -199.01662) (xy 440.279292 -199.043269)
			(xy 454.655672 -199.043269) (xy 454.655672 -198.989971) (xy 454.663615 -198.937267) (xy 454.679325 -198.886337)
			(xy 454.702451 -198.838316) (xy 454.732475 -198.794279) (xy 454.768727 -198.755208) (xy 454.810398 -198.721977)
			(xy 454.856556 -198.695328) (xy 454.90617 -198.675856) (xy 454.958132 -198.663996) (xy 455.011282 -198.660013)
			(xy 455.064432 -198.663996) (xy 455.116394 -198.675856) (xy 455.166008 -198.695328) (xy 455.212166 -198.721977)
			(xy 455.253837 -198.755208) (xy 455.290089 -198.794279) (xy 455.320113 -198.838316) (xy 455.343239 -198.886337)
			(xy 455.358949 -198.937267) (xy 455.366892 -198.989971) (xy 455.36739 -199.01662) (xy 455.366892 -199.043269)
			(xy 455.358949 -199.095973) (xy 455.343239 -199.146903) (xy 455.320113 -199.194924) (xy 455.290089 -199.238961)
			(xy 455.253837 -199.278032) (xy 455.212166 -199.311263) (xy 455.166008 -199.337912) (xy 455.116394 -199.357384)
			(xy 455.064432 -199.369244) (xy 455.011282 -199.373228) (xy 454.958132 -199.369244) (xy 454.90617 -199.357384)
			(xy 454.856556 -199.337912) (xy 454.810398 -199.311263) (xy 454.768727 -199.278032) (xy 454.732475 -199.238961)
			(xy 454.702451 -199.194924) (xy 454.679325 -199.146903) (xy 454.663615 -199.095973) (xy 454.655672 -199.043269)
			(xy 440.279292 -199.043269) (xy 440.271349 -199.095973) (xy 440.255639 -199.146903) (xy 440.232513 -199.194924)
			(xy 440.202489 -199.238961) (xy 440.166237 -199.278032) (xy 440.124566 -199.311263) (xy 440.078408 -199.337912)
			(xy 440.028794 -199.357384) (xy 439.976832 -199.369244) (xy 439.923682 -199.373228) (xy 439.870532 -199.369244)
			(xy 439.81857 -199.357384) (xy 439.768956 -199.337912) (xy 439.722798 -199.311263) (xy 439.681127 -199.278032)
			(xy 439.644875 -199.238961) (xy 439.614851 -199.194924) (xy 439.591725 -199.146903) (xy 439.576015 -199.095973)
			(xy 439.568072 -199.043269) (xy 425.191692 -199.043269) (xy 425.183749 -199.095973) (xy 425.168039 -199.146903)
			(xy 425.144913 -199.194924) (xy 425.114889 -199.238961) (xy 425.078637 -199.278032) (xy 425.036966 -199.311263)
			(xy 424.990808 -199.337912) (xy 424.941194 -199.357384) (xy 424.889232 -199.369244) (xy 424.836082 -199.373228)
			(xy 424.782932 -199.369244) (xy 424.73097 -199.357384) (xy 424.681356 -199.337912) (xy 424.635198 -199.311263)
			(xy 424.593527 -199.278032) (xy 424.557275 -199.238961) (xy 424.527251 -199.194924) (xy 424.504125 -199.146903)
			(xy 424.488415 -199.095973) (xy 424.480472 -199.043269) (xy 407.4668 -199.043269) (xy 407.4668 -199.893407)
			(xy 420.380404 -199.893407) (xy 420.380404 -199.840109) (xy 420.388347 -199.787405) (xy 420.404057 -199.736475)
			(xy 420.427183 -199.688454) (xy 420.457207 -199.644417) (xy 420.493459 -199.605346) (xy 420.53513 -199.572115)
			(xy 420.581288 -199.545466) (xy 420.630902 -199.525994) (xy 420.682864 -199.514134) (xy 420.736014 -199.510151)
			(xy 420.789164 -199.514134) (xy 420.841126 -199.525994) (xy 420.89074 -199.545466) (xy 420.936898 -199.572115)
			(xy 420.978569 -199.605346) (xy 421.014821 -199.644417) (xy 421.044845 -199.688454) (xy 421.067971 -199.736475)
			(xy 421.083681 -199.787405) (xy 421.091624 -199.840109) (xy 421.092122 -199.866758) (xy 421.091624 -199.893407)
			(xy 424.480472 -199.893407) (xy 424.480472 -199.840109) (xy 424.488415 -199.787405) (xy 424.504125 -199.736475)
			(xy 424.527251 -199.688454) (xy 424.557275 -199.644417) (xy 424.593527 -199.605346) (xy 424.635198 -199.572115)
			(xy 424.681356 -199.545466) (xy 424.73097 -199.525994) (xy 424.782932 -199.514134) (xy 424.836082 -199.510151)
			(xy 424.889232 -199.514134) (xy 424.941194 -199.525994) (xy 424.990808 -199.545466) (xy 425.036966 -199.572115)
			(xy 425.078637 -199.605346) (xy 425.114889 -199.644417) (xy 425.144913 -199.688454) (xy 425.168039 -199.736475)
			(xy 425.183749 -199.787405) (xy 425.191692 -199.840109) (xy 425.19219 -199.866758) (xy 425.191692 -199.893407)
			(xy 435.468004 -199.893407) (xy 435.468004 -199.840109) (xy 435.475947 -199.787405) (xy 435.491657 -199.736475)
			(xy 435.514783 -199.688454) (xy 435.544807 -199.644417) (xy 435.581059 -199.605346) (xy 435.62273 -199.572115)
			(xy 435.668888 -199.545466) (xy 435.718502 -199.525994) (xy 435.770464 -199.514134) (xy 435.823614 -199.510151)
			(xy 435.876764 -199.514134) (xy 435.928726 -199.525994) (xy 435.97834 -199.545466) (xy 436.024498 -199.572115)
			(xy 436.066169 -199.605346) (xy 436.102421 -199.644417) (xy 436.132445 -199.688454) (xy 436.155571 -199.736475)
			(xy 436.171281 -199.787405) (xy 436.179224 -199.840109) (xy 436.179722 -199.866758) (xy 436.179224 -199.893407)
			(xy 439.568072 -199.893407) (xy 439.568072 -199.840109) (xy 439.576015 -199.787405) (xy 439.591725 -199.736475)
			(xy 439.614851 -199.688454) (xy 439.644875 -199.644417) (xy 439.681127 -199.605346) (xy 439.722798 -199.572115)
			(xy 439.768956 -199.545466) (xy 439.81857 -199.525994) (xy 439.870532 -199.514134) (xy 439.923682 -199.510151)
			(xy 439.976832 -199.514134) (xy 440.028794 -199.525994) (xy 440.078408 -199.545466) (xy 440.124566 -199.572115)
			(xy 440.166237 -199.605346) (xy 440.202489 -199.644417) (xy 440.232513 -199.688454) (xy 440.255639 -199.736475)
			(xy 440.271349 -199.787405) (xy 440.279292 -199.840109) (xy 440.27979 -199.866758) (xy 440.279292 -199.893407)
			(xy 450.555604 -199.893407) (xy 450.555604 -199.840109) (xy 450.563547 -199.787405) (xy 450.579257 -199.736475)
			(xy 450.602383 -199.688454) (xy 450.632407 -199.644417) (xy 450.668659 -199.605346) (xy 450.71033 -199.572115)
			(xy 450.756488 -199.545466) (xy 450.806102 -199.525994) (xy 450.858064 -199.514134) (xy 450.911214 -199.510151)
			(xy 450.964364 -199.514134) (xy 451.016326 -199.525994) (xy 451.06594 -199.545466) (xy 451.112098 -199.572115)
			(xy 451.153769 -199.605346) (xy 451.190021 -199.644417) (xy 451.220045 -199.688454) (xy 451.243171 -199.736475)
			(xy 451.258881 -199.787405) (xy 451.266824 -199.840109) (xy 451.267322 -199.866758) (xy 451.266824 -199.893407)
			(xy 454.655672 -199.893407) (xy 454.655672 -199.840109) (xy 454.663615 -199.787405) (xy 454.679325 -199.736475)
			(xy 454.702451 -199.688454) (xy 454.732475 -199.644417) (xy 454.768727 -199.605346) (xy 454.810398 -199.572115)
			(xy 454.856556 -199.545466) (xy 454.90617 -199.525994) (xy 454.958132 -199.514134) (xy 455.011282 -199.510151)
			(xy 455.064432 -199.514134) (xy 455.116394 -199.525994) (xy 455.166008 -199.545466) (xy 455.212166 -199.572115)
			(xy 455.253837 -199.605346) (xy 455.290089 -199.644417) (xy 455.320113 -199.688454) (xy 455.343239 -199.736475)
			(xy 455.358949 -199.787405) (xy 455.366892 -199.840109) (xy 455.36739 -199.866758) (xy 455.366892 -199.893407)
			(xy 455.358949 -199.946111) (xy 455.343239 -199.997041) (xy 455.320113 -200.045062) (xy 455.290089 -200.089099)
			(xy 455.253837 -200.12817) (xy 455.212166 -200.161401) (xy 455.166008 -200.18805) (xy 455.116394 -200.207522)
			(xy 455.064432 -200.219382) (xy 455.011282 -200.223366) (xy 454.958132 -200.219382) (xy 454.90617 -200.207522)
			(xy 454.856556 -200.18805) (xy 454.810398 -200.161401) (xy 454.768727 -200.12817) (xy 454.732475 -200.089099)
			(xy 454.702451 -200.045062) (xy 454.679325 -199.997041) (xy 454.663615 -199.946111) (xy 454.655672 -199.893407)
			(xy 451.266824 -199.893407) (xy 451.258881 -199.946111) (xy 451.243171 -199.997041) (xy 451.220045 -200.045062)
			(xy 451.190021 -200.089099) (xy 451.153769 -200.12817) (xy 451.112098 -200.161401) (xy 451.06594 -200.18805)
			(xy 451.016326 -200.207522) (xy 450.964364 -200.219382) (xy 450.911214 -200.223366) (xy 450.858064 -200.219382)
			(xy 450.806102 -200.207522) (xy 450.756488 -200.18805) (xy 450.71033 -200.161401) (xy 450.668659 -200.12817)
			(xy 450.632407 -200.089099) (xy 450.602383 -200.045062) (xy 450.579257 -199.997041) (xy 450.563547 -199.946111)
			(xy 450.555604 -199.893407) (xy 440.279292 -199.893407) (xy 440.271349 -199.946111) (xy 440.255639 -199.997041)
			(xy 440.232513 -200.045062) (xy 440.202489 -200.089099) (xy 440.166237 -200.12817) (xy 440.124566 -200.161401)
			(xy 440.078408 -200.18805) (xy 440.028794 -200.207522) (xy 439.976832 -200.219382) (xy 439.923682 -200.223366)
			(xy 439.870532 -200.219382) (xy 439.81857 -200.207522) (xy 439.768956 -200.18805) (xy 439.722798 -200.161401)
			(xy 439.681127 -200.12817) (xy 439.644875 -200.089099) (xy 439.614851 -200.045062) (xy 439.591725 -199.997041)
			(xy 439.576015 -199.946111) (xy 439.568072 -199.893407) (xy 436.179224 -199.893407) (xy 436.171281 -199.946111)
			(xy 436.155571 -199.997041) (xy 436.132445 -200.045062) (xy 436.102421 -200.089099) (xy 436.066169 -200.12817)
			(xy 436.024498 -200.161401) (xy 435.97834 -200.18805) (xy 435.928726 -200.207522) (xy 435.876764 -200.219382)
			(xy 435.823614 -200.223366) (xy 435.770464 -200.219382) (xy 435.718502 -200.207522) (xy 435.668888 -200.18805)
			(xy 435.62273 -200.161401) (xy 435.581059 -200.12817) (xy 435.544807 -200.089099) (xy 435.514783 -200.045062)
			(xy 435.491657 -199.997041) (xy 435.475947 -199.946111) (xy 435.468004 -199.893407) (xy 425.191692 -199.893407)
			(xy 425.183749 -199.946111) (xy 425.168039 -199.997041) (xy 425.144913 -200.045062) (xy 425.114889 -200.089099)
			(xy 425.078637 -200.12817) (xy 425.036966 -200.161401) (xy 424.990808 -200.18805) (xy 424.941194 -200.207522)
			(xy 424.889232 -200.219382) (xy 424.836082 -200.223366) (xy 424.782932 -200.219382) (xy 424.73097 -200.207522)
			(xy 424.681356 -200.18805) (xy 424.635198 -200.161401) (xy 424.593527 -200.12817) (xy 424.557275 -200.089099)
			(xy 424.527251 -200.045062) (xy 424.504125 -199.997041) (xy 424.488415 -199.946111) (xy 424.480472 -199.893407)
			(xy 421.091624 -199.893407) (xy 421.083681 -199.946111) (xy 421.067971 -199.997041) (xy 421.044845 -200.045062)
			(xy 421.014821 -200.089099) (xy 420.978569 -200.12817) (xy 420.936898 -200.161401) (xy 420.89074 -200.18805)
			(xy 420.841126 -200.207522) (xy 420.789164 -200.219382) (xy 420.736014 -200.223366) (xy 420.682864 -200.219382)
			(xy 420.630902 -200.207522) (xy 420.581288 -200.18805) (xy 420.53513 -200.161401) (xy 420.493459 -200.12817)
			(xy 420.457207 -200.089099) (xy 420.427183 -200.045062) (xy 420.404057 -199.997041) (xy 420.388347 -199.946111)
			(xy 420.380404 -199.893407) (xy 407.4668 -199.893407) (xy 407.4668 -200.743291) (xy 420.380404 -200.743291)
			(xy 420.380404 -200.689993) (xy 420.388347 -200.637289) (xy 420.404057 -200.586359) (xy 420.427183 -200.538338)
			(xy 420.457207 -200.494301) (xy 420.493459 -200.45523) (xy 420.53513 -200.421999) (xy 420.581288 -200.39535)
			(xy 420.630902 -200.375878) (xy 420.682864 -200.364018) (xy 420.736014 -200.360035) (xy 420.789164 -200.364018)
			(xy 420.841126 -200.375878) (xy 420.89074 -200.39535) (xy 420.936898 -200.421999) (xy 420.978569 -200.45523)
			(xy 421.014821 -200.494301) (xy 421.044845 -200.538338) (xy 421.067971 -200.586359) (xy 421.083681 -200.637289)
			(xy 421.091624 -200.689993) (xy 421.092122 -200.716642) (xy 421.091624 -200.743291) (xy 435.468004 -200.743291)
			(xy 435.468004 -200.689993) (xy 435.475947 -200.637289) (xy 435.491657 -200.586359) (xy 435.514783 -200.538338)
			(xy 435.544807 -200.494301) (xy 435.581059 -200.45523) (xy 435.62273 -200.421999) (xy 435.668888 -200.39535)
			(xy 435.718502 -200.375878) (xy 435.770464 -200.364018) (xy 435.823614 -200.360035) (xy 435.876764 -200.364018)
			(xy 435.928726 -200.375878) (xy 435.97834 -200.39535) (xy 436.024498 -200.421999) (xy 436.066169 -200.45523)
			(xy 436.102421 -200.494301) (xy 436.132445 -200.538338) (xy 436.155571 -200.586359) (xy 436.171281 -200.637289)
			(xy 436.179224 -200.689993) (xy 436.179722 -200.716642) (xy 436.179224 -200.743291) (xy 450.555604 -200.743291)
			(xy 450.555604 -200.689993) (xy 450.563547 -200.637289) (xy 450.579257 -200.586359) (xy 450.602383 -200.538338)
			(xy 450.632407 -200.494301) (xy 450.668659 -200.45523) (xy 450.71033 -200.421999) (xy 450.756488 -200.39535)
			(xy 450.806102 -200.375878) (xy 450.858064 -200.364018) (xy 450.911214 -200.360035) (xy 450.964364 -200.364018)
			(xy 451.016326 -200.375878) (xy 451.06594 -200.39535) (xy 451.112098 -200.421999) (xy 451.153769 -200.45523)
			(xy 451.190021 -200.494301) (xy 451.220045 -200.538338) (xy 451.243171 -200.586359) (xy 451.258881 -200.637289)
			(xy 451.266824 -200.689993) (xy 451.267322 -200.716642) (xy 451.266824 -200.743291) (xy 451.258881 -200.795995)
			(xy 451.243171 -200.846925) (xy 451.220045 -200.894946) (xy 451.190021 -200.938983) (xy 451.153769 -200.978054)
			(xy 451.112098 -201.011285) (xy 451.06594 -201.037934) (xy 451.016326 -201.057406) (xy 450.964364 -201.069266)
			(xy 450.911214 -201.07325) (xy 450.858064 -201.069266) (xy 450.806102 -201.057406) (xy 450.756488 -201.037934)
			(xy 450.71033 -201.011285) (xy 450.668659 -200.978054) (xy 450.632407 -200.938983) (xy 450.602383 -200.894946)
			(xy 450.579257 -200.846925) (xy 450.563547 -200.795995) (xy 450.555604 -200.743291) (xy 436.179224 -200.743291)
			(xy 436.171281 -200.795995) (xy 436.155571 -200.846925) (xy 436.132445 -200.894946) (xy 436.102421 -200.938983)
			(xy 436.066169 -200.978054) (xy 436.024498 -201.011285) (xy 435.97834 -201.037934) (xy 435.928726 -201.057406)
			(xy 435.876764 -201.069266) (xy 435.823614 -201.07325) (xy 435.770464 -201.069266) (xy 435.718502 -201.057406)
			(xy 435.668888 -201.037934) (xy 435.62273 -201.011285) (xy 435.581059 -200.978054) (xy 435.544807 -200.938983)
			(xy 435.514783 -200.894946) (xy 435.491657 -200.846925) (xy 435.475947 -200.795995) (xy 435.468004 -200.743291)
			(xy 421.091624 -200.743291) (xy 421.083681 -200.795995) (xy 421.067971 -200.846925) (xy 421.044845 -200.894946)
			(xy 421.014821 -200.938983) (xy 420.978569 -200.978054) (xy 420.936898 -201.011285) (xy 420.89074 -201.037934)
			(xy 420.841126 -201.057406) (xy 420.789164 -201.069266) (xy 420.736014 -201.07325) (xy 420.682864 -201.069266)
			(xy 420.630902 -201.057406) (xy 420.581288 -201.037934) (xy 420.53513 -201.011285) (xy 420.493459 -200.978054)
			(xy 420.457207 -200.938983) (xy 420.427183 -200.894946) (xy 420.404057 -200.846925) (xy 420.388347 -200.795995)
			(xy 420.380404 -200.743291) (xy 407.4668 -200.743291) (xy 407.4668 -201.593429) (xy 424.480472 -201.593429)
			(xy 424.480472 -201.540131) (xy 424.488415 -201.487427) (xy 424.504125 -201.436497) (xy 424.527251 -201.388476)
			(xy 424.557275 -201.344439) (xy 424.593527 -201.305368) (xy 424.635198 -201.272137) (xy 424.681356 -201.245488)
			(xy 424.73097 -201.226016) (xy 424.782932 -201.214156) (xy 424.836082 -201.210173) (xy 424.889232 -201.214156)
			(xy 424.941194 -201.226016) (xy 424.990808 -201.245488) (xy 425.036966 -201.272137) (xy 425.078637 -201.305368)
			(xy 425.114889 -201.344439) (xy 425.144913 -201.388476) (xy 425.168039 -201.436497) (xy 425.183749 -201.487427)
			(xy 425.191692 -201.540131) (xy 425.19219 -201.56678) (xy 425.191692 -201.593429) (xy 439.568072 -201.593429)
			(xy 439.568072 -201.540131) (xy 439.576015 -201.487427) (xy 439.591725 -201.436497) (xy 439.614851 -201.388476)
			(xy 439.644875 -201.344439) (xy 439.681127 -201.305368) (xy 439.722798 -201.272137) (xy 439.768956 -201.245488)
			(xy 439.81857 -201.226016) (xy 439.870532 -201.214156) (xy 439.923682 -201.210173) (xy 439.976832 -201.214156)
			(xy 440.028794 -201.226016) (xy 440.078408 -201.245488) (xy 440.124566 -201.272137) (xy 440.166237 -201.305368)
			(xy 440.202489 -201.344439) (xy 440.232513 -201.388476) (xy 440.255639 -201.436497) (xy 440.271349 -201.487427)
			(xy 440.279292 -201.540131) (xy 440.27979 -201.56678) (xy 440.279292 -201.593429) (xy 454.655672 -201.593429)
			(xy 454.655672 -201.540131) (xy 454.663615 -201.487427) (xy 454.679325 -201.436497) (xy 454.702451 -201.388476)
			(xy 454.732475 -201.344439) (xy 454.768727 -201.305368) (xy 454.810398 -201.272137) (xy 454.856556 -201.245488)
			(xy 454.90617 -201.226016) (xy 454.958132 -201.214156) (xy 455.011282 -201.210173) (xy 455.064432 -201.214156)
			(xy 455.116394 -201.226016) (xy 455.166008 -201.245488) (xy 455.212166 -201.272137) (xy 455.253837 -201.305368)
			(xy 455.290089 -201.344439) (xy 455.320113 -201.388476) (xy 455.343239 -201.436497) (xy 455.358949 -201.487427)
			(xy 455.366892 -201.540131) (xy 455.36739 -201.56678) (xy 455.366892 -201.593429) (xy 455.358949 -201.646133)
			(xy 455.343239 -201.697063) (xy 455.320113 -201.745084) (xy 455.290089 -201.789121) (xy 455.253837 -201.828192)
			(xy 455.212166 -201.861423) (xy 455.166008 -201.888072) (xy 455.116394 -201.907544) (xy 455.064432 -201.919404)
			(xy 455.011282 -201.923388) (xy 454.958132 -201.919404) (xy 454.90617 -201.907544) (xy 454.856556 -201.888072)
			(xy 454.810398 -201.861423) (xy 454.768727 -201.828192) (xy 454.732475 -201.789121) (xy 454.702451 -201.745084)
			(xy 454.679325 -201.697063) (xy 454.663615 -201.646133) (xy 454.655672 -201.593429) (xy 440.279292 -201.593429)
			(xy 440.271349 -201.646133) (xy 440.255639 -201.697063) (xy 440.232513 -201.745084) (xy 440.202489 -201.789121)
			(xy 440.166237 -201.828192) (xy 440.124566 -201.861423) (xy 440.078408 -201.888072) (xy 440.028794 -201.907544)
			(xy 439.976832 -201.919404) (xy 439.923682 -201.923388) (xy 439.870532 -201.919404) (xy 439.81857 -201.907544)
			(xy 439.768956 -201.888072) (xy 439.722798 -201.861423) (xy 439.681127 -201.828192) (xy 439.644875 -201.789121)
			(xy 439.614851 -201.745084) (xy 439.591725 -201.697063) (xy 439.576015 -201.646133) (xy 439.568072 -201.593429)
			(xy 425.191692 -201.593429) (xy 425.183749 -201.646133) (xy 425.168039 -201.697063) (xy 425.144913 -201.745084)
			(xy 425.114889 -201.789121) (xy 425.078637 -201.828192) (xy 425.036966 -201.861423) (xy 424.990808 -201.888072)
			(xy 424.941194 -201.907544) (xy 424.889232 -201.919404) (xy 424.836082 -201.923388) (xy 424.782932 -201.919404)
			(xy 424.73097 -201.907544) (xy 424.681356 -201.888072) (xy 424.635198 -201.861423) (xy 424.593527 -201.828192)
			(xy 424.557275 -201.789121) (xy 424.527251 -201.745084) (xy 424.504125 -201.697063) (xy 424.488415 -201.646133)
			(xy 424.480472 -201.593429) (xy 407.4668 -201.593429) (xy 407.4668 -202.443313) (xy 420.380404 -202.443313)
			(xy 420.380404 -202.390015) (xy 420.388347 -202.337311) (xy 420.404057 -202.286381) (xy 420.427183 -202.23836)
			(xy 420.457207 -202.194323) (xy 420.493459 -202.155252) (xy 420.53513 -202.122021) (xy 420.581288 -202.095372)
			(xy 420.630902 -202.0759) (xy 420.682864 -202.06404) (xy 420.736014 -202.060057) (xy 420.789164 -202.06404)
			(xy 420.841126 -202.0759) (xy 420.89074 -202.095372) (xy 420.936898 -202.122021) (xy 420.978569 -202.155252)
			(xy 421.014821 -202.194323) (xy 421.044845 -202.23836) (xy 421.067971 -202.286381) (xy 421.083681 -202.337311)
			(xy 421.091624 -202.390015) (xy 421.092122 -202.416664) (xy 421.091624 -202.443313) (xy 435.468004 -202.443313)
			(xy 435.468004 -202.390015) (xy 435.475947 -202.337311) (xy 435.491657 -202.286381) (xy 435.514783 -202.23836)
			(xy 435.544807 -202.194323) (xy 435.581059 -202.155252) (xy 435.62273 -202.122021) (xy 435.668888 -202.095372)
			(xy 435.718502 -202.0759) (xy 435.770464 -202.06404) (xy 435.823614 -202.060057) (xy 435.876764 -202.06404)
			(xy 435.928726 -202.0759) (xy 435.97834 -202.095372) (xy 436.024498 -202.122021) (xy 436.066169 -202.155252)
			(xy 436.102421 -202.194323) (xy 436.132445 -202.23836) (xy 436.155571 -202.286381) (xy 436.171281 -202.337311)
			(xy 436.179224 -202.390015) (xy 436.179722 -202.416664) (xy 436.179224 -202.443313) (xy 450.555604 -202.443313)
			(xy 450.555604 -202.390015) (xy 450.563547 -202.337311) (xy 450.579257 -202.286381) (xy 450.602383 -202.23836)
			(xy 450.632407 -202.194323) (xy 450.668659 -202.155252) (xy 450.71033 -202.122021) (xy 450.756488 -202.095372)
			(xy 450.806102 -202.0759) (xy 450.858064 -202.06404) (xy 450.911214 -202.060057) (xy 450.964364 -202.06404)
			(xy 451.016326 -202.0759) (xy 451.06594 -202.095372) (xy 451.112098 -202.122021) (xy 451.153769 -202.155252)
			(xy 451.190021 -202.194323) (xy 451.220045 -202.23836) (xy 451.243171 -202.286381) (xy 451.258881 -202.337311)
			(xy 451.266824 -202.390015) (xy 451.267322 -202.416664) (xy 451.266824 -202.443313) (xy 451.258881 -202.496017)
			(xy 451.243171 -202.546947) (xy 451.220045 -202.594968) (xy 451.190021 -202.639005) (xy 451.153769 -202.678076)
			(xy 451.112098 -202.711307) (xy 451.06594 -202.737956) (xy 451.016326 -202.757428) (xy 450.964364 -202.769288)
			(xy 450.911214 -202.773272) (xy 450.858064 -202.769288) (xy 450.806102 -202.757428) (xy 450.756488 -202.737956)
			(xy 450.71033 -202.711307) (xy 450.668659 -202.678076) (xy 450.632407 -202.639005) (xy 450.602383 -202.594968)
			(xy 450.579257 -202.546947) (xy 450.563547 -202.496017) (xy 450.555604 -202.443313) (xy 436.179224 -202.443313)
			(xy 436.171281 -202.496017) (xy 436.155571 -202.546947) (xy 436.132445 -202.594968) (xy 436.102421 -202.639005)
			(xy 436.066169 -202.678076) (xy 436.024498 -202.711307) (xy 435.97834 -202.737956) (xy 435.928726 -202.757428)
			(xy 435.876764 -202.769288) (xy 435.823614 -202.773272) (xy 435.770464 -202.769288) (xy 435.718502 -202.757428)
			(xy 435.668888 -202.737956) (xy 435.62273 -202.711307) (xy 435.581059 -202.678076) (xy 435.544807 -202.639005)
			(xy 435.514783 -202.594968) (xy 435.491657 -202.546947) (xy 435.475947 -202.496017) (xy 435.468004 -202.443313)
			(xy 421.091624 -202.443313) (xy 421.083681 -202.496017) (xy 421.067971 -202.546947) (xy 421.044845 -202.594968)
			(xy 421.014821 -202.639005) (xy 420.978569 -202.678076) (xy 420.936898 -202.711307) (xy 420.89074 -202.737956)
			(xy 420.841126 -202.757428) (xy 420.789164 -202.769288) (xy 420.736014 -202.773272) (xy 420.682864 -202.769288)
			(xy 420.630902 -202.757428) (xy 420.581288 -202.737956) (xy 420.53513 -202.711307) (xy 420.493459 -202.678076)
			(xy 420.457207 -202.639005) (xy 420.427183 -202.594968) (xy 420.404057 -202.546947) (xy 420.388347 -202.496017)
			(xy 420.380404 -202.443313) (xy 407.4668 -202.443313) (xy 407.4668 -203.293451) (xy 424.480472 -203.293451)
			(xy 424.480472 -203.240153) (xy 424.488415 -203.187449) (xy 424.504125 -203.136519) (xy 424.527251 -203.088498)
			(xy 424.557275 -203.044461) (xy 424.593527 -203.00539) (xy 424.635198 -202.972159) (xy 424.681356 -202.94551)
			(xy 424.73097 -202.926038) (xy 424.782932 -202.914178) (xy 424.836082 -202.910195) (xy 424.889232 -202.914178)
			(xy 424.941194 -202.926038) (xy 424.990808 -202.94551) (xy 425.036966 -202.972159) (xy 425.078637 -203.00539)
			(xy 425.114889 -203.044461) (xy 425.144913 -203.088498) (xy 425.168039 -203.136519) (xy 425.183749 -203.187449)
			(xy 425.191692 -203.240153) (xy 425.19219 -203.266802) (xy 425.191692 -203.293451) (xy 439.568072 -203.293451)
			(xy 439.568072 -203.240153) (xy 439.576015 -203.187449) (xy 439.591725 -203.136519) (xy 439.614851 -203.088498)
			(xy 439.644875 -203.044461) (xy 439.681127 -203.00539) (xy 439.722798 -202.972159) (xy 439.768956 -202.94551)
			(xy 439.81857 -202.926038) (xy 439.870532 -202.914178) (xy 439.923682 -202.910195) (xy 439.976832 -202.914178)
			(xy 440.028794 -202.926038) (xy 440.078408 -202.94551) (xy 440.124566 -202.972159) (xy 440.166237 -203.00539)
			(xy 440.202489 -203.044461) (xy 440.232513 -203.088498) (xy 440.255639 -203.136519) (xy 440.271349 -203.187449)
			(xy 440.279292 -203.240153) (xy 440.27979 -203.266802) (xy 440.279292 -203.293451) (xy 454.655672 -203.293451)
			(xy 454.655672 -203.240153) (xy 454.663615 -203.187449) (xy 454.679325 -203.136519) (xy 454.702451 -203.088498)
			(xy 454.732475 -203.044461) (xy 454.768727 -203.00539) (xy 454.810398 -202.972159) (xy 454.856556 -202.94551)
			(xy 454.90617 -202.926038) (xy 454.958132 -202.914178) (xy 455.011282 -202.910195) (xy 455.064432 -202.914178)
			(xy 455.116394 -202.926038) (xy 455.166008 -202.94551) (xy 455.212166 -202.972159) (xy 455.253837 -203.00539)
			(xy 455.290089 -203.044461) (xy 455.320113 -203.088498) (xy 455.343239 -203.136519) (xy 455.358949 -203.187449)
			(xy 455.366892 -203.240153) (xy 455.36739 -203.266802) (xy 455.366892 -203.293451) (xy 455.358949 -203.346155)
			(xy 455.343239 -203.397085) (xy 455.320113 -203.445106) (xy 455.290089 -203.489143) (xy 455.253837 -203.528214)
			(xy 455.212166 -203.561445) (xy 455.166008 -203.588094) (xy 455.116394 -203.607566) (xy 455.064432 -203.619426)
			(xy 455.011282 -203.62341) (xy 454.958132 -203.619426) (xy 454.90617 -203.607566) (xy 454.856556 -203.588094)
			(xy 454.810398 -203.561445) (xy 454.768727 -203.528214) (xy 454.732475 -203.489143) (xy 454.702451 -203.445106)
			(xy 454.679325 -203.397085) (xy 454.663615 -203.346155) (xy 454.655672 -203.293451) (xy 440.279292 -203.293451)
			(xy 440.271349 -203.346155) (xy 440.255639 -203.397085) (xy 440.232513 -203.445106) (xy 440.202489 -203.489143)
			(xy 440.166237 -203.528214) (xy 440.124566 -203.561445) (xy 440.078408 -203.588094) (xy 440.028794 -203.607566)
			(xy 439.976832 -203.619426) (xy 439.923682 -203.62341) (xy 439.870532 -203.619426) (xy 439.81857 -203.607566)
			(xy 439.768956 -203.588094) (xy 439.722798 -203.561445) (xy 439.681127 -203.528214) (xy 439.644875 -203.489143)
			(xy 439.614851 -203.445106) (xy 439.591725 -203.397085) (xy 439.576015 -203.346155) (xy 439.568072 -203.293451)
			(xy 425.191692 -203.293451) (xy 425.183749 -203.346155) (xy 425.168039 -203.397085) (xy 425.144913 -203.445106)
			(xy 425.114889 -203.489143) (xy 425.078637 -203.528214) (xy 425.036966 -203.561445) (xy 424.990808 -203.588094)
			(xy 424.941194 -203.607566) (xy 424.889232 -203.619426) (xy 424.836082 -203.62341) (xy 424.782932 -203.619426)
			(xy 424.73097 -203.607566) (xy 424.681356 -203.588094) (xy 424.635198 -203.561445) (xy 424.593527 -203.528214)
			(xy 424.557275 -203.489143) (xy 424.527251 -203.445106) (xy 424.504125 -203.397085) (xy 424.488415 -203.346155)
			(xy 424.480472 -203.293451) (xy 407.4668 -203.293451) (xy 407.4668 -204.143335) (xy 420.380404 -204.143335)
			(xy 420.380404 -204.090037) (xy 420.388347 -204.037333) (xy 420.404057 -203.986403) (xy 420.427183 -203.938382)
			(xy 420.457207 -203.894345) (xy 420.493459 -203.855274) (xy 420.53513 -203.822043) (xy 420.581288 -203.795394)
			(xy 420.630902 -203.775922) (xy 420.682864 -203.764062) (xy 420.736014 -203.760079) (xy 420.789164 -203.764062)
			(xy 420.841126 -203.775922) (xy 420.89074 -203.795394) (xy 420.936898 -203.822043) (xy 420.978569 -203.855274)
			(xy 421.014821 -203.894345) (xy 421.044845 -203.938382) (xy 421.067971 -203.986403) (xy 421.083681 -204.037333)
			(xy 421.091624 -204.090037) (xy 421.092122 -204.116686) (xy 421.091624 -204.143335) (xy 435.468004 -204.143335)
			(xy 435.468004 -204.090037) (xy 435.475947 -204.037333) (xy 435.491657 -203.986403) (xy 435.514783 -203.938382)
			(xy 435.544807 -203.894345) (xy 435.581059 -203.855274) (xy 435.62273 -203.822043) (xy 435.668888 -203.795394)
			(xy 435.718502 -203.775922) (xy 435.770464 -203.764062) (xy 435.823614 -203.760079) (xy 435.876764 -203.764062)
			(xy 435.928726 -203.775922) (xy 435.97834 -203.795394) (xy 436.024498 -203.822043) (xy 436.066169 -203.855274)
			(xy 436.102421 -203.894345) (xy 436.132445 -203.938382) (xy 436.155571 -203.986403) (xy 436.171281 -204.037333)
			(xy 436.179224 -204.090037) (xy 436.179722 -204.116686) (xy 436.179224 -204.143335) (xy 450.555604 -204.143335)
			(xy 450.555604 -204.090037) (xy 450.563547 -204.037333) (xy 450.579257 -203.986403) (xy 450.602383 -203.938382)
			(xy 450.632407 -203.894345) (xy 450.668659 -203.855274) (xy 450.71033 -203.822043) (xy 450.756488 -203.795394)
			(xy 450.806102 -203.775922) (xy 450.858064 -203.764062) (xy 450.911214 -203.760079) (xy 450.964364 -203.764062)
			(xy 451.016326 -203.775922) (xy 451.06594 -203.795394) (xy 451.112098 -203.822043) (xy 451.153769 -203.855274)
			(xy 451.190021 -203.894345) (xy 451.220045 -203.938382) (xy 451.243171 -203.986403) (xy 451.258881 -204.037333)
			(xy 451.266824 -204.090037) (xy 451.267322 -204.116686) (xy 451.266824 -204.143335) (xy 451.258881 -204.196039)
			(xy 451.243171 -204.246969) (xy 451.220045 -204.29499) (xy 451.190021 -204.339027) (xy 451.153769 -204.378098)
			(xy 451.112098 -204.411329) (xy 451.06594 -204.437978) (xy 451.016326 -204.45745) (xy 450.964364 -204.46931)
			(xy 450.911214 -204.473294) (xy 450.858064 -204.46931) (xy 450.806102 -204.45745) (xy 450.756488 -204.437978)
			(xy 450.71033 -204.411329) (xy 450.668659 -204.378098) (xy 450.632407 -204.339027) (xy 450.602383 -204.29499)
			(xy 450.579257 -204.246969) (xy 450.563547 -204.196039) (xy 450.555604 -204.143335) (xy 436.179224 -204.143335)
			(xy 436.171281 -204.196039) (xy 436.155571 -204.246969) (xy 436.132445 -204.29499) (xy 436.102421 -204.339027)
			(xy 436.066169 -204.378098) (xy 436.024498 -204.411329) (xy 435.97834 -204.437978) (xy 435.928726 -204.45745)
			(xy 435.876764 -204.46931) (xy 435.823614 -204.473294) (xy 435.770464 -204.46931) (xy 435.718502 -204.45745)
			(xy 435.668888 -204.437978) (xy 435.62273 -204.411329) (xy 435.581059 -204.378098) (xy 435.544807 -204.339027)
			(xy 435.514783 -204.29499) (xy 435.491657 -204.246969) (xy 435.475947 -204.196039) (xy 435.468004 -204.143335)
			(xy 421.091624 -204.143335) (xy 421.083681 -204.196039) (xy 421.067971 -204.246969) (xy 421.044845 -204.29499)
			(xy 421.014821 -204.339027) (xy 420.978569 -204.378098) (xy 420.936898 -204.411329) (xy 420.89074 -204.437978)
			(xy 420.841126 -204.45745) (xy 420.789164 -204.46931) (xy 420.736014 -204.473294) (xy 420.682864 -204.46931)
			(xy 420.630902 -204.45745) (xy 420.581288 -204.437978) (xy 420.53513 -204.411329) (xy 420.493459 -204.378098)
			(xy 420.457207 -204.339027) (xy 420.427183 -204.29499) (xy 420.404057 -204.246969) (xy 420.388347 -204.196039)
			(xy 420.380404 -204.143335) (xy 407.4668 -204.143335) (xy 407.4668 -204.993219) (xy 424.480472 -204.993219)
			(xy 424.480472 -204.939921) (xy 424.488415 -204.887217) (xy 424.504125 -204.836287) (xy 424.527251 -204.788266)
			(xy 424.557275 -204.744229) (xy 424.593527 -204.705158) (xy 424.635198 -204.671927) (xy 424.681356 -204.645278)
			(xy 424.73097 -204.625806) (xy 424.782932 -204.613946) (xy 424.836082 -204.609963) (xy 424.889232 -204.613946)
			(xy 424.941194 -204.625806) (xy 424.990808 -204.645278) (xy 425.036966 -204.671927) (xy 425.078637 -204.705158)
			(xy 425.114889 -204.744229) (xy 425.144913 -204.788266) (xy 425.168039 -204.836287) (xy 425.183749 -204.887217)
			(xy 425.191692 -204.939921) (xy 425.19219 -204.96657) (xy 425.191692 -204.993219) (xy 439.568072 -204.993219)
			(xy 439.568072 -204.939921) (xy 439.576015 -204.887217) (xy 439.591725 -204.836287) (xy 439.614851 -204.788266)
			(xy 439.644875 -204.744229) (xy 439.681127 -204.705158) (xy 439.722798 -204.671927) (xy 439.768956 -204.645278)
			(xy 439.81857 -204.625806) (xy 439.870532 -204.613946) (xy 439.923682 -204.609963) (xy 439.976832 -204.613946)
			(xy 440.028794 -204.625806) (xy 440.078408 -204.645278) (xy 440.124566 -204.671927) (xy 440.166237 -204.705158)
			(xy 440.202489 -204.744229) (xy 440.232513 -204.788266) (xy 440.255639 -204.836287) (xy 440.271349 -204.887217)
			(xy 440.279292 -204.939921) (xy 440.27979 -204.96657) (xy 440.279292 -204.993219) (xy 454.655672 -204.993219)
			(xy 454.655672 -204.939921) (xy 454.663615 -204.887217) (xy 454.679325 -204.836287) (xy 454.702451 -204.788266)
			(xy 454.732475 -204.744229) (xy 454.768727 -204.705158) (xy 454.810398 -204.671927) (xy 454.856556 -204.645278)
			(xy 454.90617 -204.625806) (xy 454.958132 -204.613946) (xy 455.011282 -204.609963) (xy 455.064432 -204.613946)
			(xy 455.116394 -204.625806) (xy 455.166008 -204.645278) (xy 455.212166 -204.671927) (xy 455.253837 -204.705158)
			(xy 455.290089 -204.744229) (xy 455.320113 -204.788266) (xy 455.343239 -204.836287) (xy 455.358949 -204.887217)
			(xy 455.366892 -204.939921) (xy 455.36739 -204.96657) (xy 455.366892 -204.993219) (xy 455.358949 -205.045923)
			(xy 455.343239 -205.096853) (xy 455.320113 -205.144874) (xy 455.290089 -205.188911) (xy 455.253837 -205.227982)
			(xy 455.212166 -205.261213) (xy 455.166008 -205.287862) (xy 455.116394 -205.307334) (xy 455.064432 -205.319194)
			(xy 455.011282 -205.323178) (xy 454.958132 -205.319194) (xy 454.90617 -205.307334) (xy 454.856556 -205.287862)
			(xy 454.810398 -205.261213) (xy 454.768727 -205.227982) (xy 454.732475 -205.188911) (xy 454.702451 -205.144874)
			(xy 454.679325 -205.096853) (xy 454.663615 -205.045923) (xy 454.655672 -204.993219) (xy 440.279292 -204.993219)
			(xy 440.271349 -205.045923) (xy 440.255639 -205.096853) (xy 440.232513 -205.144874) (xy 440.202489 -205.188911)
			(xy 440.166237 -205.227982) (xy 440.124566 -205.261213) (xy 440.078408 -205.287862) (xy 440.028794 -205.307334)
			(xy 439.976832 -205.319194) (xy 439.923682 -205.323178) (xy 439.870532 -205.319194) (xy 439.81857 -205.307334)
			(xy 439.768956 -205.287862) (xy 439.722798 -205.261213) (xy 439.681127 -205.227982) (xy 439.644875 -205.188911)
			(xy 439.614851 -205.144874) (xy 439.591725 -205.096853) (xy 439.576015 -205.045923) (xy 439.568072 -204.993219)
			(xy 425.191692 -204.993219) (xy 425.183749 -205.045923) (xy 425.168039 -205.096853) (xy 425.144913 -205.144874)
			(xy 425.114889 -205.188911) (xy 425.078637 -205.227982) (xy 425.036966 -205.261213) (xy 424.990808 -205.287862)
			(xy 424.941194 -205.307334) (xy 424.889232 -205.319194) (xy 424.836082 -205.323178) (xy 424.782932 -205.319194)
			(xy 424.73097 -205.307334) (xy 424.681356 -205.287862) (xy 424.635198 -205.261213) (xy 424.593527 -205.227982)
			(xy 424.557275 -205.188911) (xy 424.527251 -205.144874) (xy 424.504125 -205.096853) (xy 424.488415 -205.045923)
			(xy 424.480472 -204.993219) (xy 407.4668 -204.993219) (xy 407.4668 -205.843357) (xy 420.380404 -205.843357)
			(xy 420.380404 -205.790059) (xy 420.388347 -205.737355) (xy 420.404057 -205.686425) (xy 420.427183 -205.638404)
			(xy 420.457207 -205.594367) (xy 420.493459 -205.555296) (xy 420.53513 -205.522065) (xy 420.581288 -205.495416)
			(xy 420.630902 -205.475944) (xy 420.682864 -205.464084) (xy 420.736014 -205.460101) (xy 420.789164 -205.464084)
			(xy 420.841126 -205.475944) (xy 420.89074 -205.495416) (xy 420.936898 -205.522065) (xy 420.978569 -205.555296)
			(xy 421.014821 -205.594367) (xy 421.044845 -205.638404) (xy 421.067971 -205.686425) (xy 421.083681 -205.737355)
			(xy 421.091624 -205.790059) (xy 421.092122 -205.816708) (xy 421.091624 -205.843357) (xy 435.468004 -205.843357)
			(xy 435.468004 -205.790059) (xy 435.475947 -205.737355) (xy 435.491657 -205.686425) (xy 435.514783 -205.638404)
			(xy 435.544807 -205.594367) (xy 435.581059 -205.555296) (xy 435.62273 -205.522065) (xy 435.668888 -205.495416)
			(xy 435.718502 -205.475944) (xy 435.770464 -205.464084) (xy 435.823614 -205.460101) (xy 435.876764 -205.464084)
			(xy 435.928726 -205.475944) (xy 435.97834 -205.495416) (xy 436.024498 -205.522065) (xy 436.066169 -205.555296)
			(xy 436.102421 -205.594367) (xy 436.132445 -205.638404) (xy 436.155571 -205.686425) (xy 436.171281 -205.737355)
			(xy 436.179224 -205.790059) (xy 436.179722 -205.816708) (xy 436.179224 -205.843357) (xy 450.555604 -205.843357)
			(xy 450.555604 -205.790059) (xy 450.563547 -205.737355) (xy 450.579257 -205.686425) (xy 450.602383 -205.638404)
			(xy 450.632407 -205.594367) (xy 450.668659 -205.555296) (xy 450.71033 -205.522065) (xy 450.756488 -205.495416)
			(xy 450.806102 -205.475944) (xy 450.858064 -205.464084) (xy 450.911214 -205.460101) (xy 450.964364 -205.464084)
			(xy 451.016326 -205.475944) (xy 451.06594 -205.495416) (xy 451.112098 -205.522065) (xy 451.153769 -205.555296)
			(xy 451.190021 -205.594367) (xy 451.220045 -205.638404) (xy 451.243171 -205.686425) (xy 451.258881 -205.737355)
			(xy 451.266824 -205.790059) (xy 451.267322 -205.816708) (xy 451.266824 -205.843357) (xy 451.258881 -205.896061)
			(xy 451.243171 -205.946991) (xy 451.220045 -205.995012) (xy 451.190021 -206.039049) (xy 451.153769 -206.07812)
			(xy 451.112098 -206.111351) (xy 451.06594 -206.138) (xy 451.016326 -206.157472) (xy 450.964364 -206.169332)
			(xy 450.911214 -206.173316) (xy 450.858064 -206.169332) (xy 450.806102 -206.157472) (xy 450.756488 -206.138)
			(xy 450.71033 -206.111351) (xy 450.668659 -206.07812) (xy 450.632407 -206.039049) (xy 450.602383 -205.995012)
			(xy 450.579257 -205.946991) (xy 450.563547 -205.896061) (xy 450.555604 -205.843357) (xy 436.179224 -205.843357)
			(xy 436.171281 -205.896061) (xy 436.155571 -205.946991) (xy 436.132445 -205.995012) (xy 436.102421 -206.039049)
			(xy 436.066169 -206.07812) (xy 436.024498 -206.111351) (xy 435.97834 -206.138) (xy 435.928726 -206.157472)
			(xy 435.876764 -206.169332) (xy 435.823614 -206.173316) (xy 435.770464 -206.169332) (xy 435.718502 -206.157472)
			(xy 435.668888 -206.138) (xy 435.62273 -206.111351) (xy 435.581059 -206.07812) (xy 435.544807 -206.039049)
			(xy 435.514783 -205.995012) (xy 435.491657 -205.946991) (xy 435.475947 -205.896061) (xy 435.468004 -205.843357)
			(xy 421.091624 -205.843357) (xy 421.083681 -205.896061) (xy 421.067971 -205.946991) (xy 421.044845 -205.995012)
			(xy 421.014821 -206.039049) (xy 420.978569 -206.07812) (xy 420.936898 -206.111351) (xy 420.89074 -206.138)
			(xy 420.841126 -206.157472) (xy 420.789164 -206.169332) (xy 420.736014 -206.173316) (xy 420.682864 -206.169332)
			(xy 420.630902 -206.157472) (xy 420.581288 -206.138) (xy 420.53513 -206.111351) (xy 420.493459 -206.07812)
			(xy 420.457207 -206.039049) (xy 420.427183 -205.995012) (xy 420.404057 -205.946991) (xy 420.388347 -205.896061)
			(xy 420.380404 -205.843357) (xy 407.4668 -205.843357) (xy 407.4668 -206.693241) (xy 424.480472 -206.693241)
			(xy 424.480472 -206.639943) (xy 424.488415 -206.587239) (xy 424.504125 -206.536309) (xy 424.527251 -206.488288)
			(xy 424.557275 -206.444251) (xy 424.593527 -206.40518) (xy 424.635198 -206.371949) (xy 424.681356 -206.3453)
			(xy 424.73097 -206.325828) (xy 424.782932 -206.313968) (xy 424.836082 -206.309985) (xy 424.889232 -206.313968)
			(xy 424.941194 -206.325828) (xy 424.990808 -206.3453) (xy 425.036966 -206.371949) (xy 425.078637 -206.40518)
			(xy 425.114889 -206.444251) (xy 425.144913 -206.488288) (xy 425.168039 -206.536309) (xy 425.183749 -206.587239)
			(xy 425.191692 -206.639943) (xy 425.19219 -206.666592) (xy 425.191692 -206.693241) (xy 439.568072 -206.693241)
			(xy 439.568072 -206.639943) (xy 439.576015 -206.587239) (xy 439.591725 -206.536309) (xy 439.614851 -206.488288)
			(xy 439.644875 -206.444251) (xy 439.681127 -206.40518) (xy 439.722798 -206.371949) (xy 439.768956 -206.3453)
			(xy 439.81857 -206.325828) (xy 439.870532 -206.313968) (xy 439.923682 -206.309985) (xy 439.976832 -206.313968)
			(xy 440.028794 -206.325828) (xy 440.078408 -206.3453) (xy 440.124566 -206.371949) (xy 440.166237 -206.40518)
			(xy 440.202489 -206.444251) (xy 440.232513 -206.488288) (xy 440.255639 -206.536309) (xy 440.271349 -206.587239)
			(xy 440.279292 -206.639943) (xy 440.27979 -206.666592) (xy 440.279292 -206.693241) (xy 454.655672 -206.693241)
			(xy 454.655672 -206.639943) (xy 454.663615 -206.587239) (xy 454.679325 -206.536309) (xy 454.702451 -206.488288)
			(xy 454.732475 -206.444251) (xy 454.768727 -206.40518) (xy 454.810398 -206.371949) (xy 454.856556 -206.3453)
			(xy 454.90617 -206.325828) (xy 454.958132 -206.313968) (xy 455.011282 -206.309985) (xy 455.064432 -206.313968)
			(xy 455.116394 -206.325828) (xy 455.166008 -206.3453) (xy 455.212166 -206.371949) (xy 455.253837 -206.40518)
			(xy 455.290089 -206.444251) (xy 455.320113 -206.488288) (xy 455.343239 -206.536309) (xy 455.358949 -206.587239)
			(xy 455.366892 -206.639943) (xy 455.36739 -206.666592) (xy 455.366892 -206.693241) (xy 455.358949 -206.745945)
			(xy 455.343239 -206.796875) (xy 455.320113 -206.844896) (xy 455.290089 -206.888933) (xy 455.253837 -206.928004)
			(xy 455.212166 -206.961235) (xy 455.166008 -206.987884) (xy 455.116394 -207.007356) (xy 455.064432 -207.019216)
			(xy 455.011282 -207.0232) (xy 454.958132 -207.019216) (xy 454.90617 -207.007356) (xy 454.856556 -206.987884)
			(xy 454.810398 -206.961235) (xy 454.768727 -206.928004) (xy 454.732475 -206.888933) (xy 454.702451 -206.844896)
			(xy 454.679325 -206.796875) (xy 454.663615 -206.745945) (xy 454.655672 -206.693241) (xy 440.279292 -206.693241)
			(xy 440.271349 -206.745945) (xy 440.255639 -206.796875) (xy 440.232513 -206.844896) (xy 440.202489 -206.888933)
			(xy 440.166237 -206.928004) (xy 440.124566 -206.961235) (xy 440.078408 -206.987884) (xy 440.028794 -207.007356)
			(xy 439.976832 -207.019216) (xy 439.923682 -207.0232) (xy 439.870532 -207.019216) (xy 439.81857 -207.007356)
			(xy 439.768956 -206.987884) (xy 439.722798 -206.961235) (xy 439.681127 -206.928004) (xy 439.644875 -206.888933)
			(xy 439.614851 -206.844896) (xy 439.591725 -206.796875) (xy 439.576015 -206.745945) (xy 439.568072 -206.693241)
			(xy 425.191692 -206.693241) (xy 425.183749 -206.745945) (xy 425.168039 -206.796875) (xy 425.144913 -206.844896)
			(xy 425.114889 -206.888933) (xy 425.078637 -206.928004) (xy 425.036966 -206.961235) (xy 424.990808 -206.987884)
			(xy 424.941194 -207.007356) (xy 424.889232 -207.019216) (xy 424.836082 -207.0232) (xy 424.782932 -207.019216)
			(xy 424.73097 -207.007356) (xy 424.681356 -206.987884) (xy 424.635198 -206.961235) (xy 424.593527 -206.928004)
			(xy 424.557275 -206.888933) (xy 424.527251 -206.844896) (xy 424.504125 -206.796875) (xy 424.488415 -206.745945)
			(xy 424.480472 -206.693241) (xy 407.4668 -206.693241) (xy 407.4668 -207.543379) (xy 420.380404 -207.543379)
			(xy 420.380404 -207.490081) (xy 420.388347 -207.437377) (xy 420.404057 -207.386447) (xy 420.427183 -207.338426)
			(xy 420.457207 -207.294389) (xy 420.493459 -207.255318) (xy 420.53513 -207.222087) (xy 420.581288 -207.195438)
			(xy 420.630902 -207.175966) (xy 420.682864 -207.164106) (xy 420.736014 -207.160123) (xy 420.789164 -207.164106)
			(xy 420.841126 -207.175966) (xy 420.89074 -207.195438) (xy 420.936898 -207.222087) (xy 420.978569 -207.255318)
			(xy 421.014821 -207.294389) (xy 421.044845 -207.338426) (xy 421.067971 -207.386447) (xy 421.083681 -207.437377)
			(xy 421.091624 -207.490081) (xy 421.092122 -207.51673) (xy 421.091624 -207.543379) (xy 435.468004 -207.543379)
			(xy 435.468004 -207.490081) (xy 435.475947 -207.437377) (xy 435.491657 -207.386447) (xy 435.514783 -207.338426)
			(xy 435.544807 -207.294389) (xy 435.581059 -207.255318) (xy 435.62273 -207.222087) (xy 435.668888 -207.195438)
			(xy 435.718502 -207.175966) (xy 435.770464 -207.164106) (xy 435.823614 -207.160123) (xy 435.876764 -207.164106)
			(xy 435.928726 -207.175966) (xy 435.97834 -207.195438) (xy 436.024498 -207.222087) (xy 436.066169 -207.255318)
			(xy 436.102421 -207.294389) (xy 436.132445 -207.338426) (xy 436.155571 -207.386447) (xy 436.171281 -207.437377)
			(xy 436.179224 -207.490081) (xy 436.179722 -207.51673) (xy 436.179224 -207.543379) (xy 450.555604 -207.543379)
			(xy 450.555604 -207.490081) (xy 450.563547 -207.437377) (xy 450.579257 -207.386447) (xy 450.602383 -207.338426)
			(xy 450.632407 -207.294389) (xy 450.668659 -207.255318) (xy 450.71033 -207.222087) (xy 450.756488 -207.195438)
			(xy 450.806102 -207.175966) (xy 450.858064 -207.164106) (xy 450.911214 -207.160123) (xy 450.964364 -207.164106)
			(xy 451.016326 -207.175966) (xy 451.06594 -207.195438) (xy 451.112098 -207.222087) (xy 451.153769 -207.255318)
			(xy 451.190021 -207.294389) (xy 451.220045 -207.338426) (xy 451.243171 -207.386447) (xy 451.258881 -207.437377)
			(xy 451.266824 -207.490081) (xy 451.267322 -207.51673) (xy 451.266824 -207.543379) (xy 451.258881 -207.596083)
			(xy 451.243171 -207.647013) (xy 451.220045 -207.695034) (xy 451.190021 -207.739071) (xy 451.153769 -207.778142)
			(xy 451.112098 -207.811373) (xy 451.06594 -207.838022) (xy 451.016326 -207.857494) (xy 450.964364 -207.869354)
			(xy 450.911214 -207.873338) (xy 450.858064 -207.869354) (xy 450.806102 -207.857494) (xy 450.756488 -207.838022)
			(xy 450.71033 -207.811373) (xy 450.668659 -207.778142) (xy 450.632407 -207.739071) (xy 450.602383 -207.695034)
			(xy 450.579257 -207.647013) (xy 450.563547 -207.596083) (xy 450.555604 -207.543379) (xy 436.179224 -207.543379)
			(xy 436.171281 -207.596083) (xy 436.155571 -207.647013) (xy 436.132445 -207.695034) (xy 436.102421 -207.739071)
			(xy 436.066169 -207.778142) (xy 436.024498 -207.811373) (xy 435.97834 -207.838022) (xy 435.928726 -207.857494)
			(xy 435.876764 -207.869354) (xy 435.823614 -207.873338) (xy 435.770464 -207.869354) (xy 435.718502 -207.857494)
			(xy 435.668888 -207.838022) (xy 435.62273 -207.811373) (xy 435.581059 -207.778142) (xy 435.544807 -207.739071)
			(xy 435.514783 -207.695034) (xy 435.491657 -207.647013) (xy 435.475947 -207.596083) (xy 435.468004 -207.543379)
			(xy 421.091624 -207.543379) (xy 421.083681 -207.596083) (xy 421.067971 -207.647013) (xy 421.044845 -207.695034)
			(xy 421.014821 -207.739071) (xy 420.978569 -207.778142) (xy 420.936898 -207.811373) (xy 420.89074 -207.838022)
			(xy 420.841126 -207.857494) (xy 420.789164 -207.869354) (xy 420.736014 -207.873338) (xy 420.682864 -207.869354)
			(xy 420.630902 -207.857494) (xy 420.581288 -207.838022) (xy 420.53513 -207.811373) (xy 420.493459 -207.778142)
			(xy 420.457207 -207.739071) (xy 420.427183 -207.695034) (xy 420.404057 -207.647013) (xy 420.388347 -207.596083)
			(xy 420.380404 -207.543379) (xy 407.4668 -207.543379) (xy 407.4668 -208.393263) (xy 424.480472 -208.393263)
			(xy 424.480472 -208.339965) (xy 424.488415 -208.287261) (xy 424.504125 -208.236331) (xy 424.527251 -208.18831)
			(xy 424.557275 -208.144273) (xy 424.593527 -208.105202) (xy 424.635198 -208.071971) (xy 424.681356 -208.045322)
			(xy 424.73097 -208.02585) (xy 424.782932 -208.01399) (xy 424.836082 -208.010007) (xy 424.889232 -208.01399)
			(xy 424.941194 -208.02585) (xy 424.990808 -208.045322) (xy 425.036966 -208.071971) (xy 425.078637 -208.105202)
			(xy 425.114889 -208.144273) (xy 425.144913 -208.18831) (xy 425.168039 -208.236331) (xy 425.183749 -208.287261)
			(xy 425.191692 -208.339965) (xy 425.19219 -208.366614) (xy 425.191692 -208.393263) (xy 439.568072 -208.393263)
			(xy 439.568072 -208.339965) (xy 439.576015 -208.287261) (xy 439.591725 -208.236331) (xy 439.614851 -208.18831)
			(xy 439.644875 -208.144273) (xy 439.681127 -208.105202) (xy 439.722798 -208.071971) (xy 439.768956 -208.045322)
			(xy 439.81857 -208.02585) (xy 439.870532 -208.01399) (xy 439.923682 -208.010007) (xy 439.976832 -208.01399)
			(xy 440.028794 -208.02585) (xy 440.078408 -208.045322) (xy 440.124566 -208.071971) (xy 440.166237 -208.105202)
			(xy 440.202489 -208.144273) (xy 440.232513 -208.18831) (xy 440.255639 -208.236331) (xy 440.271349 -208.287261)
			(xy 440.279292 -208.339965) (xy 440.27979 -208.366614) (xy 440.279292 -208.393263) (xy 454.655672 -208.393263)
			(xy 454.655672 -208.339965) (xy 454.663615 -208.287261) (xy 454.679325 -208.236331) (xy 454.702451 -208.18831)
			(xy 454.732475 -208.144273) (xy 454.768727 -208.105202) (xy 454.810398 -208.071971) (xy 454.856556 -208.045322)
			(xy 454.90617 -208.02585) (xy 454.958132 -208.01399) (xy 455.011282 -208.010007) (xy 455.064432 -208.01399)
			(xy 455.116394 -208.02585) (xy 455.166008 -208.045322) (xy 455.212166 -208.071971) (xy 455.253837 -208.105202)
			(xy 455.290089 -208.144273) (xy 455.320113 -208.18831) (xy 455.343239 -208.236331) (xy 455.358949 -208.287261)
			(xy 455.366892 -208.339965) (xy 455.36739 -208.366614) (xy 455.366892 -208.393263) (xy 455.358949 -208.445967)
			(xy 455.343239 -208.496897) (xy 455.320113 -208.544918) (xy 455.290089 -208.588955) (xy 455.253837 -208.628026)
			(xy 455.212166 -208.661257) (xy 455.166008 -208.687906) (xy 455.116394 -208.707378) (xy 455.064432 -208.719238)
			(xy 455.011282 -208.723222) (xy 454.958132 -208.719238) (xy 454.90617 -208.707378) (xy 454.856556 -208.687906)
			(xy 454.810398 -208.661257) (xy 454.768727 -208.628026) (xy 454.732475 -208.588955) (xy 454.702451 -208.544918)
			(xy 454.679325 -208.496897) (xy 454.663615 -208.445967) (xy 454.655672 -208.393263) (xy 440.279292 -208.393263)
			(xy 440.271349 -208.445967) (xy 440.255639 -208.496897) (xy 440.232513 -208.544918) (xy 440.202489 -208.588955)
			(xy 440.166237 -208.628026) (xy 440.124566 -208.661257) (xy 440.078408 -208.687906) (xy 440.028794 -208.707378)
			(xy 439.976832 -208.719238) (xy 439.923682 -208.723222) (xy 439.870532 -208.719238) (xy 439.81857 -208.707378)
			(xy 439.768956 -208.687906) (xy 439.722798 -208.661257) (xy 439.681127 -208.628026) (xy 439.644875 -208.588955)
			(xy 439.614851 -208.544918) (xy 439.591725 -208.496897) (xy 439.576015 -208.445967) (xy 439.568072 -208.393263)
			(xy 425.191692 -208.393263) (xy 425.183749 -208.445967) (xy 425.168039 -208.496897) (xy 425.144913 -208.544918)
			(xy 425.114889 -208.588955) (xy 425.078637 -208.628026) (xy 425.036966 -208.661257) (xy 424.990808 -208.687906)
			(xy 424.941194 -208.707378) (xy 424.889232 -208.719238) (xy 424.836082 -208.723222) (xy 424.782932 -208.719238)
			(xy 424.73097 -208.707378) (xy 424.681356 -208.687906) (xy 424.635198 -208.661257) (xy 424.593527 -208.628026)
			(xy 424.557275 -208.588955) (xy 424.527251 -208.544918) (xy 424.504125 -208.496897) (xy 424.488415 -208.445967)
			(xy 424.480472 -208.393263) (xy 407.4668 -208.393263) (xy 407.4668 -209.243401) (xy 420.380404 -209.243401)
			(xy 420.380404 -209.190103) (xy 420.388347 -209.137399) (xy 420.404057 -209.086469) (xy 420.427183 -209.038448)
			(xy 420.457207 -208.994411) (xy 420.493459 -208.95534) (xy 420.53513 -208.922109) (xy 420.581288 -208.89546)
			(xy 420.630902 -208.875988) (xy 420.682864 -208.864128) (xy 420.736014 -208.860145) (xy 420.789164 -208.864128)
			(xy 420.841126 -208.875988) (xy 420.89074 -208.89546) (xy 420.936898 -208.922109) (xy 420.978569 -208.95534)
			(xy 421.014821 -208.994411) (xy 421.044845 -209.038448) (xy 421.067971 -209.086469) (xy 421.083681 -209.137399)
			(xy 421.091624 -209.190103) (xy 421.092122 -209.216752) (xy 421.091624 -209.243401) (xy 424.480472 -209.243401)
			(xy 424.480472 -209.190103) (xy 424.488415 -209.137399) (xy 424.504125 -209.086469) (xy 424.527251 -209.038448)
			(xy 424.557275 -208.994411) (xy 424.593527 -208.95534) (xy 424.635198 -208.922109) (xy 424.681356 -208.89546)
			(xy 424.73097 -208.875988) (xy 424.782932 -208.864128) (xy 424.836082 -208.860145) (xy 424.889232 -208.864128)
			(xy 424.941194 -208.875988) (xy 424.990808 -208.89546) (xy 425.036966 -208.922109) (xy 425.078637 -208.95534)
			(xy 425.114889 -208.994411) (xy 425.144913 -209.038448) (xy 425.168039 -209.086469) (xy 425.183749 -209.137399)
			(xy 425.191692 -209.190103) (xy 425.19219 -209.216752) (xy 425.191692 -209.243401) (xy 435.468004 -209.243401)
			(xy 435.468004 -209.190103) (xy 435.475947 -209.137399) (xy 435.491657 -209.086469) (xy 435.514783 -209.038448)
			(xy 435.544807 -208.994411) (xy 435.581059 -208.95534) (xy 435.62273 -208.922109) (xy 435.668888 -208.89546)
			(xy 435.718502 -208.875988) (xy 435.770464 -208.864128) (xy 435.823614 -208.860145) (xy 435.876764 -208.864128)
			(xy 435.928726 -208.875988) (xy 435.97834 -208.89546) (xy 436.024498 -208.922109) (xy 436.066169 -208.95534)
			(xy 436.102421 -208.994411) (xy 436.132445 -209.038448) (xy 436.155571 -209.086469) (xy 436.171281 -209.137399)
			(xy 436.179224 -209.190103) (xy 436.179722 -209.216752) (xy 436.179224 -209.243401) (xy 439.568072 -209.243401)
			(xy 439.568072 -209.190103) (xy 439.576015 -209.137399) (xy 439.591725 -209.086469) (xy 439.614851 -209.038448)
			(xy 439.644875 -208.994411) (xy 439.681127 -208.95534) (xy 439.722798 -208.922109) (xy 439.768956 -208.89546)
			(xy 439.81857 -208.875988) (xy 439.870532 -208.864128) (xy 439.923682 -208.860145) (xy 439.976832 -208.864128)
			(xy 440.028794 -208.875988) (xy 440.078408 -208.89546) (xy 440.124566 -208.922109) (xy 440.166237 -208.95534)
			(xy 440.202489 -208.994411) (xy 440.232513 -209.038448) (xy 440.255639 -209.086469) (xy 440.271349 -209.137399)
			(xy 440.279292 -209.190103) (xy 440.27979 -209.216752) (xy 440.279292 -209.243401) (xy 450.555604 -209.243401)
			(xy 450.555604 -209.190103) (xy 450.563547 -209.137399) (xy 450.579257 -209.086469) (xy 450.602383 -209.038448)
			(xy 450.632407 -208.994411) (xy 450.668659 -208.95534) (xy 450.71033 -208.922109) (xy 450.756488 -208.89546)
			(xy 450.806102 -208.875988) (xy 450.858064 -208.864128) (xy 450.911214 -208.860145) (xy 450.964364 -208.864128)
			(xy 451.016326 -208.875988) (xy 451.06594 -208.89546) (xy 451.112098 -208.922109) (xy 451.153769 -208.95534)
			(xy 451.190021 -208.994411) (xy 451.220045 -209.038448) (xy 451.243171 -209.086469) (xy 451.258881 -209.137399)
			(xy 451.266824 -209.190103) (xy 451.267322 -209.216752) (xy 451.266824 -209.243401) (xy 454.655672 -209.243401)
			(xy 454.655672 -209.190103) (xy 454.663615 -209.137399) (xy 454.679325 -209.086469) (xy 454.702451 -209.038448)
			(xy 454.732475 -208.994411) (xy 454.768727 -208.95534) (xy 454.810398 -208.922109) (xy 454.856556 -208.89546)
			(xy 454.90617 -208.875988) (xy 454.958132 -208.864128) (xy 455.011282 -208.860145) (xy 455.064432 -208.864128)
			(xy 455.116394 -208.875988) (xy 455.166008 -208.89546) (xy 455.212166 -208.922109) (xy 455.253837 -208.95534)
			(xy 455.290089 -208.994411) (xy 455.320113 -209.038448) (xy 455.343239 -209.086469) (xy 455.358949 -209.137399)
			(xy 455.366892 -209.190103) (xy 455.36739 -209.216752) (xy 455.366892 -209.243401) (xy 455.358949 -209.296105)
			(xy 455.343239 -209.347035) (xy 455.320113 -209.395056) (xy 455.290089 -209.439093) (xy 455.253837 -209.478164)
			(xy 455.212166 -209.511395) (xy 455.166008 -209.538044) (xy 455.116394 -209.557516) (xy 455.064432 -209.569376)
			(xy 455.011282 -209.57336) (xy 454.958132 -209.569376) (xy 454.90617 -209.557516) (xy 454.856556 -209.538044)
			(xy 454.810398 -209.511395) (xy 454.768727 -209.478164) (xy 454.732475 -209.439093) (xy 454.702451 -209.395056)
			(xy 454.679325 -209.347035) (xy 454.663615 -209.296105) (xy 454.655672 -209.243401) (xy 451.266824 -209.243401)
			(xy 451.258881 -209.296105) (xy 451.243171 -209.347035) (xy 451.220045 -209.395056) (xy 451.190021 -209.439093)
			(xy 451.153769 -209.478164) (xy 451.112098 -209.511395) (xy 451.06594 -209.538044) (xy 451.016326 -209.557516)
			(xy 450.964364 -209.569376) (xy 450.911214 -209.57336) (xy 450.858064 -209.569376) (xy 450.806102 -209.557516)
			(xy 450.756488 -209.538044) (xy 450.71033 -209.511395) (xy 450.668659 -209.478164) (xy 450.632407 -209.439093)
			(xy 450.602383 -209.395056) (xy 450.579257 -209.347035) (xy 450.563547 -209.296105) (xy 450.555604 -209.243401)
			(xy 440.279292 -209.243401) (xy 440.271349 -209.296105) (xy 440.255639 -209.347035) (xy 440.232513 -209.395056)
			(xy 440.202489 -209.439093) (xy 440.166237 -209.478164) (xy 440.124566 -209.511395) (xy 440.078408 -209.538044)
			(xy 440.028794 -209.557516) (xy 439.976832 -209.569376) (xy 439.923682 -209.57336) (xy 439.870532 -209.569376)
			(xy 439.81857 -209.557516) (xy 439.768956 -209.538044) (xy 439.722798 -209.511395) (xy 439.681127 -209.478164)
			(xy 439.644875 -209.439093) (xy 439.614851 -209.395056) (xy 439.591725 -209.347035) (xy 439.576015 -209.296105)
			(xy 439.568072 -209.243401) (xy 436.179224 -209.243401) (xy 436.171281 -209.296105) (xy 436.155571 -209.347035)
			(xy 436.132445 -209.395056) (xy 436.102421 -209.439093) (xy 436.066169 -209.478164) (xy 436.024498 -209.511395)
			(xy 435.97834 -209.538044) (xy 435.928726 -209.557516) (xy 435.876764 -209.569376) (xy 435.823614 -209.57336)
			(xy 435.770464 -209.569376) (xy 435.718502 -209.557516) (xy 435.668888 -209.538044) (xy 435.62273 -209.511395)
			(xy 435.581059 -209.478164) (xy 435.544807 -209.439093) (xy 435.514783 -209.395056) (xy 435.491657 -209.347035)
			(xy 435.475947 -209.296105) (xy 435.468004 -209.243401) (xy 425.191692 -209.243401) (xy 425.183749 -209.296105)
			(xy 425.168039 -209.347035) (xy 425.144913 -209.395056) (xy 425.114889 -209.439093) (xy 425.078637 -209.478164)
			(xy 425.036966 -209.511395) (xy 424.990808 -209.538044) (xy 424.941194 -209.557516) (xy 424.889232 -209.569376)
			(xy 424.836082 -209.57336) (xy 424.782932 -209.569376) (xy 424.73097 -209.557516) (xy 424.681356 -209.538044)
			(xy 424.635198 -209.511395) (xy 424.593527 -209.478164) (xy 424.557275 -209.439093) (xy 424.527251 -209.395056)
			(xy 424.504125 -209.347035) (xy 424.488415 -209.296105) (xy 424.480472 -209.243401) (xy 421.091624 -209.243401)
			(xy 421.083681 -209.296105) (xy 421.067971 -209.347035) (xy 421.044845 -209.395056) (xy 421.014821 -209.439093)
			(xy 420.978569 -209.478164) (xy 420.936898 -209.511395) (xy 420.89074 -209.538044) (xy 420.841126 -209.557516)
			(xy 420.789164 -209.569376) (xy 420.736014 -209.57336) (xy 420.682864 -209.569376) (xy 420.630902 -209.557516)
			(xy 420.581288 -209.538044) (xy 420.53513 -209.511395) (xy 420.493459 -209.478164) (xy 420.457207 -209.439093)
			(xy 420.427183 -209.395056) (xy 420.404057 -209.347035) (xy 420.388347 -209.296105) (xy 420.380404 -209.243401)
			(xy 407.4668 -209.243401) (xy 407.4668 -210.093285) (xy 420.380404 -210.093285) (xy 420.380404 -210.039987)
			(xy 420.388347 -209.987283) (xy 420.404057 -209.936353) (xy 420.427183 -209.888332) (xy 420.457207 -209.844295)
			(xy 420.493459 -209.805224) (xy 420.53513 -209.771993) (xy 420.581288 -209.745344) (xy 420.630902 -209.725872)
			(xy 420.682864 -209.714012) (xy 420.736014 -209.710029) (xy 420.789164 -209.714012) (xy 420.841126 -209.725872)
			(xy 420.89074 -209.745344) (xy 420.936898 -209.771993) (xy 420.978569 -209.805224) (xy 421.014821 -209.844295)
			(xy 421.044845 -209.888332) (xy 421.067971 -209.936353) (xy 421.083681 -209.987283) (xy 421.091624 -210.039987)
			(xy 421.092122 -210.066636) (xy 421.091624 -210.093285) (xy 435.468004 -210.093285) (xy 435.468004 -210.039987)
			(xy 435.475947 -209.987283) (xy 435.491657 -209.936353) (xy 435.514783 -209.888332) (xy 435.544807 -209.844295)
			(xy 435.581059 -209.805224) (xy 435.62273 -209.771993) (xy 435.668888 -209.745344) (xy 435.718502 -209.725872)
			(xy 435.770464 -209.714012) (xy 435.823614 -209.710029) (xy 435.876764 -209.714012) (xy 435.928726 -209.725872)
			(xy 435.97834 -209.745344) (xy 436.024498 -209.771993) (xy 436.066169 -209.805224) (xy 436.102421 -209.844295)
			(xy 436.132445 -209.888332) (xy 436.155571 -209.936353) (xy 436.171281 -209.987283) (xy 436.179224 -210.039987)
			(xy 436.179722 -210.066636) (xy 436.179224 -210.093285) (xy 450.555604 -210.093285) (xy 450.555604 -210.039987)
			(xy 450.563547 -209.987283) (xy 450.579257 -209.936353) (xy 450.602383 -209.888332) (xy 450.632407 -209.844295)
			(xy 450.668659 -209.805224) (xy 450.71033 -209.771993) (xy 450.756488 -209.745344) (xy 450.806102 -209.725872)
			(xy 450.858064 -209.714012) (xy 450.911214 -209.710029) (xy 450.964364 -209.714012) (xy 451.016326 -209.725872)
			(xy 451.06594 -209.745344) (xy 451.112098 -209.771993) (xy 451.153769 -209.805224) (xy 451.190021 -209.844295)
			(xy 451.220045 -209.888332) (xy 451.243171 -209.936353) (xy 451.258881 -209.987283) (xy 451.266824 -210.039987)
			(xy 451.267322 -210.066636) (xy 451.266824 -210.093285) (xy 451.258881 -210.145989) (xy 451.243171 -210.196919)
			(xy 451.220045 -210.24494) (xy 451.190021 -210.288977) (xy 451.153769 -210.328048) (xy 451.112098 -210.361279)
			(xy 451.06594 -210.387928) (xy 451.016326 -210.4074) (xy 450.964364 -210.41926) (xy 450.911214 -210.423244)
			(xy 450.858064 -210.41926) (xy 450.806102 -210.4074) (xy 450.756488 -210.387928) (xy 450.71033 -210.361279)
			(xy 450.668659 -210.328048) (xy 450.632407 -210.288977) (xy 450.602383 -210.24494) (xy 450.579257 -210.196919)
			(xy 450.563547 -210.145989) (xy 450.555604 -210.093285) (xy 436.179224 -210.093285) (xy 436.171281 -210.145989)
			(xy 436.155571 -210.196919) (xy 436.132445 -210.24494) (xy 436.102421 -210.288977) (xy 436.066169 -210.328048)
			(xy 436.024498 -210.361279) (xy 435.97834 -210.387928) (xy 435.928726 -210.4074) (xy 435.876764 -210.41926)
			(xy 435.823614 -210.423244) (xy 435.770464 -210.41926) (xy 435.718502 -210.4074) (xy 435.668888 -210.387928)
			(xy 435.62273 -210.361279) (xy 435.581059 -210.328048) (xy 435.544807 -210.288977) (xy 435.514783 -210.24494)
			(xy 435.491657 -210.196919) (xy 435.475947 -210.145989) (xy 435.468004 -210.093285) (xy 421.091624 -210.093285)
			(xy 421.083681 -210.145989) (xy 421.067971 -210.196919) (xy 421.044845 -210.24494) (xy 421.014821 -210.288977)
			(xy 420.978569 -210.328048) (xy 420.936898 -210.361279) (xy 420.89074 -210.387928) (xy 420.841126 -210.4074)
			(xy 420.789164 -210.41926) (xy 420.736014 -210.423244) (xy 420.682864 -210.41926) (xy 420.630902 -210.4074)
			(xy 420.581288 -210.387928) (xy 420.53513 -210.361279) (xy 420.493459 -210.328048) (xy 420.457207 -210.288977)
			(xy 420.427183 -210.24494) (xy 420.404057 -210.196919) (xy 420.388347 -210.145989) (xy 420.380404 -210.093285)
			(xy 407.4668 -210.093285) (xy 407.4668 -210.943423) (xy 424.480472 -210.943423) (xy 424.480472 -210.890125)
			(xy 424.488415 -210.837421) (xy 424.504125 -210.786491) (xy 424.527251 -210.73847) (xy 424.557275 -210.694433)
			(xy 424.593527 -210.655362) (xy 424.635198 -210.622131) (xy 424.681356 -210.595482) (xy 424.73097 -210.57601)
			(xy 424.782932 -210.56415) (xy 424.836082 -210.560167) (xy 424.889232 -210.56415) (xy 424.941194 -210.57601)
			(xy 424.990808 -210.595482) (xy 425.036966 -210.622131) (xy 425.078637 -210.655362) (xy 425.114889 -210.694433)
			(xy 425.144913 -210.73847) (xy 425.168039 -210.786491) (xy 425.183749 -210.837421) (xy 425.191692 -210.890125)
			(xy 425.19219 -210.916774) (xy 425.191692 -210.943423) (xy 439.568072 -210.943423) (xy 439.568072 -210.890125)
			(xy 439.576015 -210.837421) (xy 439.591725 -210.786491) (xy 439.614851 -210.73847) (xy 439.644875 -210.694433)
			(xy 439.681127 -210.655362) (xy 439.722798 -210.622131) (xy 439.768956 -210.595482) (xy 439.81857 -210.57601)
			(xy 439.870532 -210.56415) (xy 439.923682 -210.560167) (xy 439.976832 -210.56415) (xy 440.028794 -210.57601)
			(xy 440.078408 -210.595482) (xy 440.124566 -210.622131) (xy 440.166237 -210.655362) (xy 440.202489 -210.694433)
			(xy 440.232513 -210.73847) (xy 440.255639 -210.786491) (xy 440.271349 -210.837421) (xy 440.279292 -210.890125)
			(xy 440.27979 -210.916774) (xy 440.279292 -210.943423) (xy 454.655672 -210.943423) (xy 454.655672 -210.890125)
			(xy 454.663615 -210.837421) (xy 454.679325 -210.786491) (xy 454.702451 -210.73847) (xy 454.732475 -210.694433)
			(xy 454.768727 -210.655362) (xy 454.810398 -210.622131) (xy 454.856556 -210.595482) (xy 454.90617 -210.57601)
			(xy 454.958132 -210.56415) (xy 455.011282 -210.560167) (xy 455.064432 -210.56415) (xy 455.116394 -210.57601)
			(xy 455.166008 -210.595482) (xy 455.212166 -210.622131) (xy 455.253837 -210.655362) (xy 455.290089 -210.694433)
			(xy 455.320113 -210.73847) (xy 455.343239 -210.786491) (xy 455.358949 -210.837421) (xy 455.366892 -210.890125)
			(xy 455.36739 -210.916774) (xy 455.366892 -210.943423) (xy 455.358949 -210.996127) (xy 455.343239 -211.047057)
			(xy 455.320113 -211.095078) (xy 455.290089 -211.139115) (xy 455.253837 -211.178186) (xy 455.212166 -211.211417)
			(xy 455.166008 -211.238066) (xy 455.116394 -211.257538) (xy 455.064432 -211.269398) (xy 455.011282 -211.273382)
			(xy 454.958132 -211.269398) (xy 454.90617 -211.257538) (xy 454.856556 -211.238066) (xy 454.810398 -211.211417)
			(xy 454.768727 -211.178186) (xy 454.732475 -211.139115) (xy 454.702451 -211.095078) (xy 454.679325 -211.047057)
			(xy 454.663615 -210.996127) (xy 454.655672 -210.943423) (xy 440.279292 -210.943423) (xy 440.271349 -210.996127)
			(xy 440.255639 -211.047057) (xy 440.232513 -211.095078) (xy 440.202489 -211.139115) (xy 440.166237 -211.178186)
			(xy 440.124566 -211.211417) (xy 440.078408 -211.238066) (xy 440.028794 -211.257538) (xy 439.976832 -211.269398)
			(xy 439.923682 -211.273382) (xy 439.870532 -211.269398) (xy 439.81857 -211.257538) (xy 439.768956 -211.238066)
			(xy 439.722798 -211.211417) (xy 439.681127 -211.178186) (xy 439.644875 -211.139115) (xy 439.614851 -211.095078)
			(xy 439.591725 -211.047057) (xy 439.576015 -210.996127) (xy 439.568072 -210.943423) (xy 425.191692 -210.943423)
			(xy 425.183749 -210.996127) (xy 425.168039 -211.047057) (xy 425.144913 -211.095078) (xy 425.114889 -211.139115)
			(xy 425.078637 -211.178186) (xy 425.036966 -211.211417) (xy 424.990808 -211.238066) (xy 424.941194 -211.257538)
			(xy 424.889232 -211.269398) (xy 424.836082 -211.273382) (xy 424.782932 -211.269398) (xy 424.73097 -211.257538)
			(xy 424.681356 -211.238066) (xy 424.635198 -211.211417) (xy 424.593527 -211.178186) (xy 424.557275 -211.139115)
			(xy 424.527251 -211.095078) (xy 424.504125 -211.047057) (xy 424.488415 -210.996127) (xy 424.480472 -210.943423)
			(xy 407.4668 -210.943423) (xy 407.4668 -211.793307) (xy 420.380404 -211.793307) (xy 420.380404 -211.740009)
			(xy 420.388347 -211.687305) (xy 420.404057 -211.636375) (xy 420.427183 -211.588354) (xy 420.457207 -211.544317)
			(xy 420.493459 -211.505246) (xy 420.53513 -211.472015) (xy 420.581288 -211.445366) (xy 420.630902 -211.425894)
			(xy 420.682864 -211.414034) (xy 420.736014 -211.410051) (xy 420.789164 -211.414034) (xy 420.841126 -211.425894)
			(xy 420.89074 -211.445366) (xy 420.936898 -211.472015) (xy 420.978569 -211.505246) (xy 421.014821 -211.544317)
			(xy 421.044845 -211.588354) (xy 421.067971 -211.636375) (xy 421.083681 -211.687305) (xy 421.091624 -211.740009)
			(xy 421.092122 -211.766658) (xy 421.091624 -211.793307) (xy 435.468004 -211.793307) (xy 435.468004 -211.740009)
			(xy 435.475947 -211.687305) (xy 435.491657 -211.636375) (xy 435.514783 -211.588354) (xy 435.544807 -211.544317)
			(xy 435.581059 -211.505246) (xy 435.62273 -211.472015) (xy 435.668888 -211.445366) (xy 435.718502 -211.425894)
			(xy 435.770464 -211.414034) (xy 435.823614 -211.410051) (xy 435.876764 -211.414034) (xy 435.928726 -211.425894)
			(xy 435.97834 -211.445366) (xy 436.024498 -211.472015) (xy 436.066169 -211.505246) (xy 436.102421 -211.544317)
			(xy 436.132445 -211.588354) (xy 436.155571 -211.636375) (xy 436.171281 -211.687305) (xy 436.179224 -211.740009)
			(xy 436.179722 -211.766658) (xy 436.179224 -211.793307) (xy 450.555604 -211.793307) (xy 450.555604 -211.740009)
			(xy 450.563547 -211.687305) (xy 450.579257 -211.636375) (xy 450.602383 -211.588354) (xy 450.632407 -211.544317)
			(xy 450.668659 -211.505246) (xy 450.71033 -211.472015) (xy 450.756488 -211.445366) (xy 450.806102 -211.425894)
			(xy 450.858064 -211.414034) (xy 450.911214 -211.410051) (xy 450.964364 -211.414034) (xy 451.016326 -211.425894)
			(xy 451.06594 -211.445366) (xy 451.112098 -211.472015) (xy 451.153769 -211.505246) (xy 451.190021 -211.544317)
			(xy 451.220045 -211.588354) (xy 451.243171 -211.636375) (xy 451.258881 -211.687305) (xy 451.266824 -211.740009)
			(xy 451.267322 -211.766658) (xy 451.266824 -211.793307) (xy 451.258881 -211.846011) (xy 451.243171 -211.896941)
			(xy 451.220045 -211.944962) (xy 451.190021 -211.988999) (xy 451.153769 -212.02807) (xy 451.112098 -212.061301)
			(xy 451.06594 -212.08795) (xy 451.016326 -212.107422) (xy 450.964364 -212.119282) (xy 450.911214 -212.123266)
			(xy 450.858064 -212.119282) (xy 450.806102 -212.107422) (xy 450.756488 -212.08795) (xy 450.71033 -212.061301)
			(xy 450.668659 -212.02807) (xy 450.632407 -211.988999) (xy 450.602383 -211.944962) (xy 450.579257 -211.896941)
			(xy 450.563547 -211.846011) (xy 450.555604 -211.793307) (xy 436.179224 -211.793307) (xy 436.171281 -211.846011)
			(xy 436.155571 -211.896941) (xy 436.132445 -211.944962) (xy 436.102421 -211.988999) (xy 436.066169 -212.02807)
			(xy 436.024498 -212.061301) (xy 435.97834 -212.08795) (xy 435.928726 -212.107422) (xy 435.876764 -212.119282)
			(xy 435.823614 -212.123266) (xy 435.770464 -212.119282) (xy 435.718502 -212.107422) (xy 435.668888 -212.08795)
			(xy 435.62273 -212.061301) (xy 435.581059 -212.02807) (xy 435.544807 -211.988999) (xy 435.514783 -211.944962)
			(xy 435.491657 -211.896941) (xy 435.475947 -211.846011) (xy 435.468004 -211.793307) (xy 421.091624 -211.793307)
			(xy 421.083681 -211.846011) (xy 421.067971 -211.896941) (xy 421.044845 -211.944962) (xy 421.014821 -211.988999)
			(xy 420.978569 -212.02807) (xy 420.936898 -212.061301) (xy 420.89074 -212.08795) (xy 420.841126 -212.107422)
			(xy 420.789164 -212.119282) (xy 420.736014 -212.123266) (xy 420.682864 -212.119282) (xy 420.630902 -212.107422)
			(xy 420.581288 -212.08795) (xy 420.53513 -212.061301) (xy 420.493459 -212.02807) (xy 420.457207 -211.988999)
			(xy 420.427183 -211.944962) (xy 420.404057 -211.896941) (xy 420.388347 -211.846011) (xy 420.380404 -211.793307)
			(xy 407.4668 -211.793307) (xy 407.4668 -212.643445) (xy 424.480472 -212.643445) (xy 424.480472 -212.590147)
			(xy 424.488415 -212.537443) (xy 424.504125 -212.486513) (xy 424.527251 -212.438492) (xy 424.557275 -212.394455)
			(xy 424.593527 -212.355384) (xy 424.635198 -212.322153) (xy 424.681356 -212.295504) (xy 424.73097 -212.276032)
			(xy 424.782932 -212.264172) (xy 424.836082 -212.260189) (xy 424.889232 -212.264172) (xy 424.941194 -212.276032)
			(xy 424.990808 -212.295504) (xy 425.036966 -212.322153) (xy 425.078637 -212.355384) (xy 425.114889 -212.394455)
			(xy 425.144913 -212.438492) (xy 425.168039 -212.486513) (xy 425.183749 -212.537443) (xy 425.191692 -212.590147)
			(xy 425.19219 -212.616796) (xy 425.191692 -212.643445) (xy 439.568072 -212.643445) (xy 439.568072 -212.590147)
			(xy 439.576015 -212.537443) (xy 439.591725 -212.486513) (xy 439.614851 -212.438492) (xy 439.644875 -212.394455)
			(xy 439.681127 -212.355384) (xy 439.722798 -212.322153) (xy 439.768956 -212.295504) (xy 439.81857 -212.276032)
			(xy 439.870532 -212.264172) (xy 439.923682 -212.260189) (xy 439.976832 -212.264172) (xy 440.028794 -212.276032)
			(xy 440.078408 -212.295504) (xy 440.124566 -212.322153) (xy 440.166237 -212.355384) (xy 440.202489 -212.394455)
			(xy 440.232513 -212.438492) (xy 440.255639 -212.486513) (xy 440.271349 -212.537443) (xy 440.279292 -212.590147)
			(xy 440.27979 -212.616796) (xy 440.279292 -212.643445) (xy 454.655672 -212.643445) (xy 454.655672 -212.590147)
			(xy 454.663615 -212.537443) (xy 454.679325 -212.486513) (xy 454.702451 -212.438492) (xy 454.732475 -212.394455)
			(xy 454.768727 -212.355384) (xy 454.810398 -212.322153) (xy 454.856556 -212.295504) (xy 454.90617 -212.276032)
			(xy 454.958132 -212.264172) (xy 455.011282 -212.260189) (xy 455.064432 -212.264172) (xy 455.116394 -212.276032)
			(xy 455.166008 -212.295504) (xy 455.212166 -212.322153) (xy 455.253837 -212.355384) (xy 455.290089 -212.394455)
			(xy 455.320113 -212.438492) (xy 455.343239 -212.486513) (xy 455.358949 -212.537443) (xy 455.366892 -212.590147)
			(xy 455.36739 -212.616796) (xy 455.366892 -212.643445) (xy 455.358949 -212.696149) (xy 455.343239 -212.747079)
			(xy 455.320113 -212.7951) (xy 455.290089 -212.839137) (xy 455.253837 -212.878208) (xy 455.212166 -212.911439)
			(xy 455.166008 -212.938088) (xy 455.116394 -212.95756) (xy 455.064432 -212.96942) (xy 455.011282 -212.973404)
			(xy 454.958132 -212.96942) (xy 454.90617 -212.95756) (xy 454.856556 -212.938088) (xy 454.810398 -212.911439)
			(xy 454.768727 -212.878208) (xy 454.732475 -212.839137) (xy 454.702451 -212.7951) (xy 454.679325 -212.747079)
			(xy 454.663615 -212.696149) (xy 454.655672 -212.643445) (xy 440.279292 -212.643445) (xy 440.271349 -212.696149)
			(xy 440.255639 -212.747079) (xy 440.232513 -212.7951) (xy 440.202489 -212.839137) (xy 440.166237 -212.878208)
			(xy 440.124566 -212.911439) (xy 440.078408 -212.938088) (xy 440.028794 -212.95756) (xy 439.976832 -212.96942)
			(xy 439.923682 -212.973404) (xy 439.870532 -212.96942) (xy 439.81857 -212.95756) (xy 439.768956 -212.938088)
			(xy 439.722798 -212.911439) (xy 439.681127 -212.878208) (xy 439.644875 -212.839137) (xy 439.614851 -212.7951)
			(xy 439.591725 -212.747079) (xy 439.576015 -212.696149) (xy 439.568072 -212.643445) (xy 425.191692 -212.643445)
			(xy 425.183749 -212.696149) (xy 425.168039 -212.747079) (xy 425.144913 -212.7951) (xy 425.114889 -212.839137)
			(xy 425.078637 -212.878208) (xy 425.036966 -212.911439) (xy 424.990808 -212.938088) (xy 424.941194 -212.95756)
			(xy 424.889232 -212.96942) (xy 424.836082 -212.973404) (xy 424.782932 -212.96942) (xy 424.73097 -212.95756)
			(xy 424.681356 -212.938088) (xy 424.635198 -212.911439) (xy 424.593527 -212.878208) (xy 424.557275 -212.839137)
			(xy 424.527251 -212.7951) (xy 424.504125 -212.747079) (xy 424.488415 -212.696149) (xy 424.480472 -212.643445)
			(xy 407.4668 -212.643445) (xy 407.4668 -213.493329) (xy 420.380404 -213.493329) (xy 420.380404 -213.440031)
			(xy 420.388347 -213.387327) (xy 420.404057 -213.336397) (xy 420.427183 -213.288376) (xy 420.457207 -213.244339)
			(xy 420.493459 -213.205268) (xy 420.53513 -213.172037) (xy 420.581288 -213.145388) (xy 420.630902 -213.125916)
			(xy 420.682864 -213.114056) (xy 420.736014 -213.110073) (xy 420.789164 -213.114056) (xy 420.841126 -213.125916)
			(xy 420.89074 -213.145388) (xy 420.936898 -213.172037) (xy 420.978569 -213.205268) (xy 421.014821 -213.244339)
			(xy 421.044845 -213.288376) (xy 421.067971 -213.336397) (xy 421.083681 -213.387327) (xy 421.091624 -213.440031)
			(xy 421.092122 -213.46668) (xy 421.091624 -213.493329) (xy 435.468004 -213.493329) (xy 435.468004 -213.440031)
			(xy 435.475947 -213.387327) (xy 435.491657 -213.336397) (xy 435.514783 -213.288376) (xy 435.544807 -213.244339)
			(xy 435.581059 -213.205268) (xy 435.62273 -213.172037) (xy 435.668888 -213.145388) (xy 435.718502 -213.125916)
			(xy 435.770464 -213.114056) (xy 435.823614 -213.110073) (xy 435.876764 -213.114056) (xy 435.928726 -213.125916)
			(xy 435.97834 -213.145388) (xy 436.024498 -213.172037) (xy 436.066169 -213.205268) (xy 436.102421 -213.244339)
			(xy 436.132445 -213.288376) (xy 436.155571 -213.336397) (xy 436.171281 -213.387327) (xy 436.179224 -213.440031)
			(xy 436.179722 -213.46668) (xy 436.179224 -213.493329) (xy 450.555604 -213.493329) (xy 450.555604 -213.440031)
			(xy 450.563547 -213.387327) (xy 450.579257 -213.336397) (xy 450.602383 -213.288376) (xy 450.632407 -213.244339)
			(xy 450.668659 -213.205268) (xy 450.71033 -213.172037) (xy 450.756488 -213.145388) (xy 450.806102 -213.125916)
			(xy 450.858064 -213.114056) (xy 450.911214 -213.110073) (xy 450.964364 -213.114056) (xy 451.016326 -213.125916)
			(xy 451.06594 -213.145388) (xy 451.112098 -213.172037) (xy 451.153769 -213.205268) (xy 451.190021 -213.244339)
			(xy 451.220045 -213.288376) (xy 451.243171 -213.336397) (xy 451.258881 -213.387327) (xy 451.266824 -213.440031)
			(xy 451.267322 -213.46668) (xy 451.266824 -213.493329) (xy 451.258881 -213.546033) (xy 451.243171 -213.596963)
			(xy 451.220045 -213.644984) (xy 451.190021 -213.689021) (xy 451.153769 -213.728092) (xy 451.112098 -213.761323)
			(xy 451.06594 -213.787972) (xy 451.016326 -213.807444) (xy 450.964364 -213.819304) (xy 450.911214 -213.823288)
			(xy 450.858064 -213.819304) (xy 450.806102 -213.807444) (xy 450.756488 -213.787972) (xy 450.71033 -213.761323)
			(xy 450.668659 -213.728092) (xy 450.632407 -213.689021) (xy 450.602383 -213.644984) (xy 450.579257 -213.596963)
			(xy 450.563547 -213.546033) (xy 450.555604 -213.493329) (xy 436.179224 -213.493329) (xy 436.171281 -213.546033)
			(xy 436.155571 -213.596963) (xy 436.132445 -213.644984) (xy 436.102421 -213.689021) (xy 436.066169 -213.728092)
			(xy 436.024498 -213.761323) (xy 435.97834 -213.787972) (xy 435.928726 -213.807444) (xy 435.876764 -213.819304)
			(xy 435.823614 -213.823288) (xy 435.770464 -213.819304) (xy 435.718502 -213.807444) (xy 435.668888 -213.787972)
			(xy 435.62273 -213.761323) (xy 435.581059 -213.728092) (xy 435.544807 -213.689021) (xy 435.514783 -213.644984)
			(xy 435.491657 -213.596963) (xy 435.475947 -213.546033) (xy 435.468004 -213.493329) (xy 421.091624 -213.493329)
			(xy 421.083681 -213.546033) (xy 421.067971 -213.596963) (xy 421.044845 -213.644984) (xy 421.014821 -213.689021)
			(xy 420.978569 -213.728092) (xy 420.936898 -213.761323) (xy 420.89074 -213.787972) (xy 420.841126 -213.807444)
			(xy 420.789164 -213.819304) (xy 420.736014 -213.823288) (xy 420.682864 -213.819304) (xy 420.630902 -213.807444)
			(xy 420.581288 -213.787972) (xy 420.53513 -213.761323) (xy 420.493459 -213.728092) (xy 420.457207 -213.689021)
			(xy 420.427183 -213.644984) (xy 420.404057 -213.596963) (xy 420.388347 -213.546033) (xy 420.380404 -213.493329)
			(xy 407.4668 -213.493329) (xy 407.4668 -214.343213) (xy 424.480472 -214.343213) (xy 424.480472 -214.289915)
			(xy 424.488415 -214.237211) (xy 424.504125 -214.186281) (xy 424.527251 -214.13826) (xy 424.557275 -214.094223)
			(xy 424.593527 -214.055152) (xy 424.635198 -214.021921) (xy 424.681356 -213.995272) (xy 424.73097 -213.9758)
			(xy 424.782932 -213.96394) (xy 424.836082 -213.959957) (xy 424.889232 -213.96394) (xy 424.941194 -213.9758)
			(xy 424.990808 -213.995272) (xy 425.036966 -214.021921) (xy 425.078637 -214.055152) (xy 425.114889 -214.094223)
			(xy 425.144913 -214.13826) (xy 425.168039 -214.186281) (xy 425.183749 -214.237211) (xy 425.191692 -214.289915)
			(xy 425.19219 -214.316564) (xy 425.191692 -214.343213) (xy 439.568072 -214.343213) (xy 439.568072 -214.289915)
			(xy 439.576015 -214.237211) (xy 439.591725 -214.186281) (xy 439.614851 -214.13826) (xy 439.644875 -214.094223)
			(xy 439.681127 -214.055152) (xy 439.722798 -214.021921) (xy 439.768956 -213.995272) (xy 439.81857 -213.9758)
			(xy 439.870532 -213.96394) (xy 439.923682 -213.959957) (xy 439.976832 -213.96394) (xy 440.028794 -213.9758)
			(xy 440.078408 -213.995272) (xy 440.124566 -214.021921) (xy 440.166237 -214.055152) (xy 440.202489 -214.094223)
			(xy 440.232513 -214.13826) (xy 440.255639 -214.186281) (xy 440.271349 -214.237211) (xy 440.279292 -214.289915)
			(xy 440.27979 -214.316564) (xy 440.279292 -214.343213) (xy 454.655672 -214.343213) (xy 454.655672 -214.289915)
			(xy 454.663615 -214.237211) (xy 454.679325 -214.186281) (xy 454.702451 -214.13826) (xy 454.732475 -214.094223)
			(xy 454.768727 -214.055152) (xy 454.810398 -214.021921) (xy 454.856556 -213.995272) (xy 454.90617 -213.9758)
			(xy 454.958132 -213.96394) (xy 455.011282 -213.959957) (xy 455.064432 -213.96394) (xy 455.116394 -213.9758)
			(xy 455.166008 -213.995272) (xy 455.212166 -214.021921) (xy 455.253837 -214.055152) (xy 455.290089 -214.094223)
			(xy 455.320113 -214.13826) (xy 455.343239 -214.186281) (xy 455.358949 -214.237211) (xy 455.366892 -214.289915)
			(xy 455.36739 -214.316564) (xy 455.366892 -214.343213) (xy 455.358949 -214.395917) (xy 455.343239 -214.446847)
			(xy 455.320113 -214.494868) (xy 455.290089 -214.538905) (xy 455.253837 -214.577976) (xy 455.212166 -214.611207)
			(xy 455.166008 -214.637856) (xy 455.116394 -214.657328) (xy 455.064432 -214.669188) (xy 455.011282 -214.673172)
			(xy 454.958132 -214.669188) (xy 454.90617 -214.657328) (xy 454.856556 -214.637856) (xy 454.810398 -214.611207)
			(xy 454.768727 -214.577976) (xy 454.732475 -214.538905) (xy 454.702451 -214.494868) (xy 454.679325 -214.446847)
			(xy 454.663615 -214.395917) (xy 454.655672 -214.343213) (xy 440.279292 -214.343213) (xy 440.271349 -214.395917)
			(xy 440.255639 -214.446847) (xy 440.232513 -214.494868) (xy 440.202489 -214.538905) (xy 440.166237 -214.577976)
			(xy 440.124566 -214.611207) (xy 440.078408 -214.637856) (xy 440.028794 -214.657328) (xy 439.976832 -214.669188)
			(xy 439.923682 -214.673172) (xy 439.870532 -214.669188) (xy 439.81857 -214.657328) (xy 439.768956 -214.637856)
			(xy 439.722798 -214.611207) (xy 439.681127 -214.577976) (xy 439.644875 -214.538905) (xy 439.614851 -214.494868)
			(xy 439.591725 -214.446847) (xy 439.576015 -214.395917) (xy 439.568072 -214.343213) (xy 425.191692 -214.343213)
			(xy 425.183749 -214.395917) (xy 425.168039 -214.446847) (xy 425.144913 -214.494868) (xy 425.114889 -214.538905)
			(xy 425.078637 -214.577976) (xy 425.036966 -214.611207) (xy 424.990808 -214.637856) (xy 424.941194 -214.657328)
			(xy 424.889232 -214.669188) (xy 424.836082 -214.673172) (xy 424.782932 -214.669188) (xy 424.73097 -214.657328)
			(xy 424.681356 -214.637856) (xy 424.635198 -214.611207) (xy 424.593527 -214.577976) (xy 424.557275 -214.538905)
			(xy 424.527251 -214.494868) (xy 424.504125 -214.446847) (xy 424.488415 -214.395917) (xy 424.480472 -214.343213)
			(xy 407.4668 -214.343213) (xy 407.4668 -215.193351) (xy 420.380404 -215.193351) (xy 420.380404 -215.140053)
			(xy 420.388347 -215.087349) (xy 420.404057 -215.036419) (xy 420.427183 -214.988398) (xy 420.457207 -214.944361)
			(xy 420.493459 -214.90529) (xy 420.53513 -214.872059) (xy 420.581288 -214.84541) (xy 420.630902 -214.825938)
			(xy 420.682864 -214.814078) (xy 420.736014 -214.810095) (xy 420.789164 -214.814078) (xy 420.841126 -214.825938)
			(xy 420.89074 -214.84541) (xy 420.936898 -214.872059) (xy 420.978569 -214.90529) (xy 421.014821 -214.944361)
			(xy 421.044845 -214.988398) (xy 421.067971 -215.036419) (xy 421.083681 -215.087349) (xy 421.091624 -215.140053)
			(xy 421.092122 -215.166702) (xy 421.091624 -215.193351) (xy 435.468004 -215.193351) (xy 435.468004 -215.140053)
			(xy 435.475947 -215.087349) (xy 435.491657 -215.036419) (xy 435.514783 -214.988398) (xy 435.544807 -214.944361)
			(xy 435.581059 -214.90529) (xy 435.62273 -214.872059) (xy 435.668888 -214.84541) (xy 435.718502 -214.825938)
			(xy 435.770464 -214.814078) (xy 435.823614 -214.810095) (xy 435.876764 -214.814078) (xy 435.928726 -214.825938)
			(xy 435.97834 -214.84541) (xy 436.024498 -214.872059) (xy 436.066169 -214.90529) (xy 436.102421 -214.944361)
			(xy 436.132445 -214.988398) (xy 436.155571 -215.036419) (xy 436.171281 -215.087349) (xy 436.179224 -215.140053)
			(xy 436.179722 -215.166702) (xy 436.179224 -215.193351) (xy 450.555604 -215.193351) (xy 450.555604 -215.140053)
			(xy 450.563547 -215.087349) (xy 450.579257 -215.036419) (xy 450.602383 -214.988398) (xy 450.632407 -214.944361)
			(xy 450.668659 -214.90529) (xy 450.71033 -214.872059) (xy 450.756488 -214.84541) (xy 450.806102 -214.825938)
			(xy 450.858064 -214.814078) (xy 450.911214 -214.810095) (xy 450.964364 -214.814078) (xy 451.016326 -214.825938)
			(xy 451.06594 -214.84541) (xy 451.112098 -214.872059) (xy 451.153769 -214.90529) (xy 451.190021 -214.944361)
			(xy 451.220045 -214.988398) (xy 451.243171 -215.036419) (xy 451.258881 -215.087349) (xy 451.266824 -215.140053)
			(xy 451.267322 -215.166702) (xy 451.266824 -215.193351) (xy 451.258881 -215.246055) (xy 451.243171 -215.296985)
			(xy 451.220045 -215.345006) (xy 451.190021 -215.389043) (xy 451.153769 -215.428114) (xy 451.112098 -215.461345)
			(xy 451.06594 -215.487994) (xy 451.016326 -215.507466) (xy 450.964364 -215.519326) (xy 450.911214 -215.52331)
			(xy 450.858064 -215.519326) (xy 450.806102 -215.507466) (xy 450.756488 -215.487994) (xy 450.71033 -215.461345)
			(xy 450.668659 -215.428114) (xy 450.632407 -215.389043) (xy 450.602383 -215.345006) (xy 450.579257 -215.296985)
			(xy 450.563547 -215.246055) (xy 450.555604 -215.193351) (xy 436.179224 -215.193351) (xy 436.171281 -215.246055)
			(xy 436.155571 -215.296985) (xy 436.132445 -215.345006) (xy 436.102421 -215.389043) (xy 436.066169 -215.428114)
			(xy 436.024498 -215.461345) (xy 435.97834 -215.487994) (xy 435.928726 -215.507466) (xy 435.876764 -215.519326)
			(xy 435.823614 -215.52331) (xy 435.770464 -215.519326) (xy 435.718502 -215.507466) (xy 435.668888 -215.487994)
			(xy 435.62273 -215.461345) (xy 435.581059 -215.428114) (xy 435.544807 -215.389043) (xy 435.514783 -215.345006)
			(xy 435.491657 -215.296985) (xy 435.475947 -215.246055) (xy 435.468004 -215.193351) (xy 421.091624 -215.193351)
			(xy 421.083681 -215.246055) (xy 421.067971 -215.296985) (xy 421.044845 -215.345006) (xy 421.014821 -215.389043)
			(xy 420.978569 -215.428114) (xy 420.936898 -215.461345) (xy 420.89074 -215.487994) (xy 420.841126 -215.507466)
			(xy 420.789164 -215.519326) (xy 420.736014 -215.52331) (xy 420.682864 -215.519326) (xy 420.630902 -215.507466)
			(xy 420.581288 -215.487994) (xy 420.53513 -215.461345) (xy 420.493459 -215.428114) (xy 420.457207 -215.389043)
			(xy 420.427183 -215.345006) (xy 420.404057 -215.296985) (xy 420.388347 -215.246055) (xy 420.380404 -215.193351)
			(xy 407.4668 -215.193351) (xy 407.4668 -216.043235) (xy 424.480472 -216.043235) (xy 424.480472 -215.989937)
			(xy 424.488415 -215.937233) (xy 424.504125 -215.886303) (xy 424.527251 -215.838282) (xy 424.557275 -215.794245)
			(xy 424.593527 -215.755174) (xy 424.635198 -215.721943) (xy 424.681356 -215.695294) (xy 424.73097 -215.675822)
			(xy 424.782932 -215.663962) (xy 424.836082 -215.659979) (xy 424.889232 -215.663962) (xy 424.941194 -215.675822)
			(xy 424.990808 -215.695294) (xy 425.036966 -215.721943) (xy 425.078637 -215.755174) (xy 425.114889 -215.794245)
			(xy 425.144913 -215.838282) (xy 425.168039 -215.886303) (xy 425.183749 -215.937233) (xy 425.191692 -215.989937)
			(xy 425.19219 -216.016586) (xy 425.191692 -216.043235) (xy 439.568072 -216.043235) (xy 439.568072 -215.989937)
			(xy 439.576015 -215.937233) (xy 439.591725 -215.886303) (xy 439.614851 -215.838282) (xy 439.644875 -215.794245)
			(xy 439.681127 -215.755174) (xy 439.722798 -215.721943) (xy 439.768956 -215.695294) (xy 439.81857 -215.675822)
			(xy 439.870532 -215.663962) (xy 439.923682 -215.659979) (xy 439.976832 -215.663962) (xy 440.028794 -215.675822)
			(xy 440.078408 -215.695294) (xy 440.124566 -215.721943) (xy 440.166237 -215.755174) (xy 440.202489 -215.794245)
			(xy 440.232513 -215.838282) (xy 440.255639 -215.886303) (xy 440.271349 -215.937233) (xy 440.279292 -215.989937)
			(xy 440.27979 -216.016586) (xy 440.279292 -216.043235) (xy 454.655672 -216.043235) (xy 454.655672 -215.989937)
			(xy 454.663615 -215.937233) (xy 454.679325 -215.886303) (xy 454.702451 -215.838282) (xy 454.732475 -215.794245)
			(xy 454.768727 -215.755174) (xy 454.810398 -215.721943) (xy 454.856556 -215.695294) (xy 454.90617 -215.675822)
			(xy 454.958132 -215.663962) (xy 455.011282 -215.659979) (xy 455.064432 -215.663962) (xy 455.116394 -215.675822)
			(xy 455.166008 -215.695294) (xy 455.212166 -215.721943) (xy 455.253837 -215.755174) (xy 455.290089 -215.794245)
			(xy 455.320113 -215.838282) (xy 455.343239 -215.886303) (xy 455.358949 -215.937233) (xy 455.366892 -215.989937)
			(xy 455.36739 -216.016586) (xy 455.366892 -216.043235) (xy 455.358949 -216.095939) (xy 455.343239 -216.146869)
			(xy 455.320113 -216.19489) (xy 455.290089 -216.238927) (xy 455.253837 -216.277998) (xy 455.212166 -216.311229)
			(xy 455.166008 -216.337878) (xy 455.116394 -216.35735) (xy 455.064432 -216.36921) (xy 455.011282 -216.373194)
			(xy 454.958132 -216.36921) (xy 454.90617 -216.35735) (xy 454.856556 -216.337878) (xy 454.810398 -216.311229)
			(xy 454.768727 -216.277998) (xy 454.732475 -216.238927) (xy 454.702451 -216.19489) (xy 454.679325 -216.146869)
			(xy 454.663615 -216.095939) (xy 454.655672 -216.043235) (xy 440.279292 -216.043235) (xy 440.271349 -216.095939)
			(xy 440.255639 -216.146869) (xy 440.232513 -216.19489) (xy 440.202489 -216.238927) (xy 440.166237 -216.277998)
			(xy 440.124566 -216.311229) (xy 440.078408 -216.337878) (xy 440.028794 -216.35735) (xy 439.976832 -216.36921)
			(xy 439.923682 -216.373194) (xy 439.870532 -216.36921) (xy 439.81857 -216.35735) (xy 439.768956 -216.337878)
			(xy 439.722798 -216.311229) (xy 439.681127 -216.277998) (xy 439.644875 -216.238927) (xy 439.614851 -216.19489)
			(xy 439.591725 -216.146869) (xy 439.576015 -216.095939) (xy 439.568072 -216.043235) (xy 425.191692 -216.043235)
			(xy 425.183749 -216.095939) (xy 425.168039 -216.146869) (xy 425.144913 -216.19489) (xy 425.114889 -216.238927)
			(xy 425.078637 -216.277998) (xy 425.036966 -216.311229) (xy 424.990808 -216.337878) (xy 424.941194 -216.35735)
			(xy 424.889232 -216.36921) (xy 424.836082 -216.373194) (xy 424.782932 -216.36921) (xy 424.73097 -216.35735)
			(xy 424.681356 -216.337878) (xy 424.635198 -216.311229) (xy 424.593527 -216.277998) (xy 424.557275 -216.238927)
			(xy 424.527251 -216.19489) (xy 424.504125 -216.146869) (xy 424.488415 -216.095939) (xy 424.480472 -216.043235)
			(xy 407.4668 -216.043235) (xy 407.4668 -216.893373) (xy 420.380404 -216.893373) (xy 420.380404 -216.840075)
			(xy 420.388347 -216.787371) (xy 420.404057 -216.736441) (xy 420.427183 -216.68842) (xy 420.457207 -216.644383)
			(xy 420.493459 -216.605312) (xy 420.53513 -216.572081) (xy 420.581288 -216.545432) (xy 420.630902 -216.52596)
			(xy 420.682864 -216.5141) (xy 420.736014 -216.510117) (xy 420.789164 -216.5141) (xy 420.841126 -216.52596)
			(xy 420.89074 -216.545432) (xy 420.936898 -216.572081) (xy 420.978569 -216.605312) (xy 421.014821 -216.644383)
			(xy 421.044845 -216.68842) (xy 421.067971 -216.736441) (xy 421.083681 -216.787371) (xy 421.091624 -216.840075)
			(xy 421.092122 -216.866724) (xy 421.091624 -216.893373) (xy 435.468004 -216.893373) (xy 435.468004 -216.840075)
			(xy 435.475947 -216.787371) (xy 435.491657 -216.736441) (xy 435.514783 -216.68842) (xy 435.544807 -216.644383)
			(xy 435.581059 -216.605312) (xy 435.62273 -216.572081) (xy 435.668888 -216.545432) (xy 435.718502 -216.52596)
			(xy 435.770464 -216.5141) (xy 435.823614 -216.510117) (xy 435.876764 -216.5141) (xy 435.928726 -216.52596)
			(xy 435.97834 -216.545432) (xy 436.024498 -216.572081) (xy 436.066169 -216.605312) (xy 436.102421 -216.644383)
			(xy 436.132445 -216.68842) (xy 436.155571 -216.736441) (xy 436.171281 -216.787371) (xy 436.179224 -216.840075)
			(xy 436.179722 -216.866724) (xy 436.179224 -216.893373) (xy 450.555604 -216.893373) (xy 450.555604 -216.840075)
			(xy 450.563547 -216.787371) (xy 450.579257 -216.736441) (xy 450.602383 -216.68842) (xy 450.632407 -216.644383)
			(xy 450.668659 -216.605312) (xy 450.71033 -216.572081) (xy 450.756488 -216.545432) (xy 450.806102 -216.52596)
			(xy 450.858064 -216.5141) (xy 450.911214 -216.510117) (xy 450.964364 -216.5141) (xy 451.016326 -216.52596)
			(xy 451.06594 -216.545432) (xy 451.112098 -216.572081) (xy 451.153769 -216.605312) (xy 451.190021 -216.644383)
			(xy 451.220045 -216.68842) (xy 451.243171 -216.736441) (xy 451.258881 -216.787371) (xy 451.266824 -216.840075)
			(xy 451.267322 -216.866724) (xy 451.266824 -216.893373) (xy 451.258881 -216.946077) (xy 451.243171 -216.997007)
			(xy 451.220045 -217.045028) (xy 451.190021 -217.089065) (xy 451.153769 -217.128136) (xy 451.112098 -217.161367)
			(xy 451.06594 -217.188016) (xy 451.016326 -217.207488) (xy 450.964364 -217.219348) (xy 450.911214 -217.223332)
			(xy 450.858064 -217.219348) (xy 450.806102 -217.207488) (xy 450.756488 -217.188016) (xy 450.71033 -217.161367)
			(xy 450.668659 -217.128136) (xy 450.632407 -217.089065) (xy 450.602383 -217.045028) (xy 450.579257 -216.997007)
			(xy 450.563547 -216.946077) (xy 450.555604 -216.893373) (xy 436.179224 -216.893373) (xy 436.171281 -216.946077)
			(xy 436.155571 -216.997007) (xy 436.132445 -217.045028) (xy 436.102421 -217.089065) (xy 436.066169 -217.128136)
			(xy 436.024498 -217.161367) (xy 435.97834 -217.188016) (xy 435.928726 -217.207488) (xy 435.876764 -217.219348)
			(xy 435.823614 -217.223332) (xy 435.770464 -217.219348) (xy 435.718502 -217.207488) (xy 435.668888 -217.188016)
			(xy 435.62273 -217.161367) (xy 435.581059 -217.128136) (xy 435.544807 -217.089065) (xy 435.514783 -217.045028)
			(xy 435.491657 -216.997007) (xy 435.475947 -216.946077) (xy 435.468004 -216.893373) (xy 421.091624 -216.893373)
			(xy 421.083681 -216.946077) (xy 421.067971 -216.997007) (xy 421.044845 -217.045028) (xy 421.014821 -217.089065)
			(xy 420.978569 -217.128136) (xy 420.936898 -217.161367) (xy 420.89074 -217.188016) (xy 420.841126 -217.207488)
			(xy 420.789164 -217.219348) (xy 420.736014 -217.223332) (xy 420.682864 -217.219348) (xy 420.630902 -217.207488)
			(xy 420.581288 -217.188016) (xy 420.53513 -217.161367) (xy 420.493459 -217.128136) (xy 420.457207 -217.089065)
			(xy 420.427183 -217.045028) (xy 420.404057 -216.997007) (xy 420.388347 -216.946077) (xy 420.380404 -216.893373)
			(xy 407.4668 -216.893373) (xy 407.4668 -217.743257) (xy 424.480472 -217.743257) (xy 424.480472 -217.689959)
			(xy 424.488415 -217.637255) (xy 424.504125 -217.586325) (xy 424.527251 -217.538304) (xy 424.557275 -217.494267)
			(xy 424.593527 -217.455196) (xy 424.635198 -217.421965) (xy 424.681356 -217.395316) (xy 424.73097 -217.375844)
			(xy 424.782932 -217.363984) (xy 424.836082 -217.360001) (xy 424.889232 -217.363984) (xy 424.941194 -217.375844)
			(xy 424.990808 -217.395316) (xy 425.036966 -217.421965) (xy 425.078637 -217.455196) (xy 425.114889 -217.494267)
			(xy 425.144913 -217.538304) (xy 425.168039 -217.586325) (xy 425.183749 -217.637255) (xy 425.191692 -217.689959)
			(xy 425.19219 -217.716608) (xy 425.191692 -217.743257) (xy 439.568072 -217.743257) (xy 439.568072 -217.689959)
			(xy 439.576015 -217.637255) (xy 439.591725 -217.586325) (xy 439.614851 -217.538304) (xy 439.644875 -217.494267)
			(xy 439.681127 -217.455196) (xy 439.722798 -217.421965) (xy 439.768956 -217.395316) (xy 439.81857 -217.375844)
			(xy 439.870532 -217.363984) (xy 439.923682 -217.360001) (xy 439.976832 -217.363984) (xy 440.028794 -217.375844)
			(xy 440.078408 -217.395316) (xy 440.124566 -217.421965) (xy 440.166237 -217.455196) (xy 440.202489 -217.494267)
			(xy 440.232513 -217.538304) (xy 440.255639 -217.586325) (xy 440.271349 -217.637255) (xy 440.279292 -217.689959)
			(xy 440.27979 -217.716608) (xy 440.279292 -217.743257) (xy 454.655672 -217.743257) (xy 454.655672 -217.689959)
			(xy 454.663615 -217.637255) (xy 454.679325 -217.586325) (xy 454.702451 -217.538304) (xy 454.732475 -217.494267)
			(xy 454.768727 -217.455196) (xy 454.810398 -217.421965) (xy 454.856556 -217.395316) (xy 454.90617 -217.375844)
			(xy 454.958132 -217.363984) (xy 455.011282 -217.360001) (xy 455.064432 -217.363984) (xy 455.116394 -217.375844)
			(xy 455.166008 -217.395316) (xy 455.212166 -217.421965) (xy 455.253837 -217.455196) (xy 455.290089 -217.494267)
			(xy 455.320113 -217.538304) (xy 455.343239 -217.586325) (xy 455.358949 -217.637255) (xy 455.366892 -217.689959)
			(xy 455.36739 -217.716608) (xy 455.366892 -217.743257) (xy 455.358949 -217.795961) (xy 455.343239 -217.846891)
			(xy 455.320113 -217.894912) (xy 455.290089 -217.938949) (xy 455.253837 -217.97802) (xy 455.212166 -218.011251)
			(xy 455.166008 -218.0379) (xy 455.116394 -218.057372) (xy 455.064432 -218.069232) (xy 455.011282 -218.073216)
			(xy 454.958132 -218.069232) (xy 454.90617 -218.057372) (xy 454.856556 -218.0379) (xy 454.810398 -218.011251)
			(xy 454.768727 -217.97802) (xy 454.732475 -217.938949) (xy 454.702451 -217.894912) (xy 454.679325 -217.846891)
			(xy 454.663615 -217.795961) (xy 454.655672 -217.743257) (xy 440.279292 -217.743257) (xy 440.271349 -217.795961)
			(xy 440.255639 -217.846891) (xy 440.232513 -217.894912) (xy 440.202489 -217.938949) (xy 440.166237 -217.97802)
			(xy 440.124566 -218.011251) (xy 440.078408 -218.0379) (xy 440.028794 -218.057372) (xy 439.976832 -218.069232)
			(xy 439.923682 -218.073216) (xy 439.870532 -218.069232) (xy 439.81857 -218.057372) (xy 439.768956 -218.0379)
			(xy 439.722798 -218.011251) (xy 439.681127 -217.97802) (xy 439.644875 -217.938949) (xy 439.614851 -217.894912)
			(xy 439.591725 -217.846891) (xy 439.576015 -217.795961) (xy 439.568072 -217.743257) (xy 425.191692 -217.743257)
			(xy 425.183749 -217.795961) (xy 425.168039 -217.846891) (xy 425.144913 -217.894912) (xy 425.114889 -217.938949)
			(xy 425.078637 -217.97802) (xy 425.036966 -218.011251) (xy 424.990808 -218.0379) (xy 424.941194 -218.057372)
			(xy 424.889232 -218.069232) (xy 424.836082 -218.073216) (xy 424.782932 -218.069232) (xy 424.73097 -218.057372)
			(xy 424.681356 -218.0379) (xy 424.635198 -218.011251) (xy 424.593527 -217.97802) (xy 424.557275 -217.938949)
			(xy 424.527251 -217.894912) (xy 424.504125 -217.846891) (xy 424.488415 -217.795961) (xy 424.480472 -217.743257)
			(xy 407.4668 -217.743257) (xy 407.4668 -218.593395) (xy 420.380404 -218.593395) (xy 420.380404 -218.540097)
			(xy 420.388347 -218.487393) (xy 420.404057 -218.436463) (xy 420.427183 -218.388442) (xy 420.457207 -218.344405)
			(xy 420.493459 -218.305334) (xy 420.53513 -218.272103) (xy 420.581288 -218.245454) (xy 420.630902 -218.225982)
			(xy 420.682864 -218.214122) (xy 420.736014 -218.210139) (xy 420.789164 -218.214122) (xy 420.841126 -218.225982)
			(xy 420.89074 -218.245454) (xy 420.936898 -218.272103) (xy 420.978569 -218.305334) (xy 421.014821 -218.344405)
			(xy 421.044845 -218.388442) (xy 421.067971 -218.436463) (xy 421.083681 -218.487393) (xy 421.091624 -218.540097)
			(xy 421.092122 -218.566746) (xy 421.091624 -218.593395) (xy 424.480472 -218.593395) (xy 424.480472 -218.540097)
			(xy 424.488415 -218.487393) (xy 424.504125 -218.436463) (xy 424.527251 -218.388442) (xy 424.557275 -218.344405)
			(xy 424.593527 -218.305334) (xy 424.635198 -218.272103) (xy 424.681356 -218.245454) (xy 424.73097 -218.225982)
			(xy 424.782932 -218.214122) (xy 424.836082 -218.210139) (xy 424.889232 -218.214122) (xy 424.941194 -218.225982)
			(xy 424.990808 -218.245454) (xy 425.036966 -218.272103) (xy 425.078637 -218.305334) (xy 425.114889 -218.344405)
			(xy 425.144913 -218.388442) (xy 425.168039 -218.436463) (xy 425.183749 -218.487393) (xy 425.191692 -218.540097)
			(xy 425.19219 -218.566746) (xy 425.191692 -218.593395) (xy 435.468004 -218.593395) (xy 435.468004 -218.540097)
			(xy 435.475947 -218.487393) (xy 435.491657 -218.436463) (xy 435.514783 -218.388442) (xy 435.544807 -218.344405)
			(xy 435.581059 -218.305334) (xy 435.62273 -218.272103) (xy 435.668888 -218.245454) (xy 435.718502 -218.225982)
			(xy 435.770464 -218.214122) (xy 435.823614 -218.210139) (xy 435.876764 -218.214122) (xy 435.928726 -218.225982)
			(xy 435.97834 -218.245454) (xy 436.024498 -218.272103) (xy 436.066169 -218.305334) (xy 436.102421 -218.344405)
			(xy 436.132445 -218.388442) (xy 436.155571 -218.436463) (xy 436.171281 -218.487393) (xy 436.179224 -218.540097)
			(xy 436.179722 -218.566746) (xy 436.179224 -218.593395) (xy 439.568072 -218.593395) (xy 439.568072 -218.540097)
			(xy 439.576015 -218.487393) (xy 439.591725 -218.436463) (xy 439.614851 -218.388442) (xy 439.644875 -218.344405)
			(xy 439.681127 -218.305334) (xy 439.722798 -218.272103) (xy 439.768956 -218.245454) (xy 439.81857 -218.225982)
			(xy 439.870532 -218.214122) (xy 439.923682 -218.210139) (xy 439.976832 -218.214122) (xy 440.028794 -218.225982)
			(xy 440.078408 -218.245454) (xy 440.124566 -218.272103) (xy 440.166237 -218.305334) (xy 440.202489 -218.344405)
			(xy 440.232513 -218.388442) (xy 440.255639 -218.436463) (xy 440.271349 -218.487393) (xy 440.279292 -218.540097)
			(xy 440.27979 -218.566746) (xy 440.279292 -218.593395) (xy 450.555604 -218.593395) (xy 450.555604 -218.540097)
			(xy 450.563547 -218.487393) (xy 450.579257 -218.436463) (xy 450.602383 -218.388442) (xy 450.632407 -218.344405)
			(xy 450.668659 -218.305334) (xy 450.71033 -218.272103) (xy 450.756488 -218.245454) (xy 450.806102 -218.225982)
			(xy 450.858064 -218.214122) (xy 450.911214 -218.210139) (xy 450.964364 -218.214122) (xy 451.016326 -218.225982)
			(xy 451.06594 -218.245454) (xy 451.112098 -218.272103) (xy 451.153769 -218.305334) (xy 451.190021 -218.344405)
			(xy 451.220045 -218.388442) (xy 451.243171 -218.436463) (xy 451.258881 -218.487393) (xy 451.266824 -218.540097)
			(xy 451.267322 -218.566746) (xy 451.266824 -218.593395) (xy 454.655672 -218.593395) (xy 454.655672 -218.540097)
			(xy 454.663615 -218.487393) (xy 454.679325 -218.436463) (xy 454.702451 -218.388442) (xy 454.732475 -218.344405)
			(xy 454.768727 -218.305334) (xy 454.810398 -218.272103) (xy 454.856556 -218.245454) (xy 454.90617 -218.225982)
			(xy 454.958132 -218.214122) (xy 455.011282 -218.210139) (xy 455.064432 -218.214122) (xy 455.116394 -218.225982)
			(xy 455.166008 -218.245454) (xy 455.212166 -218.272103) (xy 455.253837 -218.305334) (xy 455.290089 -218.344405)
			(xy 455.320113 -218.388442) (xy 455.343239 -218.436463) (xy 455.358949 -218.487393) (xy 455.366892 -218.540097)
			(xy 455.36739 -218.566746) (xy 455.366892 -218.593395) (xy 455.358949 -218.646099) (xy 455.343239 -218.697029)
			(xy 455.320113 -218.74505) (xy 455.290089 -218.789087) (xy 455.253837 -218.828158) (xy 455.212166 -218.861389)
			(xy 455.166008 -218.888038) (xy 455.116394 -218.90751) (xy 455.064432 -218.91937) (xy 455.011282 -218.923354)
			(xy 454.958132 -218.91937) (xy 454.90617 -218.90751) (xy 454.856556 -218.888038) (xy 454.810398 -218.861389)
			(xy 454.768727 -218.828158) (xy 454.732475 -218.789087) (xy 454.702451 -218.74505) (xy 454.679325 -218.697029)
			(xy 454.663615 -218.646099) (xy 454.655672 -218.593395) (xy 451.266824 -218.593395) (xy 451.258881 -218.646099)
			(xy 451.243171 -218.697029) (xy 451.220045 -218.74505) (xy 451.190021 -218.789087) (xy 451.153769 -218.828158)
			(xy 451.112098 -218.861389) (xy 451.06594 -218.888038) (xy 451.016326 -218.90751) (xy 450.964364 -218.91937)
			(xy 450.911214 -218.923354) (xy 450.858064 -218.91937) (xy 450.806102 -218.90751) (xy 450.756488 -218.888038)
			(xy 450.71033 -218.861389) (xy 450.668659 -218.828158) (xy 450.632407 -218.789087) (xy 450.602383 -218.74505)
			(xy 450.579257 -218.697029) (xy 450.563547 -218.646099) (xy 450.555604 -218.593395) (xy 440.279292 -218.593395)
			(xy 440.271349 -218.646099) (xy 440.255639 -218.697029) (xy 440.232513 -218.74505) (xy 440.202489 -218.789087)
			(xy 440.166237 -218.828158) (xy 440.124566 -218.861389) (xy 440.078408 -218.888038) (xy 440.028794 -218.90751)
			(xy 439.976832 -218.91937) (xy 439.923682 -218.923354) (xy 439.870532 -218.91937) (xy 439.81857 -218.90751)
			(xy 439.768956 -218.888038) (xy 439.722798 -218.861389) (xy 439.681127 -218.828158) (xy 439.644875 -218.789087)
			(xy 439.614851 -218.74505) (xy 439.591725 -218.697029) (xy 439.576015 -218.646099) (xy 439.568072 -218.593395)
			(xy 436.179224 -218.593395) (xy 436.171281 -218.646099) (xy 436.155571 -218.697029) (xy 436.132445 -218.74505)
			(xy 436.102421 -218.789087) (xy 436.066169 -218.828158) (xy 436.024498 -218.861389) (xy 435.97834 -218.888038)
			(xy 435.928726 -218.90751) (xy 435.876764 -218.91937) (xy 435.823614 -218.923354) (xy 435.770464 -218.91937)
			(xy 435.718502 -218.90751) (xy 435.668888 -218.888038) (xy 435.62273 -218.861389) (xy 435.581059 -218.828158)
			(xy 435.544807 -218.789087) (xy 435.514783 -218.74505) (xy 435.491657 -218.697029) (xy 435.475947 -218.646099)
			(xy 435.468004 -218.593395) (xy 425.191692 -218.593395) (xy 425.183749 -218.646099) (xy 425.168039 -218.697029)
			(xy 425.144913 -218.74505) (xy 425.114889 -218.789087) (xy 425.078637 -218.828158) (xy 425.036966 -218.861389)
			(xy 424.990808 -218.888038) (xy 424.941194 -218.90751) (xy 424.889232 -218.91937) (xy 424.836082 -218.923354)
			(xy 424.782932 -218.91937) (xy 424.73097 -218.90751) (xy 424.681356 -218.888038) (xy 424.635198 -218.861389)
			(xy 424.593527 -218.828158) (xy 424.557275 -218.789087) (xy 424.527251 -218.74505) (xy 424.504125 -218.697029)
			(xy 424.488415 -218.646099) (xy 424.480472 -218.593395) (xy 421.091624 -218.593395) (xy 421.083681 -218.646099)
			(xy 421.067971 -218.697029) (xy 421.044845 -218.74505) (xy 421.014821 -218.789087) (xy 420.978569 -218.828158)
			(xy 420.936898 -218.861389) (xy 420.89074 -218.888038) (xy 420.841126 -218.90751) (xy 420.789164 -218.91937)
			(xy 420.736014 -218.923354) (xy 420.682864 -218.91937) (xy 420.630902 -218.90751) (xy 420.581288 -218.888038)
			(xy 420.53513 -218.861389) (xy 420.493459 -218.828158) (xy 420.457207 -218.789087) (xy 420.427183 -218.74505)
			(xy 420.404057 -218.697029) (xy 420.388347 -218.646099) (xy 420.380404 -218.593395) (xy 407.4668 -218.593395)
			(xy 407.4668 -219.443279) (xy 420.380404 -219.443279) (xy 420.380404 -219.389981) (xy 420.388347 -219.337277)
			(xy 420.404057 -219.286347) (xy 420.427183 -219.238326) (xy 420.457207 -219.194289) (xy 420.493459 -219.155218)
			(xy 420.53513 -219.121987) (xy 420.581288 -219.095338) (xy 420.630902 -219.075866) (xy 420.682864 -219.064006)
			(xy 420.736014 -219.060023) (xy 420.789164 -219.064006) (xy 420.841126 -219.075866) (xy 420.89074 -219.095338)
			(xy 420.936898 -219.121987) (xy 420.978569 -219.155218) (xy 421.014821 -219.194289) (xy 421.044845 -219.238326)
			(xy 421.067971 -219.286347) (xy 421.083681 -219.337277) (xy 421.091624 -219.389981) (xy 421.092122 -219.41663)
			(xy 421.091624 -219.443279) (xy 435.468004 -219.443279) (xy 435.468004 -219.389981) (xy 435.475947 -219.337277)
			(xy 435.491657 -219.286347) (xy 435.514783 -219.238326) (xy 435.544807 -219.194289) (xy 435.581059 -219.155218)
			(xy 435.62273 -219.121987) (xy 435.668888 -219.095338) (xy 435.718502 -219.075866) (xy 435.770464 -219.064006)
			(xy 435.823614 -219.060023) (xy 435.876764 -219.064006) (xy 435.928726 -219.075866) (xy 435.97834 -219.095338)
			(xy 436.024498 -219.121987) (xy 436.066169 -219.155218) (xy 436.102421 -219.194289) (xy 436.132445 -219.238326)
			(xy 436.155571 -219.286347) (xy 436.171281 -219.337277) (xy 436.179224 -219.389981) (xy 436.179722 -219.41663)
			(xy 436.179224 -219.443279) (xy 450.555604 -219.443279) (xy 450.555604 -219.389981) (xy 450.563547 -219.337277)
			(xy 450.579257 -219.286347) (xy 450.602383 -219.238326) (xy 450.632407 -219.194289) (xy 450.668659 -219.155218)
			(xy 450.71033 -219.121987) (xy 450.756488 -219.095338) (xy 450.806102 -219.075866) (xy 450.858064 -219.064006)
			(xy 450.911214 -219.060023) (xy 450.964364 -219.064006) (xy 451.016326 -219.075866) (xy 451.06594 -219.095338)
			(xy 451.112098 -219.121987) (xy 451.153769 -219.155218) (xy 451.190021 -219.194289) (xy 451.220045 -219.238326)
			(xy 451.243171 -219.286347) (xy 451.258881 -219.337277) (xy 451.266824 -219.389981) (xy 451.267322 -219.41663)
			(xy 451.266824 -219.443279) (xy 451.258881 -219.495983) (xy 451.243171 -219.546913) (xy 451.220045 -219.594934)
			(xy 451.190021 -219.638971) (xy 451.153769 -219.678042) (xy 451.112098 -219.711273) (xy 451.06594 -219.737922)
			(xy 451.016326 -219.757394) (xy 450.964364 -219.769254) (xy 450.911214 -219.773238) (xy 450.858064 -219.769254)
			(xy 450.806102 -219.757394) (xy 450.756488 -219.737922) (xy 450.71033 -219.711273) (xy 450.668659 -219.678042)
			(xy 450.632407 -219.638971) (xy 450.602383 -219.594934) (xy 450.579257 -219.546913) (xy 450.563547 -219.495983)
			(xy 450.555604 -219.443279) (xy 436.179224 -219.443279) (xy 436.171281 -219.495983) (xy 436.155571 -219.546913)
			(xy 436.132445 -219.594934) (xy 436.102421 -219.638971) (xy 436.066169 -219.678042) (xy 436.024498 -219.711273)
			(xy 435.97834 -219.737922) (xy 435.928726 -219.757394) (xy 435.876764 -219.769254) (xy 435.823614 -219.773238)
			(xy 435.770464 -219.769254) (xy 435.718502 -219.757394) (xy 435.668888 -219.737922) (xy 435.62273 -219.711273)
			(xy 435.581059 -219.678042) (xy 435.544807 -219.638971) (xy 435.514783 -219.594934) (xy 435.491657 -219.546913)
			(xy 435.475947 -219.495983) (xy 435.468004 -219.443279) (xy 421.091624 -219.443279) (xy 421.083681 -219.495983)
			(xy 421.067971 -219.546913) (xy 421.044845 -219.594934) (xy 421.014821 -219.638971) (xy 420.978569 -219.678042)
			(xy 420.936898 -219.711273) (xy 420.89074 -219.737922) (xy 420.841126 -219.757394) (xy 420.789164 -219.769254)
			(xy 420.736014 -219.773238) (xy 420.682864 -219.769254) (xy 420.630902 -219.757394) (xy 420.581288 -219.737922)
			(xy 420.53513 -219.711273) (xy 420.493459 -219.678042) (xy 420.457207 -219.638971) (xy 420.427183 -219.594934)
			(xy 420.404057 -219.546913) (xy 420.388347 -219.495983) (xy 420.380404 -219.443279) (xy 407.4668 -219.443279)
			(xy 407.4668 -220.293417) (xy 424.480472 -220.293417) (xy 424.480472 -220.240119) (xy 424.488415 -220.187415)
			(xy 424.504125 -220.136485) (xy 424.527251 -220.088464) (xy 424.557275 -220.044427) (xy 424.593527 -220.005356)
			(xy 424.635198 -219.972125) (xy 424.681356 -219.945476) (xy 424.73097 -219.926004) (xy 424.782932 -219.914144)
			(xy 424.836082 -219.910161) (xy 424.889232 -219.914144) (xy 424.941194 -219.926004) (xy 424.990808 -219.945476)
			(xy 425.036966 -219.972125) (xy 425.078637 -220.005356) (xy 425.114889 -220.044427) (xy 425.144913 -220.088464)
			(xy 425.168039 -220.136485) (xy 425.183749 -220.187415) (xy 425.191692 -220.240119) (xy 425.19219 -220.266768)
			(xy 425.191692 -220.293417) (xy 439.568072 -220.293417) (xy 439.568072 -220.240119) (xy 439.576015 -220.187415)
			(xy 439.591725 -220.136485) (xy 439.614851 -220.088464) (xy 439.644875 -220.044427) (xy 439.681127 -220.005356)
			(xy 439.722798 -219.972125) (xy 439.768956 -219.945476) (xy 439.81857 -219.926004) (xy 439.870532 -219.914144)
			(xy 439.923682 -219.910161) (xy 439.976832 -219.914144) (xy 440.028794 -219.926004) (xy 440.078408 -219.945476)
			(xy 440.124566 -219.972125) (xy 440.166237 -220.005356) (xy 440.202489 -220.044427) (xy 440.232513 -220.088464)
			(xy 440.255639 -220.136485) (xy 440.271349 -220.187415) (xy 440.279292 -220.240119) (xy 440.27979 -220.266768)
			(xy 440.279292 -220.293417) (xy 454.655672 -220.293417) (xy 454.655672 -220.240119) (xy 454.663615 -220.187415)
			(xy 454.679325 -220.136485) (xy 454.702451 -220.088464) (xy 454.732475 -220.044427) (xy 454.768727 -220.005356)
			(xy 454.810398 -219.972125) (xy 454.856556 -219.945476) (xy 454.90617 -219.926004) (xy 454.958132 -219.914144)
			(xy 455.011282 -219.910161) (xy 455.064432 -219.914144) (xy 455.116394 -219.926004) (xy 455.166008 -219.945476)
			(xy 455.212166 -219.972125) (xy 455.253837 -220.005356) (xy 455.290089 -220.044427) (xy 455.320113 -220.088464)
			(xy 455.343239 -220.136485) (xy 455.358949 -220.187415) (xy 455.366892 -220.240119) (xy 455.36739 -220.266768)
			(xy 455.366892 -220.293417) (xy 455.358949 -220.346121) (xy 455.343239 -220.397051) (xy 455.320113 -220.445072)
			(xy 455.290089 -220.489109) (xy 455.253837 -220.52818) (xy 455.212166 -220.561411) (xy 455.166008 -220.58806)
			(xy 455.116394 -220.607532) (xy 455.064432 -220.619392) (xy 455.011282 -220.623376) (xy 454.958132 -220.619392)
			(xy 454.90617 -220.607532) (xy 454.856556 -220.58806) (xy 454.810398 -220.561411) (xy 454.768727 -220.52818)
			(xy 454.732475 -220.489109) (xy 454.702451 -220.445072) (xy 454.679325 -220.397051) (xy 454.663615 -220.346121)
			(xy 454.655672 -220.293417) (xy 440.279292 -220.293417) (xy 440.271349 -220.346121) (xy 440.255639 -220.397051)
			(xy 440.232513 -220.445072) (xy 440.202489 -220.489109) (xy 440.166237 -220.52818) (xy 440.124566 -220.561411)
			(xy 440.078408 -220.58806) (xy 440.028794 -220.607532) (xy 439.976832 -220.619392) (xy 439.923682 -220.623376)
			(xy 439.870532 -220.619392) (xy 439.81857 -220.607532) (xy 439.768956 -220.58806) (xy 439.722798 -220.561411)
			(xy 439.681127 -220.52818) (xy 439.644875 -220.489109) (xy 439.614851 -220.445072) (xy 439.591725 -220.397051)
			(xy 439.576015 -220.346121) (xy 439.568072 -220.293417) (xy 425.191692 -220.293417) (xy 425.183749 -220.346121)
			(xy 425.168039 -220.397051) (xy 425.144913 -220.445072) (xy 425.114889 -220.489109) (xy 425.078637 -220.52818)
			(xy 425.036966 -220.561411) (xy 424.990808 -220.58806) (xy 424.941194 -220.607532) (xy 424.889232 -220.619392)
			(xy 424.836082 -220.623376) (xy 424.782932 -220.619392) (xy 424.73097 -220.607532) (xy 424.681356 -220.58806)
			(xy 424.635198 -220.561411) (xy 424.593527 -220.52818) (xy 424.557275 -220.489109) (xy 424.527251 -220.445072)
			(xy 424.504125 -220.397051) (xy 424.488415 -220.346121) (xy 424.480472 -220.293417) (xy 407.4668 -220.293417)
			(xy 407.4668 -221.143301) (xy 420.380404 -221.143301) (xy 420.380404 -221.090003) (xy 420.388347 -221.037299)
			(xy 420.404057 -220.986369) (xy 420.427183 -220.938348) (xy 420.457207 -220.894311) (xy 420.493459 -220.85524)
			(xy 420.53513 -220.822009) (xy 420.581288 -220.79536) (xy 420.630902 -220.775888) (xy 420.682864 -220.764028)
			(xy 420.736014 -220.760045) (xy 420.789164 -220.764028) (xy 420.841126 -220.775888) (xy 420.89074 -220.79536)
			(xy 420.936898 -220.822009) (xy 420.978569 -220.85524) (xy 421.014821 -220.894311) (xy 421.044845 -220.938348)
			(xy 421.067971 -220.986369) (xy 421.083681 -221.037299) (xy 421.091624 -221.090003) (xy 421.092122 -221.116652)
			(xy 421.091624 -221.143301) (xy 435.468004 -221.143301) (xy 435.468004 -221.090003) (xy 435.475947 -221.037299)
			(xy 435.491657 -220.986369) (xy 435.514783 -220.938348) (xy 435.544807 -220.894311) (xy 435.581059 -220.85524)
			(xy 435.62273 -220.822009) (xy 435.668888 -220.79536) (xy 435.718502 -220.775888) (xy 435.770464 -220.764028)
			(xy 435.823614 -220.760045) (xy 435.876764 -220.764028) (xy 435.928726 -220.775888) (xy 435.97834 -220.79536)
			(xy 436.024498 -220.822009) (xy 436.066169 -220.85524) (xy 436.102421 -220.894311) (xy 436.132445 -220.938348)
			(xy 436.155571 -220.986369) (xy 436.171281 -221.037299) (xy 436.179224 -221.090003) (xy 436.179722 -221.116652)
			(xy 436.179224 -221.143301) (xy 450.555604 -221.143301) (xy 450.555604 -221.090003) (xy 450.563547 -221.037299)
			(xy 450.579257 -220.986369) (xy 450.602383 -220.938348) (xy 450.632407 -220.894311) (xy 450.668659 -220.85524)
			(xy 450.71033 -220.822009) (xy 450.756488 -220.79536) (xy 450.806102 -220.775888) (xy 450.858064 -220.764028)
			(xy 450.911214 -220.760045) (xy 450.964364 -220.764028) (xy 451.016326 -220.775888) (xy 451.06594 -220.79536)
			(xy 451.112098 -220.822009) (xy 451.153769 -220.85524) (xy 451.190021 -220.894311) (xy 451.220045 -220.938348)
			(xy 451.243171 -220.986369) (xy 451.258881 -221.037299) (xy 451.266824 -221.090003) (xy 451.267322 -221.116652)
			(xy 451.266824 -221.143301) (xy 451.258881 -221.196005) (xy 451.243171 -221.246935) (xy 451.220045 -221.294956)
			(xy 451.190021 -221.338993) (xy 451.153769 -221.378064) (xy 451.112098 -221.411295) (xy 451.06594 -221.437944)
			(xy 451.016326 -221.457416) (xy 450.964364 -221.469276) (xy 450.911214 -221.47326) (xy 450.858064 -221.469276)
			(xy 450.806102 -221.457416) (xy 450.756488 -221.437944) (xy 450.71033 -221.411295) (xy 450.668659 -221.378064)
			(xy 450.632407 -221.338993) (xy 450.602383 -221.294956) (xy 450.579257 -221.246935) (xy 450.563547 -221.196005)
			(xy 450.555604 -221.143301) (xy 436.179224 -221.143301) (xy 436.171281 -221.196005) (xy 436.155571 -221.246935)
			(xy 436.132445 -221.294956) (xy 436.102421 -221.338993) (xy 436.066169 -221.378064) (xy 436.024498 -221.411295)
			(xy 435.97834 -221.437944) (xy 435.928726 -221.457416) (xy 435.876764 -221.469276) (xy 435.823614 -221.47326)
			(xy 435.770464 -221.469276) (xy 435.718502 -221.457416) (xy 435.668888 -221.437944) (xy 435.62273 -221.411295)
			(xy 435.581059 -221.378064) (xy 435.544807 -221.338993) (xy 435.514783 -221.294956) (xy 435.491657 -221.246935)
			(xy 435.475947 -221.196005) (xy 435.468004 -221.143301) (xy 421.091624 -221.143301) (xy 421.083681 -221.196005)
			(xy 421.067971 -221.246935) (xy 421.044845 -221.294956) (xy 421.014821 -221.338993) (xy 420.978569 -221.378064)
			(xy 420.936898 -221.411295) (xy 420.89074 -221.437944) (xy 420.841126 -221.457416) (xy 420.789164 -221.469276)
			(xy 420.736014 -221.47326) (xy 420.682864 -221.469276) (xy 420.630902 -221.457416) (xy 420.581288 -221.437944)
			(xy 420.53513 -221.411295) (xy 420.493459 -221.378064) (xy 420.457207 -221.338993) (xy 420.427183 -221.294956)
			(xy 420.404057 -221.246935) (xy 420.388347 -221.196005) (xy 420.380404 -221.143301) (xy 407.4668 -221.143301)
			(xy 407.4668 -221.993439) (xy 424.480472 -221.993439) (xy 424.480472 -221.940141) (xy 424.488415 -221.887437)
			(xy 424.504125 -221.836507) (xy 424.527251 -221.788486) (xy 424.557275 -221.744449) (xy 424.593527 -221.705378)
			(xy 424.635198 -221.672147) (xy 424.681356 -221.645498) (xy 424.73097 -221.626026) (xy 424.782932 -221.614166)
			(xy 424.836082 -221.610183) (xy 424.889232 -221.614166) (xy 424.941194 -221.626026) (xy 424.990808 -221.645498)
			(xy 425.036966 -221.672147) (xy 425.078637 -221.705378) (xy 425.114889 -221.744449) (xy 425.144913 -221.788486)
			(xy 425.168039 -221.836507) (xy 425.183749 -221.887437) (xy 425.191692 -221.940141) (xy 425.19219 -221.96679)
			(xy 425.191692 -221.993439) (xy 439.568072 -221.993439) (xy 439.568072 -221.940141) (xy 439.576015 -221.887437)
			(xy 439.591725 -221.836507) (xy 439.614851 -221.788486) (xy 439.644875 -221.744449) (xy 439.681127 -221.705378)
			(xy 439.722798 -221.672147) (xy 439.768956 -221.645498) (xy 439.81857 -221.626026) (xy 439.870532 -221.614166)
			(xy 439.923682 -221.610183) (xy 439.976832 -221.614166) (xy 440.028794 -221.626026) (xy 440.078408 -221.645498)
			(xy 440.124566 -221.672147) (xy 440.166237 -221.705378) (xy 440.202489 -221.744449) (xy 440.232513 -221.788486)
			(xy 440.255639 -221.836507) (xy 440.271349 -221.887437) (xy 440.279292 -221.940141) (xy 440.27979 -221.96679)
			(xy 440.279292 -221.993439) (xy 454.655672 -221.993439) (xy 454.655672 -221.940141) (xy 454.663615 -221.887437)
			(xy 454.679325 -221.836507) (xy 454.702451 -221.788486) (xy 454.732475 -221.744449) (xy 454.768727 -221.705378)
			(xy 454.810398 -221.672147) (xy 454.856556 -221.645498) (xy 454.90617 -221.626026) (xy 454.958132 -221.614166)
			(xy 455.011282 -221.610183) (xy 455.064432 -221.614166) (xy 455.116394 -221.626026) (xy 455.166008 -221.645498)
			(xy 455.212166 -221.672147) (xy 455.253837 -221.705378) (xy 455.290089 -221.744449) (xy 455.320113 -221.788486)
			(xy 455.343239 -221.836507) (xy 455.358949 -221.887437) (xy 455.366892 -221.940141) (xy 455.36739 -221.96679)
			(xy 455.366892 -221.993439) (xy 455.358949 -222.046143) (xy 455.343239 -222.097073) (xy 455.320113 -222.145094)
			(xy 455.290089 -222.189131) (xy 455.253837 -222.228202) (xy 455.212166 -222.261433) (xy 455.166008 -222.288082)
			(xy 455.116394 -222.307554) (xy 455.064432 -222.319414) (xy 455.011282 -222.323398) (xy 454.958132 -222.319414)
			(xy 454.90617 -222.307554) (xy 454.856556 -222.288082) (xy 454.810398 -222.261433) (xy 454.768727 -222.228202)
			(xy 454.732475 -222.189131) (xy 454.702451 -222.145094) (xy 454.679325 -222.097073) (xy 454.663615 -222.046143)
			(xy 454.655672 -221.993439) (xy 440.279292 -221.993439) (xy 440.271349 -222.046143) (xy 440.255639 -222.097073)
			(xy 440.232513 -222.145094) (xy 440.202489 -222.189131) (xy 440.166237 -222.228202) (xy 440.124566 -222.261433)
			(xy 440.078408 -222.288082) (xy 440.028794 -222.307554) (xy 439.976832 -222.319414) (xy 439.923682 -222.323398)
			(xy 439.870532 -222.319414) (xy 439.81857 -222.307554) (xy 439.768956 -222.288082) (xy 439.722798 -222.261433)
			(xy 439.681127 -222.228202) (xy 439.644875 -222.189131) (xy 439.614851 -222.145094) (xy 439.591725 -222.097073)
			(xy 439.576015 -222.046143) (xy 439.568072 -221.993439) (xy 425.191692 -221.993439) (xy 425.183749 -222.046143)
			(xy 425.168039 -222.097073) (xy 425.144913 -222.145094) (xy 425.114889 -222.189131) (xy 425.078637 -222.228202)
			(xy 425.036966 -222.261433) (xy 424.990808 -222.288082) (xy 424.941194 -222.307554) (xy 424.889232 -222.319414)
			(xy 424.836082 -222.323398) (xy 424.782932 -222.319414) (xy 424.73097 -222.307554) (xy 424.681356 -222.288082)
			(xy 424.635198 -222.261433) (xy 424.593527 -222.228202) (xy 424.557275 -222.189131) (xy 424.527251 -222.145094)
			(xy 424.504125 -222.097073) (xy 424.488415 -222.046143) (xy 424.480472 -221.993439) (xy 407.4668 -221.993439)
			(xy 407.4668 -222.843323) (xy 420.380404 -222.843323) (xy 420.380404 -222.790025) (xy 420.388347 -222.737321)
			(xy 420.404057 -222.686391) (xy 420.427183 -222.63837) (xy 420.457207 -222.594333) (xy 420.493459 -222.555262)
			(xy 420.53513 -222.522031) (xy 420.581288 -222.495382) (xy 420.630902 -222.47591) (xy 420.682864 -222.46405)
			(xy 420.736014 -222.460067) (xy 420.789164 -222.46405) (xy 420.841126 -222.47591) (xy 420.89074 -222.495382)
			(xy 420.936898 -222.522031) (xy 420.978569 -222.555262) (xy 421.014821 -222.594333) (xy 421.044845 -222.63837)
			(xy 421.067971 -222.686391) (xy 421.083681 -222.737321) (xy 421.091624 -222.790025) (xy 421.092122 -222.816674)
			(xy 421.091624 -222.843323) (xy 435.468004 -222.843323) (xy 435.468004 -222.790025) (xy 435.475947 -222.737321)
			(xy 435.491657 -222.686391) (xy 435.514783 -222.63837) (xy 435.544807 -222.594333) (xy 435.581059 -222.555262)
			(xy 435.62273 -222.522031) (xy 435.668888 -222.495382) (xy 435.718502 -222.47591) (xy 435.770464 -222.46405)
			(xy 435.823614 -222.460067) (xy 435.876764 -222.46405) (xy 435.928726 -222.47591) (xy 435.97834 -222.495382)
			(xy 436.024498 -222.522031) (xy 436.066169 -222.555262) (xy 436.102421 -222.594333) (xy 436.132445 -222.63837)
			(xy 436.155571 -222.686391) (xy 436.171281 -222.737321) (xy 436.179224 -222.790025) (xy 436.179722 -222.816674)
			(xy 436.179224 -222.843323) (xy 450.555604 -222.843323) (xy 450.555604 -222.790025) (xy 450.563547 -222.737321)
			(xy 450.579257 -222.686391) (xy 450.602383 -222.63837) (xy 450.632407 -222.594333) (xy 450.668659 -222.555262)
			(xy 450.71033 -222.522031) (xy 450.756488 -222.495382) (xy 450.806102 -222.47591) (xy 450.858064 -222.46405)
			(xy 450.911214 -222.460067) (xy 450.964364 -222.46405) (xy 451.016326 -222.47591) (xy 451.06594 -222.495382)
			(xy 451.112098 -222.522031) (xy 451.153769 -222.555262) (xy 451.190021 -222.594333) (xy 451.220045 -222.63837)
			(xy 451.243171 -222.686391) (xy 451.258881 -222.737321) (xy 451.266824 -222.790025) (xy 451.267322 -222.816674)
			(xy 451.266824 -222.843323) (xy 451.258881 -222.896027) (xy 451.243171 -222.946957) (xy 451.220045 -222.994978)
			(xy 451.190021 -223.039015) (xy 451.153769 -223.078086) (xy 451.112098 -223.111317) (xy 451.06594 -223.137966)
			(xy 451.016326 -223.157438) (xy 450.964364 -223.169298) (xy 450.911214 -223.173282) (xy 450.858064 -223.169298)
			(xy 450.806102 -223.157438) (xy 450.756488 -223.137966) (xy 450.71033 -223.111317) (xy 450.668659 -223.078086)
			(xy 450.632407 -223.039015) (xy 450.602383 -222.994978) (xy 450.579257 -222.946957) (xy 450.563547 -222.896027)
			(xy 450.555604 -222.843323) (xy 436.179224 -222.843323) (xy 436.171281 -222.896027) (xy 436.155571 -222.946957)
			(xy 436.132445 -222.994978) (xy 436.102421 -223.039015) (xy 436.066169 -223.078086) (xy 436.024498 -223.111317)
			(xy 435.97834 -223.137966) (xy 435.928726 -223.157438) (xy 435.876764 -223.169298) (xy 435.823614 -223.173282)
			(xy 435.770464 -223.169298) (xy 435.718502 -223.157438) (xy 435.668888 -223.137966) (xy 435.62273 -223.111317)
			(xy 435.581059 -223.078086) (xy 435.544807 -223.039015) (xy 435.514783 -222.994978) (xy 435.491657 -222.946957)
			(xy 435.475947 -222.896027) (xy 435.468004 -222.843323) (xy 421.091624 -222.843323) (xy 421.083681 -222.896027)
			(xy 421.067971 -222.946957) (xy 421.044845 -222.994978) (xy 421.014821 -223.039015) (xy 420.978569 -223.078086)
			(xy 420.936898 -223.111317) (xy 420.89074 -223.137966) (xy 420.841126 -223.157438) (xy 420.789164 -223.169298)
			(xy 420.736014 -223.173282) (xy 420.682864 -223.169298) (xy 420.630902 -223.157438) (xy 420.581288 -223.137966)
			(xy 420.53513 -223.111317) (xy 420.493459 -223.078086) (xy 420.457207 -223.039015) (xy 420.427183 -222.994978)
			(xy 420.404057 -222.946957) (xy 420.388347 -222.896027) (xy 420.380404 -222.843323) (xy 407.4668 -222.843323)
			(xy 407.4668 -223.693207) (xy 409.367472 -223.693207) (xy 409.367472 -223.639909) (xy 409.375415 -223.587205)
			(xy 409.391125 -223.536275) (xy 409.414251 -223.488254) (xy 409.444275 -223.444217) (xy 409.480527 -223.405146)
			(xy 409.522198 -223.371915) (xy 409.568356 -223.345266) (xy 409.61797 -223.325794) (xy 409.669932 -223.313934)
			(xy 409.723082 -223.309951) (xy 409.776232 -223.313934) (xy 409.828194 -223.325794) (xy 409.877808 -223.345266)
			(xy 409.923966 -223.371915) (xy 409.965637 -223.405146) (xy 410.001889 -223.444217) (xy 410.031913 -223.488254)
			(xy 410.055039 -223.536275) (xy 410.070749 -223.587205) (xy 410.078692 -223.639909) (xy 410.07919 -223.666558)
			(xy 410.078692 -223.693207) (xy 424.480472 -223.693207) (xy 424.480472 -223.639909) (xy 424.488415 -223.587205)
			(xy 424.504125 -223.536275) (xy 424.527251 -223.488254) (xy 424.557275 -223.444217) (xy 424.593527 -223.405146)
			(xy 424.635198 -223.371915) (xy 424.681356 -223.345266) (xy 424.73097 -223.325794) (xy 424.782932 -223.313934)
			(xy 424.836082 -223.309951) (xy 424.889232 -223.313934) (xy 424.941194 -223.325794) (xy 424.990808 -223.345266)
			(xy 425.036966 -223.371915) (xy 425.078637 -223.405146) (xy 425.114889 -223.444217) (xy 425.144913 -223.488254)
			(xy 425.168039 -223.536275) (xy 425.183749 -223.587205) (xy 425.191692 -223.639909) (xy 425.19219 -223.666558)
			(xy 425.191692 -223.693207) (xy 439.568072 -223.693207) (xy 439.568072 -223.639909) (xy 439.576015 -223.587205)
			(xy 439.591725 -223.536275) (xy 439.614851 -223.488254) (xy 439.644875 -223.444217) (xy 439.681127 -223.405146)
			(xy 439.722798 -223.371915) (xy 439.768956 -223.345266) (xy 439.81857 -223.325794) (xy 439.870532 -223.313934)
			(xy 439.923682 -223.309951) (xy 439.976832 -223.313934) (xy 440.028794 -223.325794) (xy 440.078408 -223.345266)
			(xy 440.124566 -223.371915) (xy 440.166237 -223.405146) (xy 440.202489 -223.444217) (xy 440.232513 -223.488254)
			(xy 440.255639 -223.536275) (xy 440.271349 -223.587205) (xy 440.279292 -223.639909) (xy 440.27979 -223.666558)
			(xy 440.279292 -223.693207) (xy 454.655672 -223.693207) (xy 454.655672 -223.639909) (xy 454.663615 -223.587205)
			(xy 454.679325 -223.536275) (xy 454.702451 -223.488254) (xy 454.732475 -223.444217) (xy 454.768727 -223.405146)
			(xy 454.810398 -223.371915) (xy 454.856556 -223.345266) (xy 454.90617 -223.325794) (xy 454.958132 -223.313934)
			(xy 455.011282 -223.309951) (xy 455.064432 -223.313934) (xy 455.116394 -223.325794) (xy 455.166008 -223.345266)
			(xy 455.212166 -223.371915) (xy 455.253837 -223.405146) (xy 455.290089 -223.444217) (xy 455.320113 -223.488254)
			(xy 455.343239 -223.536275) (xy 455.358949 -223.587205) (xy 455.366892 -223.639909) (xy 455.36739 -223.666558)
			(xy 455.366892 -223.693207) (xy 455.358949 -223.745911) (xy 455.343239 -223.796841) (xy 455.320113 -223.844862)
			(xy 455.290089 -223.888899) (xy 455.253837 -223.92797) (xy 455.212166 -223.961201) (xy 455.166008 -223.98785)
			(xy 455.116394 -224.007322) (xy 455.064432 -224.019182) (xy 455.011282 -224.023166) (xy 454.958132 -224.019182)
			(xy 454.90617 -224.007322) (xy 454.856556 -223.98785) (xy 454.810398 -223.961201) (xy 454.768727 -223.92797)
			(xy 454.732475 -223.888899) (xy 454.702451 -223.844862) (xy 454.679325 -223.796841) (xy 454.663615 -223.745911)
			(xy 454.655672 -223.693207) (xy 440.279292 -223.693207) (xy 440.271349 -223.745911) (xy 440.255639 -223.796841)
			(xy 440.232513 -223.844862) (xy 440.202489 -223.888899) (xy 440.166237 -223.92797) (xy 440.124566 -223.961201)
			(xy 440.078408 -223.98785) (xy 440.028794 -224.007322) (xy 439.976832 -224.019182) (xy 439.923682 -224.023166)
			(xy 439.870532 -224.019182) (xy 439.81857 -224.007322) (xy 439.768956 -223.98785) (xy 439.722798 -223.961201)
			(xy 439.681127 -223.92797) (xy 439.644875 -223.888899) (xy 439.614851 -223.844862) (xy 439.591725 -223.796841)
			(xy 439.576015 -223.745911) (xy 439.568072 -223.693207) (xy 425.191692 -223.693207) (xy 425.183749 -223.745911)
			(xy 425.168039 -223.796841) (xy 425.144913 -223.844862) (xy 425.114889 -223.888899) (xy 425.078637 -223.92797)
			(xy 425.036966 -223.961201) (xy 424.990808 -223.98785) (xy 424.941194 -224.007322) (xy 424.889232 -224.019182)
			(xy 424.836082 -224.023166) (xy 424.782932 -224.019182) (xy 424.73097 -224.007322) (xy 424.681356 -223.98785)
			(xy 424.635198 -223.961201) (xy 424.593527 -223.92797) (xy 424.557275 -223.888899) (xy 424.527251 -223.844862)
			(xy 424.504125 -223.796841) (xy 424.488415 -223.745911) (xy 424.480472 -223.693207) (xy 410.078692 -223.693207)
			(xy 410.070749 -223.745911) (xy 410.055039 -223.796841) (xy 410.031913 -223.844862) (xy 410.001889 -223.888899)
			(xy 409.965637 -223.92797) (xy 409.923966 -223.961201) (xy 409.877808 -223.98785) (xy 409.828194 -224.007322)
			(xy 409.776232 -224.019182) (xy 409.723082 -224.023166) (xy 409.669932 -224.019182) (xy 409.61797 -224.007322)
			(xy 409.568356 -223.98785) (xy 409.522198 -223.961201) (xy 409.480527 -223.92797) (xy 409.444275 -223.888899)
			(xy 409.414251 -223.844862) (xy 409.391125 -223.796841) (xy 409.375415 -223.745911) (xy 409.367472 -223.693207)
			(xy 407.4668 -223.693207) (xy 407.4668 -224.543345) (xy 420.380404 -224.543345) (xy 420.380404 -224.490047)
			(xy 420.388347 -224.437343) (xy 420.404057 -224.386413) (xy 420.427183 -224.338392) (xy 420.457207 -224.294355)
			(xy 420.493459 -224.255284) (xy 420.53513 -224.222053) (xy 420.581288 -224.195404) (xy 420.630902 -224.175932)
			(xy 420.682864 -224.164072) (xy 420.736014 -224.160089) (xy 420.789164 -224.164072) (xy 420.841126 -224.175932)
			(xy 420.89074 -224.195404) (xy 420.936898 -224.222053) (xy 420.978569 -224.255284) (xy 421.014821 -224.294355)
			(xy 421.044845 -224.338392) (xy 421.067971 -224.386413) (xy 421.083681 -224.437343) (xy 421.091624 -224.490047)
			(xy 421.092122 -224.516696) (xy 421.091624 -224.543345) (xy 435.468004 -224.543345) (xy 435.468004 -224.490047)
			(xy 435.475947 -224.437343) (xy 435.491657 -224.386413) (xy 435.514783 -224.338392) (xy 435.544807 -224.294355)
			(xy 435.581059 -224.255284) (xy 435.62273 -224.222053) (xy 435.668888 -224.195404) (xy 435.718502 -224.175932)
			(xy 435.770464 -224.164072) (xy 435.823614 -224.160089) (xy 435.876764 -224.164072) (xy 435.928726 -224.175932)
			(xy 435.97834 -224.195404) (xy 436.024498 -224.222053) (xy 436.066169 -224.255284) (xy 436.102421 -224.294355)
			(xy 436.132445 -224.338392) (xy 436.155571 -224.386413) (xy 436.171281 -224.437343) (xy 436.179224 -224.490047)
			(xy 436.179722 -224.516696) (xy 436.179224 -224.543345) (xy 450.555604 -224.543345) (xy 450.555604 -224.490047)
			(xy 450.563547 -224.437343) (xy 450.579257 -224.386413) (xy 450.602383 -224.338392) (xy 450.632407 -224.294355)
			(xy 450.668659 -224.255284) (xy 450.71033 -224.222053) (xy 450.756488 -224.195404) (xy 450.806102 -224.175932)
			(xy 450.858064 -224.164072) (xy 450.911214 -224.160089) (xy 450.964364 -224.164072) (xy 451.016326 -224.175932)
			(xy 451.06594 -224.195404) (xy 451.112098 -224.222053) (xy 451.153769 -224.255284) (xy 451.190021 -224.294355)
			(xy 451.220045 -224.338392) (xy 451.243171 -224.386413) (xy 451.258881 -224.437343) (xy 451.266824 -224.490047)
			(xy 451.267322 -224.516696) (xy 451.266824 -224.543345) (xy 451.258881 -224.596049) (xy 451.243171 -224.646979)
			(xy 451.220045 -224.695) (xy 451.190021 -224.739037) (xy 451.153769 -224.778108) (xy 451.112098 -224.811339)
			(xy 451.06594 -224.837988) (xy 451.016326 -224.85746) (xy 450.964364 -224.86932) (xy 450.911214 -224.873304)
			(xy 450.858064 -224.86932) (xy 450.806102 -224.85746) (xy 450.756488 -224.837988) (xy 450.71033 -224.811339)
			(xy 450.668659 -224.778108) (xy 450.632407 -224.739037) (xy 450.602383 -224.695) (xy 450.579257 -224.646979)
			(xy 450.563547 -224.596049) (xy 450.555604 -224.543345) (xy 436.179224 -224.543345) (xy 436.171281 -224.596049)
			(xy 436.155571 -224.646979) (xy 436.132445 -224.695) (xy 436.102421 -224.739037) (xy 436.066169 -224.778108)
			(xy 436.024498 -224.811339) (xy 435.97834 -224.837988) (xy 435.928726 -224.85746) (xy 435.876764 -224.86932)
			(xy 435.823614 -224.873304) (xy 435.770464 -224.86932) (xy 435.718502 -224.85746) (xy 435.668888 -224.837988)
			(xy 435.62273 -224.811339) (xy 435.581059 -224.778108) (xy 435.544807 -224.739037) (xy 435.514783 -224.695)
			(xy 435.491657 -224.646979) (xy 435.475947 -224.596049) (xy 435.468004 -224.543345) (xy 421.091624 -224.543345)
			(xy 421.083681 -224.596049) (xy 421.067971 -224.646979) (xy 421.044845 -224.695) (xy 421.014821 -224.739037)
			(xy 420.978569 -224.778108) (xy 420.936898 -224.811339) (xy 420.89074 -224.837988) (xy 420.841126 -224.85746)
			(xy 420.789164 -224.86932) (xy 420.736014 -224.873304) (xy 420.682864 -224.86932) (xy 420.630902 -224.85746)
			(xy 420.581288 -224.837988) (xy 420.53513 -224.811339) (xy 420.493459 -224.778108) (xy 420.457207 -224.739037)
			(xy 420.427183 -224.695) (xy 420.404057 -224.646979) (xy 420.388347 -224.596049) (xy 420.380404 -224.543345)
			(xy 407.4668 -224.543345) (xy 407.4668 -225.393229) (xy 409.367472 -225.393229) (xy 409.367472 -225.339931)
			(xy 409.375415 -225.287227) (xy 409.391125 -225.236297) (xy 409.414251 -225.188276) (xy 409.444275 -225.144239)
			(xy 409.480527 -225.105168) (xy 409.522198 -225.071937) (xy 409.568356 -225.045288) (xy 409.61797 -225.025816)
			(xy 409.669932 -225.013956) (xy 409.723082 -225.009973) (xy 409.776232 -225.013956) (xy 409.828194 -225.025816)
			(xy 409.877808 -225.045288) (xy 409.923966 -225.071937) (xy 409.965637 -225.105168) (xy 410.001889 -225.144239)
			(xy 410.031913 -225.188276) (xy 410.055039 -225.236297) (xy 410.070749 -225.287227) (xy 410.078692 -225.339931)
			(xy 410.07919 -225.36658) (xy 410.078692 -225.393229) (xy 424.480472 -225.393229) (xy 424.480472 -225.339931)
			(xy 424.488415 -225.287227) (xy 424.504125 -225.236297) (xy 424.527251 -225.188276) (xy 424.557275 -225.144239)
			(xy 424.593527 -225.105168) (xy 424.635198 -225.071937) (xy 424.681356 -225.045288) (xy 424.73097 -225.025816)
			(xy 424.782932 -225.013956) (xy 424.836082 -225.009973) (xy 424.889232 -225.013956) (xy 424.941194 -225.025816)
			(xy 424.990808 -225.045288) (xy 425.036966 -225.071937) (xy 425.078637 -225.105168) (xy 425.114889 -225.144239)
			(xy 425.144913 -225.188276) (xy 425.168039 -225.236297) (xy 425.183749 -225.287227) (xy 425.191692 -225.339931)
			(xy 425.19219 -225.36658) (xy 425.191692 -225.393229) (xy 439.568072 -225.393229) (xy 439.568072 -225.339931)
			(xy 439.576015 -225.287227) (xy 439.591725 -225.236297) (xy 439.614851 -225.188276) (xy 439.644875 -225.144239)
			(xy 439.681127 -225.105168) (xy 439.722798 -225.071937) (xy 439.768956 -225.045288) (xy 439.81857 -225.025816)
			(xy 439.870532 -225.013956) (xy 439.923682 -225.009973) (xy 439.976832 -225.013956) (xy 440.028794 -225.025816)
			(xy 440.078408 -225.045288) (xy 440.124566 -225.071937) (xy 440.166237 -225.105168) (xy 440.202489 -225.144239)
			(xy 440.232513 -225.188276) (xy 440.255639 -225.236297) (xy 440.271349 -225.287227) (xy 440.279292 -225.339931)
			(xy 440.27979 -225.36658) (xy 440.279292 -225.393229) (xy 454.655672 -225.393229) (xy 454.655672 -225.339931)
			(xy 454.663615 -225.287227) (xy 454.679325 -225.236297) (xy 454.702451 -225.188276) (xy 454.732475 -225.144239)
			(xy 454.768727 -225.105168) (xy 454.810398 -225.071937) (xy 454.856556 -225.045288) (xy 454.90617 -225.025816)
			(xy 454.958132 -225.013956) (xy 455.011282 -225.009973) (xy 455.064432 -225.013956) (xy 455.116394 -225.025816)
			(xy 455.166008 -225.045288) (xy 455.212166 -225.071937) (xy 455.253837 -225.105168) (xy 455.290089 -225.144239)
			(xy 455.320113 -225.188276) (xy 455.343239 -225.236297) (xy 455.358949 -225.287227) (xy 455.366892 -225.339931)
			(xy 455.36739 -225.36658) (xy 455.366892 -225.393229) (xy 455.358949 -225.445933) (xy 455.343239 -225.496863)
			(xy 455.320113 -225.544884) (xy 455.290089 -225.588921) (xy 455.253837 -225.627992) (xy 455.212166 -225.661223)
			(xy 455.166008 -225.687872) (xy 455.116394 -225.707344) (xy 455.064432 -225.719204) (xy 455.011282 -225.723188)
			(xy 454.958132 -225.719204) (xy 454.90617 -225.707344) (xy 454.856556 -225.687872) (xy 454.810398 -225.661223)
			(xy 454.768727 -225.627992) (xy 454.732475 -225.588921) (xy 454.702451 -225.544884) (xy 454.679325 -225.496863)
			(xy 454.663615 -225.445933) (xy 454.655672 -225.393229) (xy 440.279292 -225.393229) (xy 440.271349 -225.445933)
			(xy 440.255639 -225.496863) (xy 440.232513 -225.544884) (xy 440.202489 -225.588921) (xy 440.166237 -225.627992)
			(xy 440.124566 -225.661223) (xy 440.078408 -225.687872) (xy 440.028794 -225.707344) (xy 439.976832 -225.719204)
			(xy 439.923682 -225.723188) (xy 439.870532 -225.719204) (xy 439.81857 -225.707344) (xy 439.768956 -225.687872)
			(xy 439.722798 -225.661223) (xy 439.681127 -225.627992) (xy 439.644875 -225.588921) (xy 439.614851 -225.544884)
			(xy 439.591725 -225.496863) (xy 439.576015 -225.445933) (xy 439.568072 -225.393229) (xy 425.191692 -225.393229)
			(xy 425.183749 -225.445933) (xy 425.168039 -225.496863) (xy 425.144913 -225.544884) (xy 425.114889 -225.588921)
			(xy 425.078637 -225.627992) (xy 425.036966 -225.661223) (xy 424.990808 -225.687872) (xy 424.941194 -225.707344)
			(xy 424.889232 -225.719204) (xy 424.836082 -225.723188) (xy 424.782932 -225.719204) (xy 424.73097 -225.707344)
			(xy 424.681356 -225.687872) (xy 424.635198 -225.661223) (xy 424.593527 -225.627992) (xy 424.557275 -225.588921)
			(xy 424.527251 -225.544884) (xy 424.504125 -225.496863) (xy 424.488415 -225.445933) (xy 424.480472 -225.393229)
			(xy 410.078692 -225.393229) (xy 410.070749 -225.445933) (xy 410.055039 -225.496863) (xy 410.031913 -225.544884)
			(xy 410.001889 -225.588921) (xy 409.965637 -225.627992) (xy 409.923966 -225.661223) (xy 409.877808 -225.687872)
			(xy 409.828194 -225.707344) (xy 409.776232 -225.719204) (xy 409.723082 -225.723188) (xy 409.669932 -225.719204)
			(xy 409.61797 -225.707344) (xy 409.568356 -225.687872) (xy 409.522198 -225.661223) (xy 409.480527 -225.627992)
			(xy 409.444275 -225.588921) (xy 409.414251 -225.544884) (xy 409.391125 -225.496863) (xy 409.375415 -225.445933)
			(xy 409.367472 -225.393229) (xy 407.4668 -225.393229) (xy 407.4668 -226.243367) (xy 420.380404 -226.243367)
			(xy 420.380404 -226.190069) (xy 420.388347 -226.137365) (xy 420.404057 -226.086435) (xy 420.427183 -226.038414)
			(xy 420.457207 -225.994377) (xy 420.493459 -225.955306) (xy 420.53513 -225.922075) (xy 420.581288 -225.895426)
			(xy 420.630902 -225.875954) (xy 420.682864 -225.864094) (xy 420.736014 -225.860111) (xy 420.789164 -225.864094)
			(xy 420.841126 -225.875954) (xy 420.89074 -225.895426) (xy 420.936898 -225.922075) (xy 420.978569 -225.955306)
			(xy 421.014821 -225.994377) (xy 421.044845 -226.038414) (xy 421.067971 -226.086435) (xy 421.083681 -226.137365)
			(xy 421.091624 -226.190069) (xy 421.092122 -226.216718) (xy 421.091624 -226.243367) (xy 435.468004 -226.243367)
			(xy 435.468004 -226.190069) (xy 435.475947 -226.137365) (xy 435.491657 -226.086435) (xy 435.514783 -226.038414)
			(xy 435.544807 -225.994377) (xy 435.581059 -225.955306) (xy 435.62273 -225.922075) (xy 435.668888 -225.895426)
			(xy 435.718502 -225.875954) (xy 435.770464 -225.864094) (xy 435.823614 -225.860111) (xy 435.876764 -225.864094)
			(xy 435.928726 -225.875954) (xy 435.97834 -225.895426) (xy 436.024498 -225.922075) (xy 436.066169 -225.955306)
			(xy 436.102421 -225.994377) (xy 436.132445 -226.038414) (xy 436.155571 -226.086435) (xy 436.171281 -226.137365)
			(xy 436.179224 -226.190069) (xy 436.179722 -226.216718) (xy 436.179224 -226.243367) (xy 450.555604 -226.243367)
			(xy 450.555604 -226.190069) (xy 450.563547 -226.137365) (xy 450.579257 -226.086435) (xy 450.602383 -226.038414)
			(xy 450.632407 -225.994377) (xy 450.668659 -225.955306) (xy 450.71033 -225.922075) (xy 450.756488 -225.895426)
			(xy 450.806102 -225.875954) (xy 450.858064 -225.864094) (xy 450.911214 -225.860111) (xy 450.964364 -225.864094)
			(xy 451.016326 -225.875954) (xy 451.06594 -225.895426) (xy 451.112098 -225.922075) (xy 451.153769 -225.955306)
			(xy 451.190021 -225.994377) (xy 451.220045 -226.038414) (xy 451.243171 -226.086435) (xy 451.258881 -226.137365)
			(xy 451.266824 -226.190069) (xy 451.267322 -226.216718) (xy 451.266824 -226.243367) (xy 451.258881 -226.296071)
			(xy 451.243171 -226.347001) (xy 451.220045 -226.395022) (xy 451.190021 -226.439059) (xy 451.153769 -226.47813)
			(xy 451.112098 -226.511361) (xy 451.06594 -226.53801) (xy 451.016326 -226.557482) (xy 450.964364 -226.569342)
			(xy 450.911214 -226.573326) (xy 450.858064 -226.569342) (xy 450.806102 -226.557482) (xy 450.756488 -226.53801)
			(xy 450.71033 -226.511361) (xy 450.668659 -226.47813) (xy 450.632407 -226.439059) (xy 450.602383 -226.395022)
			(xy 450.579257 -226.347001) (xy 450.563547 -226.296071) (xy 450.555604 -226.243367) (xy 436.179224 -226.243367)
			(xy 436.171281 -226.296071) (xy 436.155571 -226.347001) (xy 436.132445 -226.395022) (xy 436.102421 -226.439059)
			(xy 436.066169 -226.47813) (xy 436.024498 -226.511361) (xy 435.97834 -226.53801) (xy 435.928726 -226.557482)
			(xy 435.876764 -226.569342) (xy 435.823614 -226.573326) (xy 435.770464 -226.569342) (xy 435.718502 -226.557482)
			(xy 435.668888 -226.53801) (xy 435.62273 -226.511361) (xy 435.581059 -226.47813) (xy 435.544807 -226.439059)
			(xy 435.514783 -226.395022) (xy 435.491657 -226.347001) (xy 435.475947 -226.296071) (xy 435.468004 -226.243367)
			(xy 421.091624 -226.243367) (xy 421.083681 -226.296071) (xy 421.067971 -226.347001) (xy 421.044845 -226.395022)
			(xy 421.014821 -226.439059) (xy 420.978569 -226.47813) (xy 420.936898 -226.511361) (xy 420.89074 -226.53801)
			(xy 420.841126 -226.557482) (xy 420.789164 -226.569342) (xy 420.736014 -226.573326) (xy 420.682864 -226.569342)
			(xy 420.630902 -226.557482) (xy 420.581288 -226.53801) (xy 420.53513 -226.511361) (xy 420.493459 -226.47813)
			(xy 420.457207 -226.439059) (xy 420.427183 -226.395022) (xy 420.404057 -226.347001) (xy 420.388347 -226.296071)
			(xy 420.380404 -226.243367) (xy 407.4668 -226.243367) (xy 407.4668 -227.093251) (xy 409.367472 -227.093251)
			(xy 409.367472 -227.039953) (xy 409.375415 -226.987249) (xy 409.391125 -226.936319) (xy 409.414251 -226.888298)
			(xy 409.444275 -226.844261) (xy 409.480527 -226.80519) (xy 409.522198 -226.771959) (xy 409.568356 -226.74531)
			(xy 409.61797 -226.725838) (xy 409.669932 -226.713978) (xy 409.723082 -226.709995) (xy 409.776232 -226.713978)
			(xy 409.828194 -226.725838) (xy 409.877808 -226.74531) (xy 409.923966 -226.771959) (xy 409.965637 -226.80519)
			(xy 410.001889 -226.844261) (xy 410.031913 -226.888298) (xy 410.055039 -226.936319) (xy 410.070749 -226.987249)
			(xy 410.078692 -227.039953) (xy 410.07919 -227.066602) (xy 410.078692 -227.093251) (xy 424.480472 -227.093251)
			(xy 424.480472 -227.039953) (xy 424.488415 -226.987249) (xy 424.504125 -226.936319) (xy 424.527251 -226.888298)
			(xy 424.557275 -226.844261) (xy 424.593527 -226.80519) (xy 424.635198 -226.771959) (xy 424.681356 -226.74531)
			(xy 424.73097 -226.725838) (xy 424.782932 -226.713978) (xy 424.836082 -226.709995) (xy 424.889232 -226.713978)
			(xy 424.941194 -226.725838) (xy 424.990808 -226.74531) (xy 425.036966 -226.771959) (xy 425.078637 -226.80519)
			(xy 425.114889 -226.844261) (xy 425.144913 -226.888298) (xy 425.168039 -226.936319) (xy 425.183749 -226.987249)
			(xy 425.191692 -227.039953) (xy 425.19219 -227.066602) (xy 425.191692 -227.093251) (xy 439.568072 -227.093251)
			(xy 439.568072 -227.039953) (xy 439.576015 -226.987249) (xy 439.591725 -226.936319) (xy 439.614851 -226.888298)
			(xy 439.644875 -226.844261) (xy 439.681127 -226.80519) (xy 439.722798 -226.771959) (xy 439.768956 -226.74531)
			(xy 439.81857 -226.725838) (xy 439.870532 -226.713978) (xy 439.923682 -226.709995) (xy 439.976832 -226.713978)
			(xy 440.028794 -226.725838) (xy 440.078408 -226.74531) (xy 440.124566 -226.771959) (xy 440.166237 -226.80519)
			(xy 440.202489 -226.844261) (xy 440.232513 -226.888298) (xy 440.255639 -226.936319) (xy 440.271349 -226.987249)
			(xy 440.279292 -227.039953) (xy 440.27979 -227.066602) (xy 440.279292 -227.093251) (xy 454.655672 -227.093251)
			(xy 454.655672 -227.039953) (xy 454.663615 -226.987249) (xy 454.679325 -226.936319) (xy 454.702451 -226.888298)
			(xy 454.732475 -226.844261) (xy 454.768727 -226.80519) (xy 454.810398 -226.771959) (xy 454.856556 -226.74531)
			(xy 454.90617 -226.725838) (xy 454.958132 -226.713978) (xy 455.011282 -226.709995) (xy 455.064432 -226.713978)
			(xy 455.116394 -226.725838) (xy 455.166008 -226.74531) (xy 455.212166 -226.771959) (xy 455.253837 -226.80519)
			(xy 455.290089 -226.844261) (xy 455.320113 -226.888298) (xy 455.343239 -226.936319) (xy 455.358949 -226.987249)
			(xy 455.366892 -227.039953) (xy 455.36739 -227.066602) (xy 455.366892 -227.093251) (xy 455.358949 -227.145955)
			(xy 455.343239 -227.196885) (xy 455.320113 -227.244906) (xy 455.290089 -227.288943) (xy 455.253837 -227.328014)
			(xy 455.212166 -227.361245) (xy 455.166008 -227.387894) (xy 455.116394 -227.407366) (xy 455.064432 -227.419226)
			(xy 455.011282 -227.42321) (xy 454.958132 -227.419226) (xy 454.90617 -227.407366) (xy 454.856556 -227.387894)
			(xy 454.810398 -227.361245) (xy 454.768727 -227.328014) (xy 454.732475 -227.288943) (xy 454.702451 -227.244906)
			(xy 454.679325 -227.196885) (xy 454.663615 -227.145955) (xy 454.655672 -227.093251) (xy 440.279292 -227.093251)
			(xy 440.271349 -227.145955) (xy 440.255639 -227.196885) (xy 440.232513 -227.244906) (xy 440.202489 -227.288943)
			(xy 440.166237 -227.328014) (xy 440.124566 -227.361245) (xy 440.078408 -227.387894) (xy 440.028794 -227.407366)
			(xy 439.976832 -227.419226) (xy 439.923682 -227.42321) (xy 439.870532 -227.419226) (xy 439.81857 -227.407366)
			(xy 439.768956 -227.387894) (xy 439.722798 -227.361245) (xy 439.681127 -227.328014) (xy 439.644875 -227.288943)
			(xy 439.614851 -227.244906) (xy 439.591725 -227.196885) (xy 439.576015 -227.145955) (xy 439.568072 -227.093251)
			(xy 425.191692 -227.093251) (xy 425.183749 -227.145955) (xy 425.168039 -227.196885) (xy 425.144913 -227.244906)
			(xy 425.114889 -227.288943) (xy 425.078637 -227.328014) (xy 425.036966 -227.361245) (xy 424.990808 -227.387894)
			(xy 424.941194 -227.407366) (xy 424.889232 -227.419226) (xy 424.836082 -227.42321) (xy 424.782932 -227.419226)
			(xy 424.73097 -227.407366) (xy 424.681356 -227.387894) (xy 424.635198 -227.361245) (xy 424.593527 -227.328014)
			(xy 424.557275 -227.288943) (xy 424.527251 -227.244906) (xy 424.504125 -227.196885) (xy 424.488415 -227.145955)
			(xy 424.480472 -227.093251) (xy 410.078692 -227.093251) (xy 410.070749 -227.145955) (xy 410.055039 -227.196885)
			(xy 410.031913 -227.244906) (xy 410.001889 -227.288943) (xy 409.965637 -227.328014) (xy 409.923966 -227.361245)
			(xy 409.877808 -227.387894) (xy 409.828194 -227.407366) (xy 409.776232 -227.419226) (xy 409.723082 -227.42321)
			(xy 409.669932 -227.419226) (xy 409.61797 -227.407366) (xy 409.568356 -227.387894) (xy 409.522198 -227.361245)
			(xy 409.480527 -227.328014) (xy 409.444275 -227.288943) (xy 409.414251 -227.244906) (xy 409.391125 -227.196885)
			(xy 409.375415 -227.145955) (xy 409.367472 -227.093251) (xy 407.4668 -227.093251) (xy 407.4668 -227.943389)
			(xy 409.367472 -227.943389) (xy 409.367472 -227.890091) (xy 409.375415 -227.837387) (xy 409.391125 -227.786457)
			(xy 409.414251 -227.738436) (xy 409.444275 -227.694399) (xy 409.480527 -227.655328) (xy 409.522198 -227.622097)
			(xy 409.568356 -227.595448) (xy 409.61797 -227.575976) (xy 409.669932 -227.564116) (xy 409.723082 -227.560133)
			(xy 409.776232 -227.564116) (xy 409.828194 -227.575976) (xy 409.877808 -227.595448) (xy 409.923966 -227.622097)
			(xy 409.965637 -227.655328) (xy 410.001889 -227.694399) (xy 410.031913 -227.738436) (xy 410.055039 -227.786457)
			(xy 410.070749 -227.837387) (xy 410.078692 -227.890091) (xy 410.07919 -227.91674) (xy 410.078692 -227.943389)
			(xy 420.380404 -227.943389) (xy 420.380404 -227.890091) (xy 420.388347 -227.837387) (xy 420.404057 -227.786457)
			(xy 420.427183 -227.738436) (xy 420.457207 -227.694399) (xy 420.493459 -227.655328) (xy 420.53513 -227.622097)
			(xy 420.581288 -227.595448) (xy 420.630902 -227.575976) (xy 420.682864 -227.564116) (xy 420.736014 -227.560133)
			(xy 420.789164 -227.564116) (xy 420.841126 -227.575976) (xy 420.89074 -227.595448) (xy 420.936898 -227.622097)
			(xy 420.978569 -227.655328) (xy 421.014821 -227.694399) (xy 421.044845 -227.738436) (xy 421.067971 -227.786457)
			(xy 421.083681 -227.837387) (xy 421.091624 -227.890091) (xy 421.092122 -227.91674) (xy 421.091624 -227.943389)
			(xy 424.480472 -227.943389) (xy 424.480472 -227.890091) (xy 424.488415 -227.837387) (xy 424.504125 -227.786457)
			(xy 424.527251 -227.738436) (xy 424.557275 -227.694399) (xy 424.593527 -227.655328) (xy 424.635198 -227.622097)
			(xy 424.681356 -227.595448) (xy 424.73097 -227.575976) (xy 424.782932 -227.564116) (xy 424.836082 -227.560133)
			(xy 424.889232 -227.564116) (xy 424.941194 -227.575976) (xy 424.990808 -227.595448) (xy 425.036966 -227.622097)
			(xy 425.078637 -227.655328) (xy 425.114889 -227.694399) (xy 425.144913 -227.738436) (xy 425.168039 -227.786457)
			(xy 425.183749 -227.837387) (xy 425.191692 -227.890091) (xy 425.19219 -227.91674) (xy 425.191692 -227.943389)
			(xy 435.468004 -227.943389) (xy 435.468004 -227.890091) (xy 435.475947 -227.837387) (xy 435.491657 -227.786457)
			(xy 435.514783 -227.738436) (xy 435.544807 -227.694399) (xy 435.581059 -227.655328) (xy 435.62273 -227.622097)
			(xy 435.668888 -227.595448) (xy 435.718502 -227.575976) (xy 435.770464 -227.564116) (xy 435.823614 -227.560133)
			(xy 435.876764 -227.564116) (xy 435.928726 -227.575976) (xy 435.97834 -227.595448) (xy 436.024498 -227.622097)
			(xy 436.066169 -227.655328) (xy 436.102421 -227.694399) (xy 436.132445 -227.738436) (xy 436.155571 -227.786457)
			(xy 436.171281 -227.837387) (xy 436.179224 -227.890091) (xy 436.179722 -227.91674) (xy 436.179224 -227.943389)
			(xy 439.568072 -227.943389) (xy 439.568072 -227.890091) (xy 439.576015 -227.837387) (xy 439.591725 -227.786457)
			(xy 439.614851 -227.738436) (xy 439.644875 -227.694399) (xy 439.681127 -227.655328) (xy 439.722798 -227.622097)
			(xy 439.768956 -227.595448) (xy 439.81857 -227.575976) (xy 439.870532 -227.564116) (xy 439.923682 -227.560133)
			(xy 439.976832 -227.564116) (xy 440.028794 -227.575976) (xy 440.078408 -227.595448) (xy 440.124566 -227.622097)
			(xy 440.166237 -227.655328) (xy 440.202489 -227.694399) (xy 440.232513 -227.738436) (xy 440.255639 -227.786457)
			(xy 440.271349 -227.837387) (xy 440.279292 -227.890091) (xy 440.27979 -227.91674) (xy 440.279292 -227.943389)
			(xy 450.555604 -227.943389) (xy 450.555604 -227.890091) (xy 450.563547 -227.837387) (xy 450.579257 -227.786457)
			(xy 450.602383 -227.738436) (xy 450.632407 -227.694399) (xy 450.668659 -227.655328) (xy 450.71033 -227.622097)
			(xy 450.756488 -227.595448) (xy 450.806102 -227.575976) (xy 450.858064 -227.564116) (xy 450.911214 -227.560133)
			(xy 450.964364 -227.564116) (xy 451.016326 -227.575976) (xy 451.06594 -227.595448) (xy 451.112098 -227.622097)
			(xy 451.153769 -227.655328) (xy 451.190021 -227.694399) (xy 451.220045 -227.738436) (xy 451.243171 -227.786457)
			(xy 451.258881 -227.837387) (xy 451.266824 -227.890091) (xy 451.267322 -227.91674) (xy 451.266824 -227.943389)
			(xy 454.655672 -227.943389) (xy 454.655672 -227.890091) (xy 454.663615 -227.837387) (xy 454.679325 -227.786457)
			(xy 454.702451 -227.738436) (xy 454.732475 -227.694399) (xy 454.768727 -227.655328) (xy 454.810398 -227.622097)
			(xy 454.856556 -227.595448) (xy 454.90617 -227.575976) (xy 454.958132 -227.564116) (xy 455.011282 -227.560133)
			(xy 455.064432 -227.564116) (xy 455.116394 -227.575976) (xy 455.166008 -227.595448) (xy 455.212166 -227.622097)
			(xy 455.253837 -227.655328) (xy 455.290089 -227.694399) (xy 455.320113 -227.738436) (xy 455.343239 -227.786457)
			(xy 455.358949 -227.837387) (xy 455.366892 -227.890091) (xy 455.36739 -227.91674) (xy 455.366892 -227.943389)
			(xy 455.358949 -227.996093) (xy 455.343239 -228.047023) (xy 455.320113 -228.095044) (xy 455.290089 -228.139081)
			(xy 455.253837 -228.178152) (xy 455.212166 -228.211383) (xy 455.166008 -228.238032) (xy 455.116394 -228.257504)
			(xy 455.064432 -228.269364) (xy 455.011282 -228.273348) (xy 454.958132 -228.269364) (xy 454.90617 -228.257504)
			(xy 454.856556 -228.238032) (xy 454.810398 -228.211383) (xy 454.768727 -228.178152) (xy 454.732475 -228.139081)
			(xy 454.702451 -228.095044) (xy 454.679325 -228.047023) (xy 454.663615 -227.996093) (xy 454.655672 -227.943389)
			(xy 451.266824 -227.943389) (xy 451.258881 -227.996093) (xy 451.243171 -228.047023) (xy 451.220045 -228.095044)
			(xy 451.190021 -228.139081) (xy 451.153769 -228.178152) (xy 451.112098 -228.211383) (xy 451.06594 -228.238032)
			(xy 451.016326 -228.257504) (xy 450.964364 -228.269364) (xy 450.911214 -228.273348) (xy 450.858064 -228.269364)
			(xy 450.806102 -228.257504) (xy 450.756488 -228.238032) (xy 450.71033 -228.211383) (xy 450.668659 -228.178152)
			(xy 450.632407 -228.139081) (xy 450.602383 -228.095044) (xy 450.579257 -228.047023) (xy 450.563547 -227.996093)
			(xy 450.555604 -227.943389) (xy 440.279292 -227.943389) (xy 440.271349 -227.996093) (xy 440.255639 -228.047023)
			(xy 440.232513 -228.095044) (xy 440.202489 -228.139081) (xy 440.166237 -228.178152) (xy 440.124566 -228.211383)
			(xy 440.078408 -228.238032) (xy 440.028794 -228.257504) (xy 439.976832 -228.269364) (xy 439.923682 -228.273348)
			(xy 439.870532 -228.269364) (xy 439.81857 -228.257504) (xy 439.768956 -228.238032) (xy 439.722798 -228.211383)
			(xy 439.681127 -228.178152) (xy 439.644875 -228.139081) (xy 439.614851 -228.095044) (xy 439.591725 -228.047023)
			(xy 439.576015 -227.996093) (xy 439.568072 -227.943389) (xy 436.179224 -227.943389) (xy 436.171281 -227.996093)
			(xy 436.155571 -228.047023) (xy 436.132445 -228.095044) (xy 436.102421 -228.139081) (xy 436.066169 -228.178152)
			(xy 436.024498 -228.211383) (xy 435.97834 -228.238032) (xy 435.928726 -228.257504) (xy 435.876764 -228.269364)
			(xy 435.823614 -228.273348) (xy 435.770464 -228.269364) (xy 435.718502 -228.257504) (xy 435.668888 -228.238032)
			(xy 435.62273 -228.211383) (xy 435.581059 -228.178152) (xy 435.544807 -228.139081) (xy 435.514783 -228.095044)
			(xy 435.491657 -228.047023) (xy 435.475947 -227.996093) (xy 435.468004 -227.943389) (xy 425.191692 -227.943389)
			(xy 425.183749 -227.996093) (xy 425.168039 -228.047023) (xy 425.144913 -228.095044) (xy 425.114889 -228.139081)
			(xy 425.078637 -228.178152) (xy 425.036966 -228.211383) (xy 424.990808 -228.238032) (xy 424.941194 -228.257504)
			(xy 424.889232 -228.269364) (xy 424.836082 -228.273348) (xy 424.782932 -228.269364) (xy 424.73097 -228.257504)
			(xy 424.681356 -228.238032) (xy 424.635198 -228.211383) (xy 424.593527 -228.178152) (xy 424.557275 -228.139081)
			(xy 424.527251 -228.095044) (xy 424.504125 -228.047023) (xy 424.488415 -227.996093) (xy 424.480472 -227.943389)
			(xy 421.091624 -227.943389) (xy 421.083681 -227.996093) (xy 421.067971 -228.047023) (xy 421.044845 -228.095044)
			(xy 421.014821 -228.139081) (xy 420.978569 -228.178152) (xy 420.936898 -228.211383) (xy 420.89074 -228.238032)
			(xy 420.841126 -228.257504) (xy 420.789164 -228.269364) (xy 420.736014 -228.273348) (xy 420.682864 -228.269364)
			(xy 420.630902 -228.257504) (xy 420.581288 -228.238032) (xy 420.53513 -228.211383) (xy 420.493459 -228.178152)
			(xy 420.457207 -228.139081) (xy 420.427183 -228.095044) (xy 420.404057 -228.047023) (xy 420.388347 -227.996093)
			(xy 420.380404 -227.943389) (xy 410.078692 -227.943389) (xy 410.070749 -227.996093) (xy 410.055039 -228.047023)
			(xy 410.031913 -228.095044) (xy 410.001889 -228.139081) (xy 409.965637 -228.178152) (xy 409.923966 -228.211383)
			(xy 409.877808 -228.238032) (xy 409.828194 -228.257504) (xy 409.776232 -228.269364) (xy 409.723082 -228.273348)
			(xy 409.669932 -228.269364) (xy 409.61797 -228.257504) (xy 409.568356 -228.238032) (xy 409.522198 -228.211383)
			(xy 409.480527 -228.178152) (xy 409.444275 -228.139081) (xy 409.414251 -228.095044) (xy 409.391125 -228.047023)
			(xy 409.375415 -227.996093) (xy 409.367472 -227.943389) (xy 407.4668 -227.943389) (xy 407.4668 -228.793273)
			(xy 420.380404 -228.793273) (xy 420.380404 -228.739975) (xy 420.388347 -228.687271) (xy 420.404057 -228.636341)
			(xy 420.427183 -228.58832) (xy 420.457207 -228.544283) (xy 420.493459 -228.505212) (xy 420.53513 -228.471981)
			(xy 420.581288 -228.445332) (xy 420.630902 -228.42586) (xy 420.682864 -228.414) (xy 420.736014 -228.410017)
			(xy 420.789164 -228.414) (xy 420.841126 -228.42586) (xy 420.89074 -228.445332) (xy 420.936898 -228.471981)
			(xy 420.978569 -228.505212) (xy 421.014821 -228.544283) (xy 421.044845 -228.58832) (xy 421.067971 -228.636341)
			(xy 421.083681 -228.687271) (xy 421.091624 -228.739975) (xy 421.092122 -228.766624) (xy 421.091624 -228.793273)
			(xy 435.468004 -228.793273) (xy 435.468004 -228.739975) (xy 435.475947 -228.687271) (xy 435.491657 -228.636341)
			(xy 435.514783 -228.58832) (xy 435.544807 -228.544283) (xy 435.581059 -228.505212) (xy 435.62273 -228.471981)
			(xy 435.668888 -228.445332) (xy 435.718502 -228.42586) (xy 435.770464 -228.414) (xy 435.823614 -228.410017)
			(xy 435.876764 -228.414) (xy 435.928726 -228.42586) (xy 435.97834 -228.445332) (xy 436.024498 -228.471981)
			(xy 436.066169 -228.505212) (xy 436.102421 -228.544283) (xy 436.132445 -228.58832) (xy 436.155571 -228.636341)
			(xy 436.171281 -228.687271) (xy 436.179224 -228.739975) (xy 436.179722 -228.766624) (xy 436.179224 -228.793273)
			(xy 450.555604 -228.793273) (xy 450.555604 -228.739975) (xy 450.563547 -228.687271) (xy 450.579257 -228.636341)
			(xy 450.602383 -228.58832) (xy 450.632407 -228.544283) (xy 450.668659 -228.505212) (xy 450.71033 -228.471981)
			(xy 450.756488 -228.445332) (xy 450.806102 -228.42586) (xy 450.858064 -228.414) (xy 450.911214 -228.410017)
			(xy 450.964364 -228.414) (xy 451.016326 -228.42586) (xy 451.06594 -228.445332) (xy 451.112098 -228.471981)
			(xy 451.153769 -228.505212) (xy 451.190021 -228.544283) (xy 451.220045 -228.58832) (xy 451.243171 -228.636341)
			(xy 451.258881 -228.687271) (xy 451.266824 -228.739975) (xy 451.267322 -228.766624) (xy 451.266824 -228.793273)
			(xy 451.258881 -228.845977) (xy 451.243171 -228.896907) (xy 451.220045 -228.944928) (xy 451.190021 -228.988965)
			(xy 451.153769 -229.028036) (xy 451.112098 -229.061267) (xy 451.06594 -229.087916) (xy 451.016326 -229.107388)
			(xy 450.964364 -229.119248) (xy 450.911214 -229.123232) (xy 450.858064 -229.119248) (xy 450.806102 -229.107388)
			(xy 450.756488 -229.087916) (xy 450.71033 -229.061267) (xy 450.668659 -229.028036) (xy 450.632407 -228.988965)
			(xy 450.602383 -228.944928) (xy 450.579257 -228.896907) (xy 450.563547 -228.845977) (xy 450.555604 -228.793273)
			(xy 436.179224 -228.793273) (xy 436.171281 -228.845977) (xy 436.155571 -228.896907) (xy 436.132445 -228.944928)
			(xy 436.102421 -228.988965) (xy 436.066169 -229.028036) (xy 436.024498 -229.061267) (xy 435.97834 -229.087916)
			(xy 435.928726 -229.107388) (xy 435.876764 -229.119248) (xy 435.823614 -229.123232) (xy 435.770464 -229.119248)
			(xy 435.718502 -229.107388) (xy 435.668888 -229.087916) (xy 435.62273 -229.061267) (xy 435.581059 -229.028036)
			(xy 435.544807 -228.988965) (xy 435.514783 -228.944928) (xy 435.491657 -228.896907) (xy 435.475947 -228.845977)
			(xy 435.468004 -228.793273) (xy 421.091624 -228.793273) (xy 421.083681 -228.845977) (xy 421.067971 -228.896907)
			(xy 421.044845 -228.944928) (xy 421.014821 -228.988965) (xy 420.978569 -229.028036) (xy 420.936898 -229.061267)
			(xy 420.89074 -229.087916) (xy 420.841126 -229.107388) (xy 420.789164 -229.119248) (xy 420.736014 -229.123232)
			(xy 420.682864 -229.119248) (xy 420.630902 -229.107388) (xy 420.581288 -229.087916) (xy 420.53513 -229.061267)
			(xy 420.493459 -229.028036) (xy 420.457207 -228.988965) (xy 420.427183 -228.944928) (xy 420.404057 -228.896907)
			(xy 420.388347 -228.845977) (xy 420.380404 -228.793273) (xy 407.4668 -228.793273) (xy 407.4668 -229.643411)
			(xy 409.367472 -229.643411) (xy 409.367472 -229.590113) (xy 409.375415 -229.537409) (xy 409.391125 -229.486479)
			(xy 409.414251 -229.438458) (xy 409.444275 -229.394421) (xy 409.480527 -229.35535) (xy 409.522198 -229.322119)
			(xy 409.568356 -229.29547) (xy 409.61797 -229.275998) (xy 409.669932 -229.264138) (xy 409.723082 -229.260155)
			(xy 409.776232 -229.264138) (xy 409.828194 -229.275998) (xy 409.877808 -229.29547) (xy 409.923966 -229.322119)
			(xy 409.965637 -229.35535) (xy 410.001889 -229.394421) (xy 410.031913 -229.438458) (xy 410.055039 -229.486479)
			(xy 410.070749 -229.537409) (xy 410.078692 -229.590113) (xy 410.07919 -229.616762) (xy 410.078692 -229.643411)
			(xy 424.480472 -229.643411) (xy 424.480472 -229.590113) (xy 424.488415 -229.537409) (xy 424.504125 -229.486479)
			(xy 424.527251 -229.438458) (xy 424.557275 -229.394421) (xy 424.593527 -229.35535) (xy 424.635198 -229.322119)
			(xy 424.681356 -229.29547) (xy 424.73097 -229.275998) (xy 424.782932 -229.264138) (xy 424.836082 -229.260155)
			(xy 424.889232 -229.264138) (xy 424.941194 -229.275998) (xy 424.990808 -229.29547) (xy 425.036966 -229.322119)
			(xy 425.078637 -229.35535) (xy 425.114889 -229.394421) (xy 425.144913 -229.438458) (xy 425.168039 -229.486479)
			(xy 425.183749 -229.537409) (xy 425.191692 -229.590113) (xy 425.19219 -229.616762) (xy 425.191692 -229.643411)
			(xy 439.568072 -229.643411) (xy 439.568072 -229.590113) (xy 439.576015 -229.537409) (xy 439.591725 -229.486479)
			(xy 439.614851 -229.438458) (xy 439.644875 -229.394421) (xy 439.681127 -229.35535) (xy 439.722798 -229.322119)
			(xy 439.768956 -229.29547) (xy 439.81857 -229.275998) (xy 439.870532 -229.264138) (xy 439.923682 -229.260155)
			(xy 439.976832 -229.264138) (xy 440.028794 -229.275998) (xy 440.078408 -229.29547) (xy 440.124566 -229.322119)
			(xy 440.166237 -229.35535) (xy 440.202489 -229.394421) (xy 440.232513 -229.438458) (xy 440.255639 -229.486479)
			(xy 440.271349 -229.537409) (xy 440.279292 -229.590113) (xy 440.27979 -229.616762) (xy 440.279292 -229.643411)
			(xy 454.655672 -229.643411) (xy 454.655672 -229.590113) (xy 454.663615 -229.537409) (xy 454.679325 -229.486479)
			(xy 454.702451 -229.438458) (xy 454.732475 -229.394421) (xy 454.768727 -229.35535) (xy 454.810398 -229.322119)
			(xy 454.856556 -229.29547) (xy 454.90617 -229.275998) (xy 454.958132 -229.264138) (xy 455.011282 -229.260155)
			(xy 455.064432 -229.264138) (xy 455.116394 -229.275998) (xy 455.166008 -229.29547) (xy 455.212166 -229.322119)
			(xy 455.253837 -229.35535) (xy 455.290089 -229.394421) (xy 455.320113 -229.438458) (xy 455.343239 -229.486479)
			(xy 455.358949 -229.537409) (xy 455.366892 -229.590113) (xy 455.36739 -229.616762) (xy 455.366892 -229.643411)
			(xy 455.358949 -229.696115) (xy 455.343239 -229.747045) (xy 455.320113 -229.795066) (xy 455.290089 -229.839103)
			(xy 455.253837 -229.878174) (xy 455.212166 -229.911405) (xy 455.166008 -229.938054) (xy 455.116394 -229.957526)
			(xy 455.064432 -229.969386) (xy 455.011282 -229.97337) (xy 454.958132 -229.969386) (xy 454.90617 -229.957526)
			(xy 454.856556 -229.938054) (xy 454.810398 -229.911405) (xy 454.768727 -229.878174) (xy 454.732475 -229.839103)
			(xy 454.702451 -229.795066) (xy 454.679325 -229.747045) (xy 454.663615 -229.696115) (xy 454.655672 -229.643411)
			(xy 440.279292 -229.643411) (xy 440.271349 -229.696115) (xy 440.255639 -229.747045) (xy 440.232513 -229.795066)
			(xy 440.202489 -229.839103) (xy 440.166237 -229.878174) (xy 440.124566 -229.911405) (xy 440.078408 -229.938054)
			(xy 440.028794 -229.957526) (xy 439.976832 -229.969386) (xy 439.923682 -229.97337) (xy 439.870532 -229.969386)
			(xy 439.81857 -229.957526) (xy 439.768956 -229.938054) (xy 439.722798 -229.911405) (xy 439.681127 -229.878174)
			(xy 439.644875 -229.839103) (xy 439.614851 -229.795066) (xy 439.591725 -229.747045) (xy 439.576015 -229.696115)
			(xy 439.568072 -229.643411) (xy 425.191692 -229.643411) (xy 425.183749 -229.696115) (xy 425.168039 -229.747045)
			(xy 425.144913 -229.795066) (xy 425.114889 -229.839103) (xy 425.078637 -229.878174) (xy 425.036966 -229.911405)
			(xy 424.990808 -229.938054) (xy 424.941194 -229.957526) (xy 424.889232 -229.969386) (xy 424.836082 -229.97337)
			(xy 424.782932 -229.969386) (xy 424.73097 -229.957526) (xy 424.681356 -229.938054) (xy 424.635198 -229.911405)
			(xy 424.593527 -229.878174) (xy 424.557275 -229.839103) (xy 424.527251 -229.795066) (xy 424.504125 -229.747045)
			(xy 424.488415 -229.696115) (xy 424.480472 -229.643411) (xy 410.078692 -229.643411) (xy 410.070749 -229.696115)
			(xy 410.055039 -229.747045) (xy 410.031913 -229.795066) (xy 410.001889 -229.839103) (xy 409.965637 -229.878174)
			(xy 409.923966 -229.911405) (xy 409.877808 -229.938054) (xy 409.828194 -229.957526) (xy 409.776232 -229.969386)
			(xy 409.723082 -229.97337) (xy 409.669932 -229.969386) (xy 409.61797 -229.957526) (xy 409.568356 -229.938054)
			(xy 409.522198 -229.911405) (xy 409.480527 -229.878174) (xy 409.444275 -229.839103) (xy 409.414251 -229.795066)
			(xy 409.391125 -229.747045) (xy 409.375415 -229.696115) (xy 409.367472 -229.643411) (xy 407.4668 -229.643411)
			(xy 407.4668 -230.493295) (xy 420.380404 -230.493295) (xy 420.380404 -230.439997) (xy 420.388347 -230.387293)
			(xy 420.404057 -230.336363) (xy 420.427183 -230.288342) (xy 420.457207 -230.244305) (xy 420.493459 -230.205234)
			(xy 420.53513 -230.172003) (xy 420.581288 -230.145354) (xy 420.630902 -230.125882) (xy 420.682864 -230.114022)
			(xy 420.736014 -230.110039) (xy 420.789164 -230.114022) (xy 420.841126 -230.125882) (xy 420.89074 -230.145354)
			(xy 420.936898 -230.172003) (xy 420.978569 -230.205234) (xy 421.014821 -230.244305) (xy 421.044845 -230.288342)
			(xy 421.067971 -230.336363) (xy 421.083681 -230.387293) (xy 421.091624 -230.439997) (xy 421.092122 -230.466646)
			(xy 421.091624 -230.493295) (xy 435.468004 -230.493295) (xy 435.468004 -230.439997) (xy 435.475947 -230.387293)
			(xy 435.491657 -230.336363) (xy 435.514783 -230.288342) (xy 435.544807 -230.244305) (xy 435.581059 -230.205234)
			(xy 435.62273 -230.172003) (xy 435.668888 -230.145354) (xy 435.718502 -230.125882) (xy 435.770464 -230.114022)
			(xy 435.823614 -230.110039) (xy 435.876764 -230.114022) (xy 435.928726 -230.125882) (xy 435.97834 -230.145354)
			(xy 436.024498 -230.172003) (xy 436.066169 -230.205234) (xy 436.102421 -230.244305) (xy 436.132445 -230.288342)
			(xy 436.155571 -230.336363) (xy 436.171281 -230.387293) (xy 436.179224 -230.439997) (xy 436.179722 -230.466646)
			(xy 436.179224 -230.493295) (xy 450.555604 -230.493295) (xy 450.555604 -230.439997) (xy 450.563547 -230.387293)
			(xy 450.579257 -230.336363) (xy 450.602383 -230.288342) (xy 450.632407 -230.244305) (xy 450.668659 -230.205234)
			(xy 450.71033 -230.172003) (xy 450.756488 -230.145354) (xy 450.806102 -230.125882) (xy 450.858064 -230.114022)
			(xy 450.911214 -230.110039) (xy 450.964364 -230.114022) (xy 451.016326 -230.125882) (xy 451.06594 -230.145354)
			(xy 451.112098 -230.172003) (xy 451.153769 -230.205234) (xy 451.190021 -230.244305) (xy 451.220045 -230.288342)
			(xy 451.243171 -230.336363) (xy 451.258881 -230.387293) (xy 451.266824 -230.439997) (xy 451.267322 -230.466646)
			(xy 451.266824 -230.493295) (xy 451.258881 -230.545999) (xy 451.243171 -230.596929) (xy 451.220045 -230.64495)
			(xy 451.190021 -230.688987) (xy 451.153769 -230.728058) (xy 451.112098 -230.761289) (xy 451.06594 -230.787938)
			(xy 451.016326 -230.80741) (xy 450.964364 -230.81927) (xy 450.911214 -230.823254) (xy 450.858064 -230.81927)
			(xy 450.806102 -230.80741) (xy 450.756488 -230.787938) (xy 450.71033 -230.761289) (xy 450.668659 -230.728058)
			(xy 450.632407 -230.688987) (xy 450.602383 -230.64495) (xy 450.579257 -230.596929) (xy 450.563547 -230.545999)
			(xy 450.555604 -230.493295) (xy 436.179224 -230.493295) (xy 436.171281 -230.545999) (xy 436.155571 -230.596929)
			(xy 436.132445 -230.64495) (xy 436.102421 -230.688987) (xy 436.066169 -230.728058) (xy 436.024498 -230.761289)
			(xy 435.97834 -230.787938) (xy 435.928726 -230.80741) (xy 435.876764 -230.81927) (xy 435.823614 -230.823254)
			(xy 435.770464 -230.81927) (xy 435.718502 -230.80741) (xy 435.668888 -230.787938) (xy 435.62273 -230.761289)
			(xy 435.581059 -230.728058) (xy 435.544807 -230.688987) (xy 435.514783 -230.64495) (xy 435.491657 -230.596929)
			(xy 435.475947 -230.545999) (xy 435.468004 -230.493295) (xy 421.091624 -230.493295) (xy 421.083681 -230.545999)
			(xy 421.067971 -230.596929) (xy 421.044845 -230.64495) (xy 421.014821 -230.688987) (xy 420.978569 -230.728058)
			(xy 420.936898 -230.761289) (xy 420.89074 -230.787938) (xy 420.841126 -230.80741) (xy 420.789164 -230.81927)
			(xy 420.736014 -230.823254) (xy 420.682864 -230.81927) (xy 420.630902 -230.80741) (xy 420.581288 -230.787938)
			(xy 420.53513 -230.761289) (xy 420.493459 -230.728058) (xy 420.457207 -230.688987) (xy 420.427183 -230.64495)
			(xy 420.404057 -230.596929) (xy 420.388347 -230.545999) (xy 420.380404 -230.493295) (xy 407.4668 -230.493295)
			(xy 407.4668 -231.343433) (xy 409.367472 -231.343433) (xy 409.367472 -231.290135) (xy 409.375415 -231.237431)
			(xy 409.391125 -231.186501) (xy 409.414251 -231.13848) (xy 409.444275 -231.094443) (xy 409.480527 -231.055372)
			(xy 409.522198 -231.022141) (xy 409.568356 -230.995492) (xy 409.61797 -230.97602) (xy 409.669932 -230.96416)
			(xy 409.723082 -230.960177) (xy 409.776232 -230.96416) (xy 409.828194 -230.97602) (xy 409.877808 -230.995492)
			(xy 409.923966 -231.022141) (xy 409.965637 -231.055372) (xy 410.001889 -231.094443) (xy 410.031913 -231.13848)
			(xy 410.055039 -231.186501) (xy 410.070749 -231.237431) (xy 410.078692 -231.290135) (xy 410.07919 -231.316784)
			(xy 410.078692 -231.343433) (xy 424.480472 -231.343433) (xy 424.480472 -231.290135) (xy 424.488415 -231.237431)
			(xy 424.504125 -231.186501) (xy 424.527251 -231.13848) (xy 424.557275 -231.094443) (xy 424.593527 -231.055372)
			(xy 424.635198 -231.022141) (xy 424.681356 -230.995492) (xy 424.73097 -230.97602) (xy 424.782932 -230.96416)
			(xy 424.836082 -230.960177) (xy 424.889232 -230.96416) (xy 424.941194 -230.97602) (xy 424.990808 -230.995492)
			(xy 425.036966 -231.022141) (xy 425.078637 -231.055372) (xy 425.114889 -231.094443) (xy 425.144913 -231.13848)
			(xy 425.168039 -231.186501) (xy 425.183749 -231.237431) (xy 425.191692 -231.290135) (xy 425.19219 -231.316784)
			(xy 425.191692 -231.343433) (xy 439.568072 -231.343433) (xy 439.568072 -231.290135) (xy 439.576015 -231.237431)
			(xy 439.591725 -231.186501) (xy 439.614851 -231.13848) (xy 439.644875 -231.094443) (xy 439.681127 -231.055372)
			(xy 439.722798 -231.022141) (xy 439.768956 -230.995492) (xy 439.81857 -230.97602) (xy 439.870532 -230.96416)
			(xy 439.923682 -230.960177) (xy 439.976832 -230.96416) (xy 440.028794 -230.97602) (xy 440.078408 -230.995492)
			(xy 440.124566 -231.022141) (xy 440.166237 -231.055372) (xy 440.202489 -231.094443) (xy 440.232513 -231.13848)
			(xy 440.255639 -231.186501) (xy 440.271349 -231.237431) (xy 440.279292 -231.290135) (xy 440.27979 -231.316784)
			(xy 440.279292 -231.343433) (xy 454.655672 -231.343433) (xy 454.655672 -231.290135) (xy 454.663615 -231.237431)
			(xy 454.679325 -231.186501) (xy 454.702451 -231.13848) (xy 454.732475 -231.094443) (xy 454.768727 -231.055372)
			(xy 454.810398 -231.022141) (xy 454.856556 -230.995492) (xy 454.90617 -230.97602) (xy 454.958132 -230.96416)
			(xy 455.011282 -230.960177) (xy 455.064432 -230.96416) (xy 455.116394 -230.97602) (xy 455.166008 -230.995492)
			(xy 455.212166 -231.022141) (xy 455.253837 -231.055372) (xy 455.290089 -231.094443) (xy 455.320113 -231.13848)
			(xy 455.343239 -231.186501) (xy 455.358949 -231.237431) (xy 455.366892 -231.290135) (xy 455.36739 -231.316784)
			(xy 455.366892 -231.343433) (xy 455.358949 -231.396137) (xy 455.343239 -231.447067) (xy 455.320113 -231.495088)
			(xy 455.290089 -231.539125) (xy 455.253837 -231.578196) (xy 455.212166 -231.611427) (xy 455.166008 -231.638076)
			(xy 455.116394 -231.657548) (xy 455.064432 -231.669408) (xy 455.011282 -231.673392) (xy 454.958132 -231.669408)
			(xy 454.90617 -231.657548) (xy 454.856556 -231.638076) (xy 454.810398 -231.611427) (xy 454.768727 -231.578196)
			(xy 454.732475 -231.539125) (xy 454.702451 -231.495088) (xy 454.679325 -231.447067) (xy 454.663615 -231.396137)
			(xy 454.655672 -231.343433) (xy 440.279292 -231.343433) (xy 440.271349 -231.396137) (xy 440.255639 -231.447067)
			(xy 440.232513 -231.495088) (xy 440.202489 -231.539125) (xy 440.166237 -231.578196) (xy 440.124566 -231.611427)
			(xy 440.078408 -231.638076) (xy 440.028794 -231.657548) (xy 439.976832 -231.669408) (xy 439.923682 -231.673392)
			(xy 439.870532 -231.669408) (xy 439.81857 -231.657548) (xy 439.768956 -231.638076) (xy 439.722798 -231.611427)
			(xy 439.681127 -231.578196) (xy 439.644875 -231.539125) (xy 439.614851 -231.495088) (xy 439.591725 -231.447067)
			(xy 439.576015 -231.396137) (xy 439.568072 -231.343433) (xy 425.191692 -231.343433) (xy 425.183749 -231.396137)
			(xy 425.168039 -231.447067) (xy 425.144913 -231.495088) (xy 425.114889 -231.539125) (xy 425.078637 -231.578196)
			(xy 425.036966 -231.611427) (xy 424.990808 -231.638076) (xy 424.941194 -231.657548) (xy 424.889232 -231.669408)
			(xy 424.836082 -231.673392) (xy 424.782932 -231.669408) (xy 424.73097 -231.657548) (xy 424.681356 -231.638076)
			(xy 424.635198 -231.611427) (xy 424.593527 -231.578196) (xy 424.557275 -231.539125) (xy 424.527251 -231.495088)
			(xy 424.504125 -231.447067) (xy 424.488415 -231.396137) (xy 424.480472 -231.343433) (xy 410.078692 -231.343433)
			(xy 410.070749 -231.396137) (xy 410.055039 -231.447067) (xy 410.031913 -231.495088) (xy 410.001889 -231.539125)
			(xy 409.965637 -231.578196) (xy 409.923966 -231.611427) (xy 409.877808 -231.638076) (xy 409.828194 -231.657548)
			(xy 409.776232 -231.669408) (xy 409.723082 -231.673392) (xy 409.669932 -231.669408) (xy 409.61797 -231.657548)
			(xy 409.568356 -231.638076) (xy 409.522198 -231.611427) (xy 409.480527 -231.578196) (xy 409.444275 -231.539125)
			(xy 409.414251 -231.495088) (xy 409.391125 -231.447067) (xy 409.375415 -231.396137) (xy 409.367472 -231.343433)
			(xy 407.4668 -231.343433) (xy 407.4668 -232.193317) (xy 420.380404 -232.193317) (xy 420.380404 -232.140019)
			(xy 420.388347 -232.087315) (xy 420.404057 -232.036385) (xy 420.427183 -231.988364) (xy 420.457207 -231.944327)
			(xy 420.493459 -231.905256) (xy 420.53513 -231.872025) (xy 420.581288 -231.845376) (xy 420.630902 -231.825904)
			(xy 420.682864 -231.814044) (xy 420.736014 -231.810061) (xy 420.789164 -231.814044) (xy 420.841126 -231.825904)
			(xy 420.89074 -231.845376) (xy 420.936898 -231.872025) (xy 420.978569 -231.905256) (xy 421.014821 -231.944327)
			(xy 421.044845 -231.988364) (xy 421.067971 -232.036385) (xy 421.083681 -232.087315) (xy 421.091624 -232.140019)
			(xy 421.092122 -232.166668) (xy 421.091624 -232.193317) (xy 435.468004 -232.193317) (xy 435.468004 -232.140019)
			(xy 435.475947 -232.087315) (xy 435.491657 -232.036385) (xy 435.514783 -231.988364) (xy 435.544807 -231.944327)
			(xy 435.581059 -231.905256) (xy 435.62273 -231.872025) (xy 435.668888 -231.845376) (xy 435.718502 -231.825904)
			(xy 435.770464 -231.814044) (xy 435.823614 -231.810061) (xy 435.876764 -231.814044) (xy 435.928726 -231.825904)
			(xy 435.97834 -231.845376) (xy 436.024498 -231.872025) (xy 436.066169 -231.905256) (xy 436.102421 -231.944327)
			(xy 436.132445 -231.988364) (xy 436.155571 -232.036385) (xy 436.171281 -232.087315) (xy 436.179224 -232.140019)
			(xy 436.179722 -232.166668) (xy 436.179224 -232.193317) (xy 450.555604 -232.193317) (xy 450.555604 -232.140019)
			(xy 450.563547 -232.087315) (xy 450.579257 -232.036385) (xy 450.602383 -231.988364) (xy 450.632407 -231.944327)
			(xy 450.668659 -231.905256) (xy 450.71033 -231.872025) (xy 450.756488 -231.845376) (xy 450.806102 -231.825904)
			(xy 450.858064 -231.814044) (xy 450.911214 -231.810061) (xy 450.964364 -231.814044) (xy 451.016326 -231.825904)
			(xy 451.06594 -231.845376) (xy 451.112098 -231.872025) (xy 451.153769 -231.905256) (xy 451.190021 -231.944327)
			(xy 451.220045 -231.988364) (xy 451.243171 -232.036385) (xy 451.258881 -232.087315) (xy 451.266824 -232.140019)
			(xy 451.267322 -232.166668) (xy 451.266824 -232.193317) (xy 451.258881 -232.246021) (xy 451.243171 -232.296951)
			(xy 451.220045 -232.344972) (xy 451.190021 -232.389009) (xy 451.153769 -232.42808) (xy 451.112098 -232.461311)
			(xy 451.06594 -232.48796) (xy 451.016326 -232.507432) (xy 450.964364 -232.519292) (xy 450.911214 -232.523276)
			(xy 450.858064 -232.519292) (xy 450.806102 -232.507432) (xy 450.756488 -232.48796) (xy 450.71033 -232.461311)
			(xy 450.668659 -232.42808) (xy 450.632407 -232.389009) (xy 450.602383 -232.344972) (xy 450.579257 -232.296951)
			(xy 450.563547 -232.246021) (xy 450.555604 -232.193317) (xy 436.179224 -232.193317) (xy 436.171281 -232.246021)
			(xy 436.155571 -232.296951) (xy 436.132445 -232.344972) (xy 436.102421 -232.389009) (xy 436.066169 -232.42808)
			(xy 436.024498 -232.461311) (xy 435.97834 -232.48796) (xy 435.928726 -232.507432) (xy 435.876764 -232.519292)
			(xy 435.823614 -232.523276) (xy 435.770464 -232.519292) (xy 435.718502 -232.507432) (xy 435.668888 -232.48796)
			(xy 435.62273 -232.461311) (xy 435.581059 -232.42808) (xy 435.544807 -232.389009) (xy 435.514783 -232.344972)
			(xy 435.491657 -232.296951) (xy 435.475947 -232.246021) (xy 435.468004 -232.193317) (xy 421.091624 -232.193317)
			(xy 421.083681 -232.246021) (xy 421.067971 -232.296951) (xy 421.044845 -232.344972) (xy 421.014821 -232.389009)
			(xy 420.978569 -232.42808) (xy 420.936898 -232.461311) (xy 420.89074 -232.48796) (xy 420.841126 -232.507432)
			(xy 420.789164 -232.519292) (xy 420.736014 -232.523276) (xy 420.682864 -232.519292) (xy 420.630902 -232.507432)
			(xy 420.581288 -232.48796) (xy 420.53513 -232.461311) (xy 420.493459 -232.42808) (xy 420.457207 -232.389009)
			(xy 420.427183 -232.344972) (xy 420.404057 -232.296951) (xy 420.388347 -232.246021) (xy 420.380404 -232.193317)
			(xy 407.4668 -232.193317) (xy 407.4668 -233.043455) (xy 424.480472 -233.043455) (xy 424.480472 -232.990157)
			(xy 424.488415 -232.937453) (xy 424.504125 -232.886523) (xy 424.527251 -232.838502) (xy 424.557275 -232.794465)
			(xy 424.593527 -232.755394) (xy 424.635198 -232.722163) (xy 424.681356 -232.695514) (xy 424.73097 -232.676042)
			(xy 424.782932 -232.664182) (xy 424.836082 -232.660199) (xy 424.889232 -232.664182) (xy 424.941194 -232.676042)
			(xy 424.990808 -232.695514) (xy 425.036966 -232.722163) (xy 425.078637 -232.755394) (xy 425.114889 -232.794465)
			(xy 425.144913 -232.838502) (xy 425.168039 -232.886523) (xy 425.183749 -232.937453) (xy 425.191692 -232.990157)
			(xy 425.19219 -233.016806) (xy 425.191692 -233.043455) (xy 439.568072 -233.043455) (xy 439.568072 -232.990157)
			(xy 439.576015 -232.937453) (xy 439.591725 -232.886523) (xy 439.614851 -232.838502) (xy 439.644875 -232.794465)
			(xy 439.681127 -232.755394) (xy 439.722798 -232.722163) (xy 439.768956 -232.695514) (xy 439.81857 -232.676042)
			(xy 439.870532 -232.664182) (xy 439.923682 -232.660199) (xy 439.976832 -232.664182) (xy 440.028794 -232.676042)
			(xy 440.078408 -232.695514) (xy 440.124566 -232.722163) (xy 440.166237 -232.755394) (xy 440.202489 -232.794465)
			(xy 440.232513 -232.838502) (xy 440.255639 -232.886523) (xy 440.271349 -232.937453) (xy 440.279292 -232.990157)
			(xy 440.27979 -233.016806) (xy 440.279292 -233.043455) (xy 454.655672 -233.043455) (xy 454.655672 -232.990157)
			(xy 454.663615 -232.937453) (xy 454.679325 -232.886523) (xy 454.702451 -232.838502) (xy 454.732475 -232.794465)
			(xy 454.768727 -232.755394) (xy 454.810398 -232.722163) (xy 454.856556 -232.695514) (xy 454.90617 -232.676042)
			(xy 454.958132 -232.664182) (xy 455.011282 -232.660199) (xy 455.064432 -232.664182) (xy 455.116394 -232.676042)
			(xy 455.166008 -232.695514) (xy 455.212166 -232.722163) (xy 455.253837 -232.755394) (xy 455.290089 -232.794465)
			(xy 455.320113 -232.838502) (xy 455.343239 -232.886523) (xy 455.358949 -232.937453) (xy 455.366892 -232.990157)
			(xy 455.36739 -233.016806) (xy 455.366892 -233.043455) (xy 455.358949 -233.096159) (xy 455.343239 -233.147089)
			(xy 455.320113 -233.19511) (xy 455.290089 -233.239147) (xy 455.253837 -233.278218) (xy 455.212166 -233.311449)
			(xy 455.166008 -233.338098) (xy 455.116394 -233.35757) (xy 455.064432 -233.36943) (xy 455.011282 -233.373414)
			(xy 454.958132 -233.36943) (xy 454.90617 -233.35757) (xy 454.856556 -233.338098) (xy 454.810398 -233.311449)
			(xy 454.768727 -233.278218) (xy 454.732475 -233.239147) (xy 454.702451 -233.19511) (xy 454.679325 -233.147089)
			(xy 454.663615 -233.096159) (xy 454.655672 -233.043455) (xy 440.279292 -233.043455) (xy 440.271349 -233.096159)
			(xy 440.255639 -233.147089) (xy 440.232513 -233.19511) (xy 440.202489 -233.239147) (xy 440.166237 -233.278218)
			(xy 440.124566 -233.311449) (xy 440.078408 -233.338098) (xy 440.028794 -233.35757) (xy 439.976832 -233.36943)
			(xy 439.923682 -233.373414) (xy 439.870532 -233.36943) (xy 439.81857 -233.35757) (xy 439.768956 -233.338098)
			(xy 439.722798 -233.311449) (xy 439.681127 -233.278218) (xy 439.644875 -233.239147) (xy 439.614851 -233.19511)
			(xy 439.591725 -233.147089) (xy 439.576015 -233.096159) (xy 439.568072 -233.043455) (xy 425.191692 -233.043455)
			(xy 425.183749 -233.096159) (xy 425.168039 -233.147089) (xy 425.144913 -233.19511) (xy 425.114889 -233.239147)
			(xy 425.078637 -233.278218) (xy 425.036966 -233.311449) (xy 424.990808 -233.338098) (xy 424.941194 -233.35757)
			(xy 424.889232 -233.36943) (xy 424.836082 -233.373414) (xy 424.782932 -233.36943) (xy 424.73097 -233.35757)
			(xy 424.681356 -233.338098) (xy 424.635198 -233.311449) (xy 424.593527 -233.278218) (xy 424.557275 -233.239147)
			(xy 424.527251 -233.19511) (xy 424.504125 -233.147089) (xy 424.488415 -233.096159) (xy 424.480472 -233.043455)
			(xy 407.4668 -233.043455) (xy 407.4668 -233.893339) (xy 420.380404 -233.893339) (xy 420.380404 -233.840041)
			(xy 420.388347 -233.787337) (xy 420.404057 -233.736407) (xy 420.427183 -233.688386) (xy 420.457207 -233.644349)
			(xy 420.493459 -233.605278) (xy 420.53513 -233.572047) (xy 420.581288 -233.545398) (xy 420.630902 -233.525926)
			(xy 420.682864 -233.514066) (xy 420.736014 -233.510083) (xy 420.789164 -233.514066) (xy 420.841126 -233.525926)
			(xy 420.89074 -233.545398) (xy 420.936898 -233.572047) (xy 420.978569 -233.605278) (xy 421.014821 -233.644349)
			(xy 421.044845 -233.688386) (xy 421.067971 -233.736407) (xy 421.083681 -233.787337) (xy 421.091624 -233.840041)
			(xy 421.092122 -233.86669) (xy 421.091624 -233.893339) (xy 435.468004 -233.893339) (xy 435.468004 -233.840041)
			(xy 435.475947 -233.787337) (xy 435.491657 -233.736407) (xy 435.514783 -233.688386) (xy 435.544807 -233.644349)
			(xy 435.581059 -233.605278) (xy 435.62273 -233.572047) (xy 435.668888 -233.545398) (xy 435.718502 -233.525926)
			(xy 435.770464 -233.514066) (xy 435.823614 -233.510083) (xy 435.876764 -233.514066) (xy 435.928726 -233.525926)
			(xy 435.97834 -233.545398) (xy 436.024498 -233.572047) (xy 436.066169 -233.605278) (xy 436.102421 -233.644349)
			(xy 436.132445 -233.688386) (xy 436.155571 -233.736407) (xy 436.171281 -233.787337) (xy 436.179224 -233.840041)
			(xy 436.179722 -233.86669) (xy 436.179224 -233.893339) (xy 450.555604 -233.893339) (xy 450.555604 -233.840041)
			(xy 450.563547 -233.787337) (xy 450.579257 -233.736407) (xy 450.602383 -233.688386) (xy 450.632407 -233.644349)
			(xy 450.668659 -233.605278) (xy 450.71033 -233.572047) (xy 450.756488 -233.545398) (xy 450.806102 -233.525926)
			(xy 450.858064 -233.514066) (xy 450.911214 -233.510083) (xy 450.964364 -233.514066) (xy 451.016326 -233.525926)
			(xy 451.06594 -233.545398) (xy 451.112098 -233.572047) (xy 451.153769 -233.605278) (xy 451.190021 -233.644349)
			(xy 451.220045 -233.688386) (xy 451.243171 -233.736407) (xy 451.258881 -233.787337) (xy 451.266824 -233.840041)
			(xy 451.267322 -233.86669) (xy 451.266824 -233.893339) (xy 451.258881 -233.946043) (xy 451.243171 -233.996973)
			(xy 451.220045 -234.044994) (xy 451.190021 -234.089031) (xy 451.153769 -234.128102) (xy 451.112098 -234.161333)
			(xy 451.06594 -234.187982) (xy 451.016326 -234.207454) (xy 450.964364 -234.219314) (xy 450.911214 -234.223298)
			(xy 450.858064 -234.219314) (xy 450.806102 -234.207454) (xy 450.756488 -234.187982) (xy 450.71033 -234.161333)
			(xy 450.668659 -234.128102) (xy 450.632407 -234.089031) (xy 450.602383 -234.044994) (xy 450.579257 -233.996973)
			(xy 450.563547 -233.946043) (xy 450.555604 -233.893339) (xy 436.179224 -233.893339) (xy 436.171281 -233.946043)
			(xy 436.155571 -233.996973) (xy 436.132445 -234.044994) (xy 436.102421 -234.089031) (xy 436.066169 -234.128102)
			(xy 436.024498 -234.161333) (xy 435.97834 -234.187982) (xy 435.928726 -234.207454) (xy 435.876764 -234.219314)
			(xy 435.823614 -234.223298) (xy 435.770464 -234.219314) (xy 435.718502 -234.207454) (xy 435.668888 -234.187982)
			(xy 435.62273 -234.161333) (xy 435.581059 -234.128102) (xy 435.544807 -234.089031) (xy 435.514783 -234.044994)
			(xy 435.491657 -233.996973) (xy 435.475947 -233.946043) (xy 435.468004 -233.893339) (xy 421.091624 -233.893339)
			(xy 421.083681 -233.946043) (xy 421.067971 -233.996973) (xy 421.044845 -234.044994) (xy 421.014821 -234.089031)
			(xy 420.978569 -234.128102) (xy 420.936898 -234.161333) (xy 420.89074 -234.187982) (xy 420.841126 -234.207454)
			(xy 420.789164 -234.219314) (xy 420.736014 -234.223298) (xy 420.682864 -234.219314) (xy 420.630902 -234.207454)
			(xy 420.581288 -234.187982) (xy 420.53513 -234.161333) (xy 420.493459 -234.128102) (xy 420.457207 -234.089031)
			(xy 420.427183 -234.044994) (xy 420.404057 -233.996973) (xy 420.388347 -233.946043) (xy 420.380404 -233.893339)
			(xy 407.4668 -233.893339) (xy 407.4668 -234.743223) (xy 424.480472 -234.743223) (xy 424.480472 -234.689925)
			(xy 424.488415 -234.637221) (xy 424.504125 -234.586291) (xy 424.527251 -234.53827) (xy 424.557275 -234.494233)
			(xy 424.593527 -234.455162) (xy 424.635198 -234.421931) (xy 424.681356 -234.395282) (xy 424.73097 -234.37581)
			(xy 424.782932 -234.36395) (xy 424.836082 -234.359967) (xy 424.889232 -234.36395) (xy 424.941194 -234.37581)
			(xy 424.990808 -234.395282) (xy 425.036966 -234.421931) (xy 425.078637 -234.455162) (xy 425.114889 -234.494233)
			(xy 425.144913 -234.53827) (xy 425.168039 -234.586291) (xy 425.183749 -234.637221) (xy 425.191692 -234.689925)
			(xy 425.19219 -234.716574) (xy 425.191692 -234.743223) (xy 439.568072 -234.743223) (xy 439.568072 -234.689925)
			(xy 439.576015 -234.637221) (xy 439.591725 -234.586291) (xy 439.614851 -234.53827) (xy 439.644875 -234.494233)
			(xy 439.681127 -234.455162) (xy 439.722798 -234.421931) (xy 439.768956 -234.395282) (xy 439.81857 -234.37581)
			(xy 439.870532 -234.36395) (xy 439.923682 -234.359967) (xy 439.976832 -234.36395) (xy 440.028794 -234.37581)
			(xy 440.078408 -234.395282) (xy 440.124566 -234.421931) (xy 440.166237 -234.455162) (xy 440.202489 -234.494233)
			(xy 440.232513 -234.53827) (xy 440.255639 -234.586291) (xy 440.271349 -234.637221) (xy 440.279292 -234.689925)
			(xy 440.27979 -234.716574) (xy 440.279292 -234.743223) (xy 454.655672 -234.743223) (xy 454.655672 -234.689925)
			(xy 454.663615 -234.637221) (xy 454.679325 -234.586291) (xy 454.702451 -234.53827) (xy 454.732475 -234.494233)
			(xy 454.768727 -234.455162) (xy 454.810398 -234.421931) (xy 454.856556 -234.395282) (xy 454.90617 -234.37581)
			(xy 454.958132 -234.36395) (xy 455.011282 -234.359967) (xy 455.064432 -234.36395) (xy 455.116394 -234.37581)
			(xy 455.166008 -234.395282) (xy 455.212166 -234.421931) (xy 455.253837 -234.455162) (xy 455.290089 -234.494233)
			(xy 455.320113 -234.53827) (xy 455.343239 -234.586291) (xy 455.358949 -234.637221) (xy 455.366892 -234.689925)
			(xy 455.36739 -234.716574) (xy 455.366892 -234.743223) (xy 455.358949 -234.795927) (xy 455.343239 -234.846857)
			(xy 455.320113 -234.894878) (xy 455.290089 -234.938915) (xy 455.253837 -234.977986) (xy 455.212166 -235.011217)
			(xy 455.166008 -235.037866) (xy 455.116394 -235.057338) (xy 455.064432 -235.069198) (xy 455.011282 -235.073182)
			(xy 454.958132 -235.069198) (xy 454.90617 -235.057338) (xy 454.856556 -235.037866) (xy 454.810398 -235.011217)
			(xy 454.768727 -234.977986) (xy 454.732475 -234.938915) (xy 454.702451 -234.894878) (xy 454.679325 -234.846857)
			(xy 454.663615 -234.795927) (xy 454.655672 -234.743223) (xy 440.279292 -234.743223) (xy 440.271349 -234.795927)
			(xy 440.255639 -234.846857) (xy 440.232513 -234.894878) (xy 440.202489 -234.938915) (xy 440.166237 -234.977986)
			(xy 440.124566 -235.011217) (xy 440.078408 -235.037866) (xy 440.028794 -235.057338) (xy 439.976832 -235.069198)
			(xy 439.923682 -235.073182) (xy 439.870532 -235.069198) (xy 439.81857 -235.057338) (xy 439.768956 -235.037866)
			(xy 439.722798 -235.011217) (xy 439.681127 -234.977986) (xy 439.644875 -234.938915) (xy 439.614851 -234.894878)
			(xy 439.591725 -234.846857) (xy 439.576015 -234.795927) (xy 439.568072 -234.743223) (xy 425.191692 -234.743223)
			(xy 425.183749 -234.795927) (xy 425.168039 -234.846857) (xy 425.144913 -234.894878) (xy 425.114889 -234.938915)
			(xy 425.078637 -234.977986) (xy 425.036966 -235.011217) (xy 424.990808 -235.037866) (xy 424.941194 -235.057338)
			(xy 424.889232 -235.069198) (xy 424.836082 -235.073182) (xy 424.782932 -235.069198) (xy 424.73097 -235.057338)
			(xy 424.681356 -235.037866) (xy 424.635198 -235.011217) (xy 424.593527 -234.977986) (xy 424.557275 -234.938915)
			(xy 424.527251 -234.894878) (xy 424.504125 -234.846857) (xy 424.488415 -234.795927) (xy 424.480472 -234.743223)
			(xy 407.4668 -234.743223) (xy 407.4668 -235.593361) (xy 420.380404 -235.593361) (xy 420.380404 -235.540063)
			(xy 420.388347 -235.487359) (xy 420.404057 -235.436429) (xy 420.427183 -235.388408) (xy 420.457207 -235.344371)
			(xy 420.493459 -235.3053) (xy 420.53513 -235.272069) (xy 420.581288 -235.24542) (xy 420.630902 -235.225948)
			(xy 420.682864 -235.214088) (xy 420.736014 -235.210105) (xy 420.789164 -235.214088) (xy 420.841126 -235.225948)
			(xy 420.89074 -235.24542) (xy 420.936898 -235.272069) (xy 420.978569 -235.3053) (xy 421.014821 -235.344371)
			(xy 421.044845 -235.388408) (xy 421.067971 -235.436429) (xy 421.083681 -235.487359) (xy 421.091624 -235.540063)
			(xy 421.092122 -235.566712) (xy 421.091624 -235.593361) (xy 435.468004 -235.593361) (xy 435.468004 -235.540063)
			(xy 435.475947 -235.487359) (xy 435.491657 -235.436429) (xy 435.514783 -235.388408) (xy 435.544807 -235.344371)
			(xy 435.581059 -235.3053) (xy 435.62273 -235.272069) (xy 435.668888 -235.24542) (xy 435.718502 -235.225948)
			(xy 435.770464 -235.214088) (xy 435.823614 -235.210105) (xy 435.876764 -235.214088) (xy 435.928726 -235.225948)
			(xy 435.97834 -235.24542) (xy 436.024498 -235.272069) (xy 436.066169 -235.3053) (xy 436.102421 -235.344371)
			(xy 436.132445 -235.388408) (xy 436.155571 -235.436429) (xy 436.171281 -235.487359) (xy 436.179224 -235.540063)
			(xy 436.179722 -235.566712) (xy 436.179224 -235.593361) (xy 450.555604 -235.593361) (xy 450.555604 -235.540063)
			(xy 450.563547 -235.487359) (xy 450.579257 -235.436429) (xy 450.602383 -235.388408) (xy 450.632407 -235.344371)
			(xy 450.668659 -235.3053) (xy 450.71033 -235.272069) (xy 450.756488 -235.24542) (xy 450.806102 -235.225948)
			(xy 450.858064 -235.214088) (xy 450.911214 -235.210105) (xy 450.964364 -235.214088) (xy 451.016326 -235.225948)
			(xy 451.06594 -235.24542) (xy 451.112098 -235.272069) (xy 451.153769 -235.3053) (xy 451.190021 -235.344371)
			(xy 451.220045 -235.388408) (xy 451.243171 -235.436429) (xy 451.258881 -235.487359) (xy 451.266824 -235.540063)
			(xy 451.267322 -235.566712) (xy 451.266824 -235.593361) (xy 451.258881 -235.646065) (xy 451.243171 -235.696995)
			(xy 451.220045 -235.745016) (xy 451.190021 -235.789053) (xy 451.153769 -235.828124) (xy 451.112098 -235.861355)
			(xy 451.06594 -235.888004) (xy 451.016326 -235.907476) (xy 450.964364 -235.919336) (xy 450.911214 -235.92332)
			(xy 450.858064 -235.919336) (xy 450.806102 -235.907476) (xy 450.756488 -235.888004) (xy 450.71033 -235.861355)
			(xy 450.668659 -235.828124) (xy 450.632407 -235.789053) (xy 450.602383 -235.745016) (xy 450.579257 -235.696995)
			(xy 450.563547 -235.646065) (xy 450.555604 -235.593361) (xy 436.179224 -235.593361) (xy 436.171281 -235.646065)
			(xy 436.155571 -235.696995) (xy 436.132445 -235.745016) (xy 436.102421 -235.789053) (xy 436.066169 -235.828124)
			(xy 436.024498 -235.861355) (xy 435.97834 -235.888004) (xy 435.928726 -235.907476) (xy 435.876764 -235.919336)
			(xy 435.823614 -235.92332) (xy 435.770464 -235.919336) (xy 435.718502 -235.907476) (xy 435.668888 -235.888004)
			(xy 435.62273 -235.861355) (xy 435.581059 -235.828124) (xy 435.544807 -235.789053) (xy 435.514783 -235.745016)
			(xy 435.491657 -235.696995) (xy 435.475947 -235.646065) (xy 435.468004 -235.593361) (xy 421.091624 -235.593361)
			(xy 421.083681 -235.646065) (xy 421.067971 -235.696995) (xy 421.044845 -235.745016) (xy 421.014821 -235.789053)
			(xy 420.978569 -235.828124) (xy 420.936898 -235.861355) (xy 420.89074 -235.888004) (xy 420.841126 -235.907476)
			(xy 420.789164 -235.919336) (xy 420.736014 -235.92332) (xy 420.682864 -235.919336) (xy 420.630902 -235.907476)
			(xy 420.581288 -235.888004) (xy 420.53513 -235.861355) (xy 420.493459 -235.828124) (xy 420.457207 -235.789053)
			(xy 420.427183 -235.745016) (xy 420.404057 -235.696995) (xy 420.388347 -235.646065) (xy 420.380404 -235.593361)
			(xy 407.4668 -235.593361) (xy 407.4668 -236.443245) (xy 424.480472 -236.443245) (xy 424.480472 -236.389947)
			(xy 424.488415 -236.337243) (xy 424.504125 -236.286313) (xy 424.527251 -236.238292) (xy 424.557275 -236.194255)
			(xy 424.593527 -236.155184) (xy 424.635198 -236.121953) (xy 424.681356 -236.095304) (xy 424.73097 -236.075832)
			(xy 424.782932 -236.063972) (xy 424.836082 -236.059989) (xy 424.889232 -236.063972) (xy 424.941194 -236.075832)
			(xy 424.990808 -236.095304) (xy 425.036966 -236.121953) (xy 425.078637 -236.155184) (xy 425.114889 -236.194255)
			(xy 425.144913 -236.238292) (xy 425.168039 -236.286313) (xy 425.183749 -236.337243) (xy 425.191692 -236.389947)
			(xy 425.19219 -236.416596) (xy 425.191692 -236.443245) (xy 439.568072 -236.443245) (xy 439.568072 -236.389947)
			(xy 439.576015 -236.337243) (xy 439.591725 -236.286313) (xy 439.614851 -236.238292) (xy 439.644875 -236.194255)
			(xy 439.681127 -236.155184) (xy 439.722798 -236.121953) (xy 439.768956 -236.095304) (xy 439.81857 -236.075832)
			(xy 439.870532 -236.063972) (xy 439.923682 -236.059989) (xy 439.976832 -236.063972) (xy 440.028794 -236.075832)
			(xy 440.078408 -236.095304) (xy 440.124566 -236.121953) (xy 440.166237 -236.155184) (xy 440.202489 -236.194255)
			(xy 440.232513 -236.238292) (xy 440.255639 -236.286313) (xy 440.271349 -236.337243) (xy 440.279292 -236.389947)
			(xy 440.27979 -236.416596) (xy 440.279292 -236.443245) (xy 454.655672 -236.443245) (xy 454.655672 -236.389947)
			(xy 454.663615 -236.337243) (xy 454.679325 -236.286313) (xy 454.702451 -236.238292) (xy 454.732475 -236.194255)
			(xy 454.768727 -236.155184) (xy 454.810398 -236.121953) (xy 454.856556 -236.095304) (xy 454.90617 -236.075832)
			(xy 454.958132 -236.063972) (xy 455.011282 -236.059989) (xy 455.064432 -236.063972) (xy 455.116394 -236.075832)
			(xy 455.166008 -236.095304) (xy 455.212166 -236.121953) (xy 455.253837 -236.155184) (xy 455.290089 -236.194255)
			(xy 455.320113 -236.238292) (xy 455.343239 -236.286313) (xy 455.358949 -236.337243) (xy 455.366892 -236.389947)
			(xy 455.36739 -236.416596) (xy 455.366892 -236.443245) (xy 455.358949 -236.495949) (xy 455.343239 -236.546879)
			(xy 455.320113 -236.5949) (xy 455.290089 -236.638937) (xy 455.253837 -236.678008) (xy 455.212166 -236.711239)
			(xy 455.166008 -236.737888) (xy 455.116394 -236.75736) (xy 455.064432 -236.76922) (xy 455.011282 -236.773204)
			(xy 454.958132 -236.76922) (xy 454.90617 -236.75736) (xy 454.856556 -236.737888) (xy 454.810398 -236.711239)
			(xy 454.768727 -236.678008) (xy 454.732475 -236.638937) (xy 454.702451 -236.5949) (xy 454.679325 -236.546879)
			(xy 454.663615 -236.495949) (xy 454.655672 -236.443245) (xy 440.279292 -236.443245) (xy 440.271349 -236.495949)
			(xy 440.255639 -236.546879) (xy 440.232513 -236.5949) (xy 440.202489 -236.638937) (xy 440.166237 -236.678008)
			(xy 440.124566 -236.711239) (xy 440.078408 -236.737888) (xy 440.028794 -236.75736) (xy 439.976832 -236.76922)
			(xy 439.923682 -236.773204) (xy 439.870532 -236.76922) (xy 439.81857 -236.75736) (xy 439.768956 -236.737888)
			(xy 439.722798 -236.711239) (xy 439.681127 -236.678008) (xy 439.644875 -236.638937) (xy 439.614851 -236.5949)
			(xy 439.591725 -236.546879) (xy 439.576015 -236.495949) (xy 439.568072 -236.443245) (xy 425.191692 -236.443245)
			(xy 425.183749 -236.495949) (xy 425.168039 -236.546879) (xy 425.144913 -236.5949) (xy 425.114889 -236.638937)
			(xy 425.078637 -236.678008) (xy 425.036966 -236.711239) (xy 424.990808 -236.737888) (xy 424.941194 -236.75736)
			(xy 424.889232 -236.76922) (xy 424.836082 -236.773204) (xy 424.782932 -236.76922) (xy 424.73097 -236.75736)
			(xy 424.681356 -236.737888) (xy 424.635198 -236.711239) (xy 424.593527 -236.678008) (xy 424.557275 -236.638937)
			(xy 424.527251 -236.5949) (xy 424.504125 -236.546879) (xy 424.488415 -236.495949) (xy 424.480472 -236.443245)
			(xy 407.4668 -236.443245) (xy 407.4668 -237.293383) (xy 420.380404 -237.293383) (xy 420.380404 -237.240085)
			(xy 420.388347 -237.187381) (xy 420.404057 -237.136451) (xy 420.427183 -237.08843) (xy 420.457207 -237.044393)
			(xy 420.493459 -237.005322) (xy 420.53513 -236.972091) (xy 420.581288 -236.945442) (xy 420.630902 -236.92597)
			(xy 420.682864 -236.91411) (xy 420.736014 -236.910127) (xy 420.789164 -236.91411) (xy 420.841126 -236.92597)
			(xy 420.89074 -236.945442) (xy 420.936898 -236.972091) (xy 420.978569 -237.005322) (xy 421.014821 -237.044393)
			(xy 421.044845 -237.08843) (xy 421.067971 -237.136451) (xy 421.083681 -237.187381) (xy 421.091624 -237.240085)
			(xy 421.092122 -237.266734) (xy 421.091624 -237.293383) (xy 424.480472 -237.293383) (xy 424.480472 -237.240085)
			(xy 424.488415 -237.187381) (xy 424.504125 -237.136451) (xy 424.527251 -237.08843) (xy 424.557275 -237.044393)
			(xy 424.593527 -237.005322) (xy 424.635198 -236.972091) (xy 424.681356 -236.945442) (xy 424.73097 -236.92597)
			(xy 424.782932 -236.91411) (xy 424.836082 -236.910127) (xy 424.889232 -236.91411) (xy 424.941194 -236.92597)
			(xy 424.990808 -236.945442) (xy 425.036966 -236.972091) (xy 425.078637 -237.005322) (xy 425.114889 -237.044393)
			(xy 425.144913 -237.08843) (xy 425.168039 -237.136451) (xy 425.183749 -237.187381) (xy 425.191692 -237.240085)
			(xy 425.19219 -237.266734) (xy 425.191692 -237.293383) (xy 435.468004 -237.293383) (xy 435.468004 -237.240085)
			(xy 435.475947 -237.187381) (xy 435.491657 -237.136451) (xy 435.514783 -237.08843) (xy 435.544807 -237.044393)
			(xy 435.581059 -237.005322) (xy 435.62273 -236.972091) (xy 435.668888 -236.945442) (xy 435.718502 -236.92597)
			(xy 435.770464 -236.91411) (xy 435.823614 -236.910127) (xy 435.876764 -236.91411) (xy 435.928726 -236.92597)
			(xy 435.97834 -236.945442) (xy 436.024498 -236.972091) (xy 436.066169 -237.005322) (xy 436.102421 -237.044393)
			(xy 436.132445 -237.08843) (xy 436.155571 -237.136451) (xy 436.171281 -237.187381) (xy 436.179224 -237.240085)
			(xy 436.179722 -237.266734) (xy 436.179224 -237.293383) (xy 439.568072 -237.293383) (xy 439.568072 -237.240085)
			(xy 439.576015 -237.187381) (xy 439.591725 -237.136451) (xy 439.614851 -237.08843) (xy 439.644875 -237.044393)
			(xy 439.681127 -237.005322) (xy 439.722798 -236.972091) (xy 439.768956 -236.945442) (xy 439.81857 -236.92597)
			(xy 439.870532 -236.91411) (xy 439.923682 -236.910127) (xy 439.976832 -236.91411) (xy 440.028794 -236.92597)
			(xy 440.078408 -236.945442) (xy 440.124566 -236.972091) (xy 440.166237 -237.005322) (xy 440.202489 -237.044393)
			(xy 440.232513 -237.08843) (xy 440.255639 -237.136451) (xy 440.271349 -237.187381) (xy 440.279292 -237.240085)
			(xy 440.27979 -237.266734) (xy 440.279292 -237.293383) (xy 450.555604 -237.293383) (xy 450.555604 -237.240085)
			(xy 450.563547 -237.187381) (xy 450.579257 -237.136451) (xy 450.602383 -237.08843) (xy 450.632407 -237.044393)
			(xy 450.668659 -237.005322) (xy 450.71033 -236.972091) (xy 450.756488 -236.945442) (xy 450.806102 -236.92597)
			(xy 450.858064 -236.91411) (xy 450.911214 -236.910127) (xy 450.964364 -236.91411) (xy 451.016326 -236.92597)
			(xy 451.06594 -236.945442) (xy 451.112098 -236.972091) (xy 451.153769 -237.005322) (xy 451.190021 -237.044393)
			(xy 451.220045 -237.08843) (xy 451.243171 -237.136451) (xy 451.258881 -237.187381) (xy 451.266824 -237.240085)
			(xy 451.267322 -237.266734) (xy 451.266824 -237.293383) (xy 454.655672 -237.293383) (xy 454.655672 -237.240085)
			(xy 454.663615 -237.187381) (xy 454.679325 -237.136451) (xy 454.702451 -237.08843) (xy 454.732475 -237.044393)
			(xy 454.768727 -237.005322) (xy 454.810398 -236.972091) (xy 454.856556 -236.945442) (xy 454.90617 -236.92597)
			(xy 454.958132 -236.91411) (xy 455.011282 -236.910127) (xy 455.064432 -236.91411) (xy 455.116394 -236.92597)
			(xy 455.166008 -236.945442) (xy 455.212166 -236.972091) (xy 455.253837 -237.005322) (xy 455.290089 -237.044393)
			(xy 455.320113 -237.08843) (xy 455.343239 -237.136451) (xy 455.358949 -237.187381) (xy 455.366892 -237.240085)
			(xy 455.36739 -237.266734) (xy 455.366892 -237.293383) (xy 455.358949 -237.346087) (xy 455.343239 -237.397017)
			(xy 455.320113 -237.445038) (xy 455.290089 -237.489075) (xy 455.253837 -237.528146) (xy 455.212166 -237.561377)
			(xy 455.166008 -237.588026) (xy 455.116394 -237.607498) (xy 455.064432 -237.619358) (xy 455.011282 -237.623342)
			(xy 454.958132 -237.619358) (xy 454.90617 -237.607498) (xy 454.856556 -237.588026) (xy 454.810398 -237.561377)
			(xy 454.768727 -237.528146) (xy 454.732475 -237.489075) (xy 454.702451 -237.445038) (xy 454.679325 -237.397017)
			(xy 454.663615 -237.346087) (xy 454.655672 -237.293383) (xy 451.266824 -237.293383) (xy 451.258881 -237.346087)
			(xy 451.243171 -237.397017) (xy 451.220045 -237.445038) (xy 451.190021 -237.489075) (xy 451.153769 -237.528146)
			(xy 451.112098 -237.561377) (xy 451.06594 -237.588026) (xy 451.016326 -237.607498) (xy 450.964364 -237.619358)
			(xy 450.911214 -237.623342) (xy 450.858064 -237.619358) (xy 450.806102 -237.607498) (xy 450.756488 -237.588026)
			(xy 450.71033 -237.561377) (xy 450.668659 -237.528146) (xy 450.632407 -237.489075) (xy 450.602383 -237.445038)
			(xy 450.579257 -237.397017) (xy 450.563547 -237.346087) (xy 450.555604 -237.293383) (xy 440.279292 -237.293383)
			(xy 440.271349 -237.346087) (xy 440.255639 -237.397017) (xy 440.232513 -237.445038) (xy 440.202489 -237.489075)
			(xy 440.166237 -237.528146) (xy 440.124566 -237.561377) (xy 440.078408 -237.588026) (xy 440.028794 -237.607498)
			(xy 439.976832 -237.619358) (xy 439.923682 -237.623342) (xy 439.870532 -237.619358) (xy 439.81857 -237.607498)
			(xy 439.768956 -237.588026) (xy 439.722798 -237.561377) (xy 439.681127 -237.528146) (xy 439.644875 -237.489075)
			(xy 439.614851 -237.445038) (xy 439.591725 -237.397017) (xy 439.576015 -237.346087) (xy 439.568072 -237.293383)
			(xy 436.179224 -237.293383) (xy 436.171281 -237.346087) (xy 436.155571 -237.397017) (xy 436.132445 -237.445038)
			(xy 436.102421 -237.489075) (xy 436.066169 -237.528146) (xy 436.024498 -237.561377) (xy 435.97834 -237.588026)
			(xy 435.928726 -237.607498) (xy 435.876764 -237.619358) (xy 435.823614 -237.623342) (xy 435.770464 -237.619358)
			(xy 435.718502 -237.607498) (xy 435.668888 -237.588026) (xy 435.62273 -237.561377) (xy 435.581059 -237.528146)
			(xy 435.544807 -237.489075) (xy 435.514783 -237.445038) (xy 435.491657 -237.397017) (xy 435.475947 -237.346087)
			(xy 435.468004 -237.293383) (xy 425.191692 -237.293383) (xy 425.183749 -237.346087) (xy 425.168039 -237.397017)
			(xy 425.144913 -237.445038) (xy 425.114889 -237.489075) (xy 425.078637 -237.528146) (xy 425.036966 -237.561377)
			(xy 424.990808 -237.588026) (xy 424.941194 -237.607498) (xy 424.889232 -237.619358) (xy 424.836082 -237.623342)
			(xy 424.782932 -237.619358) (xy 424.73097 -237.607498) (xy 424.681356 -237.588026) (xy 424.635198 -237.561377)
			(xy 424.593527 -237.528146) (xy 424.557275 -237.489075) (xy 424.527251 -237.445038) (xy 424.504125 -237.397017)
			(xy 424.488415 -237.346087) (xy 424.480472 -237.293383) (xy 421.091624 -237.293383) (xy 421.083681 -237.346087)
			(xy 421.067971 -237.397017) (xy 421.044845 -237.445038) (xy 421.014821 -237.489075) (xy 420.978569 -237.528146)
			(xy 420.936898 -237.561377) (xy 420.89074 -237.588026) (xy 420.841126 -237.607498) (xy 420.789164 -237.619358)
			(xy 420.736014 -237.623342) (xy 420.682864 -237.619358) (xy 420.630902 -237.607498) (xy 420.581288 -237.588026)
			(xy 420.53513 -237.561377) (xy 420.493459 -237.528146) (xy 420.457207 -237.489075) (xy 420.427183 -237.445038)
			(xy 420.404057 -237.397017) (xy 420.388347 -237.346087) (xy 420.380404 -237.293383) (xy 407.4668 -237.293383)
			(xy 407.4668 -238.143267) (xy 420.380404 -238.143267) (xy 420.380404 -238.089969) (xy 420.388347 -238.037265)
			(xy 420.404057 -237.986335) (xy 420.427183 -237.938314) (xy 420.457207 -237.894277) (xy 420.493459 -237.855206)
			(xy 420.53513 -237.821975) (xy 420.581288 -237.795326) (xy 420.630902 -237.775854) (xy 420.682864 -237.763994)
			(xy 420.736014 -237.760011) (xy 420.789164 -237.763994) (xy 420.841126 -237.775854) (xy 420.89074 -237.795326)
			(xy 420.936898 -237.821975) (xy 420.978569 -237.855206) (xy 421.014821 -237.894277) (xy 421.044845 -237.938314)
			(xy 421.067971 -237.986335) (xy 421.083681 -238.037265) (xy 421.091624 -238.089969) (xy 421.092122 -238.116618)
			(xy 421.091624 -238.143267) (xy 435.468004 -238.143267) (xy 435.468004 -238.089969) (xy 435.475947 -238.037265)
			(xy 435.491657 -237.986335) (xy 435.514783 -237.938314) (xy 435.544807 -237.894277) (xy 435.581059 -237.855206)
			(xy 435.62273 -237.821975) (xy 435.668888 -237.795326) (xy 435.718502 -237.775854) (xy 435.770464 -237.763994)
			(xy 435.823614 -237.760011) (xy 435.876764 -237.763994) (xy 435.928726 -237.775854) (xy 435.97834 -237.795326)
			(xy 436.024498 -237.821975) (xy 436.066169 -237.855206) (xy 436.102421 -237.894277) (xy 436.132445 -237.938314)
			(xy 436.155571 -237.986335) (xy 436.171281 -238.037265) (xy 436.179224 -238.089969) (xy 436.179722 -238.116618)
			(xy 436.179224 -238.143267) (xy 450.555604 -238.143267) (xy 450.555604 -238.089969) (xy 450.563547 -238.037265)
			(xy 450.579257 -237.986335) (xy 450.602383 -237.938314) (xy 450.632407 -237.894277) (xy 450.668659 -237.855206)
			(xy 450.71033 -237.821975) (xy 450.756488 -237.795326) (xy 450.806102 -237.775854) (xy 450.858064 -237.763994)
			(xy 450.911214 -237.760011) (xy 450.964364 -237.763994) (xy 451.016326 -237.775854) (xy 451.06594 -237.795326)
			(xy 451.112098 -237.821975) (xy 451.153769 -237.855206) (xy 451.190021 -237.894277) (xy 451.220045 -237.938314)
			(xy 451.243171 -237.986335) (xy 451.258881 -238.037265) (xy 451.266824 -238.089969) (xy 451.267322 -238.116618)
			(xy 451.266824 -238.143267) (xy 451.258881 -238.195971) (xy 451.243171 -238.246901) (xy 451.220045 -238.294922)
			(xy 451.190021 -238.338959) (xy 451.153769 -238.37803) (xy 451.112098 -238.411261) (xy 451.06594 -238.43791)
			(xy 451.016326 -238.457382) (xy 450.964364 -238.469242) (xy 450.911214 -238.473226) (xy 450.858064 -238.469242)
			(xy 450.806102 -238.457382) (xy 450.756488 -238.43791) (xy 450.71033 -238.411261) (xy 450.668659 -238.37803)
			(xy 450.632407 -238.338959) (xy 450.602383 -238.294922) (xy 450.579257 -238.246901) (xy 450.563547 -238.195971)
			(xy 450.555604 -238.143267) (xy 436.179224 -238.143267) (xy 436.171281 -238.195971) (xy 436.155571 -238.246901)
			(xy 436.132445 -238.294922) (xy 436.102421 -238.338959) (xy 436.066169 -238.37803) (xy 436.024498 -238.411261)
			(xy 435.97834 -238.43791) (xy 435.928726 -238.457382) (xy 435.876764 -238.469242) (xy 435.823614 -238.473226)
			(xy 435.770464 -238.469242) (xy 435.718502 -238.457382) (xy 435.668888 -238.43791) (xy 435.62273 -238.411261)
			(xy 435.581059 -238.37803) (xy 435.544807 -238.338959) (xy 435.514783 -238.294922) (xy 435.491657 -238.246901)
			(xy 435.475947 -238.195971) (xy 435.468004 -238.143267) (xy 421.091624 -238.143267) (xy 421.083681 -238.195971)
			(xy 421.067971 -238.246901) (xy 421.044845 -238.294922) (xy 421.014821 -238.338959) (xy 420.978569 -238.37803)
			(xy 420.936898 -238.411261) (xy 420.89074 -238.43791) (xy 420.841126 -238.457382) (xy 420.789164 -238.469242)
			(xy 420.736014 -238.473226) (xy 420.682864 -238.469242) (xy 420.630902 -238.457382) (xy 420.581288 -238.43791)
			(xy 420.53513 -238.411261) (xy 420.493459 -238.37803) (xy 420.457207 -238.338959) (xy 420.427183 -238.294922)
			(xy 420.404057 -238.246901) (xy 420.388347 -238.195971) (xy 420.380404 -238.143267) (xy 407.4668 -238.143267)
			(xy 407.4668 -238.993405) (xy 424.480472 -238.993405) (xy 424.480472 -238.940107) (xy 424.488415 -238.887403)
			(xy 424.504125 -238.836473) (xy 424.527251 -238.788452) (xy 424.557275 -238.744415) (xy 424.593527 -238.705344)
			(xy 424.635198 -238.672113) (xy 424.681356 -238.645464) (xy 424.73097 -238.625992) (xy 424.782932 -238.614132)
			(xy 424.836082 -238.610149) (xy 424.889232 -238.614132) (xy 424.941194 -238.625992) (xy 424.990808 -238.645464)
			(xy 425.036966 -238.672113) (xy 425.078637 -238.705344) (xy 425.114889 -238.744415) (xy 425.144913 -238.788452)
			(xy 425.168039 -238.836473) (xy 425.183749 -238.887403) (xy 425.191692 -238.940107) (xy 425.19219 -238.966756)
			(xy 425.191692 -238.993405) (xy 439.568072 -238.993405) (xy 439.568072 -238.940107) (xy 439.576015 -238.887403)
			(xy 439.591725 -238.836473) (xy 439.614851 -238.788452) (xy 439.644875 -238.744415) (xy 439.681127 -238.705344)
			(xy 439.722798 -238.672113) (xy 439.768956 -238.645464) (xy 439.81857 -238.625992) (xy 439.870532 -238.614132)
			(xy 439.923682 -238.610149) (xy 439.976832 -238.614132) (xy 440.028794 -238.625992) (xy 440.078408 -238.645464)
			(xy 440.124566 -238.672113) (xy 440.166237 -238.705344) (xy 440.202489 -238.744415) (xy 440.232513 -238.788452)
			(xy 440.255639 -238.836473) (xy 440.271349 -238.887403) (xy 440.279292 -238.940107) (xy 440.27979 -238.966756)
			(xy 440.279292 -238.993405) (xy 454.655672 -238.993405) (xy 454.655672 -238.940107) (xy 454.663615 -238.887403)
			(xy 454.679325 -238.836473) (xy 454.702451 -238.788452) (xy 454.732475 -238.744415) (xy 454.768727 -238.705344)
			(xy 454.810398 -238.672113) (xy 454.856556 -238.645464) (xy 454.90617 -238.625992) (xy 454.958132 -238.614132)
			(xy 455.011282 -238.610149) (xy 455.064432 -238.614132) (xy 455.116394 -238.625992) (xy 455.166008 -238.645464)
			(xy 455.212166 -238.672113) (xy 455.253837 -238.705344) (xy 455.290089 -238.744415) (xy 455.320113 -238.788452)
			(xy 455.343239 -238.836473) (xy 455.358949 -238.887403) (xy 455.366892 -238.940107) (xy 455.36739 -238.966756)
			(xy 455.366892 -238.993405) (xy 455.358949 -239.046109) (xy 455.343239 -239.097039) (xy 455.320113 -239.14506)
			(xy 455.290089 -239.189097) (xy 455.253837 -239.228168) (xy 455.212166 -239.261399) (xy 455.166008 -239.288048)
			(xy 455.116394 -239.30752) (xy 455.064432 -239.31938) (xy 455.011282 -239.323364) (xy 454.958132 -239.31938)
			(xy 454.90617 -239.30752) (xy 454.856556 -239.288048) (xy 454.810398 -239.261399) (xy 454.768727 -239.228168)
			(xy 454.732475 -239.189097) (xy 454.702451 -239.14506) (xy 454.679325 -239.097039) (xy 454.663615 -239.046109)
			(xy 454.655672 -238.993405) (xy 440.279292 -238.993405) (xy 440.271349 -239.046109) (xy 440.255639 -239.097039)
			(xy 440.232513 -239.14506) (xy 440.202489 -239.189097) (xy 440.166237 -239.228168) (xy 440.124566 -239.261399)
			(xy 440.078408 -239.288048) (xy 440.028794 -239.30752) (xy 439.976832 -239.31938) (xy 439.923682 -239.323364)
			(xy 439.870532 -239.31938) (xy 439.81857 -239.30752) (xy 439.768956 -239.288048) (xy 439.722798 -239.261399)
			(xy 439.681127 -239.228168) (xy 439.644875 -239.189097) (xy 439.614851 -239.14506) (xy 439.591725 -239.097039)
			(xy 439.576015 -239.046109) (xy 439.568072 -238.993405) (xy 425.191692 -238.993405) (xy 425.183749 -239.046109)
			(xy 425.168039 -239.097039) (xy 425.144913 -239.14506) (xy 425.114889 -239.189097) (xy 425.078637 -239.228168)
			(xy 425.036966 -239.261399) (xy 424.990808 -239.288048) (xy 424.941194 -239.30752) (xy 424.889232 -239.31938)
			(xy 424.836082 -239.323364) (xy 424.782932 -239.31938) (xy 424.73097 -239.30752) (xy 424.681356 -239.288048)
			(xy 424.635198 -239.261399) (xy 424.593527 -239.228168) (xy 424.557275 -239.189097) (xy 424.527251 -239.14506)
			(xy 424.504125 -239.097039) (xy 424.488415 -239.046109) (xy 424.480472 -238.993405) (xy 407.4668 -238.993405)
			(xy 407.4668 -239.843289) (xy 420.380404 -239.843289) (xy 420.380404 -239.789991) (xy 420.388347 -239.737287)
			(xy 420.404057 -239.686357) (xy 420.427183 -239.638336) (xy 420.457207 -239.594299) (xy 420.493459 -239.555228)
			(xy 420.53513 -239.521997) (xy 420.581288 -239.495348) (xy 420.630902 -239.475876) (xy 420.682864 -239.464016)
			(xy 420.736014 -239.460033) (xy 420.789164 -239.464016) (xy 420.841126 -239.475876) (xy 420.89074 -239.495348)
			(xy 420.936898 -239.521997) (xy 420.978569 -239.555228) (xy 421.014821 -239.594299) (xy 421.044845 -239.638336)
			(xy 421.067971 -239.686357) (xy 421.083681 -239.737287) (xy 421.091624 -239.789991) (xy 421.092122 -239.81664)
			(xy 421.091624 -239.843289) (xy 435.468004 -239.843289) (xy 435.468004 -239.789991) (xy 435.475947 -239.737287)
			(xy 435.491657 -239.686357) (xy 435.514783 -239.638336) (xy 435.544807 -239.594299) (xy 435.581059 -239.555228)
			(xy 435.62273 -239.521997) (xy 435.668888 -239.495348) (xy 435.718502 -239.475876) (xy 435.770464 -239.464016)
			(xy 435.823614 -239.460033) (xy 435.876764 -239.464016) (xy 435.928726 -239.475876) (xy 435.97834 -239.495348)
			(xy 436.024498 -239.521997) (xy 436.066169 -239.555228) (xy 436.102421 -239.594299) (xy 436.132445 -239.638336)
			(xy 436.155571 -239.686357) (xy 436.171281 -239.737287) (xy 436.179224 -239.789991) (xy 436.179722 -239.81664)
			(xy 436.179224 -239.843289) (xy 450.555604 -239.843289) (xy 450.555604 -239.789991) (xy 450.563547 -239.737287)
			(xy 450.579257 -239.686357) (xy 450.602383 -239.638336) (xy 450.632407 -239.594299) (xy 450.668659 -239.555228)
			(xy 450.71033 -239.521997) (xy 450.756488 -239.495348) (xy 450.806102 -239.475876) (xy 450.858064 -239.464016)
			(xy 450.911214 -239.460033) (xy 450.964364 -239.464016) (xy 451.016326 -239.475876) (xy 451.06594 -239.495348)
			(xy 451.112098 -239.521997) (xy 451.153769 -239.555228) (xy 451.190021 -239.594299) (xy 451.220045 -239.638336)
			(xy 451.243171 -239.686357) (xy 451.258881 -239.737287) (xy 451.266824 -239.789991) (xy 451.267322 -239.81664)
			(xy 451.266824 -239.843289) (xy 451.258881 -239.895993) (xy 451.243171 -239.946923) (xy 451.220045 -239.994944)
			(xy 451.190021 -240.038981) (xy 451.153769 -240.078052) (xy 451.112098 -240.111283) (xy 451.06594 -240.137932)
			(xy 451.016326 -240.157404) (xy 450.964364 -240.169264) (xy 450.911214 -240.173248) (xy 450.858064 -240.169264)
			(xy 450.806102 -240.157404) (xy 450.756488 -240.137932) (xy 450.71033 -240.111283) (xy 450.668659 -240.078052)
			(xy 450.632407 -240.038981) (xy 450.602383 -239.994944) (xy 450.579257 -239.946923) (xy 450.563547 -239.895993)
			(xy 450.555604 -239.843289) (xy 436.179224 -239.843289) (xy 436.171281 -239.895993) (xy 436.155571 -239.946923)
			(xy 436.132445 -239.994944) (xy 436.102421 -240.038981) (xy 436.066169 -240.078052) (xy 436.024498 -240.111283)
			(xy 435.97834 -240.137932) (xy 435.928726 -240.157404) (xy 435.876764 -240.169264) (xy 435.823614 -240.173248)
			(xy 435.770464 -240.169264) (xy 435.718502 -240.157404) (xy 435.668888 -240.137932) (xy 435.62273 -240.111283)
			(xy 435.581059 -240.078052) (xy 435.544807 -240.038981) (xy 435.514783 -239.994944) (xy 435.491657 -239.946923)
			(xy 435.475947 -239.895993) (xy 435.468004 -239.843289) (xy 421.091624 -239.843289) (xy 421.083681 -239.895993)
			(xy 421.067971 -239.946923) (xy 421.044845 -239.994944) (xy 421.014821 -240.038981) (xy 420.978569 -240.078052)
			(xy 420.936898 -240.111283) (xy 420.89074 -240.137932) (xy 420.841126 -240.157404) (xy 420.789164 -240.169264)
			(xy 420.736014 -240.173248) (xy 420.682864 -240.169264) (xy 420.630902 -240.157404) (xy 420.581288 -240.137932)
			(xy 420.53513 -240.111283) (xy 420.493459 -240.078052) (xy 420.457207 -240.038981) (xy 420.427183 -239.994944)
			(xy 420.404057 -239.946923) (xy 420.388347 -239.895993) (xy 420.380404 -239.843289) (xy 407.4668 -239.843289)
			(xy 407.4668 -240.693427) (xy 424.480472 -240.693427) (xy 424.480472 -240.640129) (xy 424.488415 -240.587425)
			(xy 424.504125 -240.536495) (xy 424.527251 -240.488474) (xy 424.557275 -240.444437) (xy 424.593527 -240.405366)
			(xy 424.635198 -240.372135) (xy 424.681356 -240.345486) (xy 424.73097 -240.326014) (xy 424.782932 -240.314154)
			(xy 424.836082 -240.310171) (xy 424.889232 -240.314154) (xy 424.941194 -240.326014) (xy 424.990808 -240.345486)
			(xy 425.036966 -240.372135) (xy 425.078637 -240.405366) (xy 425.114889 -240.444437) (xy 425.144913 -240.488474)
			(xy 425.168039 -240.536495) (xy 425.183749 -240.587425) (xy 425.191692 -240.640129) (xy 425.19219 -240.666778)
			(xy 425.191692 -240.693427) (xy 439.568072 -240.693427) (xy 439.568072 -240.640129) (xy 439.576015 -240.587425)
			(xy 439.591725 -240.536495) (xy 439.614851 -240.488474) (xy 439.644875 -240.444437) (xy 439.681127 -240.405366)
			(xy 439.722798 -240.372135) (xy 439.768956 -240.345486) (xy 439.81857 -240.326014) (xy 439.870532 -240.314154)
			(xy 439.923682 -240.310171) (xy 439.976832 -240.314154) (xy 440.028794 -240.326014) (xy 440.078408 -240.345486)
			(xy 440.124566 -240.372135) (xy 440.166237 -240.405366) (xy 440.202489 -240.444437) (xy 440.232513 -240.488474)
			(xy 440.255639 -240.536495) (xy 440.271349 -240.587425) (xy 440.279292 -240.640129) (xy 440.27979 -240.666778)
			(xy 440.279292 -240.693427) (xy 454.655672 -240.693427) (xy 454.655672 -240.640129) (xy 454.663615 -240.587425)
			(xy 454.679325 -240.536495) (xy 454.702451 -240.488474) (xy 454.732475 -240.444437) (xy 454.768727 -240.405366)
			(xy 454.810398 -240.372135) (xy 454.856556 -240.345486) (xy 454.90617 -240.326014) (xy 454.958132 -240.314154)
			(xy 455.011282 -240.310171) (xy 455.064432 -240.314154) (xy 455.116394 -240.326014) (xy 455.166008 -240.345486)
			(xy 455.212166 -240.372135) (xy 455.253837 -240.405366) (xy 455.290089 -240.444437) (xy 455.320113 -240.488474)
			(xy 455.343239 -240.536495) (xy 455.358949 -240.587425) (xy 455.366892 -240.640129) (xy 455.36739 -240.666778)
			(xy 455.366892 -240.693427) (xy 455.358949 -240.746131) (xy 455.343239 -240.797061) (xy 455.320113 -240.845082)
			(xy 455.290089 -240.889119) (xy 455.253837 -240.92819) (xy 455.212166 -240.961421) (xy 455.166008 -240.98807)
			(xy 455.116394 -241.007542) (xy 455.064432 -241.019402) (xy 455.011282 -241.023386) (xy 454.958132 -241.019402)
			(xy 454.90617 -241.007542) (xy 454.856556 -240.98807) (xy 454.810398 -240.961421) (xy 454.768727 -240.92819)
			(xy 454.732475 -240.889119) (xy 454.702451 -240.845082) (xy 454.679325 -240.797061) (xy 454.663615 -240.746131)
			(xy 454.655672 -240.693427) (xy 440.279292 -240.693427) (xy 440.271349 -240.746131) (xy 440.255639 -240.797061)
			(xy 440.232513 -240.845082) (xy 440.202489 -240.889119) (xy 440.166237 -240.92819) (xy 440.124566 -240.961421)
			(xy 440.078408 -240.98807) (xy 440.028794 -241.007542) (xy 439.976832 -241.019402) (xy 439.923682 -241.023386)
			(xy 439.870532 -241.019402) (xy 439.81857 -241.007542) (xy 439.768956 -240.98807) (xy 439.722798 -240.961421)
			(xy 439.681127 -240.92819) (xy 439.644875 -240.889119) (xy 439.614851 -240.845082) (xy 439.591725 -240.797061)
			(xy 439.576015 -240.746131) (xy 439.568072 -240.693427) (xy 425.191692 -240.693427) (xy 425.183749 -240.746131)
			(xy 425.168039 -240.797061) (xy 425.144913 -240.845082) (xy 425.114889 -240.889119) (xy 425.078637 -240.92819)
			(xy 425.036966 -240.961421) (xy 424.990808 -240.98807) (xy 424.941194 -241.007542) (xy 424.889232 -241.019402)
			(xy 424.836082 -241.023386) (xy 424.782932 -241.019402) (xy 424.73097 -241.007542) (xy 424.681356 -240.98807)
			(xy 424.635198 -240.961421) (xy 424.593527 -240.92819) (xy 424.557275 -240.889119) (xy 424.527251 -240.845082)
			(xy 424.504125 -240.797061) (xy 424.488415 -240.746131) (xy 424.480472 -240.693427) (xy 407.4668 -240.693427)
			(xy 407.4668 -241.543311) (xy 420.380404 -241.543311) (xy 420.380404 -241.490013) (xy 420.388347 -241.437309)
			(xy 420.404057 -241.386379) (xy 420.427183 -241.338358) (xy 420.457207 -241.294321) (xy 420.493459 -241.25525)
			(xy 420.53513 -241.222019) (xy 420.581288 -241.19537) (xy 420.630902 -241.175898) (xy 420.682864 -241.164038)
			(xy 420.736014 -241.160055) (xy 420.789164 -241.164038) (xy 420.841126 -241.175898) (xy 420.89074 -241.19537)
			(xy 420.936898 -241.222019) (xy 420.978569 -241.25525) (xy 421.014821 -241.294321) (xy 421.044845 -241.338358)
			(xy 421.067971 -241.386379) (xy 421.083681 -241.437309) (xy 421.091624 -241.490013) (xy 421.092122 -241.516662)
			(xy 421.091624 -241.543311) (xy 435.468004 -241.543311) (xy 435.468004 -241.490013) (xy 435.475947 -241.437309)
			(xy 435.491657 -241.386379) (xy 435.514783 -241.338358) (xy 435.544807 -241.294321) (xy 435.581059 -241.25525)
			(xy 435.62273 -241.222019) (xy 435.668888 -241.19537) (xy 435.718502 -241.175898) (xy 435.770464 -241.164038)
			(xy 435.823614 -241.160055) (xy 435.876764 -241.164038) (xy 435.928726 -241.175898) (xy 435.97834 -241.19537)
			(xy 436.024498 -241.222019) (xy 436.066169 -241.25525) (xy 436.102421 -241.294321) (xy 436.132445 -241.338358)
			(xy 436.155571 -241.386379) (xy 436.171281 -241.437309) (xy 436.179224 -241.490013) (xy 436.179722 -241.516662)
			(xy 436.179224 -241.543311) (xy 450.555604 -241.543311) (xy 450.555604 -241.490013) (xy 450.563547 -241.437309)
			(xy 450.579257 -241.386379) (xy 450.602383 -241.338358) (xy 450.632407 -241.294321) (xy 450.668659 -241.25525)
			(xy 450.71033 -241.222019) (xy 450.756488 -241.19537) (xy 450.806102 -241.175898) (xy 450.858064 -241.164038)
			(xy 450.911214 -241.160055) (xy 450.964364 -241.164038) (xy 451.016326 -241.175898) (xy 451.06594 -241.19537)
			(xy 451.112098 -241.222019) (xy 451.153769 -241.25525) (xy 451.190021 -241.294321) (xy 451.220045 -241.338358)
			(xy 451.243171 -241.386379) (xy 451.258881 -241.437309) (xy 451.266824 -241.490013) (xy 451.267322 -241.516662)
			(xy 451.266824 -241.543311) (xy 451.258881 -241.596015) (xy 451.243171 -241.646945) (xy 451.220045 -241.694966)
			(xy 451.190021 -241.739003) (xy 451.153769 -241.778074) (xy 451.112098 -241.811305) (xy 451.06594 -241.837954)
			(xy 451.016326 -241.857426) (xy 450.964364 -241.869286) (xy 450.911214 -241.87327) (xy 450.858064 -241.869286)
			(xy 450.806102 -241.857426) (xy 450.756488 -241.837954) (xy 450.71033 -241.811305) (xy 450.668659 -241.778074)
			(xy 450.632407 -241.739003) (xy 450.602383 -241.694966) (xy 450.579257 -241.646945) (xy 450.563547 -241.596015)
			(xy 450.555604 -241.543311) (xy 436.179224 -241.543311) (xy 436.171281 -241.596015) (xy 436.155571 -241.646945)
			(xy 436.132445 -241.694966) (xy 436.102421 -241.739003) (xy 436.066169 -241.778074) (xy 436.024498 -241.811305)
			(xy 435.97834 -241.837954) (xy 435.928726 -241.857426) (xy 435.876764 -241.869286) (xy 435.823614 -241.87327)
			(xy 435.770464 -241.869286) (xy 435.718502 -241.857426) (xy 435.668888 -241.837954) (xy 435.62273 -241.811305)
			(xy 435.581059 -241.778074) (xy 435.544807 -241.739003) (xy 435.514783 -241.694966) (xy 435.491657 -241.646945)
			(xy 435.475947 -241.596015) (xy 435.468004 -241.543311) (xy 421.091624 -241.543311) (xy 421.083681 -241.596015)
			(xy 421.067971 -241.646945) (xy 421.044845 -241.694966) (xy 421.014821 -241.739003) (xy 420.978569 -241.778074)
			(xy 420.936898 -241.811305) (xy 420.89074 -241.837954) (xy 420.841126 -241.857426) (xy 420.789164 -241.869286)
			(xy 420.736014 -241.87327) (xy 420.682864 -241.869286) (xy 420.630902 -241.857426) (xy 420.581288 -241.837954)
			(xy 420.53513 -241.811305) (xy 420.493459 -241.778074) (xy 420.457207 -241.739003) (xy 420.427183 -241.694966)
			(xy 420.404057 -241.646945) (xy 420.388347 -241.596015) (xy 420.380404 -241.543311) (xy 407.4668 -241.543311)
			(xy 407.4668 -242.393449) (xy 409.367472 -242.393449) (xy 409.367472 -242.340151) (xy 409.375415 -242.287447)
			(xy 409.391125 -242.236517) (xy 409.414251 -242.188496) (xy 409.444275 -242.144459) (xy 409.480527 -242.105388)
			(xy 409.522198 -242.072157) (xy 409.568356 -242.045508) (xy 409.61797 -242.026036) (xy 409.669932 -242.014176)
			(xy 409.723082 -242.010193) (xy 409.776232 -242.014176) (xy 409.828194 -242.026036) (xy 409.877808 -242.045508)
			(xy 409.923966 -242.072157) (xy 409.965637 -242.105388) (xy 410.001889 -242.144459) (xy 410.031913 -242.188496)
			(xy 410.055039 -242.236517) (xy 410.070749 -242.287447) (xy 410.078692 -242.340151) (xy 410.07919 -242.3668)
			(xy 410.078692 -242.393449) (xy 416.911272 -242.393449) (xy 416.911272 -242.340151) (xy 416.919215 -242.287447)
			(xy 416.934925 -242.236517) (xy 416.958051 -242.188496) (xy 416.988075 -242.144459) (xy 417.024327 -242.105388)
			(xy 417.065998 -242.072157) (xy 417.112156 -242.045508) (xy 417.16177 -242.026036) (xy 417.213732 -242.014176)
			(xy 417.266882 -242.010193) (xy 417.320032 -242.014176) (xy 417.371994 -242.026036) (xy 417.421608 -242.045508)
			(xy 417.467766 -242.072157) (xy 417.509437 -242.105388) (xy 417.545689 -242.144459) (xy 417.575713 -242.188496)
			(xy 417.598839 -242.236517) (xy 417.614549 -242.287447) (xy 417.622492 -242.340151) (xy 417.62299 -242.3668)
			(xy 417.622492 -242.393449) (xy 424.480472 -242.393449) (xy 424.480472 -242.340151) (xy 424.488415 -242.287447)
			(xy 424.504125 -242.236517) (xy 424.527251 -242.188496) (xy 424.557275 -242.144459) (xy 424.593527 -242.105388)
			(xy 424.635198 -242.072157) (xy 424.681356 -242.045508) (xy 424.73097 -242.026036) (xy 424.782932 -242.014176)
			(xy 424.836082 -242.010193) (xy 424.889232 -242.014176) (xy 424.941194 -242.026036) (xy 424.990808 -242.045508)
			(xy 425.036966 -242.072157) (xy 425.078637 -242.105388) (xy 425.114889 -242.144459) (xy 425.144913 -242.188496)
			(xy 425.168039 -242.236517) (xy 425.183749 -242.287447) (xy 425.191692 -242.340151) (xy 425.19219 -242.3668)
			(xy 425.191692 -242.393449) (xy 431.998872 -242.393449) (xy 431.998872 -242.340151) (xy 432.006815 -242.287447)
			(xy 432.022525 -242.236517) (xy 432.045651 -242.188496) (xy 432.075675 -242.144459) (xy 432.111927 -242.105388)
			(xy 432.153598 -242.072157) (xy 432.199756 -242.045508) (xy 432.24937 -242.026036) (xy 432.301332 -242.014176)
			(xy 432.354482 -242.010193) (xy 432.407632 -242.014176) (xy 432.459594 -242.026036) (xy 432.509208 -242.045508)
			(xy 432.555366 -242.072157) (xy 432.597037 -242.105388) (xy 432.633289 -242.144459) (xy 432.663313 -242.188496)
			(xy 432.686439 -242.236517) (xy 432.702149 -242.287447) (xy 432.710092 -242.340151) (xy 432.71059 -242.3668)
			(xy 432.710092 -242.393449) (xy 439.568072 -242.393449) (xy 439.568072 -242.340151) (xy 439.576015 -242.287447)
			(xy 439.591725 -242.236517) (xy 439.614851 -242.188496) (xy 439.644875 -242.144459) (xy 439.681127 -242.105388)
			(xy 439.722798 -242.072157) (xy 439.768956 -242.045508) (xy 439.81857 -242.026036) (xy 439.870532 -242.014176)
			(xy 439.923682 -242.010193) (xy 439.976832 -242.014176) (xy 440.028794 -242.026036) (xy 440.078408 -242.045508)
			(xy 440.124566 -242.072157) (xy 440.166237 -242.105388) (xy 440.202489 -242.144459) (xy 440.232513 -242.188496)
			(xy 440.255639 -242.236517) (xy 440.271349 -242.287447) (xy 440.279292 -242.340151) (xy 440.27979 -242.3668)
			(xy 440.279292 -242.393449) (xy 447.111872 -242.393449) (xy 447.111872 -242.340151) (xy 447.119815 -242.287447)
			(xy 447.135525 -242.236517) (xy 447.158651 -242.188496) (xy 447.188675 -242.144459) (xy 447.224927 -242.105388)
			(xy 447.266598 -242.072157) (xy 447.312756 -242.045508) (xy 447.36237 -242.026036) (xy 447.414332 -242.014176)
			(xy 447.467482 -242.010193) (xy 447.520632 -242.014176) (xy 447.572594 -242.026036) (xy 447.622208 -242.045508)
			(xy 447.668366 -242.072157) (xy 447.710037 -242.105388) (xy 447.746289 -242.144459) (xy 447.776313 -242.188496)
			(xy 447.799439 -242.236517) (xy 447.815149 -242.287447) (xy 447.823092 -242.340151) (xy 447.82359 -242.3668)
			(xy 447.823092 -242.393449) (xy 454.655672 -242.393449) (xy 454.655672 -242.340151) (xy 454.663615 -242.287447)
			(xy 454.679325 -242.236517) (xy 454.702451 -242.188496) (xy 454.732475 -242.144459) (xy 454.768727 -242.105388)
			(xy 454.810398 -242.072157) (xy 454.856556 -242.045508) (xy 454.90617 -242.026036) (xy 454.958132 -242.014176)
			(xy 455.011282 -242.010193) (xy 455.064432 -242.014176) (xy 455.116394 -242.026036) (xy 455.166008 -242.045508)
			(xy 455.212166 -242.072157) (xy 455.253837 -242.105388) (xy 455.290089 -242.144459) (xy 455.320113 -242.188496)
			(xy 455.343239 -242.236517) (xy 455.358949 -242.287447) (xy 455.366892 -242.340151) (xy 455.36739 -242.3668)
			(xy 455.366892 -242.393449) (xy 462.174072 -242.393449) (xy 462.174072 -242.340151) (xy 462.182015 -242.287447)
			(xy 462.197725 -242.236517) (xy 462.220851 -242.188496) (xy 462.250875 -242.144459) (xy 462.287127 -242.105388)
			(xy 462.328798 -242.072157) (xy 462.374956 -242.045508) (xy 462.42457 -242.026036) (xy 462.476532 -242.014176)
			(xy 462.529682 -242.010193) (xy 462.582832 -242.014176) (xy 462.634794 -242.026036) (xy 462.684408 -242.045508)
			(xy 462.730566 -242.072157) (xy 462.772237 -242.105388) (xy 462.808489 -242.144459) (xy 462.838513 -242.188496)
			(xy 462.861639 -242.236517) (xy 462.877349 -242.287447) (xy 462.885292 -242.340151) (xy 462.88579 -242.3668)
			(xy 462.885292 -242.393449) (xy 462.877349 -242.446153) (xy 462.861639 -242.497083) (xy 462.838513 -242.545104)
			(xy 462.808489 -242.589141) (xy 462.772237 -242.628212) (xy 462.730566 -242.661443) (xy 462.684408 -242.688092)
			(xy 462.634794 -242.707564) (xy 462.582832 -242.719424) (xy 462.529682 -242.723408) (xy 462.476532 -242.719424)
			(xy 462.42457 -242.707564) (xy 462.374956 -242.688092) (xy 462.328798 -242.661443) (xy 462.287127 -242.628212)
			(xy 462.250875 -242.589141) (xy 462.220851 -242.545104) (xy 462.197725 -242.497083) (xy 462.182015 -242.446153)
			(xy 462.174072 -242.393449) (xy 455.366892 -242.393449) (xy 455.358949 -242.446153) (xy 455.343239 -242.497083)
			(xy 455.320113 -242.545104) (xy 455.290089 -242.589141) (xy 455.253837 -242.628212) (xy 455.212166 -242.661443)
			(xy 455.166008 -242.688092) (xy 455.116394 -242.707564) (xy 455.064432 -242.719424) (xy 455.011282 -242.723408)
			(xy 454.958132 -242.719424) (xy 454.90617 -242.707564) (xy 454.856556 -242.688092) (xy 454.810398 -242.661443)
			(xy 454.768727 -242.628212) (xy 454.732475 -242.589141) (xy 454.702451 -242.545104) (xy 454.679325 -242.497083)
			(xy 454.663615 -242.446153) (xy 454.655672 -242.393449) (xy 447.823092 -242.393449) (xy 447.815149 -242.446153)
			(xy 447.799439 -242.497083) (xy 447.776313 -242.545104) (xy 447.746289 -242.589141) (xy 447.710037 -242.628212)
			(xy 447.668366 -242.661443) (xy 447.622208 -242.688092) (xy 447.572594 -242.707564) (xy 447.520632 -242.719424)
			(xy 447.467482 -242.723408) (xy 447.414332 -242.719424) (xy 447.36237 -242.707564) (xy 447.312756 -242.688092)
			(xy 447.266598 -242.661443) (xy 447.224927 -242.628212) (xy 447.188675 -242.589141) (xy 447.158651 -242.545104)
			(xy 447.135525 -242.497083) (xy 447.119815 -242.446153) (xy 447.111872 -242.393449) (xy 440.279292 -242.393449)
			(xy 440.271349 -242.446153) (xy 440.255639 -242.497083) (xy 440.232513 -242.545104) (xy 440.202489 -242.589141)
			(xy 440.166237 -242.628212) (xy 440.124566 -242.661443) (xy 440.078408 -242.688092) (xy 440.028794 -242.707564)
			(xy 439.976832 -242.719424) (xy 439.923682 -242.723408) (xy 439.870532 -242.719424) (xy 439.81857 -242.707564)
			(xy 439.768956 -242.688092) (xy 439.722798 -242.661443) (xy 439.681127 -242.628212) (xy 439.644875 -242.589141)
			(xy 439.614851 -242.545104) (xy 439.591725 -242.497083) (xy 439.576015 -242.446153) (xy 439.568072 -242.393449)
			(xy 432.710092 -242.393449) (xy 432.702149 -242.446153) (xy 432.686439 -242.497083) (xy 432.663313 -242.545104)
			(xy 432.633289 -242.589141) (xy 432.597037 -242.628212) (xy 432.555366 -242.661443) (xy 432.509208 -242.688092)
			(xy 432.459594 -242.707564) (xy 432.407632 -242.719424) (xy 432.354482 -242.723408) (xy 432.301332 -242.719424)
			(xy 432.24937 -242.707564) (xy 432.199756 -242.688092) (xy 432.153598 -242.661443) (xy 432.111927 -242.628212)
			(xy 432.075675 -242.589141) (xy 432.045651 -242.545104) (xy 432.022525 -242.497083) (xy 432.006815 -242.446153)
			(xy 431.998872 -242.393449) (xy 425.191692 -242.393449) (xy 425.183749 -242.446153) (xy 425.168039 -242.497083)
			(xy 425.144913 -242.545104) (xy 425.114889 -242.589141) (xy 425.078637 -242.628212) (xy 425.036966 -242.661443)
			(xy 424.990808 -242.688092) (xy 424.941194 -242.707564) (xy 424.889232 -242.719424) (xy 424.836082 -242.723408)
			(xy 424.782932 -242.719424) (xy 424.73097 -242.707564) (xy 424.681356 -242.688092) (xy 424.635198 -242.661443)
			(xy 424.593527 -242.628212) (xy 424.557275 -242.589141) (xy 424.527251 -242.545104) (xy 424.504125 -242.497083)
			(xy 424.488415 -242.446153) (xy 424.480472 -242.393449) (xy 417.622492 -242.393449) (xy 417.614549 -242.446153)
			(xy 417.598839 -242.497083) (xy 417.575713 -242.545104) (xy 417.545689 -242.589141) (xy 417.509437 -242.628212)
			(xy 417.467766 -242.661443) (xy 417.421608 -242.688092) (xy 417.371994 -242.707564) (xy 417.320032 -242.719424)
			(xy 417.266882 -242.723408) (xy 417.213732 -242.719424) (xy 417.16177 -242.707564) (xy 417.112156 -242.688092)
			(xy 417.065998 -242.661443) (xy 417.024327 -242.628212) (xy 416.988075 -242.589141) (xy 416.958051 -242.545104)
			(xy 416.934925 -242.497083) (xy 416.919215 -242.446153) (xy 416.911272 -242.393449) (xy 410.078692 -242.393449)
			(xy 410.070749 -242.446153) (xy 410.055039 -242.497083) (xy 410.031913 -242.545104) (xy 410.001889 -242.589141)
			(xy 409.965637 -242.628212) (xy 409.923966 -242.661443) (xy 409.877808 -242.688092) (xy 409.828194 -242.707564)
			(xy 409.776232 -242.719424) (xy 409.723082 -242.723408) (xy 409.669932 -242.719424) (xy 409.61797 -242.707564)
			(xy 409.568356 -242.688092) (xy 409.522198 -242.661443) (xy 409.480527 -242.628212) (xy 409.444275 -242.589141)
			(xy 409.414251 -242.545104) (xy 409.391125 -242.497083) (xy 409.375415 -242.446153) (xy 409.367472 -242.393449)
			(xy 407.4668 -242.393449) (xy 407.4668 -243.243333) (xy 409.367472 -243.243333) (xy 409.367472 -243.190035)
			(xy 409.375415 -243.137331) (xy 409.391125 -243.086401) (xy 409.414251 -243.03838) (xy 409.444275 -242.994343)
			(xy 409.480527 -242.955272) (xy 409.522198 -242.922041) (xy 409.568356 -242.895392) (xy 409.61797 -242.87592)
			(xy 409.669932 -242.86406) (xy 409.723082 -242.860077) (xy 409.776232 -242.86406) (xy 409.828194 -242.87592)
			(xy 409.877808 -242.895392) (xy 409.923966 -242.922041) (xy 409.965637 -242.955272) (xy 410.001889 -242.994343)
			(xy 410.031913 -243.03838) (xy 410.055039 -243.086401) (xy 410.070749 -243.137331) (xy 410.078692 -243.190035)
			(xy 410.07919 -243.216684) (xy 410.078692 -243.243333) (xy 412.811204 -243.243333) (xy 412.811204 -243.190035)
			(xy 412.819147 -243.137331) (xy 412.834857 -243.086401) (xy 412.857983 -243.03838) (xy 412.888007 -242.994343)
			(xy 412.924259 -242.955272) (xy 412.96593 -242.922041) (xy 413.012088 -242.895392) (xy 413.061702 -242.87592)
			(xy 413.113664 -242.86406) (xy 413.166814 -242.860077) (xy 413.219964 -242.86406) (xy 413.271926 -242.87592)
			(xy 413.32154 -242.895392) (xy 413.367698 -242.922041) (xy 413.409369 -242.955272) (xy 413.445621 -242.994343)
			(xy 413.475645 -243.03838) (xy 413.498771 -243.086401) (xy 413.514481 -243.137331) (xy 413.522424 -243.190035)
			(xy 413.522922 -243.216684) (xy 413.522424 -243.243333) (xy 416.911272 -243.243333) (xy 416.911272 -243.190035)
			(xy 416.919215 -243.137331) (xy 416.934925 -243.086401) (xy 416.958051 -243.03838) (xy 416.988075 -242.994343)
			(xy 417.024327 -242.955272) (xy 417.065998 -242.922041) (xy 417.112156 -242.895392) (xy 417.16177 -242.87592)
			(xy 417.213732 -242.86406) (xy 417.266882 -242.860077) (xy 417.320032 -242.86406) (xy 417.371994 -242.87592)
			(xy 417.421608 -242.895392) (xy 417.467766 -242.922041) (xy 417.509437 -242.955272) (xy 417.545689 -242.994343)
			(xy 417.575713 -243.03838) (xy 417.598839 -243.086401) (xy 417.614549 -243.137331) (xy 417.622492 -243.190035)
			(xy 417.62299 -243.216684) (xy 417.622492 -243.243333) (xy 420.380404 -243.243333) (xy 420.380404 -243.190035)
			(xy 420.388347 -243.137331) (xy 420.404057 -243.086401) (xy 420.427183 -243.03838) (xy 420.457207 -242.994343)
			(xy 420.493459 -242.955272) (xy 420.53513 -242.922041) (xy 420.581288 -242.895392) (xy 420.630902 -242.87592)
			(xy 420.682864 -242.86406) (xy 420.736014 -242.860077) (xy 420.789164 -242.86406) (xy 420.841126 -242.87592)
			(xy 420.89074 -242.895392) (xy 420.936898 -242.922041) (xy 420.978569 -242.955272) (xy 421.014821 -242.994343)
			(xy 421.044845 -243.03838) (xy 421.067971 -243.086401) (xy 421.083681 -243.137331) (xy 421.091624 -243.190035)
			(xy 421.092122 -243.216684) (xy 421.091624 -243.243333) (xy 424.480472 -243.243333) (xy 424.480472 -243.190035)
			(xy 424.488415 -243.137331) (xy 424.504125 -243.086401) (xy 424.527251 -243.03838) (xy 424.557275 -242.994343)
			(xy 424.593527 -242.955272) (xy 424.635198 -242.922041) (xy 424.681356 -242.895392) (xy 424.73097 -242.87592)
			(xy 424.782932 -242.86406) (xy 424.836082 -242.860077) (xy 424.889232 -242.86406) (xy 424.941194 -242.87592)
			(xy 424.990808 -242.895392) (xy 425.036966 -242.922041) (xy 425.078637 -242.955272) (xy 425.114889 -242.994343)
			(xy 425.144913 -243.03838) (xy 425.168039 -243.086401) (xy 425.183749 -243.137331) (xy 425.191692 -243.190035)
			(xy 425.19219 -243.216684) (xy 425.191692 -243.243333) (xy 427.898804 -243.243333) (xy 427.898804 -243.190035)
			(xy 427.906747 -243.137331) (xy 427.922457 -243.086401) (xy 427.945583 -243.03838) (xy 427.975607 -242.994343)
			(xy 428.011859 -242.955272) (xy 428.05353 -242.922041) (xy 428.099688 -242.895392) (xy 428.149302 -242.87592)
			(xy 428.201264 -242.86406) (xy 428.254414 -242.860077) (xy 428.307564 -242.86406) (xy 428.359526 -242.87592)
			(xy 428.40914 -242.895392) (xy 428.455298 -242.922041) (xy 428.496969 -242.955272) (xy 428.533221 -242.994343)
			(xy 428.563245 -243.03838) (xy 428.586371 -243.086401) (xy 428.602081 -243.137331) (xy 428.610024 -243.190035)
			(xy 428.610522 -243.216684) (xy 428.610024 -243.243333) (xy 431.998872 -243.243333) (xy 431.998872 -243.190035)
			(xy 432.006815 -243.137331) (xy 432.022525 -243.086401) (xy 432.045651 -243.03838) (xy 432.075675 -242.994343)
			(xy 432.111927 -242.955272) (xy 432.153598 -242.922041) (xy 432.199756 -242.895392) (xy 432.24937 -242.87592)
			(xy 432.301332 -242.86406) (xy 432.354482 -242.860077) (xy 432.407632 -242.86406) (xy 432.459594 -242.87592)
			(xy 432.509208 -242.895392) (xy 432.555366 -242.922041) (xy 432.597037 -242.955272) (xy 432.633289 -242.994343)
			(xy 432.663313 -243.03838) (xy 432.686439 -243.086401) (xy 432.702149 -243.137331) (xy 432.710092 -243.190035)
			(xy 432.71059 -243.216684) (xy 432.710092 -243.243333) (xy 435.468004 -243.243333) (xy 435.468004 -243.190035)
			(xy 435.475947 -243.137331) (xy 435.491657 -243.086401) (xy 435.514783 -243.03838) (xy 435.544807 -242.994343)
			(xy 435.581059 -242.955272) (xy 435.62273 -242.922041) (xy 435.668888 -242.895392) (xy 435.718502 -242.87592)
			(xy 435.770464 -242.86406) (xy 435.823614 -242.860077) (xy 435.876764 -242.86406) (xy 435.928726 -242.87592)
			(xy 435.97834 -242.895392) (xy 436.024498 -242.922041) (xy 436.066169 -242.955272) (xy 436.102421 -242.994343)
			(xy 436.132445 -243.03838) (xy 436.155571 -243.086401) (xy 436.171281 -243.137331) (xy 436.179224 -243.190035)
			(xy 436.179722 -243.216684) (xy 436.179224 -243.243333) (xy 439.568072 -243.243333) (xy 439.568072 -243.190035)
			(xy 439.576015 -243.137331) (xy 439.591725 -243.086401) (xy 439.614851 -243.03838) (xy 439.644875 -242.994343)
			(xy 439.681127 -242.955272) (xy 439.722798 -242.922041) (xy 439.768956 -242.895392) (xy 439.81857 -242.87592)
			(xy 439.870532 -242.86406) (xy 439.923682 -242.860077) (xy 439.976832 -242.86406) (xy 440.028794 -242.87592)
			(xy 440.078408 -242.895392) (xy 440.124566 -242.922041) (xy 440.166237 -242.955272) (xy 440.202489 -242.994343)
			(xy 440.232513 -243.03838) (xy 440.255639 -243.086401) (xy 440.271349 -243.137331) (xy 440.279292 -243.190035)
			(xy 440.27979 -243.216684) (xy 440.279292 -243.243333) (xy 443.011804 -243.243333) (xy 443.011804 -243.190035)
			(xy 443.019747 -243.137331) (xy 443.035457 -243.086401) (xy 443.058583 -243.03838) (xy 443.088607 -242.994343)
			(xy 443.124859 -242.955272) (xy 443.16653 -242.922041) (xy 443.212688 -242.895392) (xy 443.262302 -242.87592)
			(xy 443.314264 -242.86406) (xy 443.367414 -242.860077) (xy 443.420564 -242.86406) (xy 443.472526 -242.87592)
			(xy 443.52214 -242.895392) (xy 443.568298 -242.922041) (xy 443.609969 -242.955272) (xy 443.646221 -242.994343)
			(xy 443.676245 -243.03838) (xy 443.699371 -243.086401) (xy 443.715081 -243.137331) (xy 443.723024 -243.190035)
			(xy 443.723522 -243.216684) (xy 443.723024 -243.243333) (xy 447.111872 -243.243333) (xy 447.111872 -243.190035)
			(xy 447.119815 -243.137331) (xy 447.135525 -243.086401) (xy 447.158651 -243.03838) (xy 447.188675 -242.994343)
			(xy 447.224927 -242.955272) (xy 447.266598 -242.922041) (xy 447.312756 -242.895392) (xy 447.36237 -242.87592)
			(xy 447.414332 -242.86406) (xy 447.467482 -242.860077) (xy 447.520632 -242.86406) (xy 447.572594 -242.87592)
			(xy 447.622208 -242.895392) (xy 447.668366 -242.922041) (xy 447.710037 -242.955272) (xy 447.746289 -242.994343)
			(xy 447.776313 -243.03838) (xy 447.799439 -243.086401) (xy 447.815149 -243.137331) (xy 447.823092 -243.190035)
			(xy 447.82359 -243.216684) (xy 447.823092 -243.243333) (xy 450.555604 -243.243333) (xy 450.555604 -243.190035)
			(xy 450.563547 -243.137331) (xy 450.579257 -243.086401) (xy 450.602383 -243.03838) (xy 450.632407 -242.994343)
			(xy 450.668659 -242.955272) (xy 450.71033 -242.922041) (xy 450.756488 -242.895392) (xy 450.806102 -242.87592)
			(xy 450.858064 -242.86406) (xy 450.911214 -242.860077) (xy 450.964364 -242.86406) (xy 451.016326 -242.87592)
			(xy 451.06594 -242.895392) (xy 451.112098 -242.922041) (xy 451.153769 -242.955272) (xy 451.190021 -242.994343)
			(xy 451.220045 -243.03838) (xy 451.243171 -243.086401) (xy 451.258881 -243.137331) (xy 451.266824 -243.190035)
			(xy 451.267322 -243.216684) (xy 451.266824 -243.243333) (xy 454.655672 -243.243333) (xy 454.655672 -243.190035)
			(xy 454.663615 -243.137331) (xy 454.679325 -243.086401) (xy 454.702451 -243.03838) (xy 454.732475 -242.994343)
			(xy 454.768727 -242.955272) (xy 454.810398 -242.922041) (xy 454.856556 -242.895392) (xy 454.90617 -242.87592)
			(xy 454.958132 -242.86406) (xy 455.011282 -242.860077) (xy 455.064432 -242.86406) (xy 455.116394 -242.87592)
			(xy 455.166008 -242.895392) (xy 455.212166 -242.922041) (xy 455.253837 -242.955272) (xy 455.290089 -242.994343)
			(xy 455.320113 -243.03838) (xy 455.343239 -243.086401) (xy 455.358949 -243.137331) (xy 455.366892 -243.190035)
			(xy 455.36739 -243.216684) (xy 455.366892 -243.243333) (xy 458.099404 -243.243333) (xy 458.099404 -243.190035)
			(xy 458.107347 -243.137331) (xy 458.123057 -243.086401) (xy 458.146183 -243.03838) (xy 458.176207 -242.994343)
			(xy 458.212459 -242.955272) (xy 458.25413 -242.922041) (xy 458.300288 -242.895392) (xy 458.349902 -242.87592)
			(xy 458.401864 -242.86406) (xy 458.455014 -242.860077) (xy 458.508164 -242.86406) (xy 458.560126 -242.87592)
			(xy 458.60974 -242.895392) (xy 458.655898 -242.922041) (xy 458.697569 -242.955272) (xy 458.733821 -242.994343)
			(xy 458.763845 -243.03838) (xy 458.786971 -243.086401) (xy 458.802681 -243.137331) (xy 458.810624 -243.190035)
			(xy 458.811122 -243.216684) (xy 458.810624 -243.243333) (xy 462.174072 -243.243333) (xy 462.174072 -243.190035)
			(xy 462.182015 -243.137331) (xy 462.197725 -243.086401) (xy 462.220851 -243.03838) (xy 462.250875 -242.994343)
			(xy 462.287127 -242.955272) (xy 462.328798 -242.922041) (xy 462.374956 -242.895392) (xy 462.42457 -242.87592)
			(xy 462.476532 -242.86406) (xy 462.529682 -242.860077) (xy 462.582832 -242.86406) (xy 462.634794 -242.87592)
			(xy 462.684408 -242.895392) (xy 462.730566 -242.922041) (xy 462.772237 -242.955272) (xy 462.808489 -242.994343)
			(xy 462.838513 -243.03838) (xy 462.861639 -243.086401) (xy 462.877349 -243.137331) (xy 462.885292 -243.190035)
			(xy 462.88579 -243.216684) (xy 462.885292 -243.243333) (xy 462.877349 -243.296037) (xy 462.861639 -243.346967)
			(xy 462.838513 -243.394988) (xy 462.808489 -243.439025) (xy 462.772237 -243.478096) (xy 462.730566 -243.511327)
			(xy 462.684408 -243.537976) (xy 462.634794 -243.557448) (xy 462.582832 -243.569308) (xy 462.529682 -243.573292)
			(xy 462.476532 -243.569308) (xy 462.42457 -243.557448) (xy 462.374956 -243.537976) (xy 462.328798 -243.511327)
			(xy 462.287127 -243.478096) (xy 462.250875 -243.439025) (xy 462.220851 -243.394988) (xy 462.197725 -243.346967)
			(xy 462.182015 -243.296037) (xy 462.174072 -243.243333) (xy 458.810624 -243.243333) (xy 458.802681 -243.296037)
			(xy 458.786971 -243.346967) (xy 458.763845 -243.394988) (xy 458.733821 -243.439025) (xy 458.697569 -243.478096)
			(xy 458.655898 -243.511327) (xy 458.60974 -243.537976) (xy 458.560126 -243.557448) (xy 458.508164 -243.569308)
			(xy 458.455014 -243.573292) (xy 458.401864 -243.569308) (xy 458.349902 -243.557448) (xy 458.300288 -243.537976)
			(xy 458.25413 -243.511327) (xy 458.212459 -243.478096) (xy 458.176207 -243.439025) (xy 458.146183 -243.394988)
			(xy 458.123057 -243.346967) (xy 458.107347 -243.296037) (xy 458.099404 -243.243333) (xy 455.366892 -243.243333)
			(xy 455.358949 -243.296037) (xy 455.343239 -243.346967) (xy 455.320113 -243.394988) (xy 455.290089 -243.439025)
			(xy 455.253837 -243.478096) (xy 455.212166 -243.511327) (xy 455.166008 -243.537976) (xy 455.116394 -243.557448)
			(xy 455.064432 -243.569308) (xy 455.011282 -243.573292) (xy 454.958132 -243.569308) (xy 454.90617 -243.557448)
			(xy 454.856556 -243.537976) (xy 454.810398 -243.511327) (xy 454.768727 -243.478096) (xy 454.732475 -243.439025)
			(xy 454.702451 -243.394988) (xy 454.679325 -243.346967) (xy 454.663615 -243.296037) (xy 454.655672 -243.243333)
			(xy 451.266824 -243.243333) (xy 451.258881 -243.296037) (xy 451.243171 -243.346967) (xy 451.220045 -243.394988)
			(xy 451.190021 -243.439025) (xy 451.153769 -243.478096) (xy 451.112098 -243.511327) (xy 451.06594 -243.537976)
			(xy 451.016326 -243.557448) (xy 450.964364 -243.569308) (xy 450.911214 -243.573292) (xy 450.858064 -243.569308)
			(xy 450.806102 -243.557448) (xy 450.756488 -243.537976) (xy 450.71033 -243.511327) (xy 450.668659 -243.478096)
			(xy 450.632407 -243.439025) (xy 450.602383 -243.394988) (xy 450.579257 -243.346967) (xy 450.563547 -243.296037)
			(xy 450.555604 -243.243333) (xy 447.823092 -243.243333) (xy 447.815149 -243.296037) (xy 447.799439 -243.346967)
			(xy 447.776313 -243.394988) (xy 447.746289 -243.439025) (xy 447.710037 -243.478096) (xy 447.668366 -243.511327)
			(xy 447.622208 -243.537976) (xy 447.572594 -243.557448) (xy 447.520632 -243.569308) (xy 447.467482 -243.573292)
			(xy 447.414332 -243.569308) (xy 447.36237 -243.557448) (xy 447.312756 -243.537976) (xy 447.266598 -243.511327)
			(xy 447.224927 -243.478096) (xy 447.188675 -243.439025) (xy 447.158651 -243.394988) (xy 447.135525 -243.346967)
			(xy 447.119815 -243.296037) (xy 447.111872 -243.243333) (xy 443.723024 -243.243333) (xy 443.715081 -243.296037)
			(xy 443.699371 -243.346967) (xy 443.676245 -243.394988) (xy 443.646221 -243.439025) (xy 443.609969 -243.478096)
			(xy 443.568298 -243.511327) (xy 443.52214 -243.537976) (xy 443.472526 -243.557448) (xy 443.420564 -243.569308)
			(xy 443.367414 -243.573292) (xy 443.314264 -243.569308) (xy 443.262302 -243.557448) (xy 443.212688 -243.537976)
			(xy 443.16653 -243.511327) (xy 443.124859 -243.478096) (xy 443.088607 -243.439025) (xy 443.058583 -243.394988)
			(xy 443.035457 -243.346967) (xy 443.019747 -243.296037) (xy 443.011804 -243.243333) (xy 440.279292 -243.243333)
			(xy 440.271349 -243.296037) (xy 440.255639 -243.346967) (xy 440.232513 -243.394988) (xy 440.202489 -243.439025)
			(xy 440.166237 -243.478096) (xy 440.124566 -243.511327) (xy 440.078408 -243.537976) (xy 440.028794 -243.557448)
			(xy 439.976832 -243.569308) (xy 439.923682 -243.573292) (xy 439.870532 -243.569308) (xy 439.81857 -243.557448)
			(xy 439.768956 -243.537976) (xy 439.722798 -243.511327) (xy 439.681127 -243.478096) (xy 439.644875 -243.439025)
			(xy 439.614851 -243.394988) (xy 439.591725 -243.346967) (xy 439.576015 -243.296037) (xy 439.568072 -243.243333)
			(xy 436.179224 -243.243333) (xy 436.171281 -243.296037) (xy 436.155571 -243.346967) (xy 436.132445 -243.394988)
			(xy 436.102421 -243.439025) (xy 436.066169 -243.478096) (xy 436.024498 -243.511327) (xy 435.97834 -243.537976)
			(xy 435.928726 -243.557448) (xy 435.876764 -243.569308) (xy 435.823614 -243.573292) (xy 435.770464 -243.569308)
			(xy 435.718502 -243.557448) (xy 435.668888 -243.537976) (xy 435.62273 -243.511327) (xy 435.581059 -243.478096)
			(xy 435.544807 -243.439025) (xy 435.514783 -243.394988) (xy 435.491657 -243.346967) (xy 435.475947 -243.296037)
			(xy 435.468004 -243.243333) (xy 432.710092 -243.243333) (xy 432.702149 -243.296037) (xy 432.686439 -243.346967)
			(xy 432.663313 -243.394988) (xy 432.633289 -243.439025) (xy 432.597037 -243.478096) (xy 432.555366 -243.511327)
			(xy 432.509208 -243.537976) (xy 432.459594 -243.557448) (xy 432.407632 -243.569308) (xy 432.354482 -243.573292)
			(xy 432.301332 -243.569308) (xy 432.24937 -243.557448) (xy 432.199756 -243.537976) (xy 432.153598 -243.511327)
			(xy 432.111927 -243.478096) (xy 432.075675 -243.439025) (xy 432.045651 -243.394988) (xy 432.022525 -243.346967)
			(xy 432.006815 -243.296037) (xy 431.998872 -243.243333) (xy 428.610024 -243.243333) (xy 428.602081 -243.296037)
			(xy 428.586371 -243.346967) (xy 428.563245 -243.394988) (xy 428.533221 -243.439025) (xy 428.496969 -243.478096)
			(xy 428.455298 -243.511327) (xy 428.40914 -243.537976) (xy 428.359526 -243.557448) (xy 428.307564 -243.569308)
			(xy 428.254414 -243.573292) (xy 428.201264 -243.569308) (xy 428.149302 -243.557448) (xy 428.099688 -243.537976)
			(xy 428.05353 -243.511327) (xy 428.011859 -243.478096) (xy 427.975607 -243.439025) (xy 427.945583 -243.394988)
			(xy 427.922457 -243.346967) (xy 427.906747 -243.296037) (xy 427.898804 -243.243333) (xy 425.191692 -243.243333)
			(xy 425.183749 -243.296037) (xy 425.168039 -243.346967) (xy 425.144913 -243.394988) (xy 425.114889 -243.439025)
			(xy 425.078637 -243.478096) (xy 425.036966 -243.511327) (xy 424.990808 -243.537976) (xy 424.941194 -243.557448)
			(xy 424.889232 -243.569308) (xy 424.836082 -243.573292) (xy 424.782932 -243.569308) (xy 424.73097 -243.557448)
			(xy 424.681356 -243.537976) (xy 424.635198 -243.511327) (xy 424.593527 -243.478096) (xy 424.557275 -243.439025)
			(xy 424.527251 -243.394988) (xy 424.504125 -243.346967) (xy 424.488415 -243.296037) (xy 424.480472 -243.243333)
			(xy 421.091624 -243.243333) (xy 421.083681 -243.296037) (xy 421.067971 -243.346967) (xy 421.044845 -243.394988)
			(xy 421.014821 -243.439025) (xy 420.978569 -243.478096) (xy 420.936898 -243.511327) (xy 420.89074 -243.537976)
			(xy 420.841126 -243.557448) (xy 420.789164 -243.569308) (xy 420.736014 -243.573292) (xy 420.682864 -243.569308)
			(xy 420.630902 -243.557448) (xy 420.581288 -243.537976) (xy 420.53513 -243.511327) (xy 420.493459 -243.478096)
			(xy 420.457207 -243.439025) (xy 420.427183 -243.394988) (xy 420.404057 -243.346967) (xy 420.388347 -243.296037)
			(xy 420.380404 -243.243333) (xy 417.622492 -243.243333) (xy 417.614549 -243.296037) (xy 417.598839 -243.346967)
			(xy 417.575713 -243.394988) (xy 417.545689 -243.439025) (xy 417.509437 -243.478096) (xy 417.467766 -243.511327)
			(xy 417.421608 -243.537976) (xy 417.371994 -243.557448) (xy 417.320032 -243.569308) (xy 417.266882 -243.573292)
			(xy 417.213732 -243.569308) (xy 417.16177 -243.557448) (xy 417.112156 -243.537976) (xy 417.065998 -243.511327)
			(xy 417.024327 -243.478096) (xy 416.988075 -243.439025) (xy 416.958051 -243.394988) (xy 416.934925 -243.346967)
			(xy 416.919215 -243.296037) (xy 416.911272 -243.243333) (xy 413.522424 -243.243333) (xy 413.514481 -243.296037)
			(xy 413.498771 -243.346967) (xy 413.475645 -243.394988) (xy 413.445621 -243.439025) (xy 413.409369 -243.478096)
			(xy 413.367698 -243.511327) (xy 413.32154 -243.537976) (xy 413.271926 -243.557448) (xy 413.219964 -243.569308)
			(xy 413.166814 -243.573292) (xy 413.113664 -243.569308) (xy 413.061702 -243.557448) (xy 413.012088 -243.537976)
			(xy 412.96593 -243.511327) (xy 412.924259 -243.478096) (xy 412.888007 -243.439025) (xy 412.857983 -243.394988)
			(xy 412.834857 -243.346967) (xy 412.819147 -243.296037) (xy 412.811204 -243.243333) (xy 410.078692 -243.243333)
			(xy 410.070749 -243.296037) (xy 410.055039 -243.346967) (xy 410.031913 -243.394988) (xy 410.001889 -243.439025)
			(xy 409.965637 -243.478096) (xy 409.923966 -243.511327) (xy 409.877808 -243.537976) (xy 409.828194 -243.557448)
			(xy 409.776232 -243.569308) (xy 409.723082 -243.573292) (xy 409.669932 -243.569308) (xy 409.61797 -243.557448)
			(xy 409.568356 -243.537976) (xy 409.522198 -243.511327) (xy 409.480527 -243.478096) (xy 409.444275 -243.439025)
			(xy 409.414251 -243.394988) (xy 409.391125 -243.346967) (xy 409.375415 -243.296037) (xy 409.367472 -243.243333)
			(xy 407.4668 -243.243333) (xy 407.4668 -244.093217) (xy 412.811204 -244.093217) (xy 412.811204 -244.039919)
			(xy 412.819147 -243.987215) (xy 412.834857 -243.936285) (xy 412.857983 -243.888264) (xy 412.888007 -243.844227)
			(xy 412.924259 -243.805156) (xy 412.96593 -243.771925) (xy 413.012088 -243.745276) (xy 413.061702 -243.725804)
			(xy 413.113664 -243.713944) (xy 413.166814 -243.709961) (xy 413.219964 -243.713944) (xy 413.271926 -243.725804)
			(xy 413.32154 -243.745276) (xy 413.367698 -243.771925) (xy 413.409369 -243.805156) (xy 413.445621 -243.844227)
			(xy 413.475645 -243.888264) (xy 413.498771 -243.936285) (xy 413.514481 -243.987215) (xy 413.522424 -244.039919)
			(xy 413.522922 -244.066568) (xy 413.522424 -244.093217) (xy 420.380404 -244.093217) (xy 420.380404 -244.039919)
			(xy 420.388347 -243.987215) (xy 420.404057 -243.936285) (xy 420.427183 -243.888264) (xy 420.457207 -243.844227)
			(xy 420.493459 -243.805156) (xy 420.53513 -243.771925) (xy 420.581288 -243.745276) (xy 420.630902 -243.725804)
			(xy 420.682864 -243.713944) (xy 420.736014 -243.709961) (xy 420.789164 -243.713944) (xy 420.841126 -243.725804)
			(xy 420.89074 -243.745276) (xy 420.936898 -243.771925) (xy 420.978569 -243.805156) (xy 421.014821 -243.844227)
			(xy 421.044845 -243.888264) (xy 421.067971 -243.936285) (xy 421.083681 -243.987215) (xy 421.091624 -244.039919)
			(xy 421.092122 -244.066568) (xy 421.091624 -244.093217) (xy 427.898804 -244.093217) (xy 427.898804 -244.039919)
			(xy 427.906747 -243.987215) (xy 427.922457 -243.936285) (xy 427.945583 -243.888264) (xy 427.975607 -243.844227)
			(xy 428.011859 -243.805156) (xy 428.05353 -243.771925) (xy 428.099688 -243.745276) (xy 428.149302 -243.725804)
			(xy 428.201264 -243.713944) (xy 428.254414 -243.709961) (xy 428.307564 -243.713944) (xy 428.359526 -243.725804)
			(xy 428.40914 -243.745276) (xy 428.455298 -243.771925) (xy 428.496969 -243.805156) (xy 428.533221 -243.844227)
			(xy 428.563245 -243.888264) (xy 428.586371 -243.936285) (xy 428.602081 -243.987215) (xy 428.610024 -244.039919)
			(xy 428.610522 -244.066568) (xy 428.610024 -244.093217) (xy 435.468004 -244.093217) (xy 435.468004 -244.039919)
			(xy 435.475947 -243.987215) (xy 435.491657 -243.936285) (xy 435.514783 -243.888264) (xy 435.544807 -243.844227)
			(xy 435.581059 -243.805156) (xy 435.62273 -243.771925) (xy 435.668888 -243.745276) (xy 435.718502 -243.725804)
			(xy 435.770464 -243.713944) (xy 435.823614 -243.709961) (xy 435.876764 -243.713944) (xy 435.928726 -243.725804)
			(xy 435.97834 -243.745276) (xy 436.024498 -243.771925) (xy 436.066169 -243.805156) (xy 436.102421 -243.844227)
			(xy 436.132445 -243.888264) (xy 436.155571 -243.936285) (xy 436.171281 -243.987215) (xy 436.179224 -244.039919)
			(xy 436.179722 -244.066568) (xy 436.179224 -244.093217) (xy 443.011804 -244.093217) (xy 443.011804 -244.039919)
			(xy 443.019747 -243.987215) (xy 443.035457 -243.936285) (xy 443.058583 -243.888264) (xy 443.088607 -243.844227)
			(xy 443.124859 -243.805156) (xy 443.16653 -243.771925) (xy 443.212688 -243.745276) (xy 443.262302 -243.725804)
			(xy 443.314264 -243.713944) (xy 443.367414 -243.709961) (xy 443.420564 -243.713944) (xy 443.472526 -243.725804)
			(xy 443.52214 -243.745276) (xy 443.568298 -243.771925) (xy 443.609969 -243.805156) (xy 443.646221 -243.844227)
			(xy 443.676245 -243.888264) (xy 443.699371 -243.936285) (xy 443.715081 -243.987215) (xy 443.723024 -244.039919)
			(xy 443.723522 -244.066568) (xy 443.723024 -244.093217) (xy 450.555604 -244.093217) (xy 450.555604 -244.039919)
			(xy 450.563547 -243.987215) (xy 450.579257 -243.936285) (xy 450.602383 -243.888264) (xy 450.632407 -243.844227)
			(xy 450.668659 -243.805156) (xy 450.71033 -243.771925) (xy 450.756488 -243.745276) (xy 450.806102 -243.725804)
			(xy 450.858064 -243.713944) (xy 450.911214 -243.709961) (xy 450.964364 -243.713944) (xy 451.016326 -243.725804)
			(xy 451.06594 -243.745276) (xy 451.112098 -243.771925) (xy 451.153769 -243.805156) (xy 451.190021 -243.844227)
			(xy 451.220045 -243.888264) (xy 451.243171 -243.936285) (xy 451.258881 -243.987215) (xy 451.266824 -244.039919)
			(xy 451.267322 -244.066568) (xy 451.266824 -244.093217) (xy 458.099404 -244.093217) (xy 458.099404 -244.039919)
			(xy 458.107347 -243.987215) (xy 458.123057 -243.936285) (xy 458.146183 -243.888264) (xy 458.176207 -243.844227)
			(xy 458.212459 -243.805156) (xy 458.25413 -243.771925) (xy 458.300288 -243.745276) (xy 458.349902 -243.725804)
			(xy 458.401864 -243.713944) (xy 458.455014 -243.709961) (xy 458.508164 -243.713944) (xy 458.560126 -243.725804)
			(xy 458.60974 -243.745276) (xy 458.655898 -243.771925) (xy 458.697569 -243.805156) (xy 458.733821 -243.844227)
			(xy 458.763845 -243.888264) (xy 458.786971 -243.936285) (xy 458.802681 -243.987215) (xy 458.810624 -244.039919)
			(xy 458.811122 -244.066568) (xy 458.810624 -244.093217) (xy 458.802681 -244.145921) (xy 458.786971 -244.196851)
			(xy 458.763845 -244.244872) (xy 458.733821 -244.288909) (xy 458.697569 -244.32798) (xy 458.655898 -244.361211)
			(xy 458.60974 -244.38786) (xy 458.560126 -244.407332) (xy 458.508164 -244.419192) (xy 458.455014 -244.423176)
			(xy 458.401864 -244.419192) (xy 458.349902 -244.407332) (xy 458.300288 -244.38786) (xy 458.25413 -244.361211)
			(xy 458.212459 -244.32798) (xy 458.176207 -244.288909) (xy 458.146183 -244.244872) (xy 458.123057 -244.196851)
			(xy 458.107347 -244.145921) (xy 458.099404 -244.093217) (xy 451.266824 -244.093217) (xy 451.258881 -244.145921)
			(xy 451.243171 -244.196851) (xy 451.220045 -244.244872) (xy 451.190021 -244.288909) (xy 451.153769 -244.32798)
			(xy 451.112098 -244.361211) (xy 451.06594 -244.38786) (xy 451.016326 -244.407332) (xy 450.964364 -244.419192)
			(xy 450.911214 -244.423176) (xy 450.858064 -244.419192) (xy 450.806102 -244.407332) (xy 450.756488 -244.38786)
			(xy 450.71033 -244.361211) (xy 450.668659 -244.32798) (xy 450.632407 -244.288909) (xy 450.602383 -244.244872)
			(xy 450.579257 -244.196851) (xy 450.563547 -244.145921) (xy 450.555604 -244.093217) (xy 443.723024 -244.093217)
			(xy 443.715081 -244.145921) (xy 443.699371 -244.196851) (xy 443.676245 -244.244872) (xy 443.646221 -244.288909)
			(xy 443.609969 -244.32798) (xy 443.568298 -244.361211) (xy 443.52214 -244.38786) (xy 443.472526 -244.407332)
			(xy 443.420564 -244.419192) (xy 443.367414 -244.423176) (xy 443.314264 -244.419192) (xy 443.262302 -244.407332)
			(xy 443.212688 -244.38786) (xy 443.16653 -244.361211) (xy 443.124859 -244.32798) (xy 443.088607 -244.288909)
			(xy 443.058583 -244.244872) (xy 443.035457 -244.196851) (xy 443.019747 -244.145921) (xy 443.011804 -244.093217)
			(xy 436.179224 -244.093217) (xy 436.171281 -244.145921) (xy 436.155571 -244.196851) (xy 436.132445 -244.244872)
			(xy 436.102421 -244.288909) (xy 436.066169 -244.32798) (xy 436.024498 -244.361211) (xy 435.97834 -244.38786)
			(xy 435.928726 -244.407332) (xy 435.876764 -244.419192) (xy 435.823614 -244.423176) (xy 435.770464 -244.419192)
			(xy 435.718502 -244.407332) (xy 435.668888 -244.38786) (xy 435.62273 -244.361211) (xy 435.581059 -244.32798)
			(xy 435.544807 -244.288909) (xy 435.514783 -244.244872) (xy 435.491657 -244.196851) (xy 435.475947 -244.145921)
			(xy 435.468004 -244.093217) (xy 428.610024 -244.093217) (xy 428.602081 -244.145921) (xy 428.586371 -244.196851)
			(xy 428.563245 -244.244872) (xy 428.533221 -244.288909) (xy 428.496969 -244.32798) (xy 428.455298 -244.361211)
			(xy 428.40914 -244.38786) (xy 428.359526 -244.407332) (xy 428.307564 -244.419192) (xy 428.254414 -244.423176)
			(xy 428.201264 -244.419192) (xy 428.149302 -244.407332) (xy 428.099688 -244.38786) (xy 428.05353 -244.361211)
			(xy 428.011859 -244.32798) (xy 427.975607 -244.288909) (xy 427.945583 -244.244872) (xy 427.922457 -244.196851)
			(xy 427.906747 -244.145921) (xy 427.898804 -244.093217) (xy 421.091624 -244.093217) (xy 421.083681 -244.145921)
			(xy 421.067971 -244.196851) (xy 421.044845 -244.244872) (xy 421.014821 -244.288909) (xy 420.978569 -244.32798)
			(xy 420.936898 -244.361211) (xy 420.89074 -244.38786) (xy 420.841126 -244.407332) (xy 420.789164 -244.419192)
			(xy 420.736014 -244.423176) (xy 420.682864 -244.419192) (xy 420.630902 -244.407332) (xy 420.581288 -244.38786)
			(xy 420.53513 -244.361211) (xy 420.493459 -244.32798) (xy 420.457207 -244.288909) (xy 420.427183 -244.244872)
			(xy 420.404057 -244.196851) (xy 420.388347 -244.145921) (xy 420.380404 -244.093217) (xy 413.522424 -244.093217)
			(xy 413.514481 -244.145921) (xy 413.498771 -244.196851) (xy 413.475645 -244.244872) (xy 413.445621 -244.288909)
			(xy 413.409369 -244.32798) (xy 413.367698 -244.361211) (xy 413.32154 -244.38786) (xy 413.271926 -244.407332)
			(xy 413.219964 -244.419192) (xy 413.166814 -244.423176) (xy 413.113664 -244.419192) (xy 413.061702 -244.407332)
			(xy 413.012088 -244.38786) (xy 412.96593 -244.361211) (xy 412.924259 -244.32798) (xy 412.888007 -244.288909)
			(xy 412.857983 -244.244872) (xy 412.834857 -244.196851) (xy 412.819147 -244.145921) (xy 412.811204 -244.093217)
			(xy 407.4668 -244.093217) (xy 407.4668 -244.943355) (xy 424.480472 -244.943355) (xy 424.480472 -244.890057)
			(xy 424.488415 -244.837353) (xy 424.504125 -244.786423) (xy 424.527251 -244.738402) (xy 424.557275 -244.694365)
			(xy 424.593527 -244.655294) (xy 424.635198 -244.622063) (xy 424.681356 -244.595414) (xy 424.73097 -244.575942)
			(xy 424.782932 -244.564082) (xy 424.836082 -244.560099) (xy 424.889232 -244.564082) (xy 424.941194 -244.575942)
			(xy 424.990808 -244.595414) (xy 425.036966 -244.622063) (xy 425.078637 -244.655294) (xy 425.114889 -244.694365)
			(xy 425.144913 -244.738402) (xy 425.168039 -244.786423) (xy 425.183749 -244.837353) (xy 425.191692 -244.890057)
			(xy 425.19219 -244.916706) (xy 425.191692 -244.943355) (xy 432.024272 -244.943355) (xy 432.024272 -244.890057)
			(xy 432.032215 -244.837353) (xy 432.047925 -244.786423) (xy 432.071051 -244.738402) (xy 432.101075 -244.694365)
			(xy 432.137327 -244.655294) (xy 432.178998 -244.622063) (xy 432.225156 -244.595414) (xy 432.27477 -244.575942)
			(xy 432.326732 -244.564082) (xy 432.379882 -244.560099) (xy 432.433032 -244.564082) (xy 432.484994 -244.575942)
			(xy 432.534608 -244.595414) (xy 432.580766 -244.622063) (xy 432.622437 -244.655294) (xy 432.658689 -244.694365)
			(xy 432.688713 -244.738402) (xy 432.711839 -244.786423) (xy 432.727549 -244.837353) (xy 432.735492 -244.890057)
			(xy 432.73599 -244.916706) (xy 432.735492 -244.943355) (xy 439.568072 -244.943355) (xy 439.568072 -244.890057)
			(xy 439.576015 -244.837353) (xy 439.591725 -244.786423) (xy 439.614851 -244.738402) (xy 439.644875 -244.694365)
			(xy 439.681127 -244.655294) (xy 439.722798 -244.622063) (xy 439.768956 -244.595414) (xy 439.81857 -244.575942)
			(xy 439.870532 -244.564082) (xy 439.923682 -244.560099) (xy 439.976832 -244.564082) (xy 440.028794 -244.575942)
			(xy 440.078408 -244.595414) (xy 440.124566 -244.622063) (xy 440.166237 -244.655294) (xy 440.202489 -244.694365)
			(xy 440.232513 -244.738402) (xy 440.255639 -244.786423) (xy 440.271349 -244.837353) (xy 440.279292 -244.890057)
			(xy 440.27979 -244.916706) (xy 440.279292 -244.943355) (xy 447.111872 -244.943355) (xy 447.111872 -244.890057)
			(xy 447.119815 -244.837353) (xy 447.135525 -244.786423) (xy 447.158651 -244.738402) (xy 447.188675 -244.694365)
			(xy 447.224927 -244.655294) (xy 447.266598 -244.622063) (xy 447.312756 -244.595414) (xy 447.36237 -244.575942)
			(xy 447.414332 -244.564082) (xy 447.467482 -244.560099) (xy 447.520632 -244.564082) (xy 447.572594 -244.575942)
			(xy 447.622208 -244.595414) (xy 447.668366 -244.622063) (xy 447.710037 -244.655294) (xy 447.746289 -244.694365)
			(xy 447.776313 -244.738402) (xy 447.799439 -244.786423) (xy 447.815149 -244.837353) (xy 447.823092 -244.890057)
			(xy 447.82359 -244.916706) (xy 447.823092 -244.943355) (xy 454.655672 -244.943355) (xy 454.655672 -244.890057)
			(xy 454.663615 -244.837353) (xy 454.679325 -244.786423) (xy 454.702451 -244.738402) (xy 454.732475 -244.694365)
			(xy 454.768727 -244.655294) (xy 454.810398 -244.622063) (xy 454.856556 -244.595414) (xy 454.90617 -244.575942)
			(xy 454.958132 -244.564082) (xy 455.011282 -244.560099) (xy 455.064432 -244.564082) (xy 455.116394 -244.575942)
			(xy 455.166008 -244.595414) (xy 455.212166 -244.622063) (xy 455.253837 -244.655294) (xy 455.290089 -244.694365)
			(xy 455.320113 -244.738402) (xy 455.343239 -244.786423) (xy 455.358949 -244.837353) (xy 455.366892 -244.890057)
			(xy 455.36739 -244.916706) (xy 455.366892 -244.943355) (xy 462.199472 -244.943355) (xy 462.199472 -244.890057)
			(xy 462.207415 -244.837353) (xy 462.223125 -244.786423) (xy 462.246251 -244.738402) (xy 462.276275 -244.694365)
			(xy 462.312527 -244.655294) (xy 462.354198 -244.622063) (xy 462.400356 -244.595414) (xy 462.44997 -244.575942)
			(xy 462.501932 -244.564082) (xy 462.555082 -244.560099) (xy 462.608232 -244.564082) (xy 462.660194 -244.575942)
			(xy 462.709808 -244.595414) (xy 462.755966 -244.622063) (xy 462.797637 -244.655294) (xy 462.833889 -244.694365)
			(xy 462.863913 -244.738402) (xy 462.887039 -244.786423) (xy 462.902749 -244.837353) (xy 462.910692 -244.890057)
			(xy 462.91119 -244.916706) (xy 462.910692 -244.943355) (xy 462.902749 -244.996059) (xy 462.887039 -245.046989)
			(xy 462.863913 -245.09501) (xy 462.833889 -245.139047) (xy 462.797637 -245.178118) (xy 462.755966 -245.211349)
			(xy 462.709808 -245.237998) (xy 462.660194 -245.25747) (xy 462.608232 -245.26933) (xy 462.555082 -245.273314)
			(xy 462.501932 -245.26933) (xy 462.44997 -245.25747) (xy 462.400356 -245.237998) (xy 462.354198 -245.211349)
			(xy 462.312527 -245.178118) (xy 462.276275 -245.139047) (xy 462.246251 -245.09501) (xy 462.223125 -245.046989)
			(xy 462.207415 -244.996059) (xy 462.199472 -244.943355) (xy 455.366892 -244.943355) (xy 455.358949 -244.996059)
			(xy 455.343239 -245.046989) (xy 455.320113 -245.09501) (xy 455.290089 -245.139047) (xy 455.253837 -245.178118)
			(xy 455.212166 -245.211349) (xy 455.166008 -245.237998) (xy 455.116394 -245.25747) (xy 455.064432 -245.26933)
			(xy 455.011282 -245.273314) (xy 454.958132 -245.26933) (xy 454.90617 -245.25747) (xy 454.856556 -245.237998)
			(xy 454.810398 -245.211349) (xy 454.768727 -245.178118) (xy 454.732475 -245.139047) (xy 454.702451 -245.09501)
			(xy 454.679325 -245.046989) (xy 454.663615 -244.996059) (xy 454.655672 -244.943355) (xy 447.823092 -244.943355)
			(xy 447.815149 -244.996059) (xy 447.799439 -245.046989) (xy 447.776313 -245.09501) (xy 447.746289 -245.139047)
			(xy 447.710037 -245.178118) (xy 447.668366 -245.211349) (xy 447.622208 -245.237998) (xy 447.572594 -245.25747)
			(xy 447.520632 -245.26933) (xy 447.467482 -245.273314) (xy 447.414332 -245.26933) (xy 447.36237 -245.25747)
			(xy 447.312756 -245.237998) (xy 447.266598 -245.211349) (xy 447.224927 -245.178118) (xy 447.188675 -245.139047)
			(xy 447.158651 -245.09501) (xy 447.135525 -245.046989) (xy 447.119815 -244.996059) (xy 447.111872 -244.943355)
			(xy 440.279292 -244.943355) (xy 440.271349 -244.996059) (xy 440.255639 -245.046989) (xy 440.232513 -245.09501)
			(xy 440.202489 -245.139047) (xy 440.166237 -245.178118) (xy 440.124566 -245.211349) (xy 440.078408 -245.237998)
			(xy 440.028794 -245.25747) (xy 439.976832 -245.26933) (xy 439.923682 -245.273314) (xy 439.870532 -245.26933)
			(xy 439.81857 -245.25747) (xy 439.768956 -245.237998) (xy 439.722798 -245.211349) (xy 439.681127 -245.178118)
			(xy 439.644875 -245.139047) (xy 439.614851 -245.09501) (xy 439.591725 -245.046989) (xy 439.576015 -244.996059)
			(xy 439.568072 -244.943355) (xy 432.735492 -244.943355) (xy 432.727549 -244.996059) (xy 432.711839 -245.046989)
			(xy 432.688713 -245.09501) (xy 432.658689 -245.139047) (xy 432.622437 -245.178118) (xy 432.580766 -245.211349)
			(xy 432.534608 -245.237998) (xy 432.484994 -245.25747) (xy 432.433032 -245.26933) (xy 432.379882 -245.273314)
			(xy 432.326732 -245.26933) (xy 432.27477 -245.25747) (xy 432.225156 -245.237998) (xy 432.178998 -245.211349)
			(xy 432.137327 -245.178118) (xy 432.101075 -245.139047) (xy 432.071051 -245.09501) (xy 432.047925 -245.046989)
			(xy 432.032215 -244.996059) (xy 432.024272 -244.943355) (xy 425.191692 -244.943355) (xy 425.183749 -244.996059)
			(xy 425.168039 -245.046989) (xy 425.144913 -245.09501) (xy 425.114889 -245.139047) (xy 425.078637 -245.178118)
			(xy 425.036966 -245.211349) (xy 424.990808 -245.237998) (xy 424.941194 -245.25747) (xy 424.889232 -245.26933)
			(xy 424.836082 -245.273314) (xy 424.782932 -245.26933) (xy 424.73097 -245.25747) (xy 424.681356 -245.237998)
			(xy 424.635198 -245.211349) (xy 424.593527 -245.178118) (xy 424.557275 -245.139047) (xy 424.527251 -245.09501)
			(xy 424.504125 -245.046989) (xy 424.488415 -244.996059) (xy 424.480472 -244.943355) (xy 407.4668 -244.943355)
			(xy 407.4668 -245.793239) (xy 420.380404 -245.793239) (xy 420.380404 -245.739941) (xy 420.388347 -245.687237)
			(xy 420.404057 -245.636307) (xy 420.427183 -245.588286) (xy 420.457207 -245.544249) (xy 420.493459 -245.505178)
			(xy 420.53513 -245.471947) (xy 420.581288 -245.445298) (xy 420.630902 -245.425826) (xy 420.682864 -245.413966)
			(xy 420.736014 -245.409983) (xy 420.789164 -245.413966) (xy 420.841126 -245.425826) (xy 420.89074 -245.445298)
			(xy 420.936898 -245.471947) (xy 420.978569 -245.505178) (xy 421.014821 -245.544249) (xy 421.044845 -245.588286)
			(xy 421.067971 -245.636307) (xy 421.083681 -245.687237) (xy 421.091624 -245.739941) (xy 421.092122 -245.76659)
			(xy 421.091624 -245.793239) (xy 427.924204 -245.793239) (xy 427.924204 -245.739941) (xy 427.932147 -245.687237)
			(xy 427.947857 -245.636307) (xy 427.970983 -245.588286) (xy 428.001007 -245.544249) (xy 428.037259 -245.505178)
			(xy 428.07893 -245.471947) (xy 428.125088 -245.445298) (xy 428.174702 -245.425826) (xy 428.226664 -245.413966)
			(xy 428.279814 -245.409983) (xy 428.332964 -245.413966) (xy 428.384926 -245.425826) (xy 428.43454 -245.445298)
			(xy 428.480698 -245.471947) (xy 428.522369 -245.505178) (xy 428.558621 -245.544249) (xy 428.588645 -245.588286)
			(xy 428.611771 -245.636307) (xy 428.627481 -245.687237) (xy 428.635424 -245.739941) (xy 428.635922 -245.76659)
			(xy 428.635424 -245.793239) (xy 435.468004 -245.793239) (xy 435.468004 -245.739941) (xy 435.475947 -245.687237)
			(xy 435.491657 -245.636307) (xy 435.514783 -245.588286) (xy 435.544807 -245.544249) (xy 435.581059 -245.505178)
			(xy 435.62273 -245.471947) (xy 435.668888 -245.445298) (xy 435.718502 -245.425826) (xy 435.770464 -245.413966)
			(xy 435.823614 -245.409983) (xy 435.876764 -245.413966) (xy 435.928726 -245.425826) (xy 435.97834 -245.445298)
			(xy 436.024498 -245.471947) (xy 436.066169 -245.505178) (xy 436.102421 -245.544249) (xy 436.132445 -245.588286)
			(xy 436.155571 -245.636307) (xy 436.171281 -245.687237) (xy 436.179224 -245.739941) (xy 436.179722 -245.76659)
			(xy 436.179224 -245.793239) (xy 443.011804 -245.793239) (xy 443.011804 -245.739941) (xy 443.019747 -245.687237)
			(xy 443.035457 -245.636307) (xy 443.058583 -245.588286) (xy 443.088607 -245.544249) (xy 443.124859 -245.505178)
			(xy 443.16653 -245.471947) (xy 443.212688 -245.445298) (xy 443.262302 -245.425826) (xy 443.314264 -245.413966)
			(xy 443.367414 -245.409983) (xy 443.420564 -245.413966) (xy 443.472526 -245.425826) (xy 443.52214 -245.445298)
			(xy 443.568298 -245.471947) (xy 443.609969 -245.505178) (xy 443.646221 -245.544249) (xy 443.676245 -245.588286)
			(xy 443.699371 -245.636307) (xy 443.715081 -245.687237) (xy 443.723024 -245.739941) (xy 443.723522 -245.76659)
			(xy 443.723024 -245.793239) (xy 450.555604 -245.793239) (xy 450.555604 -245.739941) (xy 450.563547 -245.687237)
			(xy 450.579257 -245.636307) (xy 450.602383 -245.588286) (xy 450.632407 -245.544249) (xy 450.668659 -245.505178)
			(xy 450.71033 -245.471947) (xy 450.756488 -245.445298) (xy 450.806102 -245.425826) (xy 450.858064 -245.413966)
			(xy 450.911214 -245.409983) (xy 450.964364 -245.413966) (xy 451.016326 -245.425826) (xy 451.06594 -245.445298)
			(xy 451.112098 -245.471947) (xy 451.153769 -245.505178) (xy 451.190021 -245.544249) (xy 451.220045 -245.588286)
			(xy 451.243171 -245.636307) (xy 451.258881 -245.687237) (xy 451.266824 -245.739941) (xy 451.267322 -245.76659)
			(xy 451.266824 -245.793239) (xy 458.099404 -245.793239) (xy 458.099404 -245.739941) (xy 458.107347 -245.687237)
			(xy 458.123057 -245.636307) (xy 458.146183 -245.588286) (xy 458.176207 -245.544249) (xy 458.212459 -245.505178)
			(xy 458.25413 -245.471947) (xy 458.300288 -245.445298) (xy 458.349902 -245.425826) (xy 458.401864 -245.413966)
			(xy 458.455014 -245.409983) (xy 458.508164 -245.413966) (xy 458.560126 -245.425826) (xy 458.60974 -245.445298)
			(xy 458.655898 -245.471947) (xy 458.697569 -245.505178) (xy 458.733821 -245.544249) (xy 458.763845 -245.588286)
			(xy 458.786971 -245.636307) (xy 458.802681 -245.687237) (xy 458.810624 -245.739941) (xy 458.811122 -245.76659)
			(xy 458.810624 -245.793239) (xy 458.802681 -245.845943) (xy 458.786971 -245.896873) (xy 458.763845 -245.944894)
			(xy 458.733821 -245.988931) (xy 458.697569 -246.028002) (xy 458.655898 -246.061233) (xy 458.60974 -246.087882)
			(xy 458.560126 -246.107354) (xy 458.508164 -246.119214) (xy 458.455014 -246.123198) (xy 458.401864 -246.119214)
			(xy 458.349902 -246.107354) (xy 458.300288 -246.087882) (xy 458.25413 -246.061233) (xy 458.212459 -246.028002)
			(xy 458.176207 -245.988931) (xy 458.146183 -245.944894) (xy 458.123057 -245.896873) (xy 458.107347 -245.845943)
			(xy 458.099404 -245.793239) (xy 451.266824 -245.793239) (xy 451.258881 -245.845943) (xy 451.243171 -245.896873)
			(xy 451.220045 -245.944894) (xy 451.190021 -245.988931) (xy 451.153769 -246.028002) (xy 451.112098 -246.061233)
			(xy 451.06594 -246.087882) (xy 451.016326 -246.107354) (xy 450.964364 -246.119214) (xy 450.911214 -246.123198)
			(xy 450.858064 -246.119214) (xy 450.806102 -246.107354) (xy 450.756488 -246.087882) (xy 450.71033 -246.061233)
			(xy 450.668659 -246.028002) (xy 450.632407 -245.988931) (xy 450.602383 -245.944894) (xy 450.579257 -245.896873)
			(xy 450.563547 -245.845943) (xy 450.555604 -245.793239) (xy 443.723024 -245.793239) (xy 443.715081 -245.845943)
			(xy 443.699371 -245.896873) (xy 443.676245 -245.944894) (xy 443.646221 -245.988931) (xy 443.609969 -246.028002)
			(xy 443.568298 -246.061233) (xy 443.52214 -246.087882) (xy 443.472526 -246.107354) (xy 443.420564 -246.119214)
			(xy 443.367414 -246.123198) (xy 443.314264 -246.119214) (xy 443.262302 -246.107354) (xy 443.212688 -246.087882)
			(xy 443.16653 -246.061233) (xy 443.124859 -246.028002) (xy 443.088607 -245.988931) (xy 443.058583 -245.944894)
			(xy 443.035457 -245.896873) (xy 443.019747 -245.845943) (xy 443.011804 -245.793239) (xy 436.179224 -245.793239)
			(xy 436.171281 -245.845943) (xy 436.155571 -245.896873) (xy 436.132445 -245.944894) (xy 436.102421 -245.988931)
			(xy 436.066169 -246.028002) (xy 436.024498 -246.061233) (xy 435.97834 -246.087882) (xy 435.928726 -246.107354)
			(xy 435.876764 -246.119214) (xy 435.823614 -246.123198) (xy 435.770464 -246.119214) (xy 435.718502 -246.107354)
			(xy 435.668888 -246.087882) (xy 435.62273 -246.061233) (xy 435.581059 -246.028002) (xy 435.544807 -245.988931)
			(xy 435.514783 -245.944894) (xy 435.491657 -245.896873) (xy 435.475947 -245.845943) (xy 435.468004 -245.793239)
			(xy 428.635424 -245.793239) (xy 428.627481 -245.845943) (xy 428.611771 -245.896873) (xy 428.588645 -245.944894)
			(xy 428.558621 -245.988931) (xy 428.522369 -246.028002) (xy 428.480698 -246.061233) (xy 428.43454 -246.087882)
			(xy 428.384926 -246.107354) (xy 428.332964 -246.119214) (xy 428.279814 -246.123198) (xy 428.226664 -246.119214)
			(xy 428.174702 -246.107354) (xy 428.125088 -246.087882) (xy 428.07893 -246.061233) (xy 428.037259 -246.028002)
			(xy 428.001007 -245.988931) (xy 427.970983 -245.944894) (xy 427.947857 -245.896873) (xy 427.932147 -245.845943)
			(xy 427.924204 -245.793239) (xy 421.091624 -245.793239) (xy 421.083681 -245.845943) (xy 421.067971 -245.896873)
			(xy 421.044845 -245.944894) (xy 421.014821 -245.988931) (xy 420.978569 -246.028002) (xy 420.936898 -246.061233)
			(xy 420.89074 -246.087882) (xy 420.841126 -246.107354) (xy 420.789164 -246.119214) (xy 420.736014 -246.123198)
			(xy 420.682864 -246.119214) (xy 420.630902 -246.107354) (xy 420.581288 -246.087882) (xy 420.53513 -246.061233)
			(xy 420.493459 -246.028002) (xy 420.457207 -245.988931) (xy 420.427183 -245.944894) (xy 420.404057 -245.896873)
			(xy 420.388347 -245.845943) (xy 420.380404 -245.793239) (xy 407.4668 -245.793239) (xy 407.4668 -246.643377)
			(xy 424.480472 -246.643377) (xy 424.480472 -246.590079) (xy 424.488415 -246.537375) (xy 424.504125 -246.486445)
			(xy 424.527251 -246.438424) (xy 424.557275 -246.394387) (xy 424.593527 -246.355316) (xy 424.635198 -246.322085)
			(xy 424.681356 -246.295436) (xy 424.73097 -246.275964) (xy 424.782932 -246.264104) (xy 424.836082 -246.260121)
			(xy 424.889232 -246.264104) (xy 424.941194 -246.275964) (xy 424.990808 -246.295436) (xy 425.036966 -246.322085)
			(xy 425.078637 -246.355316) (xy 425.114889 -246.394387) (xy 425.144913 -246.438424) (xy 425.168039 -246.486445)
			(xy 425.183749 -246.537375) (xy 425.191692 -246.590079) (xy 425.19219 -246.616728) (xy 425.191692 -246.643377)
			(xy 439.542672 -246.643377) (xy 439.542672 -246.590079) (xy 439.550615 -246.537375) (xy 439.566325 -246.486445)
			(xy 439.589451 -246.438424) (xy 439.619475 -246.394387) (xy 439.655727 -246.355316) (xy 439.697398 -246.322085)
			(xy 439.743556 -246.295436) (xy 439.79317 -246.275964) (xy 439.845132 -246.264104) (xy 439.898282 -246.260121)
			(xy 439.951432 -246.264104) (xy 440.003394 -246.275964) (xy 440.053008 -246.295436) (xy 440.099166 -246.322085)
			(xy 440.140837 -246.355316) (xy 440.177089 -246.394387) (xy 440.207113 -246.438424) (xy 440.230239 -246.486445)
			(xy 440.245949 -246.537375) (xy 440.253892 -246.590079) (xy 440.25439 -246.616728) (xy 440.253892 -246.643377)
			(xy 454.655672 -246.643377) (xy 454.655672 -246.590079) (xy 454.663615 -246.537375) (xy 454.679325 -246.486445)
			(xy 454.702451 -246.438424) (xy 454.732475 -246.394387) (xy 454.768727 -246.355316) (xy 454.810398 -246.322085)
			(xy 454.856556 -246.295436) (xy 454.90617 -246.275964) (xy 454.958132 -246.264104) (xy 455.011282 -246.260121)
			(xy 455.064432 -246.264104) (xy 455.116394 -246.275964) (xy 455.166008 -246.295436) (xy 455.212166 -246.322085)
			(xy 455.253837 -246.355316) (xy 455.290089 -246.394387) (xy 455.320113 -246.438424) (xy 455.343239 -246.486445)
			(xy 455.358949 -246.537375) (xy 455.366892 -246.590079) (xy 455.36739 -246.616728) (xy 455.366892 -246.643377)
			(xy 455.358949 -246.696081) (xy 455.343239 -246.747011) (xy 455.320113 -246.795032) (xy 455.290089 -246.839069)
			(xy 455.253837 -246.87814) (xy 455.212166 -246.911371) (xy 455.166008 -246.93802) (xy 455.116394 -246.957492)
			(xy 455.064432 -246.969352) (xy 455.011282 -246.973336) (xy 454.958132 -246.969352) (xy 454.90617 -246.957492)
			(xy 454.856556 -246.93802) (xy 454.810398 -246.911371) (xy 454.768727 -246.87814) (xy 454.732475 -246.839069)
			(xy 454.702451 -246.795032) (xy 454.679325 -246.747011) (xy 454.663615 -246.696081) (xy 454.655672 -246.643377)
			(xy 440.253892 -246.643377) (xy 440.245949 -246.696081) (xy 440.230239 -246.747011) (xy 440.207113 -246.795032)
			(xy 440.177089 -246.839069) (xy 440.140837 -246.87814) (xy 440.099166 -246.911371) (xy 440.053008 -246.93802)
			(xy 440.003394 -246.957492) (xy 439.951432 -246.969352) (xy 439.898282 -246.973336) (xy 439.845132 -246.969352)
			(xy 439.79317 -246.957492) (xy 439.743556 -246.93802) (xy 439.697398 -246.911371) (xy 439.655727 -246.87814)
			(xy 439.619475 -246.839069) (xy 439.589451 -246.795032) (xy 439.566325 -246.747011) (xy 439.550615 -246.696081)
			(xy 439.542672 -246.643377) (xy 425.191692 -246.643377) (xy 425.183749 -246.696081) (xy 425.168039 -246.747011)
			(xy 425.144913 -246.795032) (xy 425.114889 -246.839069) (xy 425.078637 -246.87814) (xy 425.036966 -246.911371)
			(xy 424.990808 -246.93802) (xy 424.941194 -246.957492) (xy 424.889232 -246.969352) (xy 424.836082 -246.973336)
			(xy 424.782932 -246.969352) (xy 424.73097 -246.957492) (xy 424.681356 -246.93802) (xy 424.635198 -246.911371)
			(xy 424.593527 -246.87814) (xy 424.557275 -246.839069) (xy 424.527251 -246.795032) (xy 424.504125 -246.747011)
			(xy 424.488415 -246.696081) (xy 424.480472 -246.643377) (xy 407.4668 -246.643377) (xy 407.4668 -247.493261)
			(xy 420.380404 -247.493261) (xy 420.380404 -247.439963) (xy 420.388347 -247.387259) (xy 420.404057 -247.336329)
			(xy 420.427183 -247.288308) (xy 420.457207 -247.244271) (xy 420.493459 -247.2052) (xy 420.53513 -247.171969)
			(xy 420.581288 -247.14532) (xy 420.630902 -247.125848) (xy 420.682864 -247.113988) (xy 420.736014 -247.110005)
			(xy 420.789164 -247.113988) (xy 420.841126 -247.125848) (xy 420.89074 -247.14532) (xy 420.936898 -247.171969)
			(xy 420.978569 -247.2052) (xy 421.014821 -247.244271) (xy 421.044845 -247.288308) (xy 421.067971 -247.336329)
			(xy 421.083681 -247.387259) (xy 421.091624 -247.439963) (xy 421.092122 -247.466612) (xy 421.091624 -247.493261)
			(xy 435.468004 -247.493261) (xy 435.468004 -247.439963) (xy 435.475947 -247.387259) (xy 435.491657 -247.336329)
			(xy 435.514783 -247.288308) (xy 435.544807 -247.244271) (xy 435.581059 -247.2052) (xy 435.62273 -247.171969)
			(xy 435.668888 -247.14532) (xy 435.718502 -247.125848) (xy 435.770464 -247.113988) (xy 435.823614 -247.110005)
			(xy 435.876764 -247.113988) (xy 435.928726 -247.125848) (xy 435.97834 -247.14532) (xy 436.024498 -247.171969)
			(xy 436.066169 -247.2052) (xy 436.102421 -247.244271) (xy 436.132445 -247.288308) (xy 436.155571 -247.336329)
			(xy 436.171281 -247.387259) (xy 436.179224 -247.439963) (xy 436.179722 -247.466612) (xy 436.179224 -247.493261)
			(xy 450.555604 -247.493261) (xy 450.555604 -247.439963) (xy 450.563547 -247.387259) (xy 450.579257 -247.336329)
			(xy 450.602383 -247.288308) (xy 450.632407 -247.244271) (xy 450.668659 -247.2052) (xy 450.71033 -247.171969)
			(xy 450.756488 -247.14532) (xy 450.806102 -247.125848) (xy 450.858064 -247.113988) (xy 450.911214 -247.110005)
			(xy 450.964364 -247.113988) (xy 451.016326 -247.125848) (xy 451.06594 -247.14532) (xy 451.112098 -247.171969)
			(xy 451.153769 -247.2052) (xy 451.190021 -247.244271) (xy 451.220045 -247.288308) (xy 451.243171 -247.336329)
			(xy 451.258881 -247.387259) (xy 451.266824 -247.439963) (xy 451.267322 -247.466612) (xy 451.266824 -247.493261)
			(xy 451.258881 -247.545965) (xy 451.243171 -247.596895) (xy 451.220045 -247.644916) (xy 451.190021 -247.688953)
			(xy 451.153769 -247.728024) (xy 451.112098 -247.761255) (xy 451.06594 -247.787904) (xy 451.016326 -247.807376)
			(xy 450.964364 -247.819236) (xy 450.911214 -247.82322) (xy 450.858064 -247.819236) (xy 450.806102 -247.807376)
			(xy 450.756488 -247.787904) (xy 450.71033 -247.761255) (xy 450.668659 -247.728024) (xy 450.632407 -247.688953)
			(xy 450.602383 -247.644916) (xy 450.579257 -247.596895) (xy 450.563547 -247.545965) (xy 450.555604 -247.493261)
			(xy 436.179224 -247.493261) (xy 436.171281 -247.545965) (xy 436.155571 -247.596895) (xy 436.132445 -247.644916)
			(xy 436.102421 -247.688953) (xy 436.066169 -247.728024) (xy 436.024498 -247.761255) (xy 435.97834 -247.787904)
			(xy 435.928726 -247.807376) (xy 435.876764 -247.819236) (xy 435.823614 -247.82322) (xy 435.770464 -247.819236)
			(xy 435.718502 -247.807376) (xy 435.668888 -247.787904) (xy 435.62273 -247.761255) (xy 435.581059 -247.728024)
			(xy 435.544807 -247.688953) (xy 435.514783 -247.644916) (xy 435.491657 -247.596895) (xy 435.475947 -247.545965)
			(xy 435.468004 -247.493261) (xy 421.091624 -247.493261) (xy 421.083681 -247.545965) (xy 421.067971 -247.596895)
			(xy 421.044845 -247.644916) (xy 421.014821 -247.688953) (xy 420.978569 -247.728024) (xy 420.936898 -247.761255)
			(xy 420.89074 -247.787904) (xy 420.841126 -247.807376) (xy 420.789164 -247.819236) (xy 420.736014 -247.82322)
			(xy 420.682864 -247.819236) (xy 420.630902 -247.807376) (xy 420.581288 -247.787904) (xy 420.53513 -247.761255)
			(xy 420.493459 -247.728024) (xy 420.457207 -247.688953) (xy 420.427183 -247.644916) (xy 420.404057 -247.596895)
			(xy 420.388347 -247.545965) (xy 420.380404 -247.493261) (xy 407.4668 -247.493261) (xy 407.4668 -248.343399)
			(xy 424.480472 -248.343399) (xy 424.480472 -248.290101) (xy 424.488415 -248.237397) (xy 424.504125 -248.186467)
			(xy 424.527251 -248.138446) (xy 424.557275 -248.094409) (xy 424.593527 -248.055338) (xy 424.635198 -248.022107)
			(xy 424.681356 -247.995458) (xy 424.73097 -247.975986) (xy 424.782932 -247.964126) (xy 424.836082 -247.960143)
			(xy 424.889232 -247.964126) (xy 424.941194 -247.975986) (xy 424.990808 -247.995458) (xy 425.036966 -248.022107)
			(xy 425.078637 -248.055338) (xy 425.114889 -248.094409) (xy 425.144913 -248.138446) (xy 425.168039 -248.186467)
			(xy 425.183749 -248.237397) (xy 425.191692 -248.290101) (xy 425.19219 -248.31675) (xy 425.191692 -248.343399)
			(xy 439.568072 -248.343399) (xy 439.568072 -248.290101) (xy 439.576015 -248.237397) (xy 439.591725 -248.186467)
			(xy 439.614851 -248.138446) (xy 439.644875 -248.094409) (xy 439.681127 -248.055338) (xy 439.722798 -248.022107)
			(xy 439.768956 -247.995458) (xy 439.81857 -247.975986) (xy 439.870532 -247.964126) (xy 439.923682 -247.960143)
			(xy 439.976832 -247.964126) (xy 440.028794 -247.975986) (xy 440.078408 -247.995458) (xy 440.124566 -248.022107)
			(xy 440.166237 -248.055338) (xy 440.202489 -248.094409) (xy 440.232513 -248.138446) (xy 440.255639 -248.186467)
			(xy 440.271349 -248.237397) (xy 440.279292 -248.290101) (xy 440.27979 -248.31675) (xy 440.279292 -248.343399)
			(xy 454.655672 -248.343399) (xy 454.655672 -248.290101) (xy 454.663615 -248.237397) (xy 454.679325 -248.186467)
			(xy 454.702451 -248.138446) (xy 454.732475 -248.094409) (xy 454.768727 -248.055338) (xy 454.810398 -248.022107)
			(xy 454.856556 -247.995458) (xy 454.90617 -247.975986) (xy 454.958132 -247.964126) (xy 455.011282 -247.960143)
			(xy 455.064432 -247.964126) (xy 455.116394 -247.975986) (xy 455.166008 -247.995458) (xy 455.212166 -248.022107)
			(xy 455.253837 -248.055338) (xy 455.290089 -248.094409) (xy 455.320113 -248.138446) (xy 455.343239 -248.186467)
			(xy 455.358949 -248.237397) (xy 455.366892 -248.290101) (xy 455.36739 -248.31675) (xy 455.366892 -248.343399)
			(xy 455.358949 -248.396103) (xy 455.343239 -248.447033) (xy 455.320113 -248.495054) (xy 455.290089 -248.539091)
			(xy 455.253837 -248.578162) (xy 455.212166 -248.611393) (xy 455.166008 -248.638042) (xy 455.116394 -248.657514)
			(xy 455.064432 -248.669374) (xy 455.011282 -248.673358) (xy 454.958132 -248.669374) (xy 454.90617 -248.657514)
			(xy 454.856556 -248.638042) (xy 454.810398 -248.611393) (xy 454.768727 -248.578162) (xy 454.732475 -248.539091)
			(xy 454.702451 -248.495054) (xy 454.679325 -248.447033) (xy 454.663615 -248.396103) (xy 454.655672 -248.343399)
			(xy 440.279292 -248.343399) (xy 440.271349 -248.396103) (xy 440.255639 -248.447033) (xy 440.232513 -248.495054)
			(xy 440.202489 -248.539091) (xy 440.166237 -248.578162) (xy 440.124566 -248.611393) (xy 440.078408 -248.638042)
			(xy 440.028794 -248.657514) (xy 439.976832 -248.669374) (xy 439.923682 -248.673358) (xy 439.870532 -248.669374)
			(xy 439.81857 -248.657514) (xy 439.768956 -248.638042) (xy 439.722798 -248.611393) (xy 439.681127 -248.578162)
			(xy 439.644875 -248.539091) (xy 439.614851 -248.495054) (xy 439.591725 -248.447033) (xy 439.576015 -248.396103)
			(xy 439.568072 -248.343399) (xy 425.191692 -248.343399) (xy 425.183749 -248.396103) (xy 425.168039 -248.447033)
			(xy 425.144913 -248.495054) (xy 425.114889 -248.539091) (xy 425.078637 -248.578162) (xy 425.036966 -248.611393)
			(xy 424.990808 -248.638042) (xy 424.941194 -248.657514) (xy 424.889232 -248.669374) (xy 424.836082 -248.673358)
			(xy 424.782932 -248.669374) (xy 424.73097 -248.657514) (xy 424.681356 -248.638042) (xy 424.635198 -248.611393)
			(xy 424.593527 -248.578162) (xy 424.557275 -248.539091) (xy 424.527251 -248.495054) (xy 424.504125 -248.447033)
			(xy 424.488415 -248.396103) (xy 424.480472 -248.343399) (xy 407.4668 -248.343399) (xy 407.4668 -249.193283)
			(xy 420.380404 -249.193283) (xy 420.380404 -249.139985) (xy 420.388347 -249.087281) (xy 420.404057 -249.036351)
			(xy 420.427183 -248.98833) (xy 420.457207 -248.944293) (xy 420.493459 -248.905222) (xy 420.53513 -248.871991)
			(xy 420.581288 -248.845342) (xy 420.630902 -248.82587) (xy 420.682864 -248.81401) (xy 420.736014 -248.810027)
			(xy 420.789164 -248.81401) (xy 420.841126 -248.82587) (xy 420.89074 -248.845342) (xy 420.936898 -248.871991)
			(xy 420.978569 -248.905222) (xy 421.014821 -248.944293) (xy 421.044845 -248.98833) (xy 421.067971 -249.036351)
			(xy 421.083681 -249.087281) (xy 421.091624 -249.139985) (xy 421.092122 -249.166634) (xy 421.091624 -249.193283)
			(xy 435.468004 -249.193283) (xy 435.468004 -249.139985) (xy 435.475947 -249.087281) (xy 435.491657 -249.036351)
			(xy 435.514783 -248.98833) (xy 435.544807 -248.944293) (xy 435.581059 -248.905222) (xy 435.62273 -248.871991)
			(xy 435.668888 -248.845342) (xy 435.718502 -248.82587) (xy 435.770464 -248.81401) (xy 435.823614 -248.810027)
			(xy 435.876764 -248.81401) (xy 435.928726 -248.82587) (xy 435.97834 -248.845342) (xy 436.024498 -248.871991)
			(xy 436.066169 -248.905222) (xy 436.102421 -248.944293) (xy 436.132445 -248.98833) (xy 436.155571 -249.036351)
			(xy 436.171281 -249.087281) (xy 436.179224 -249.139985) (xy 436.179722 -249.166634) (xy 436.179224 -249.193283)
			(xy 450.555604 -249.193283) (xy 450.555604 -249.139985) (xy 450.563547 -249.087281) (xy 450.579257 -249.036351)
			(xy 450.602383 -248.98833) (xy 450.632407 -248.944293) (xy 450.668659 -248.905222) (xy 450.71033 -248.871991)
			(xy 450.756488 -248.845342) (xy 450.806102 -248.82587) (xy 450.858064 -248.81401) (xy 450.911214 -248.810027)
			(xy 450.964364 -248.81401) (xy 451.016326 -248.82587) (xy 451.06594 -248.845342) (xy 451.112098 -248.871991)
			(xy 451.153769 -248.905222) (xy 451.190021 -248.944293) (xy 451.220045 -248.98833) (xy 451.243171 -249.036351)
			(xy 451.258881 -249.087281) (xy 451.266824 -249.139985) (xy 451.267322 -249.166634) (xy 451.266824 -249.193283)
			(xy 451.258881 -249.245987) (xy 451.243171 -249.296917) (xy 451.220045 -249.344938) (xy 451.190021 -249.388975)
			(xy 451.153769 -249.428046) (xy 451.112098 -249.461277) (xy 451.06594 -249.487926) (xy 451.016326 -249.507398)
			(xy 450.964364 -249.519258) (xy 450.911214 -249.523242) (xy 450.858064 -249.519258) (xy 450.806102 -249.507398)
			(xy 450.756488 -249.487926) (xy 450.71033 -249.461277) (xy 450.668659 -249.428046) (xy 450.632407 -249.388975)
			(xy 450.602383 -249.344938) (xy 450.579257 -249.296917) (xy 450.563547 -249.245987) (xy 450.555604 -249.193283)
			(xy 436.179224 -249.193283) (xy 436.171281 -249.245987) (xy 436.155571 -249.296917) (xy 436.132445 -249.344938)
			(xy 436.102421 -249.388975) (xy 436.066169 -249.428046) (xy 436.024498 -249.461277) (xy 435.97834 -249.487926)
			(xy 435.928726 -249.507398) (xy 435.876764 -249.519258) (xy 435.823614 -249.523242) (xy 435.770464 -249.519258)
			(xy 435.718502 -249.507398) (xy 435.668888 -249.487926) (xy 435.62273 -249.461277) (xy 435.581059 -249.428046)
			(xy 435.544807 -249.388975) (xy 435.514783 -249.344938) (xy 435.491657 -249.296917) (xy 435.475947 -249.245987)
			(xy 435.468004 -249.193283) (xy 421.091624 -249.193283) (xy 421.083681 -249.245987) (xy 421.067971 -249.296917)
			(xy 421.044845 -249.344938) (xy 421.014821 -249.388975) (xy 420.978569 -249.428046) (xy 420.936898 -249.461277)
			(xy 420.89074 -249.487926) (xy 420.841126 -249.507398) (xy 420.789164 -249.519258) (xy 420.736014 -249.523242)
			(xy 420.682864 -249.519258) (xy 420.630902 -249.507398) (xy 420.581288 -249.487926) (xy 420.53513 -249.461277)
			(xy 420.493459 -249.428046) (xy 420.457207 -249.388975) (xy 420.427183 -249.344938) (xy 420.404057 -249.296917)
			(xy 420.388347 -249.245987) (xy 420.380404 -249.193283) (xy 407.4668 -249.193283) (xy 407.4668 -250.043421)
			(xy 424.480472 -250.043421) (xy 424.480472 -249.990123) (xy 424.488415 -249.937419) (xy 424.504125 -249.886489)
			(xy 424.527251 -249.838468) (xy 424.557275 -249.794431) (xy 424.593527 -249.75536) (xy 424.635198 -249.722129)
			(xy 424.681356 -249.69548) (xy 424.73097 -249.676008) (xy 424.782932 -249.664148) (xy 424.836082 -249.660165)
			(xy 424.889232 -249.664148) (xy 424.941194 -249.676008) (xy 424.990808 -249.69548) (xy 425.036966 -249.722129)
			(xy 425.078637 -249.75536) (xy 425.114889 -249.794431) (xy 425.144913 -249.838468) (xy 425.168039 -249.886489)
			(xy 425.183749 -249.937419) (xy 425.191692 -249.990123) (xy 425.19219 -250.016772) (xy 425.191692 -250.043421)
			(xy 439.568072 -250.043421) (xy 439.568072 -249.990123) (xy 439.576015 -249.937419) (xy 439.591725 -249.886489)
			(xy 439.614851 -249.838468) (xy 439.644875 -249.794431) (xy 439.681127 -249.75536) (xy 439.722798 -249.722129)
			(xy 439.768956 -249.69548) (xy 439.81857 -249.676008) (xy 439.870532 -249.664148) (xy 439.923682 -249.660165)
			(xy 439.976832 -249.664148) (xy 440.028794 -249.676008) (xy 440.078408 -249.69548) (xy 440.124566 -249.722129)
			(xy 440.166237 -249.75536) (xy 440.202489 -249.794431) (xy 440.232513 -249.838468) (xy 440.255639 -249.886489)
			(xy 440.271349 -249.937419) (xy 440.279292 -249.990123) (xy 440.27979 -250.016772) (xy 440.279292 -250.043421)
			(xy 454.655672 -250.043421) (xy 454.655672 -249.990123) (xy 454.663615 -249.937419) (xy 454.679325 -249.886489)
			(xy 454.702451 -249.838468) (xy 454.732475 -249.794431) (xy 454.768727 -249.75536) (xy 454.810398 -249.722129)
			(xy 454.856556 -249.69548) (xy 454.90617 -249.676008) (xy 454.958132 -249.664148) (xy 455.011282 -249.660165)
			(xy 455.064432 -249.664148) (xy 455.116394 -249.676008) (xy 455.166008 -249.69548) (xy 455.212166 -249.722129)
			(xy 455.253837 -249.75536) (xy 455.290089 -249.794431) (xy 455.320113 -249.838468) (xy 455.343239 -249.886489)
			(xy 455.358949 -249.937419) (xy 455.366892 -249.990123) (xy 455.36739 -250.016772) (xy 455.366892 -250.043421)
			(xy 455.358949 -250.096125) (xy 455.343239 -250.147055) (xy 455.320113 -250.195076) (xy 455.290089 -250.239113)
			(xy 455.253837 -250.278184) (xy 455.212166 -250.311415) (xy 455.166008 -250.338064) (xy 455.116394 -250.357536)
			(xy 455.064432 -250.369396) (xy 455.011282 -250.37338) (xy 454.958132 -250.369396) (xy 454.90617 -250.357536)
			(xy 454.856556 -250.338064) (xy 454.810398 -250.311415) (xy 454.768727 -250.278184) (xy 454.732475 -250.239113)
			(xy 454.702451 -250.195076) (xy 454.679325 -250.147055) (xy 454.663615 -250.096125) (xy 454.655672 -250.043421)
			(xy 440.279292 -250.043421) (xy 440.271349 -250.096125) (xy 440.255639 -250.147055) (xy 440.232513 -250.195076)
			(xy 440.202489 -250.239113) (xy 440.166237 -250.278184) (xy 440.124566 -250.311415) (xy 440.078408 -250.338064)
			(xy 440.028794 -250.357536) (xy 439.976832 -250.369396) (xy 439.923682 -250.37338) (xy 439.870532 -250.369396)
			(xy 439.81857 -250.357536) (xy 439.768956 -250.338064) (xy 439.722798 -250.311415) (xy 439.681127 -250.278184)
			(xy 439.644875 -250.239113) (xy 439.614851 -250.195076) (xy 439.591725 -250.147055) (xy 439.576015 -250.096125)
			(xy 439.568072 -250.043421) (xy 425.191692 -250.043421) (xy 425.183749 -250.096125) (xy 425.168039 -250.147055)
			(xy 425.144913 -250.195076) (xy 425.114889 -250.239113) (xy 425.078637 -250.278184) (xy 425.036966 -250.311415)
			(xy 424.990808 -250.338064) (xy 424.941194 -250.357536) (xy 424.889232 -250.369396) (xy 424.836082 -250.37338)
			(xy 424.782932 -250.369396) (xy 424.73097 -250.357536) (xy 424.681356 -250.338064) (xy 424.635198 -250.311415)
			(xy 424.593527 -250.278184) (xy 424.557275 -250.239113) (xy 424.527251 -250.195076) (xy 424.504125 -250.147055)
			(xy 424.488415 -250.096125) (xy 424.480472 -250.043421) (xy 407.4668 -250.043421) (xy 407.4668 -250.893305)
			(xy 420.380404 -250.893305) (xy 420.380404 -250.840007) (xy 420.388347 -250.787303) (xy 420.404057 -250.736373)
			(xy 420.427183 -250.688352) (xy 420.457207 -250.644315) (xy 420.493459 -250.605244) (xy 420.53513 -250.572013)
			(xy 420.581288 -250.545364) (xy 420.630902 -250.525892) (xy 420.682864 -250.514032) (xy 420.736014 -250.510049)
			(xy 420.789164 -250.514032) (xy 420.841126 -250.525892) (xy 420.89074 -250.545364) (xy 420.936898 -250.572013)
			(xy 420.978569 -250.605244) (xy 421.014821 -250.644315) (xy 421.044845 -250.688352) (xy 421.067971 -250.736373)
			(xy 421.083681 -250.787303) (xy 421.091624 -250.840007) (xy 421.092122 -250.866656) (xy 421.091624 -250.893305)
			(xy 435.468004 -250.893305) (xy 435.468004 -250.840007) (xy 435.475947 -250.787303) (xy 435.491657 -250.736373)
			(xy 435.514783 -250.688352) (xy 435.544807 -250.644315) (xy 435.581059 -250.605244) (xy 435.62273 -250.572013)
			(xy 435.668888 -250.545364) (xy 435.718502 -250.525892) (xy 435.770464 -250.514032) (xy 435.823614 -250.510049)
			(xy 435.876764 -250.514032) (xy 435.928726 -250.525892) (xy 435.97834 -250.545364) (xy 436.024498 -250.572013)
			(xy 436.066169 -250.605244) (xy 436.102421 -250.644315) (xy 436.132445 -250.688352) (xy 436.155571 -250.736373)
			(xy 436.171281 -250.787303) (xy 436.179224 -250.840007) (xy 436.179722 -250.866656) (xy 436.179224 -250.893305)
			(xy 450.555604 -250.893305) (xy 450.555604 -250.840007) (xy 450.563547 -250.787303) (xy 450.579257 -250.736373)
			(xy 450.602383 -250.688352) (xy 450.632407 -250.644315) (xy 450.668659 -250.605244) (xy 450.71033 -250.572013)
			(xy 450.756488 -250.545364) (xy 450.806102 -250.525892) (xy 450.858064 -250.514032) (xy 450.911214 -250.510049)
			(xy 450.964364 -250.514032) (xy 451.016326 -250.525892) (xy 451.06594 -250.545364) (xy 451.112098 -250.572013)
			(xy 451.153769 -250.605244) (xy 451.190021 -250.644315) (xy 451.220045 -250.688352) (xy 451.243171 -250.736373)
			(xy 451.258881 -250.787303) (xy 451.266824 -250.840007) (xy 451.267322 -250.866656) (xy 451.266824 -250.893305)
			(xy 451.258881 -250.946009) (xy 451.243171 -250.996939) (xy 451.220045 -251.04496) (xy 451.190021 -251.088997)
			(xy 451.153769 -251.128068) (xy 451.112098 -251.161299) (xy 451.06594 -251.187948) (xy 451.016326 -251.20742)
			(xy 450.964364 -251.21928) (xy 450.911214 -251.223264) (xy 450.858064 -251.21928) (xy 450.806102 -251.20742)
			(xy 450.756488 -251.187948) (xy 450.71033 -251.161299) (xy 450.668659 -251.128068) (xy 450.632407 -251.088997)
			(xy 450.602383 -251.04496) (xy 450.579257 -250.996939) (xy 450.563547 -250.946009) (xy 450.555604 -250.893305)
			(xy 436.179224 -250.893305) (xy 436.171281 -250.946009) (xy 436.155571 -250.996939) (xy 436.132445 -251.04496)
			(xy 436.102421 -251.088997) (xy 436.066169 -251.128068) (xy 436.024498 -251.161299) (xy 435.97834 -251.187948)
			(xy 435.928726 -251.20742) (xy 435.876764 -251.21928) (xy 435.823614 -251.223264) (xy 435.770464 -251.21928)
			(xy 435.718502 -251.20742) (xy 435.668888 -251.187948) (xy 435.62273 -251.161299) (xy 435.581059 -251.128068)
			(xy 435.544807 -251.088997) (xy 435.514783 -251.04496) (xy 435.491657 -250.996939) (xy 435.475947 -250.946009)
			(xy 435.468004 -250.893305) (xy 421.091624 -250.893305) (xy 421.083681 -250.946009) (xy 421.067971 -250.996939)
			(xy 421.044845 -251.04496) (xy 421.014821 -251.088997) (xy 420.978569 -251.128068) (xy 420.936898 -251.161299)
			(xy 420.89074 -251.187948) (xy 420.841126 -251.20742) (xy 420.789164 -251.21928) (xy 420.736014 -251.223264)
			(xy 420.682864 -251.21928) (xy 420.630902 -251.20742) (xy 420.581288 -251.187948) (xy 420.53513 -251.161299)
			(xy 420.493459 -251.128068) (xy 420.457207 -251.088997) (xy 420.427183 -251.04496) (xy 420.404057 -250.996939)
			(xy 420.388347 -250.946009) (xy 420.380404 -250.893305) (xy 407.4668 -250.893305) (xy 407.4668 -251.743443)
			(xy 424.480472 -251.743443) (xy 424.480472 -251.690145) (xy 424.488415 -251.637441) (xy 424.504125 -251.586511)
			(xy 424.527251 -251.53849) (xy 424.557275 -251.494453) (xy 424.593527 -251.455382) (xy 424.635198 -251.422151)
			(xy 424.681356 -251.395502) (xy 424.73097 -251.37603) (xy 424.782932 -251.36417) (xy 424.836082 -251.360187)
			(xy 424.889232 -251.36417) (xy 424.941194 -251.37603) (xy 424.990808 -251.395502) (xy 425.036966 -251.422151)
			(xy 425.078637 -251.455382) (xy 425.114889 -251.494453) (xy 425.144913 -251.53849) (xy 425.168039 -251.586511)
			(xy 425.183749 -251.637441) (xy 425.191692 -251.690145) (xy 425.19219 -251.716794) (xy 425.191692 -251.743443)
			(xy 439.568072 -251.743443) (xy 439.568072 -251.690145) (xy 439.576015 -251.637441) (xy 439.591725 -251.586511)
			(xy 439.614851 -251.53849) (xy 439.644875 -251.494453) (xy 439.681127 -251.455382) (xy 439.722798 -251.422151)
			(xy 439.768956 -251.395502) (xy 439.81857 -251.37603) (xy 439.870532 -251.36417) (xy 439.923682 -251.360187)
			(xy 439.976832 -251.36417) (xy 440.028794 -251.37603) (xy 440.078408 -251.395502) (xy 440.124566 -251.422151)
			(xy 440.166237 -251.455382) (xy 440.202489 -251.494453) (xy 440.232513 -251.53849) (xy 440.255639 -251.586511)
			(xy 440.271349 -251.637441) (xy 440.279292 -251.690145) (xy 440.27979 -251.716794) (xy 440.279292 -251.743443)
			(xy 454.655672 -251.743443) (xy 454.655672 -251.690145) (xy 454.663615 -251.637441) (xy 454.679325 -251.586511)
			(xy 454.702451 -251.53849) (xy 454.732475 -251.494453) (xy 454.768727 -251.455382) (xy 454.810398 -251.422151)
			(xy 454.856556 -251.395502) (xy 454.90617 -251.37603) (xy 454.958132 -251.36417) (xy 455.011282 -251.360187)
			(xy 455.064432 -251.36417) (xy 455.116394 -251.37603) (xy 455.166008 -251.395502) (xy 455.212166 -251.422151)
			(xy 455.253837 -251.455382) (xy 455.290089 -251.494453) (xy 455.320113 -251.53849) (xy 455.343239 -251.586511)
			(xy 455.358949 -251.637441) (xy 455.366892 -251.690145) (xy 455.36739 -251.716794) (xy 455.366892 -251.743443)
			(xy 455.358949 -251.796147) (xy 455.343239 -251.847077) (xy 455.320113 -251.895098) (xy 455.290089 -251.939135)
			(xy 455.253837 -251.978206) (xy 455.212166 -252.011437) (xy 455.166008 -252.038086) (xy 455.116394 -252.057558)
			(xy 455.064432 -252.069418) (xy 455.011282 -252.073402) (xy 454.958132 -252.069418) (xy 454.90617 -252.057558)
			(xy 454.856556 -252.038086) (xy 454.810398 -252.011437) (xy 454.768727 -251.978206) (xy 454.732475 -251.939135)
			(xy 454.702451 -251.895098) (xy 454.679325 -251.847077) (xy 454.663615 -251.796147) (xy 454.655672 -251.743443)
			(xy 440.279292 -251.743443) (xy 440.271349 -251.796147) (xy 440.255639 -251.847077) (xy 440.232513 -251.895098)
			(xy 440.202489 -251.939135) (xy 440.166237 -251.978206) (xy 440.124566 -252.011437) (xy 440.078408 -252.038086)
			(xy 440.028794 -252.057558) (xy 439.976832 -252.069418) (xy 439.923682 -252.073402) (xy 439.870532 -252.069418)
			(xy 439.81857 -252.057558) (xy 439.768956 -252.038086) (xy 439.722798 -252.011437) (xy 439.681127 -251.978206)
			(xy 439.644875 -251.939135) (xy 439.614851 -251.895098) (xy 439.591725 -251.847077) (xy 439.576015 -251.796147)
			(xy 439.568072 -251.743443) (xy 425.191692 -251.743443) (xy 425.183749 -251.796147) (xy 425.168039 -251.847077)
			(xy 425.144913 -251.895098) (xy 425.114889 -251.939135) (xy 425.078637 -251.978206) (xy 425.036966 -252.011437)
			(xy 424.990808 -252.038086) (xy 424.941194 -252.057558) (xy 424.889232 -252.069418) (xy 424.836082 -252.073402)
			(xy 424.782932 -252.069418) (xy 424.73097 -252.057558) (xy 424.681356 -252.038086) (xy 424.635198 -252.011437)
			(xy 424.593527 -251.978206) (xy 424.557275 -251.939135) (xy 424.527251 -251.895098) (xy 424.504125 -251.847077)
			(xy 424.488415 -251.796147) (xy 424.480472 -251.743443) (xy 407.4668 -251.743443) (xy 407.4668 -252.593327)
			(xy 420.380404 -252.593327) (xy 420.380404 -252.540029) (xy 420.388347 -252.487325) (xy 420.404057 -252.436395)
			(xy 420.427183 -252.388374) (xy 420.457207 -252.344337) (xy 420.493459 -252.305266) (xy 420.53513 -252.272035)
			(xy 420.581288 -252.245386) (xy 420.630902 -252.225914) (xy 420.682864 -252.214054) (xy 420.736014 -252.210071)
			(xy 420.789164 -252.214054) (xy 420.841126 -252.225914) (xy 420.89074 -252.245386) (xy 420.936898 -252.272035)
			(xy 420.978569 -252.305266) (xy 421.014821 -252.344337) (xy 421.044845 -252.388374) (xy 421.067971 -252.436395)
			(xy 421.083681 -252.487325) (xy 421.091624 -252.540029) (xy 421.092122 -252.566678) (xy 421.091624 -252.593327)
			(xy 424.480472 -252.593327) (xy 424.480472 -252.540029) (xy 424.488415 -252.487325) (xy 424.504125 -252.436395)
			(xy 424.527251 -252.388374) (xy 424.557275 -252.344337) (xy 424.593527 -252.305266) (xy 424.635198 -252.272035)
			(xy 424.681356 -252.245386) (xy 424.73097 -252.225914) (xy 424.782932 -252.214054) (xy 424.836082 -252.210071)
			(xy 424.889232 -252.214054) (xy 424.941194 -252.225914) (xy 424.990808 -252.245386) (xy 425.036966 -252.272035)
			(xy 425.078637 -252.305266) (xy 425.114889 -252.344337) (xy 425.144913 -252.388374) (xy 425.168039 -252.436395)
			(xy 425.183749 -252.487325) (xy 425.191692 -252.540029) (xy 425.19219 -252.566678) (xy 425.191692 -252.593327)
			(xy 431.998872 -252.593327) (xy 431.998872 -252.540029) (xy 432.006815 -252.487325) (xy 432.022525 -252.436395)
			(xy 432.045651 -252.388374) (xy 432.075675 -252.344337) (xy 432.111927 -252.305266) (xy 432.153598 -252.272035)
			(xy 432.199756 -252.245386) (xy 432.24937 -252.225914) (xy 432.301332 -252.214054) (xy 432.354482 -252.210071)
			(xy 432.407632 -252.214054) (xy 432.459594 -252.225914) (xy 432.509208 -252.245386) (xy 432.555366 -252.272035)
			(xy 432.597037 -252.305266) (xy 432.633289 -252.344337) (xy 432.663313 -252.388374) (xy 432.686439 -252.436395)
			(xy 432.702149 -252.487325) (xy 432.710092 -252.540029) (xy 432.71059 -252.566678) (xy 432.710092 -252.593327)
			(xy 435.468004 -252.593327) (xy 435.468004 -252.540029) (xy 435.475947 -252.487325) (xy 435.491657 -252.436395)
			(xy 435.514783 -252.388374) (xy 435.544807 -252.344337) (xy 435.581059 -252.305266) (xy 435.62273 -252.272035)
			(xy 435.668888 -252.245386) (xy 435.718502 -252.225914) (xy 435.770464 -252.214054) (xy 435.823614 -252.210071)
			(xy 435.876764 -252.214054) (xy 435.928726 -252.225914) (xy 435.97834 -252.245386) (xy 436.024498 -252.272035)
			(xy 436.066169 -252.305266) (xy 436.102421 -252.344337) (xy 436.132445 -252.388374) (xy 436.155571 -252.436395)
			(xy 436.171281 -252.487325) (xy 436.179224 -252.540029) (xy 436.179722 -252.566678) (xy 436.179224 -252.593327)
			(xy 439.568072 -252.593327) (xy 439.568072 -252.540029) (xy 439.576015 -252.487325) (xy 439.591725 -252.436395)
			(xy 439.614851 -252.388374) (xy 439.644875 -252.344337) (xy 439.681127 -252.305266) (xy 439.722798 -252.272035)
			(xy 439.768956 -252.245386) (xy 439.81857 -252.225914) (xy 439.870532 -252.214054) (xy 439.923682 -252.210071)
			(xy 439.976832 -252.214054) (xy 440.028794 -252.225914) (xy 440.078408 -252.245386) (xy 440.124566 -252.272035)
			(xy 440.166237 -252.305266) (xy 440.202489 -252.344337) (xy 440.232513 -252.388374) (xy 440.255639 -252.436395)
			(xy 440.271349 -252.487325) (xy 440.279292 -252.540029) (xy 440.27979 -252.566678) (xy 440.279292 -252.593327)
			(xy 447.111872 -252.593327) (xy 447.111872 -252.540029) (xy 447.119815 -252.487325) (xy 447.135525 -252.436395)
			(xy 447.158651 -252.388374) (xy 447.188675 -252.344337) (xy 447.224927 -252.305266) (xy 447.266598 -252.272035)
			(xy 447.312756 -252.245386) (xy 447.36237 -252.225914) (xy 447.414332 -252.214054) (xy 447.467482 -252.210071)
			(xy 447.520632 -252.214054) (xy 447.572594 -252.225914) (xy 447.622208 -252.245386) (xy 447.668366 -252.272035)
			(xy 447.710037 -252.305266) (xy 447.746289 -252.344337) (xy 447.776313 -252.388374) (xy 447.799439 -252.436395)
			(xy 447.815149 -252.487325) (xy 447.823092 -252.540029) (xy 447.82359 -252.566678) (xy 447.823092 -252.593327)
			(xy 450.555604 -252.593327) (xy 450.555604 -252.540029) (xy 450.563547 -252.487325) (xy 450.579257 -252.436395)
			(xy 450.602383 -252.388374) (xy 450.632407 -252.344337) (xy 450.668659 -252.305266) (xy 450.71033 -252.272035)
			(xy 450.756488 -252.245386) (xy 450.806102 -252.225914) (xy 450.858064 -252.214054) (xy 450.911214 -252.210071)
			(xy 450.964364 -252.214054) (xy 451.016326 -252.225914) (xy 451.06594 -252.245386) (xy 451.112098 -252.272035)
			(xy 451.153769 -252.305266) (xy 451.190021 -252.344337) (xy 451.220045 -252.388374) (xy 451.243171 -252.436395)
			(xy 451.258881 -252.487325) (xy 451.266824 -252.540029) (xy 451.267322 -252.566678) (xy 451.266824 -252.593327)
			(xy 454.655672 -252.593327) (xy 454.655672 -252.540029) (xy 454.663615 -252.487325) (xy 454.679325 -252.436395)
			(xy 454.702451 -252.388374) (xy 454.732475 -252.344337) (xy 454.768727 -252.305266) (xy 454.810398 -252.272035)
			(xy 454.856556 -252.245386) (xy 454.90617 -252.225914) (xy 454.958132 -252.214054) (xy 455.011282 -252.210071)
			(xy 455.064432 -252.214054) (xy 455.116394 -252.225914) (xy 455.166008 -252.245386) (xy 455.212166 -252.272035)
			(xy 455.253837 -252.305266) (xy 455.290089 -252.344337) (xy 455.320113 -252.388374) (xy 455.343239 -252.436395)
			(xy 455.358949 -252.487325) (xy 455.366892 -252.540029) (xy 455.36739 -252.566678) (xy 455.366892 -252.593327)
			(xy 462.174072 -252.593327) (xy 462.174072 -252.540029) (xy 462.182015 -252.487325) (xy 462.197725 -252.436395)
			(xy 462.220851 -252.388374) (xy 462.250875 -252.344337) (xy 462.287127 -252.305266) (xy 462.328798 -252.272035)
			(xy 462.374956 -252.245386) (xy 462.42457 -252.225914) (xy 462.476532 -252.214054) (xy 462.529682 -252.210071)
			(xy 462.582832 -252.214054) (xy 462.634794 -252.225914) (xy 462.684408 -252.245386) (xy 462.730566 -252.272035)
			(xy 462.772237 -252.305266) (xy 462.808489 -252.344337) (xy 462.838513 -252.388374) (xy 462.861639 -252.436395)
			(xy 462.877349 -252.487325) (xy 462.885292 -252.540029) (xy 462.88579 -252.566678) (xy 462.885292 -252.593327)
			(xy 462.877349 -252.646031) (xy 462.861639 -252.696961) (xy 462.838513 -252.744982) (xy 462.808489 -252.789019)
			(xy 462.772237 -252.82809) (xy 462.730566 -252.861321) (xy 462.684408 -252.88797) (xy 462.634794 -252.907442)
			(xy 462.582832 -252.919302) (xy 462.529682 -252.923286) (xy 462.476532 -252.919302) (xy 462.42457 -252.907442)
			(xy 462.374956 -252.88797) (xy 462.328798 -252.861321) (xy 462.287127 -252.82809) (xy 462.250875 -252.789019)
			(xy 462.220851 -252.744982) (xy 462.197725 -252.696961) (xy 462.182015 -252.646031) (xy 462.174072 -252.593327)
			(xy 455.366892 -252.593327) (xy 455.358949 -252.646031) (xy 455.343239 -252.696961) (xy 455.320113 -252.744982)
			(xy 455.290089 -252.789019) (xy 455.253837 -252.82809) (xy 455.212166 -252.861321) (xy 455.166008 -252.88797)
			(xy 455.116394 -252.907442) (xy 455.064432 -252.919302) (xy 455.011282 -252.923286) (xy 454.958132 -252.919302)
			(xy 454.90617 -252.907442) (xy 454.856556 -252.88797) (xy 454.810398 -252.861321) (xy 454.768727 -252.82809)
			(xy 454.732475 -252.789019) (xy 454.702451 -252.744982) (xy 454.679325 -252.696961) (xy 454.663615 -252.646031)
			(xy 454.655672 -252.593327) (xy 451.266824 -252.593327) (xy 451.258881 -252.646031) (xy 451.243171 -252.696961)
			(xy 451.220045 -252.744982) (xy 451.190021 -252.789019) (xy 451.153769 -252.82809) (xy 451.112098 -252.861321)
			(xy 451.06594 -252.88797) (xy 451.016326 -252.907442) (xy 450.964364 -252.919302) (xy 450.911214 -252.923286)
			(xy 450.858064 -252.919302) (xy 450.806102 -252.907442) (xy 450.756488 -252.88797) (xy 450.71033 -252.861321)
			(xy 450.668659 -252.82809) (xy 450.632407 -252.789019) (xy 450.602383 -252.744982) (xy 450.579257 -252.696961)
			(xy 450.563547 -252.646031) (xy 450.555604 -252.593327) (xy 447.823092 -252.593327) (xy 447.815149 -252.646031)
			(xy 447.799439 -252.696961) (xy 447.776313 -252.744982) (xy 447.746289 -252.789019) (xy 447.710037 -252.82809)
			(xy 447.668366 -252.861321) (xy 447.622208 -252.88797) (xy 447.572594 -252.907442) (xy 447.520632 -252.919302)
			(xy 447.467482 -252.923286) (xy 447.414332 -252.919302) (xy 447.36237 -252.907442) (xy 447.312756 -252.88797)
			(xy 447.266598 -252.861321) (xy 447.224927 -252.82809) (xy 447.188675 -252.789019) (xy 447.158651 -252.744982)
			(xy 447.135525 -252.696961) (xy 447.119815 -252.646031) (xy 447.111872 -252.593327) (xy 440.279292 -252.593327)
			(xy 440.271349 -252.646031) (xy 440.255639 -252.696961) (xy 440.232513 -252.744982) (xy 440.202489 -252.789019)
			(xy 440.166237 -252.82809) (xy 440.124566 -252.861321) (xy 440.078408 -252.88797) (xy 440.028794 -252.907442)
			(xy 439.976832 -252.919302) (xy 439.923682 -252.923286) (xy 439.870532 -252.919302) (xy 439.81857 -252.907442)
			(xy 439.768956 -252.88797) (xy 439.722798 -252.861321) (xy 439.681127 -252.82809) (xy 439.644875 -252.789019)
			(xy 439.614851 -252.744982) (xy 439.591725 -252.696961) (xy 439.576015 -252.646031) (xy 439.568072 -252.593327)
			(xy 436.179224 -252.593327) (xy 436.171281 -252.646031) (xy 436.155571 -252.696961) (xy 436.132445 -252.744982)
			(xy 436.102421 -252.789019) (xy 436.066169 -252.82809) (xy 436.024498 -252.861321) (xy 435.97834 -252.88797)
			(xy 435.928726 -252.907442) (xy 435.876764 -252.919302) (xy 435.823614 -252.923286) (xy 435.770464 -252.919302)
			(xy 435.718502 -252.907442) (xy 435.668888 -252.88797) (xy 435.62273 -252.861321) (xy 435.581059 -252.82809)
			(xy 435.544807 -252.789019) (xy 435.514783 -252.744982) (xy 435.491657 -252.696961) (xy 435.475947 -252.646031)
			(xy 435.468004 -252.593327) (xy 432.710092 -252.593327) (xy 432.702149 -252.646031) (xy 432.686439 -252.696961)
			(xy 432.663313 -252.744982) (xy 432.633289 -252.789019) (xy 432.597037 -252.82809) (xy 432.555366 -252.861321)
			(xy 432.509208 -252.88797) (xy 432.459594 -252.907442) (xy 432.407632 -252.919302) (xy 432.354482 -252.923286)
			(xy 432.301332 -252.919302) (xy 432.24937 -252.907442) (xy 432.199756 -252.88797) (xy 432.153598 -252.861321)
			(xy 432.111927 -252.82809) (xy 432.075675 -252.789019) (xy 432.045651 -252.744982) (xy 432.022525 -252.696961)
			(xy 432.006815 -252.646031) (xy 431.998872 -252.593327) (xy 425.191692 -252.593327) (xy 425.183749 -252.646031)
			(xy 425.168039 -252.696961) (xy 425.144913 -252.744982) (xy 425.114889 -252.789019) (xy 425.078637 -252.82809)
			(xy 425.036966 -252.861321) (xy 424.990808 -252.88797) (xy 424.941194 -252.907442) (xy 424.889232 -252.919302)
			(xy 424.836082 -252.923286) (xy 424.782932 -252.919302) (xy 424.73097 -252.907442) (xy 424.681356 -252.88797)
			(xy 424.635198 -252.861321) (xy 424.593527 -252.82809) (xy 424.557275 -252.789019) (xy 424.527251 -252.744982)
			(xy 424.504125 -252.696961) (xy 424.488415 -252.646031) (xy 424.480472 -252.593327) (xy 421.091624 -252.593327)
			(xy 421.083681 -252.646031) (xy 421.067971 -252.696961) (xy 421.044845 -252.744982) (xy 421.014821 -252.789019)
			(xy 420.978569 -252.82809) (xy 420.936898 -252.861321) (xy 420.89074 -252.88797) (xy 420.841126 -252.907442)
			(xy 420.789164 -252.919302) (xy 420.736014 -252.923286) (xy 420.682864 -252.919302) (xy 420.630902 -252.907442)
			(xy 420.581288 -252.88797) (xy 420.53513 -252.861321) (xy 420.493459 -252.82809) (xy 420.457207 -252.789019)
			(xy 420.427183 -252.744982) (xy 420.404057 -252.696961) (xy 420.388347 -252.646031) (xy 420.380404 -252.593327)
			(xy 407.4668 -252.593327) (xy 407.4668 -254.79629) (xy 410.227018 -254.79629) (xy 410.227511 -254.768199)
			(xy 410.236357 -254.712719) (xy 410.253811 -254.659317) (xy 410.27944 -254.609322) (xy 410.312607 -254.563976)
			(xy 410.332174 -254.543814) (xy 410.342335 -254.532941) (xy 410.35649 -254.506781) (xy 410.36252 -254.477654)
			(xy 410.359915 -254.448024) (xy 410.348897 -254.420396) (xy 410.340048 -254.408432) (xy 410.321888 -254.38462)
			(xy 410.292959 -254.332193) (xy 410.273208 -254.275665) (xy 410.263192 -254.21663) (xy 410.262578 -254.18669)
			(xy 410.263076 -254.160041) (xy 410.271019 -254.107337) (xy 410.286729 -254.056407) (xy 410.309855 -254.008386)
			(xy 410.339879 -253.964349) (xy 410.376131 -253.925278) (xy 410.417802 -253.892047) (xy 410.46396 -253.865398)
			(xy 410.513574 -253.845926) (xy 410.565536 -253.834066) (xy 410.618686 -253.830083) (xy 410.671836 -253.834066)
			(xy 410.723798 -253.845926) (xy 410.773412 -253.865398) (xy 410.81957 -253.892047) (xy 410.861241 -253.925278)
			(xy 410.897493 -253.964349) (xy 410.927517 -254.008386) (xy 410.950643 -254.056407) (xy 410.958707 -254.08255)
			(xy 411.225238 -254.08255) (xy 411.225695 -254.054563) (xy 411.234459 -253.99928) (xy 411.251763 -253.946048)
			(xy 411.277181 -253.896179) (xy 411.310088 -253.8509) (xy 411.349673 -253.811326) (xy 411.394961 -253.778431)
			(xy 411.444837 -253.753026) (xy 411.498073 -253.735736) (xy 411.553359 -253.726987) (xy 411.581346 -253.726442)
			(xy 411.606804 -253.726877) (xy 411.6572 -253.734134) (xy 411.706049 -253.748494) (xy 411.752356 -253.769664)
			(xy 411.795176 -253.797212) (xy 411.833637 -253.830577) (xy 411.866954 -253.869079) (xy 411.881066 -253.890272)
			(xy 411.88872 -253.90139) (xy 411.908742 -253.919477) (xy 411.932802 -253.93169) (xy 411.95922 -253.937176)
			(xy 411.986154 -253.935554) (xy 412.011722 -253.926936) (xy 412.034143 -253.911924) (xy 412.05185 -253.891565)
			(xy 412.058104 -253.879604) (xy 412.070993 -253.854129) (xy 412.103686 -253.807328) (xy 412.143425 -253.76634)
			(xy 412.189193 -253.732215) (xy 412.239817 -253.705827) (xy 412.294003 -253.68785) (xy 412.350361 -253.678746)
			(xy 412.378906 -253.678182) (xy 412.406889 -253.678735) (xy 412.409679 -253.679177) (xy 418.28846 -253.679177)
			(xy 418.28846 -253.625879) (xy 418.296403 -253.573175) (xy 418.312113 -253.522245) (xy 418.335239 -253.474224)
			(xy 418.365263 -253.430187) (xy 418.401515 -253.391116) (xy 418.443186 -253.357885) (xy 418.489344 -253.331236)
			(xy 418.538958 -253.311764) (xy 418.59092 -253.299904) (xy 418.64407 -253.295921) (xy 418.69722 -253.299904)
			(xy 418.749182 -253.311764) (xy 418.798796 -253.331236) (xy 418.844954 -253.357885) (xy 418.886625 -253.391116)
			(xy 418.922877 -253.430187) (xy 418.952901 -253.474224) (xy 418.976027 -253.522245) (xy 418.991737 -253.573175)
			(xy 418.99968 -253.625879) (xy 419.000178 -253.652528) (xy 418.99968 -253.679177) (xy 418.991737 -253.731881)
			(xy 418.976027 -253.782811) (xy 418.952901 -253.830832) (xy 418.922877 -253.874869) (xy 418.886625 -253.91394)
			(xy 418.844954 -253.947171) (xy 418.798796 -253.97382) (xy 418.749182 -253.993292) (xy 418.69722 -254.005152)
			(xy 418.64407 -254.009136) (xy 418.59092 -254.005152) (xy 418.538958 -253.993292) (xy 418.489344 -253.97382)
			(xy 418.443186 -253.947171) (xy 418.401515 -253.91394) (xy 418.365263 -253.874869) (xy 418.335239 -253.830832)
			(xy 418.312113 -253.782811) (xy 418.296403 -253.731881) (xy 418.28846 -253.679177) (xy 412.409679 -253.679177)
			(xy 412.462165 -253.687491) (xy 412.515391 -253.704786) (xy 412.565257 -253.730194) (xy 412.610534 -253.763089)
			(xy 412.650108 -253.802663) (xy 412.683004 -253.84794) (xy 412.708413 -253.897805) (xy 412.725708 -253.951031)
			(xy 412.734464 -254.006307) (xy 412.735014 -254.03429) (xy 412.734574 -254.059267) (xy 412.727578 -254.108729)
			(xy 412.713736 -254.156728) (xy 412.69332 -254.20232) (xy 412.66673 -254.24461) (xy 412.63449 -254.282768)
			(xy 412.616142 -254.29972) (xy 412.605596 -254.309813) (xy 412.590214 -254.334605) (xy 412.58247 -254.362735)
			(xy 412.582996 -254.391907) (xy 412.591748 -254.41974) (xy 412.608014 -254.443962) (xy 412.618936 -254.453644)
			(xy 412.627342 -254.460693) (xy 412.643355 -254.47569) (xy 412.65094 -254.483616) (xy 412.660917 -254.493546)
			(xy 412.6851 -254.507936) (xy 412.71229 -254.515189) (xy 412.740428 -254.514756) (xy 412.767381 -254.506669)
			(xy 412.791111 -254.491542) (xy 412.8008 -254.48133) (xy 412.817761 -254.462822) (xy 412.856004 -254.4303)
			(xy 412.898438 -254.403475) (xy 412.944219 -254.382877) (xy 412.992441 -254.368916) (xy 413.042145 -254.361869)
			(xy 413.067246 -254.361442) (xy 413.093897 -254.361843) (xy 413.146602 -254.369793) (xy 413.197534 -254.38551)
			(xy 413.245555 -254.408641) (xy 413.289593 -254.43867) (xy 413.328663 -254.474927) (xy 413.361894 -254.516602)
			(xy 413.388543 -254.562764) (xy 413.408015 -254.612382) (xy 413.419875 -254.664347) (xy 413.423858 -254.7175)
			(xy 413.419875 -254.770653) (xy 413.408015 -254.822618) (xy 413.388543 -254.872236) (xy 413.361894 -254.918398)
			(xy 413.328663 -254.960073) (xy 413.289593 -254.99633) (xy 413.245555 -255.026359) (xy 413.197534 -255.04949)
			(xy 413.146602 -255.065207) (xy 413.093897 -255.073157) (xy 413.067246 -255.073658) (xy 413.038181 -255.073067)
			(xy 412.98082 -255.063644) (xy 412.925752 -255.045026) (xy 412.874441 -255.017707) (xy 412.828252 -254.982414)
			(xy 412.807912 -254.961644) (xy 412.797885 -254.95177) (xy 412.773715 -254.937383) (xy 412.746539 -254.930127)
			(xy 412.718414 -254.93055) (xy 412.691469 -254.938621) (xy 412.667743 -254.953728) (xy 412.658052 -254.96393)
			(xy 412.641056 -254.982405) (xy 412.602821 -255.014931) (xy 412.560396 -255.041762) (xy 412.514621 -255.062366)
			(xy 412.466405 -255.076333) (xy 412.416705 -255.083387) (xy 412.391606 -255.083818) (xy 412.363241 -255.083281)
			(xy 412.307225 -255.074307) (xy 412.25334 -255.056568) (xy 412.202948 -255.030512) (xy 412.157322 -254.9968)
			(xy 412.117616 -254.956282) (xy 412.100776 -254.93345) (xy 412.091544 -254.921413) (xy 412.067574 -254.902855)
			(xy 412.039209 -254.89216) (xy 412.008954 -254.890272) (xy 411.979479 -254.897359) (xy 411.953389 -254.912794)
			(xy 411.932987 -254.935215) (xy 411.926024 -254.94869) (xy 411.91485 -254.9712) (xy 411.88718 -255.01315)
			(xy 411.853886 -255.050792) (xy 411.815629 -255.083378) (xy 411.77317 -255.110259) (xy 411.727352 -255.130903)
			(xy 411.679087 -255.144897) (xy 411.629333 -255.151965) (xy 411.604206 -255.152398) (xy 411.57622 -255.151882)
			(xy 411.520938 -255.143127) (xy 411.467706 -255.125831) (xy 411.417835 -255.100421) (xy 411.372553 -255.067522)
			(xy 411.332976 -255.027944) (xy 411.300077 -254.982662) (xy 411.274667 -254.93279) (xy 411.257372 -254.879558)
			(xy 411.248618 -254.824276) (xy 411.248098 -254.79629) (xy 411.248535 -254.770677) (xy 411.255865 -254.719977)
			(xy 411.270385 -254.670852) (xy 411.291797 -254.624315) (xy 411.319657 -254.581327) (xy 411.353392 -254.542777)
			(xy 411.372558 -254.52578) (xy 411.383768 -254.515513) (xy 411.400024 -254.489842) (xy 411.408015 -254.460527)
			(xy 411.407036 -254.430157) (xy 411.397172 -254.401418) (xy 411.379296 -254.376848) (xy 411.367478 -254.367284)
			(xy 411.345821 -254.35031) (xy 411.307428 -254.3109) (xy 411.275554 -254.266053) (xy 411.250958 -254.216837)
			(xy 411.234225 -254.164424) (xy 411.225754 -254.11006) (xy 411.225238 -254.08255) (xy 410.958707 -254.08255)
			(xy 410.966353 -254.107337) (xy 410.974296 -254.160041) (xy 410.974794 -254.18669) (xy 410.974285 -254.21478)
			(xy 410.965443 -254.27026) (xy 410.947992 -254.323661) (xy 410.922367 -254.373656) (xy 410.889203 -254.419004)
			(xy 410.869638 -254.439166) (xy 410.859495 -254.450055) (xy 410.845337 -254.47621) (xy 410.839303 -254.505332)
			(xy 410.841903 -254.534959) (xy 410.852917 -254.562585) (xy 410.861764 -254.574548) (xy 410.879916 -254.598365)
			(xy 410.908847 -254.65079) (xy 410.9286 -254.707317) (xy 410.938618 -254.766351) (xy 410.939234 -254.79629)
			(xy 410.938736 -254.822939) (xy 410.930793 -254.875643) (xy 410.915083 -254.926573) (xy 410.891957 -254.974594)
			(xy 410.861933 -255.018631) (xy 410.825681 -255.057702) (xy 410.78401 -255.090933) (xy 410.737852 -255.117582)
			(xy 410.688238 -255.137054) (xy 410.636276 -255.148914) (xy 410.583126 -255.152898) (xy 410.529976 -255.148914)
			(xy 410.478014 -255.137054) (xy 410.4284 -255.117582) (xy 410.382242 -255.090933) (xy 410.340571 -255.057702)
			(xy 410.304319 -255.018631) (xy 410.274295 -254.974594) (xy 410.251169 -254.926573) (xy 410.235459 -254.875643)
			(xy 410.227516 -254.822939) (xy 410.227018 -254.79629) (xy 407.4668 -254.79629) (xy 407.4668 -259.393415)
			(xy 420.380404 -259.393415) (xy 420.380404 -259.340117) (xy 420.388347 -259.287413) (xy 420.404057 -259.236483)
			(xy 420.427183 -259.188462) (xy 420.457207 -259.144425) (xy 420.493459 -259.105354) (xy 420.53513 -259.072123)
			(xy 420.581288 -259.045474) (xy 420.630902 -259.026002) (xy 420.682864 -259.014142) (xy 420.736014 -259.010159)
			(xy 420.789164 -259.014142) (xy 420.841126 -259.026002) (xy 420.89074 -259.045474) (xy 420.936898 -259.072123)
			(xy 420.978569 -259.105354) (xy 421.014821 -259.144425) (xy 421.044845 -259.188462) (xy 421.067971 -259.236483)
			(xy 421.083681 -259.287413) (xy 421.091624 -259.340117) (xy 421.092122 -259.366766) (xy 421.091624 -259.393415)
			(xy 424.480472 -259.393415) (xy 424.480472 -259.340117) (xy 424.488415 -259.287413) (xy 424.504125 -259.236483)
			(xy 424.527251 -259.188462) (xy 424.557275 -259.144425) (xy 424.593527 -259.105354) (xy 424.635198 -259.072123)
			(xy 424.681356 -259.045474) (xy 424.73097 -259.026002) (xy 424.782932 -259.014142) (xy 424.836082 -259.010159)
			(xy 424.889232 -259.014142) (xy 424.941194 -259.026002) (xy 424.990808 -259.045474) (xy 425.036966 -259.072123)
			(xy 425.078637 -259.105354) (xy 425.114889 -259.144425) (xy 425.144913 -259.188462) (xy 425.168039 -259.236483)
			(xy 425.183749 -259.287413) (xy 425.191692 -259.340117) (xy 425.19219 -259.366766) (xy 425.191692 -259.393415)
			(xy 432.024272 -259.393415) (xy 432.024272 -259.340117) (xy 432.032215 -259.287413) (xy 432.047925 -259.236483)
			(xy 432.071051 -259.188462) (xy 432.101075 -259.144425) (xy 432.137327 -259.105354) (xy 432.178998 -259.072123)
			(xy 432.225156 -259.045474) (xy 432.27477 -259.026002) (xy 432.326732 -259.014142) (xy 432.379882 -259.010159)
			(xy 432.433032 -259.014142) (xy 432.484994 -259.026002) (xy 432.534608 -259.045474) (xy 432.580766 -259.072123)
			(xy 432.622437 -259.105354) (xy 432.658689 -259.144425) (xy 432.688713 -259.188462) (xy 432.711839 -259.236483)
			(xy 432.727549 -259.287413) (xy 432.735492 -259.340117) (xy 432.73599 -259.366766) (xy 432.735492 -259.393415)
			(xy 435.468004 -259.393415) (xy 435.468004 -259.340117) (xy 435.475947 -259.287413) (xy 435.491657 -259.236483)
			(xy 435.514783 -259.188462) (xy 435.544807 -259.144425) (xy 435.581059 -259.105354) (xy 435.62273 -259.072123)
			(xy 435.668888 -259.045474) (xy 435.718502 -259.026002) (xy 435.770464 -259.014142) (xy 435.823614 -259.010159)
			(xy 435.876764 -259.014142) (xy 435.928726 -259.026002) (xy 435.97834 -259.045474) (xy 436.024498 -259.072123)
			(xy 436.066169 -259.105354) (xy 436.102421 -259.144425) (xy 436.132445 -259.188462) (xy 436.155571 -259.236483)
			(xy 436.171281 -259.287413) (xy 436.179224 -259.340117) (xy 436.179722 -259.366766) (xy 436.179224 -259.393415)
			(xy 439.568072 -259.393415) (xy 439.568072 -259.340117) (xy 439.576015 -259.287413) (xy 439.591725 -259.236483)
			(xy 439.614851 -259.188462) (xy 439.644875 -259.144425) (xy 439.681127 -259.105354) (xy 439.722798 -259.072123)
			(xy 439.768956 -259.045474) (xy 439.81857 -259.026002) (xy 439.870532 -259.014142) (xy 439.923682 -259.010159)
			(xy 439.976832 -259.014142) (xy 440.028794 -259.026002) (xy 440.078408 -259.045474) (xy 440.124566 -259.072123)
			(xy 440.166237 -259.105354) (xy 440.202489 -259.144425) (xy 440.232513 -259.188462) (xy 440.255639 -259.236483)
			(xy 440.271349 -259.287413) (xy 440.279292 -259.340117) (xy 440.27979 -259.366766) (xy 440.279292 -259.393415)
			(xy 447.111872 -259.393415) (xy 447.111872 -259.340117) (xy 447.119815 -259.287413) (xy 447.135525 -259.236483)
			(xy 447.158651 -259.188462) (xy 447.188675 -259.144425) (xy 447.224927 -259.105354) (xy 447.266598 -259.072123)
			(xy 447.312756 -259.045474) (xy 447.36237 -259.026002) (xy 447.414332 -259.014142) (xy 447.467482 -259.010159)
			(xy 447.520632 -259.014142) (xy 447.572594 -259.026002) (xy 447.622208 -259.045474) (xy 447.668366 -259.072123)
			(xy 447.710037 -259.105354) (xy 447.746289 -259.144425) (xy 447.776313 -259.188462) (xy 447.799439 -259.236483)
			(xy 447.815149 -259.287413) (xy 447.823092 -259.340117) (xy 447.82359 -259.366766) (xy 447.823092 -259.393415)
			(xy 450.555604 -259.393415) (xy 450.555604 -259.340117) (xy 450.563547 -259.287413) (xy 450.579257 -259.236483)
			(xy 450.602383 -259.188462) (xy 450.632407 -259.144425) (xy 450.668659 -259.105354) (xy 450.71033 -259.072123)
			(xy 450.756488 -259.045474) (xy 450.806102 -259.026002) (xy 450.858064 -259.014142) (xy 450.911214 -259.010159)
			(xy 450.964364 -259.014142) (xy 451.016326 -259.026002) (xy 451.06594 -259.045474) (xy 451.112098 -259.072123)
			(xy 451.153769 -259.105354) (xy 451.190021 -259.144425) (xy 451.220045 -259.188462) (xy 451.243171 -259.236483)
			(xy 451.258881 -259.287413) (xy 451.266824 -259.340117) (xy 451.267322 -259.366766) (xy 451.266824 -259.393415)
			(xy 454.655672 -259.393415) (xy 454.655672 -259.340117) (xy 454.663615 -259.287413) (xy 454.679325 -259.236483)
			(xy 454.702451 -259.188462) (xy 454.732475 -259.144425) (xy 454.768727 -259.105354) (xy 454.810398 -259.072123)
			(xy 454.856556 -259.045474) (xy 454.90617 -259.026002) (xy 454.958132 -259.014142) (xy 455.011282 -259.010159)
			(xy 455.064432 -259.014142) (xy 455.116394 -259.026002) (xy 455.166008 -259.045474) (xy 455.212166 -259.072123)
			(xy 455.253837 -259.105354) (xy 455.290089 -259.144425) (xy 455.320113 -259.188462) (xy 455.343239 -259.236483)
			(xy 455.358949 -259.287413) (xy 455.366892 -259.340117) (xy 455.36739 -259.366766) (xy 455.366892 -259.393415)
			(xy 462.199472 -259.393415) (xy 462.199472 -259.340117) (xy 462.207415 -259.287413) (xy 462.223125 -259.236483)
			(xy 462.246251 -259.188462) (xy 462.276275 -259.144425) (xy 462.312527 -259.105354) (xy 462.354198 -259.072123)
			(xy 462.400356 -259.045474) (xy 462.44997 -259.026002) (xy 462.501932 -259.014142) (xy 462.555082 -259.010159)
			(xy 462.608232 -259.014142) (xy 462.660194 -259.026002) (xy 462.709808 -259.045474) (xy 462.755966 -259.072123)
			(xy 462.797637 -259.105354) (xy 462.833889 -259.144425) (xy 462.863913 -259.188462) (xy 462.887039 -259.236483)
			(xy 462.902749 -259.287413) (xy 462.910692 -259.340117) (xy 462.91119 -259.366766) (xy 462.910692 -259.393415)
			(xy 462.902749 -259.446119) (xy 462.887039 -259.497049) (xy 462.863913 -259.54507) (xy 462.833889 -259.589107)
			(xy 462.797637 -259.628178) (xy 462.755966 -259.661409) (xy 462.709808 -259.688058) (xy 462.660194 -259.70753)
			(xy 462.608232 -259.71939) (xy 462.555082 -259.723374) (xy 462.501932 -259.71939) (xy 462.44997 -259.70753)
			(xy 462.400356 -259.688058) (xy 462.354198 -259.661409) (xy 462.312527 -259.628178) (xy 462.276275 -259.589107)
			(xy 462.246251 -259.54507) (xy 462.223125 -259.497049) (xy 462.207415 -259.446119) (xy 462.199472 -259.393415)
			(xy 455.366892 -259.393415) (xy 455.358949 -259.446119) (xy 455.343239 -259.497049) (xy 455.320113 -259.54507)
			(xy 455.290089 -259.589107) (xy 455.253837 -259.628178) (xy 455.212166 -259.661409) (xy 455.166008 -259.688058)
			(xy 455.116394 -259.70753) (xy 455.064432 -259.71939) (xy 455.011282 -259.723374) (xy 454.958132 -259.71939)
			(xy 454.90617 -259.70753) (xy 454.856556 -259.688058) (xy 454.810398 -259.661409) (xy 454.768727 -259.628178)
			(xy 454.732475 -259.589107) (xy 454.702451 -259.54507) (xy 454.679325 -259.497049) (xy 454.663615 -259.446119)
			(xy 454.655672 -259.393415) (xy 451.266824 -259.393415) (xy 451.258881 -259.446119) (xy 451.243171 -259.497049)
			(xy 451.220045 -259.54507) (xy 451.190021 -259.589107) (xy 451.153769 -259.628178) (xy 451.112098 -259.661409)
			(xy 451.06594 -259.688058) (xy 451.016326 -259.70753) (xy 450.964364 -259.71939) (xy 450.911214 -259.723374)
			(xy 450.858064 -259.71939) (xy 450.806102 -259.70753) (xy 450.756488 -259.688058) (xy 450.71033 -259.661409)
			(xy 450.668659 -259.628178) (xy 450.632407 -259.589107) (xy 450.602383 -259.54507) (xy 450.579257 -259.497049)
			(xy 450.563547 -259.446119) (xy 450.555604 -259.393415) (xy 447.823092 -259.393415) (xy 447.815149 -259.446119)
			(xy 447.799439 -259.497049) (xy 447.776313 -259.54507) (xy 447.746289 -259.589107) (xy 447.710037 -259.628178)
			(xy 447.668366 -259.661409) (xy 447.622208 -259.688058) (xy 447.572594 -259.70753) (xy 447.520632 -259.71939)
			(xy 447.467482 -259.723374) (xy 447.414332 -259.71939) (xy 447.36237 -259.70753) (xy 447.312756 -259.688058)
			(xy 447.266598 -259.661409) (xy 447.224927 -259.628178) (xy 447.188675 -259.589107) (xy 447.158651 -259.54507)
			(xy 447.135525 -259.497049) (xy 447.119815 -259.446119) (xy 447.111872 -259.393415) (xy 440.279292 -259.393415)
			(xy 440.271349 -259.446119) (xy 440.255639 -259.497049) (xy 440.232513 -259.54507) (xy 440.202489 -259.589107)
			(xy 440.166237 -259.628178) (xy 440.124566 -259.661409) (xy 440.078408 -259.688058) (xy 440.028794 -259.70753)
			(xy 439.976832 -259.71939) (xy 439.923682 -259.723374) (xy 439.870532 -259.71939) (xy 439.81857 -259.70753)
			(xy 439.768956 -259.688058) (xy 439.722798 -259.661409) (xy 439.681127 -259.628178) (xy 439.644875 -259.589107)
			(xy 439.614851 -259.54507) (xy 439.591725 -259.497049) (xy 439.576015 -259.446119) (xy 439.568072 -259.393415)
			(xy 436.179224 -259.393415) (xy 436.171281 -259.446119) (xy 436.155571 -259.497049) (xy 436.132445 -259.54507)
			(xy 436.102421 -259.589107) (xy 436.066169 -259.628178) (xy 436.024498 -259.661409) (xy 435.97834 -259.688058)
			(xy 435.928726 -259.70753) (xy 435.876764 -259.71939) (xy 435.823614 -259.723374) (xy 435.770464 -259.71939)
			(xy 435.718502 -259.70753) (xy 435.668888 -259.688058) (xy 435.62273 -259.661409) (xy 435.581059 -259.628178)
			(xy 435.544807 -259.589107) (xy 435.514783 -259.54507) (xy 435.491657 -259.497049) (xy 435.475947 -259.446119)
			(xy 435.468004 -259.393415) (xy 432.735492 -259.393415) (xy 432.727549 -259.446119) (xy 432.711839 -259.497049)
			(xy 432.688713 -259.54507) (xy 432.658689 -259.589107) (xy 432.622437 -259.628178) (xy 432.580766 -259.661409)
			(xy 432.534608 -259.688058) (xy 432.484994 -259.70753) (xy 432.433032 -259.71939) (xy 432.379882 -259.723374)
			(xy 432.326732 -259.71939) (xy 432.27477 -259.70753) (xy 432.225156 -259.688058) (xy 432.178998 -259.661409)
			(xy 432.137327 -259.628178) (xy 432.101075 -259.589107) (xy 432.071051 -259.54507) (xy 432.047925 -259.497049)
			(xy 432.032215 -259.446119) (xy 432.024272 -259.393415) (xy 425.191692 -259.393415) (xy 425.183749 -259.446119)
			(xy 425.168039 -259.497049) (xy 425.144913 -259.54507) (xy 425.114889 -259.589107) (xy 425.078637 -259.628178)
			(xy 425.036966 -259.661409) (xy 424.990808 -259.688058) (xy 424.941194 -259.70753) (xy 424.889232 -259.71939)
			(xy 424.836082 -259.723374) (xy 424.782932 -259.71939) (xy 424.73097 -259.70753) (xy 424.681356 -259.688058)
			(xy 424.635198 -259.661409) (xy 424.593527 -259.628178) (xy 424.557275 -259.589107) (xy 424.527251 -259.54507)
			(xy 424.504125 -259.497049) (xy 424.488415 -259.446119) (xy 424.480472 -259.393415) (xy 421.091624 -259.393415)
			(xy 421.083681 -259.446119) (xy 421.067971 -259.497049) (xy 421.044845 -259.54507) (xy 421.014821 -259.589107)
			(xy 420.978569 -259.628178) (xy 420.936898 -259.661409) (xy 420.89074 -259.688058) (xy 420.841126 -259.70753)
			(xy 420.789164 -259.71939) (xy 420.736014 -259.723374) (xy 420.682864 -259.71939) (xy 420.630902 -259.70753)
			(xy 420.581288 -259.688058) (xy 420.53513 -259.661409) (xy 420.493459 -259.628178) (xy 420.457207 -259.589107)
			(xy 420.427183 -259.54507) (xy 420.404057 -259.497049) (xy 420.388347 -259.446119) (xy 420.380404 -259.393415)
			(xy 407.4668 -259.393415) (xy 407.4668 -260.243299) (xy 424.480472 -260.243299) (xy 424.480472 -260.190001)
			(xy 424.488415 -260.137297) (xy 424.504125 -260.086367) (xy 424.527251 -260.038346) (xy 424.557275 -259.994309)
			(xy 424.593527 -259.955238) (xy 424.635198 -259.922007) (xy 424.681356 -259.895358) (xy 424.73097 -259.875886)
			(xy 424.782932 -259.864026) (xy 424.836082 -259.860043) (xy 424.889232 -259.864026) (xy 424.941194 -259.875886)
			(xy 424.990808 -259.895358) (xy 425.036966 -259.922007) (xy 425.078637 -259.955238) (xy 425.114889 -259.994309)
			(xy 425.144913 -260.038346) (xy 425.168039 -260.086367) (xy 425.183749 -260.137297) (xy 425.191692 -260.190001)
			(xy 425.19219 -260.21665) (xy 425.191692 -260.243299) (xy 432.024272 -260.243299) (xy 432.024272 -260.190001)
			(xy 432.032215 -260.137297) (xy 432.047925 -260.086367) (xy 432.071051 -260.038346) (xy 432.101075 -259.994309)
			(xy 432.137327 -259.955238) (xy 432.178998 -259.922007) (xy 432.225156 -259.895358) (xy 432.27477 -259.875886)
			(xy 432.326732 -259.864026) (xy 432.379882 -259.860043) (xy 432.433032 -259.864026) (xy 432.484994 -259.875886)
			(xy 432.534608 -259.895358) (xy 432.580766 -259.922007) (xy 432.622437 -259.955238) (xy 432.658689 -259.994309)
			(xy 432.688713 -260.038346) (xy 432.711839 -260.086367) (xy 432.727549 -260.137297) (xy 432.735492 -260.190001)
			(xy 432.73599 -260.21665) (xy 432.735492 -260.243299) (xy 439.568072 -260.243299) (xy 439.568072 -260.190001)
			(xy 439.576015 -260.137297) (xy 439.591725 -260.086367) (xy 439.614851 -260.038346) (xy 439.644875 -259.994309)
			(xy 439.681127 -259.955238) (xy 439.722798 -259.922007) (xy 439.768956 -259.895358) (xy 439.81857 -259.875886)
			(xy 439.870532 -259.864026) (xy 439.923682 -259.860043) (xy 439.976832 -259.864026) (xy 440.028794 -259.875886)
			(xy 440.078408 -259.895358) (xy 440.124566 -259.922007) (xy 440.166237 -259.955238) (xy 440.202489 -259.994309)
			(xy 440.232513 -260.038346) (xy 440.255639 -260.086367) (xy 440.271349 -260.137297) (xy 440.279292 -260.190001)
			(xy 440.27979 -260.21665) (xy 440.279292 -260.243299) (xy 447.111872 -260.243299) (xy 447.111872 -260.190001)
			(xy 447.119815 -260.137297) (xy 447.135525 -260.086367) (xy 447.158651 -260.038346) (xy 447.188675 -259.994309)
			(xy 447.224927 -259.955238) (xy 447.266598 -259.922007) (xy 447.312756 -259.895358) (xy 447.36237 -259.875886)
			(xy 447.414332 -259.864026) (xy 447.467482 -259.860043) (xy 447.520632 -259.864026) (xy 447.572594 -259.875886)
			(xy 447.622208 -259.895358) (xy 447.668366 -259.922007) (xy 447.710037 -259.955238) (xy 447.746289 -259.994309)
			(xy 447.776313 -260.038346) (xy 447.799439 -260.086367) (xy 447.815149 -260.137297) (xy 447.823092 -260.190001)
			(xy 447.82359 -260.21665) (xy 447.823092 -260.243299) (xy 454.655672 -260.243299) (xy 454.655672 -260.190001)
			(xy 454.663615 -260.137297) (xy 454.679325 -260.086367) (xy 454.702451 -260.038346) (xy 454.732475 -259.994309)
			(xy 454.768727 -259.955238) (xy 454.810398 -259.922007) (xy 454.856556 -259.895358) (xy 454.90617 -259.875886)
			(xy 454.958132 -259.864026) (xy 455.011282 -259.860043) (xy 455.064432 -259.864026) (xy 455.116394 -259.875886)
			(xy 455.166008 -259.895358) (xy 455.212166 -259.922007) (xy 455.253837 -259.955238) (xy 455.290089 -259.994309)
			(xy 455.320113 -260.038346) (xy 455.343239 -260.086367) (xy 455.358949 -260.137297) (xy 455.366892 -260.190001)
			(xy 455.36739 -260.21665) (xy 455.366892 -260.243299) (xy 462.199472 -260.243299) (xy 462.199472 -260.190001)
			(xy 462.207415 -260.137297) (xy 462.223125 -260.086367) (xy 462.246251 -260.038346) (xy 462.276275 -259.994309)
			(xy 462.312527 -259.955238) (xy 462.354198 -259.922007) (xy 462.400356 -259.895358) (xy 462.44997 -259.875886)
			(xy 462.501932 -259.864026) (xy 462.555082 -259.860043) (xy 462.608232 -259.864026) (xy 462.660194 -259.875886)
			(xy 462.709808 -259.895358) (xy 462.755966 -259.922007) (xy 462.797637 -259.955238) (xy 462.833889 -259.994309)
			(xy 462.863913 -260.038346) (xy 462.887039 -260.086367) (xy 462.902749 -260.137297) (xy 462.910692 -260.190001)
			(xy 462.91119 -260.21665) (xy 462.910692 -260.243299) (xy 462.902749 -260.296003) (xy 462.887039 -260.346933)
			(xy 462.863913 -260.394954) (xy 462.833889 -260.438991) (xy 462.797637 -260.478062) (xy 462.755966 -260.511293)
			(xy 462.709808 -260.537942) (xy 462.660194 -260.557414) (xy 462.608232 -260.569274) (xy 462.555082 -260.573258)
			(xy 462.501932 -260.569274) (xy 462.44997 -260.557414) (xy 462.400356 -260.537942) (xy 462.354198 -260.511293)
			(xy 462.312527 -260.478062) (xy 462.276275 -260.438991) (xy 462.246251 -260.394954) (xy 462.223125 -260.346933)
			(xy 462.207415 -260.296003) (xy 462.199472 -260.243299) (xy 455.366892 -260.243299) (xy 455.358949 -260.296003)
			(xy 455.343239 -260.346933) (xy 455.320113 -260.394954) (xy 455.290089 -260.438991) (xy 455.253837 -260.478062)
			(xy 455.212166 -260.511293) (xy 455.166008 -260.537942) (xy 455.116394 -260.557414) (xy 455.064432 -260.569274)
			(xy 455.011282 -260.573258) (xy 454.958132 -260.569274) (xy 454.90617 -260.557414) (xy 454.856556 -260.537942)
			(xy 454.810398 -260.511293) (xy 454.768727 -260.478062) (xy 454.732475 -260.438991) (xy 454.702451 -260.394954)
			(xy 454.679325 -260.346933) (xy 454.663615 -260.296003) (xy 454.655672 -260.243299) (xy 447.823092 -260.243299)
			(xy 447.815149 -260.296003) (xy 447.799439 -260.346933) (xy 447.776313 -260.394954) (xy 447.746289 -260.438991)
			(xy 447.710037 -260.478062) (xy 447.668366 -260.511293) (xy 447.622208 -260.537942) (xy 447.572594 -260.557414)
			(xy 447.520632 -260.569274) (xy 447.467482 -260.573258) (xy 447.414332 -260.569274) (xy 447.36237 -260.557414)
			(xy 447.312756 -260.537942) (xy 447.266598 -260.511293) (xy 447.224927 -260.478062) (xy 447.188675 -260.438991)
			(xy 447.158651 -260.394954) (xy 447.135525 -260.346933) (xy 447.119815 -260.296003) (xy 447.111872 -260.243299)
			(xy 440.279292 -260.243299) (xy 440.271349 -260.296003) (xy 440.255639 -260.346933) (xy 440.232513 -260.394954)
			(xy 440.202489 -260.438991) (xy 440.166237 -260.478062) (xy 440.124566 -260.511293) (xy 440.078408 -260.537942)
			(xy 440.028794 -260.557414) (xy 439.976832 -260.569274) (xy 439.923682 -260.573258) (xy 439.870532 -260.569274)
			(xy 439.81857 -260.557414) (xy 439.768956 -260.537942) (xy 439.722798 -260.511293) (xy 439.681127 -260.478062)
			(xy 439.644875 -260.438991) (xy 439.614851 -260.394954) (xy 439.591725 -260.346933) (xy 439.576015 -260.296003)
			(xy 439.568072 -260.243299) (xy 432.735492 -260.243299) (xy 432.727549 -260.296003) (xy 432.711839 -260.346933)
			(xy 432.688713 -260.394954) (xy 432.658689 -260.438991) (xy 432.622437 -260.478062) (xy 432.580766 -260.511293)
			(xy 432.534608 -260.537942) (xy 432.484994 -260.557414) (xy 432.433032 -260.569274) (xy 432.379882 -260.573258)
			(xy 432.326732 -260.569274) (xy 432.27477 -260.557414) (xy 432.225156 -260.537942) (xy 432.178998 -260.511293)
			(xy 432.137327 -260.478062) (xy 432.101075 -260.438991) (xy 432.071051 -260.394954) (xy 432.047925 -260.346933)
			(xy 432.032215 -260.296003) (xy 432.024272 -260.243299) (xy 425.191692 -260.243299) (xy 425.183749 -260.296003)
			(xy 425.168039 -260.346933) (xy 425.144913 -260.394954) (xy 425.114889 -260.438991) (xy 425.078637 -260.478062)
			(xy 425.036966 -260.511293) (xy 424.990808 -260.537942) (xy 424.941194 -260.557414) (xy 424.889232 -260.569274)
			(xy 424.836082 -260.573258) (xy 424.782932 -260.569274) (xy 424.73097 -260.557414) (xy 424.681356 -260.537942)
			(xy 424.635198 -260.511293) (xy 424.593527 -260.478062) (xy 424.557275 -260.438991) (xy 424.527251 -260.394954)
			(xy 424.504125 -260.346933) (xy 424.488415 -260.296003) (xy 424.480472 -260.243299) (xy 407.4668 -260.243299)
			(xy 407.4668 -261.093437) (xy 420.304204 -261.093437) (xy 420.304204 -261.040139) (xy 420.312147 -260.987435)
			(xy 420.327857 -260.936505) (xy 420.350983 -260.888484) (xy 420.381007 -260.844447) (xy 420.417259 -260.805376)
			(xy 420.45893 -260.772145) (xy 420.505088 -260.745496) (xy 420.554702 -260.726024) (xy 420.606664 -260.714164)
			(xy 420.659814 -260.710181) (xy 420.712964 -260.714164) (xy 420.764926 -260.726024) (xy 420.81454 -260.745496)
			(xy 420.860698 -260.772145) (xy 420.902369 -260.805376) (xy 420.938621 -260.844447) (xy 420.968645 -260.888484)
			(xy 420.991771 -260.936505) (xy 421.007481 -260.987435) (xy 421.015424 -261.040139) (xy 421.015922 -261.066788)
			(xy 421.015424 -261.093437) (xy 435.468004 -261.093437) (xy 435.468004 -261.040139) (xy 435.475947 -260.987435)
			(xy 435.491657 -260.936505) (xy 435.514783 -260.888484) (xy 435.544807 -260.844447) (xy 435.581059 -260.805376)
			(xy 435.62273 -260.772145) (xy 435.668888 -260.745496) (xy 435.718502 -260.726024) (xy 435.770464 -260.714164)
			(xy 435.823614 -260.710181) (xy 435.876764 -260.714164) (xy 435.928726 -260.726024) (xy 435.97834 -260.745496)
			(xy 436.024498 -260.772145) (xy 436.066169 -260.805376) (xy 436.102421 -260.844447) (xy 436.132445 -260.888484)
			(xy 436.155571 -260.936505) (xy 436.171281 -260.987435) (xy 436.179224 -261.040139) (xy 436.179722 -261.066788)
			(xy 436.179224 -261.093437) (xy 450.555604 -261.093437) (xy 450.555604 -261.040139) (xy 450.563547 -260.987435)
			(xy 450.579257 -260.936505) (xy 450.602383 -260.888484) (xy 450.632407 -260.844447) (xy 450.668659 -260.805376)
			(xy 450.71033 -260.772145) (xy 450.756488 -260.745496) (xy 450.806102 -260.726024) (xy 450.858064 -260.714164)
			(xy 450.911214 -260.710181) (xy 450.964364 -260.714164) (xy 451.016326 -260.726024) (xy 451.06594 -260.745496)
			(xy 451.112098 -260.772145) (xy 451.153769 -260.805376) (xy 451.190021 -260.844447) (xy 451.220045 -260.888484)
			(xy 451.243171 -260.936505) (xy 451.258881 -260.987435) (xy 451.266824 -261.040139) (xy 451.267322 -261.066788)
			(xy 451.266824 -261.093437) (xy 451.258881 -261.146141) (xy 451.243171 -261.197071) (xy 451.220045 -261.245092)
			(xy 451.190021 -261.289129) (xy 451.153769 -261.3282) (xy 451.112098 -261.361431) (xy 451.06594 -261.38808)
			(xy 451.016326 -261.407552) (xy 450.964364 -261.419412) (xy 450.911214 -261.423396) (xy 450.858064 -261.419412)
			(xy 450.806102 -261.407552) (xy 450.756488 -261.38808) (xy 450.71033 -261.361431) (xy 450.668659 -261.3282)
			(xy 450.632407 -261.289129) (xy 450.602383 -261.245092) (xy 450.579257 -261.197071) (xy 450.563547 -261.146141)
			(xy 450.555604 -261.093437) (xy 436.179224 -261.093437) (xy 436.171281 -261.146141) (xy 436.155571 -261.197071)
			(xy 436.132445 -261.245092) (xy 436.102421 -261.289129) (xy 436.066169 -261.3282) (xy 436.024498 -261.361431)
			(xy 435.97834 -261.38808) (xy 435.928726 -261.407552) (xy 435.876764 -261.419412) (xy 435.823614 -261.423396)
			(xy 435.770464 -261.419412) (xy 435.718502 -261.407552) (xy 435.668888 -261.38808) (xy 435.62273 -261.361431)
			(xy 435.581059 -261.3282) (xy 435.544807 -261.289129) (xy 435.514783 -261.245092) (xy 435.491657 -261.197071)
			(xy 435.475947 -261.146141) (xy 435.468004 -261.093437) (xy 421.015424 -261.093437) (xy 421.007481 -261.146141)
			(xy 420.991771 -261.197071) (xy 420.968645 -261.245092) (xy 420.938621 -261.289129) (xy 420.902369 -261.3282)
			(xy 420.860698 -261.361431) (xy 420.81454 -261.38808) (xy 420.764926 -261.407552) (xy 420.712964 -261.419412)
			(xy 420.659814 -261.423396) (xy 420.606664 -261.419412) (xy 420.554702 -261.407552) (xy 420.505088 -261.38808)
			(xy 420.45893 -261.361431) (xy 420.417259 -261.3282) (xy 420.381007 -261.289129) (xy 420.350983 -261.245092)
			(xy 420.327857 -261.197071) (xy 420.312147 -261.146141) (xy 420.304204 -261.093437) (xy 407.4668 -261.093437)
			(xy 407.4668 -261.943321) (xy 424.480472 -261.943321) (xy 424.480472 -261.890023) (xy 424.488415 -261.837319)
			(xy 424.504125 -261.786389) (xy 424.527251 -261.738368) (xy 424.557275 -261.694331) (xy 424.593527 -261.65526)
			(xy 424.635198 -261.622029) (xy 424.681356 -261.59538) (xy 424.73097 -261.575908) (xy 424.782932 -261.564048)
			(xy 424.836082 -261.560065) (xy 424.889232 -261.564048) (xy 424.941194 -261.575908) (xy 424.990808 -261.59538)
			(xy 425.036966 -261.622029) (xy 425.078637 -261.65526) (xy 425.114889 -261.694331) (xy 425.144913 -261.738368)
			(xy 425.168039 -261.786389) (xy 425.183749 -261.837319) (xy 425.191692 -261.890023) (xy 425.19219 -261.916672)
			(xy 425.191692 -261.943321) (xy 439.568072 -261.943321) (xy 439.568072 -261.890023) (xy 439.576015 -261.837319)
			(xy 439.591725 -261.786389) (xy 439.614851 -261.738368) (xy 439.644875 -261.694331) (xy 439.681127 -261.65526)
			(xy 439.722798 -261.622029) (xy 439.768956 -261.59538) (xy 439.81857 -261.575908) (xy 439.870532 -261.564048)
			(xy 439.923682 -261.560065) (xy 439.976832 -261.564048) (xy 440.028794 -261.575908) (xy 440.078408 -261.59538)
			(xy 440.124566 -261.622029) (xy 440.166237 -261.65526) (xy 440.202489 -261.694331) (xy 440.232513 -261.738368)
			(xy 440.255639 -261.786389) (xy 440.271349 -261.837319) (xy 440.279292 -261.890023) (xy 440.27979 -261.916672)
			(xy 440.279292 -261.943321) (xy 454.655672 -261.943321) (xy 454.655672 -261.890023) (xy 454.663615 -261.837319)
			(xy 454.679325 -261.786389) (xy 454.702451 -261.738368) (xy 454.732475 -261.694331) (xy 454.768727 -261.65526)
			(xy 454.810398 -261.622029) (xy 454.856556 -261.59538) (xy 454.90617 -261.575908) (xy 454.958132 -261.564048)
			(xy 455.011282 -261.560065) (xy 455.064432 -261.564048) (xy 455.116394 -261.575908) (xy 455.166008 -261.59538)
			(xy 455.212166 -261.622029) (xy 455.253837 -261.65526) (xy 455.290089 -261.694331) (xy 455.320113 -261.738368)
			(xy 455.343239 -261.786389) (xy 455.358949 -261.837319) (xy 455.366892 -261.890023) (xy 455.36739 -261.916672)
			(xy 455.366892 -261.943321) (xy 455.358949 -261.996025) (xy 455.343239 -262.046955) (xy 455.320113 -262.094976)
			(xy 455.290089 -262.139013) (xy 455.253837 -262.178084) (xy 455.212166 -262.211315) (xy 455.166008 -262.237964)
			(xy 455.116394 -262.257436) (xy 455.064432 -262.269296) (xy 455.011282 -262.27328) (xy 454.958132 -262.269296)
			(xy 454.90617 -262.257436) (xy 454.856556 -262.237964) (xy 454.810398 -262.211315) (xy 454.768727 -262.178084)
			(xy 454.732475 -262.139013) (xy 454.702451 -262.094976) (xy 454.679325 -262.046955) (xy 454.663615 -261.996025)
			(xy 454.655672 -261.943321) (xy 440.279292 -261.943321) (xy 440.271349 -261.996025) (xy 440.255639 -262.046955)
			(xy 440.232513 -262.094976) (xy 440.202489 -262.139013) (xy 440.166237 -262.178084) (xy 440.124566 -262.211315)
			(xy 440.078408 -262.237964) (xy 440.028794 -262.257436) (xy 439.976832 -262.269296) (xy 439.923682 -262.27328)
			(xy 439.870532 -262.269296) (xy 439.81857 -262.257436) (xy 439.768956 -262.237964) (xy 439.722798 -262.211315)
			(xy 439.681127 -262.178084) (xy 439.644875 -262.139013) (xy 439.614851 -262.094976) (xy 439.591725 -262.046955)
			(xy 439.576015 -261.996025) (xy 439.568072 -261.943321) (xy 425.191692 -261.943321) (xy 425.183749 -261.996025)
			(xy 425.168039 -262.046955) (xy 425.144913 -262.094976) (xy 425.114889 -262.139013) (xy 425.078637 -262.178084)
			(xy 425.036966 -262.211315) (xy 424.990808 -262.237964) (xy 424.941194 -262.257436) (xy 424.889232 -262.269296)
			(xy 424.836082 -262.27328) (xy 424.782932 -262.269296) (xy 424.73097 -262.257436) (xy 424.681356 -262.237964)
			(xy 424.635198 -262.211315) (xy 424.593527 -262.178084) (xy 424.557275 -262.139013) (xy 424.527251 -262.094976)
			(xy 424.504125 -262.046955) (xy 424.488415 -261.996025) (xy 424.480472 -261.943321) (xy 407.4668 -261.943321)
			(xy 407.4668 -262.793205) (xy 420.304204 -262.793205) (xy 420.304204 -262.739907) (xy 420.312147 -262.687203)
			(xy 420.327857 -262.636273) (xy 420.350983 -262.588252) (xy 420.381007 -262.544215) (xy 420.417259 -262.505144)
			(xy 420.45893 -262.471913) (xy 420.505088 -262.445264) (xy 420.554702 -262.425792) (xy 420.606664 -262.413932)
			(xy 420.659814 -262.409949) (xy 420.712964 -262.413932) (xy 420.764926 -262.425792) (xy 420.81454 -262.445264)
			(xy 420.860698 -262.471913) (xy 420.902369 -262.505144) (xy 420.938621 -262.544215) (xy 420.968645 -262.588252)
			(xy 420.991771 -262.636273) (xy 421.007481 -262.687203) (xy 421.015424 -262.739907) (xy 421.015922 -262.766556)
			(xy 421.015424 -262.793205) (xy 435.468004 -262.793205) (xy 435.468004 -262.739907) (xy 435.475947 -262.687203)
			(xy 435.491657 -262.636273) (xy 435.514783 -262.588252) (xy 435.544807 -262.544215) (xy 435.581059 -262.505144)
			(xy 435.62273 -262.471913) (xy 435.668888 -262.445264) (xy 435.718502 -262.425792) (xy 435.770464 -262.413932)
			(xy 435.823614 -262.409949) (xy 435.876764 -262.413932) (xy 435.928726 -262.425792) (xy 435.97834 -262.445264)
			(xy 436.024498 -262.471913) (xy 436.066169 -262.505144) (xy 436.102421 -262.544215) (xy 436.132445 -262.588252)
			(xy 436.155571 -262.636273) (xy 436.171281 -262.687203) (xy 436.179224 -262.739907) (xy 436.179722 -262.766556)
			(xy 436.179224 -262.793205) (xy 436.179186 -262.793459) (xy 450.555604 -262.793459) (xy 450.555604 -262.740161)
			(xy 450.563547 -262.687457) (xy 450.579257 -262.636527) (xy 450.602383 -262.588506) (xy 450.632407 -262.544469)
			(xy 450.668659 -262.505398) (xy 450.71033 -262.472167) (xy 450.756488 -262.445518) (xy 450.806102 -262.426046)
			(xy 450.858064 -262.414186) (xy 450.911214 -262.410203) (xy 450.964364 -262.414186) (xy 451.016326 -262.426046)
			(xy 451.06594 -262.445518) (xy 451.112098 -262.472167) (xy 451.153769 -262.505398) (xy 451.190021 -262.544469)
			(xy 451.220045 -262.588506) (xy 451.243171 -262.636527) (xy 451.258881 -262.687457) (xy 451.266824 -262.740161)
			(xy 451.267322 -262.76681) (xy 451.266824 -262.793459) (xy 451.258881 -262.846163) (xy 451.243171 -262.897093)
			(xy 451.220045 -262.945114) (xy 451.190021 -262.989151) (xy 451.153769 -263.028222) (xy 451.112098 -263.061453)
			(xy 451.06594 -263.088102) (xy 451.016326 -263.107574) (xy 450.964364 -263.119434) (xy 450.911214 -263.123418)
			(xy 450.858064 -263.119434) (xy 450.806102 -263.107574) (xy 450.756488 -263.088102) (xy 450.71033 -263.061453)
			(xy 450.668659 -263.028222) (xy 450.632407 -262.989151) (xy 450.602383 -262.945114) (xy 450.579257 -262.897093)
			(xy 450.563547 -262.846163) (xy 450.555604 -262.793459) (xy 436.179186 -262.793459) (xy 436.171281 -262.845909)
			(xy 436.155571 -262.896839) (xy 436.132445 -262.94486) (xy 436.102421 -262.988897) (xy 436.066169 -263.027968)
			(xy 436.024498 -263.061199) (xy 435.97834 -263.087848) (xy 435.928726 -263.10732) (xy 435.876764 -263.11918)
			(xy 435.823614 -263.123164) (xy 435.770464 -263.11918) (xy 435.718502 -263.10732) (xy 435.668888 -263.087848)
			(xy 435.62273 -263.061199) (xy 435.581059 -263.027968) (xy 435.544807 -262.988897) (xy 435.514783 -262.94486)
			(xy 435.491657 -262.896839) (xy 435.475947 -262.845909) (xy 435.468004 -262.793205) (xy 421.015424 -262.793205)
			(xy 421.007481 -262.845909) (xy 420.991771 -262.896839) (xy 420.968645 -262.94486) (xy 420.938621 -262.988897)
			(xy 420.902369 -263.027968) (xy 420.860698 -263.061199) (xy 420.81454 -263.087848) (xy 420.764926 -263.10732)
			(xy 420.712964 -263.11918) (xy 420.659814 -263.123164) (xy 420.606664 -263.11918) (xy 420.554702 -263.10732)
			(xy 420.505088 -263.087848) (xy 420.45893 -263.061199) (xy 420.417259 -263.027968) (xy 420.381007 -262.988897)
			(xy 420.350983 -262.94486) (xy 420.327857 -262.896839) (xy 420.312147 -262.845909) (xy 420.304204 -262.793205)
			(xy 407.4668 -262.793205) (xy 407.4668 -263.643343) (xy 424.404272 -263.643343) (xy 424.404272 -263.590045)
			(xy 424.412215 -263.537341) (xy 424.427925 -263.486411) (xy 424.451051 -263.43839) (xy 424.481075 -263.394353)
			(xy 424.517327 -263.355282) (xy 424.558998 -263.322051) (xy 424.605156 -263.295402) (xy 424.65477 -263.27593)
			(xy 424.706732 -263.26407) (xy 424.759882 -263.260087) (xy 424.813032 -263.26407) (xy 424.864994 -263.27593)
			(xy 424.914608 -263.295402) (xy 424.960766 -263.322051) (xy 425.002437 -263.355282) (xy 425.038689 -263.394353)
			(xy 425.068713 -263.43839) (xy 425.091839 -263.486411) (xy 425.107549 -263.537341) (xy 425.115492 -263.590045)
			(xy 425.11599 -263.616694) (xy 425.115492 -263.643343) (xy 439.491872 -263.643343) (xy 439.491872 -263.590045)
			(xy 439.499815 -263.537341) (xy 439.515525 -263.486411) (xy 439.538651 -263.43839) (xy 439.568675 -263.394353)
			(xy 439.604927 -263.355282) (xy 439.646598 -263.322051) (xy 439.692756 -263.295402) (xy 439.74237 -263.27593)
			(xy 439.794332 -263.26407) (xy 439.847482 -263.260087) (xy 439.900632 -263.26407) (xy 439.952594 -263.27593)
			(xy 440.002208 -263.295402) (xy 440.048366 -263.322051) (xy 440.090037 -263.355282) (xy 440.126289 -263.394353)
			(xy 440.156313 -263.43839) (xy 440.179439 -263.486411) (xy 440.195149 -263.537341) (xy 440.203092 -263.590045)
			(xy 440.20359 -263.616694) (xy 440.203092 -263.643343) (xy 454.655672 -263.643343) (xy 454.655672 -263.590045)
			(xy 454.663615 -263.537341) (xy 454.679325 -263.486411) (xy 454.702451 -263.43839) (xy 454.732475 -263.394353)
			(xy 454.768727 -263.355282) (xy 454.810398 -263.322051) (xy 454.856556 -263.295402) (xy 454.90617 -263.27593)
			(xy 454.958132 -263.26407) (xy 455.011282 -263.260087) (xy 455.064432 -263.26407) (xy 455.116394 -263.27593)
			(xy 455.166008 -263.295402) (xy 455.212166 -263.322051) (xy 455.253837 -263.355282) (xy 455.290089 -263.394353)
			(xy 455.320113 -263.43839) (xy 455.343239 -263.486411) (xy 455.358949 -263.537341) (xy 455.366892 -263.590045)
			(xy 455.36739 -263.616694) (xy 455.366892 -263.643343) (xy 455.358949 -263.696047) (xy 455.343239 -263.746977)
			(xy 455.320113 -263.794998) (xy 455.290089 -263.839035) (xy 455.253837 -263.878106) (xy 455.212166 -263.911337)
			(xy 455.166008 -263.937986) (xy 455.116394 -263.957458) (xy 455.064432 -263.969318) (xy 455.011282 -263.973302)
			(xy 454.958132 -263.969318) (xy 454.90617 -263.957458) (xy 454.856556 -263.937986) (xy 454.810398 -263.911337)
			(xy 454.768727 -263.878106) (xy 454.732475 -263.839035) (xy 454.702451 -263.794998) (xy 454.679325 -263.746977)
			(xy 454.663615 -263.696047) (xy 454.655672 -263.643343) (xy 440.203092 -263.643343) (xy 440.195149 -263.696047)
			(xy 440.179439 -263.746977) (xy 440.156313 -263.794998) (xy 440.126289 -263.839035) (xy 440.090037 -263.878106)
			(xy 440.048366 -263.911337) (xy 440.002208 -263.937986) (xy 439.952594 -263.957458) (xy 439.900632 -263.969318)
			(xy 439.847482 -263.973302) (xy 439.794332 -263.969318) (xy 439.74237 -263.957458) (xy 439.692756 -263.937986)
			(xy 439.646598 -263.911337) (xy 439.604927 -263.878106) (xy 439.568675 -263.839035) (xy 439.538651 -263.794998)
			(xy 439.515525 -263.746977) (xy 439.499815 -263.696047) (xy 439.491872 -263.643343) (xy 425.115492 -263.643343)
			(xy 425.107549 -263.696047) (xy 425.091839 -263.746977) (xy 425.068713 -263.794998) (xy 425.038689 -263.839035)
			(xy 425.002437 -263.878106) (xy 424.960766 -263.911337) (xy 424.914608 -263.937986) (xy 424.864994 -263.957458)
			(xy 424.813032 -263.969318) (xy 424.759882 -263.973302) (xy 424.706732 -263.969318) (xy 424.65477 -263.957458)
			(xy 424.605156 -263.937986) (xy 424.558998 -263.911337) (xy 424.517327 -263.878106) (xy 424.481075 -263.839035)
			(xy 424.451051 -263.794998) (xy 424.427925 -263.746977) (xy 424.412215 -263.696047) (xy 424.404272 -263.643343)
			(xy 407.4668 -263.643343) (xy 407.4668 -264.493227) (xy 420.304204 -264.493227) (xy 420.304204 -264.439929)
			(xy 420.312147 -264.387225) (xy 420.327857 -264.336295) (xy 420.350983 -264.288274) (xy 420.381007 -264.244237)
			(xy 420.417259 -264.205166) (xy 420.45893 -264.171935) (xy 420.505088 -264.145286) (xy 420.554702 -264.125814)
			(xy 420.606664 -264.113954) (xy 420.659814 -264.109971) (xy 420.712964 -264.113954) (xy 420.764926 -264.125814)
			(xy 420.81454 -264.145286) (xy 420.860698 -264.171935) (xy 420.902369 -264.205166) (xy 420.938621 -264.244237)
			(xy 420.968645 -264.288274) (xy 420.991771 -264.336295) (xy 421.007481 -264.387225) (xy 421.015424 -264.439929)
			(xy 421.015922 -264.466578) (xy 421.015424 -264.493227) (xy 435.468004 -264.493227) (xy 435.468004 -264.439929)
			(xy 435.475947 -264.387225) (xy 435.491657 -264.336295) (xy 435.514783 -264.288274) (xy 435.544807 -264.244237)
			(xy 435.581059 -264.205166) (xy 435.62273 -264.171935) (xy 435.668888 -264.145286) (xy 435.718502 -264.125814)
			(xy 435.770464 -264.113954) (xy 435.823614 -264.109971) (xy 435.876764 -264.113954) (xy 435.928726 -264.125814)
			(xy 435.97834 -264.145286) (xy 436.024498 -264.171935) (xy 436.066169 -264.205166) (xy 436.102421 -264.244237)
			(xy 436.132445 -264.288274) (xy 436.155571 -264.336295) (xy 436.171281 -264.387225) (xy 436.179224 -264.439929)
			(xy 436.179722 -264.466578) (xy 436.179224 -264.493227) (xy 450.555604 -264.493227) (xy 450.555604 -264.439929)
			(xy 450.563547 -264.387225) (xy 450.579257 -264.336295) (xy 450.602383 -264.288274) (xy 450.632407 -264.244237)
			(xy 450.668659 -264.205166) (xy 450.71033 -264.171935) (xy 450.756488 -264.145286) (xy 450.806102 -264.125814)
			(xy 450.858064 -264.113954) (xy 450.911214 -264.109971) (xy 450.964364 -264.113954) (xy 451.016326 -264.125814)
			(xy 451.06594 -264.145286) (xy 451.112098 -264.171935) (xy 451.153769 -264.205166) (xy 451.190021 -264.244237)
			(xy 451.220045 -264.288274) (xy 451.243171 -264.336295) (xy 451.258881 -264.387225) (xy 451.266824 -264.439929)
			(xy 451.267322 -264.466578) (xy 451.266824 -264.493227) (xy 451.258881 -264.545931) (xy 451.243171 -264.596861)
			(xy 451.220045 -264.644882) (xy 451.190021 -264.688919) (xy 451.153769 -264.72799) (xy 451.112098 -264.761221)
			(xy 451.06594 -264.78787) (xy 451.016326 -264.807342) (xy 450.964364 -264.819202) (xy 450.911214 -264.823186)
			(xy 450.858064 -264.819202) (xy 450.806102 -264.807342) (xy 450.756488 -264.78787) (xy 450.71033 -264.761221)
			(xy 450.668659 -264.72799) (xy 450.632407 -264.688919) (xy 450.602383 -264.644882) (xy 450.579257 -264.596861)
			(xy 450.563547 -264.545931) (xy 450.555604 -264.493227) (xy 436.179224 -264.493227) (xy 436.171281 -264.545931)
			(xy 436.155571 -264.596861) (xy 436.132445 -264.644882) (xy 436.102421 -264.688919) (xy 436.066169 -264.72799)
			(xy 436.024498 -264.761221) (xy 435.97834 -264.78787) (xy 435.928726 -264.807342) (xy 435.876764 -264.819202)
			(xy 435.823614 -264.823186) (xy 435.770464 -264.819202) (xy 435.718502 -264.807342) (xy 435.668888 -264.78787)
			(xy 435.62273 -264.761221) (xy 435.581059 -264.72799) (xy 435.544807 -264.688919) (xy 435.514783 -264.644882)
			(xy 435.491657 -264.596861) (xy 435.475947 -264.545931) (xy 435.468004 -264.493227) (xy 421.015424 -264.493227)
			(xy 421.007481 -264.545931) (xy 420.991771 -264.596861) (xy 420.968645 -264.644882) (xy 420.938621 -264.688919)
			(xy 420.902369 -264.72799) (xy 420.860698 -264.761221) (xy 420.81454 -264.78787) (xy 420.764926 -264.807342)
			(xy 420.712964 -264.819202) (xy 420.659814 -264.823186) (xy 420.606664 -264.819202) (xy 420.554702 -264.807342)
			(xy 420.505088 -264.78787) (xy 420.45893 -264.761221) (xy 420.417259 -264.72799) (xy 420.381007 -264.688919)
			(xy 420.350983 -264.644882) (xy 420.327857 -264.596861) (xy 420.312147 -264.545931) (xy 420.304204 -264.493227)
			(xy 407.4668 -264.493227) (xy 407.4668 -265.343365) (xy 424.404272 -265.343365) (xy 424.404272 -265.290067)
			(xy 424.412215 -265.237363) (xy 424.427925 -265.186433) (xy 424.451051 -265.138412) (xy 424.481075 -265.094375)
			(xy 424.517327 -265.055304) (xy 424.558998 -265.022073) (xy 424.605156 -264.995424) (xy 424.65477 -264.975952)
			(xy 424.706732 -264.964092) (xy 424.759882 -264.960109) (xy 424.813032 -264.964092) (xy 424.864994 -264.975952)
			(xy 424.914608 -264.995424) (xy 424.960766 -265.022073) (xy 425.002437 -265.055304) (xy 425.038689 -265.094375)
			(xy 425.068713 -265.138412) (xy 425.091839 -265.186433) (xy 425.107549 -265.237363) (xy 425.115492 -265.290067)
			(xy 425.11599 -265.316716) (xy 425.115492 -265.343365) (xy 439.491872 -265.343365) (xy 439.491872 -265.290067)
			(xy 439.499815 -265.237363) (xy 439.515525 -265.186433) (xy 439.538651 -265.138412) (xy 439.568675 -265.094375)
			(xy 439.604927 -265.055304) (xy 439.646598 -265.022073) (xy 439.692756 -264.995424) (xy 439.74237 -264.975952)
			(xy 439.794332 -264.964092) (xy 439.847482 -264.960109) (xy 439.900632 -264.964092) (xy 439.952594 -264.975952)
			(xy 440.002208 -264.995424) (xy 440.048366 -265.022073) (xy 440.090037 -265.055304) (xy 440.126289 -265.094375)
			(xy 440.156313 -265.138412) (xy 440.179439 -265.186433) (xy 440.195149 -265.237363) (xy 440.203092 -265.290067)
			(xy 440.20359 -265.316716) (xy 440.203092 -265.343365) (xy 454.655672 -265.343365) (xy 454.655672 -265.290067)
			(xy 454.663615 -265.237363) (xy 454.679325 -265.186433) (xy 454.702451 -265.138412) (xy 454.732475 -265.094375)
			(xy 454.768727 -265.055304) (xy 454.810398 -265.022073) (xy 454.856556 -264.995424) (xy 454.90617 -264.975952)
			(xy 454.958132 -264.964092) (xy 455.011282 -264.960109) (xy 455.064432 -264.964092) (xy 455.116394 -264.975952)
			(xy 455.166008 -264.995424) (xy 455.212166 -265.022073) (xy 455.253837 -265.055304) (xy 455.290089 -265.094375)
			(xy 455.320113 -265.138412) (xy 455.343239 -265.186433) (xy 455.358949 -265.237363) (xy 455.366892 -265.290067)
			(xy 455.36739 -265.316716) (xy 455.366892 -265.343365) (xy 455.358949 -265.396069) (xy 455.343239 -265.446999)
			(xy 455.320113 -265.49502) (xy 455.290089 -265.539057) (xy 455.253837 -265.578128) (xy 455.212166 -265.611359)
			(xy 455.166008 -265.638008) (xy 455.116394 -265.65748) (xy 455.064432 -265.66934) (xy 455.011282 -265.673324)
			(xy 454.958132 -265.66934) (xy 454.90617 -265.65748) (xy 454.856556 -265.638008) (xy 454.810398 -265.611359)
			(xy 454.768727 -265.578128) (xy 454.732475 -265.539057) (xy 454.702451 -265.49502) (xy 454.679325 -265.446999)
			(xy 454.663615 -265.396069) (xy 454.655672 -265.343365) (xy 440.203092 -265.343365) (xy 440.195149 -265.396069)
			(xy 440.179439 -265.446999) (xy 440.156313 -265.49502) (xy 440.126289 -265.539057) (xy 440.090037 -265.578128)
			(xy 440.048366 -265.611359) (xy 440.002208 -265.638008) (xy 439.952594 -265.65748) (xy 439.900632 -265.66934)
			(xy 439.847482 -265.673324) (xy 439.794332 -265.66934) (xy 439.74237 -265.65748) (xy 439.692756 -265.638008)
			(xy 439.646598 -265.611359) (xy 439.604927 -265.578128) (xy 439.568675 -265.539057) (xy 439.538651 -265.49502)
			(xy 439.515525 -265.446999) (xy 439.499815 -265.396069) (xy 439.491872 -265.343365) (xy 425.115492 -265.343365)
			(xy 425.107549 -265.396069) (xy 425.091839 -265.446999) (xy 425.068713 -265.49502) (xy 425.038689 -265.539057)
			(xy 425.002437 -265.578128) (xy 424.960766 -265.611359) (xy 424.914608 -265.638008) (xy 424.864994 -265.65748)
			(xy 424.813032 -265.66934) (xy 424.759882 -265.673324) (xy 424.706732 -265.66934) (xy 424.65477 -265.65748)
			(xy 424.605156 -265.638008) (xy 424.558998 -265.611359) (xy 424.517327 -265.578128) (xy 424.481075 -265.539057)
			(xy 424.451051 -265.49502) (xy 424.427925 -265.446999) (xy 424.412215 -265.396069) (xy 424.404272 -265.343365)
			(xy 407.4668 -265.343365) (xy 407.4668 -266.193249) (xy 420.304204 -266.193249) (xy 420.304204 -266.139951)
			(xy 420.312147 -266.087247) (xy 420.327857 -266.036317) (xy 420.350983 -265.988296) (xy 420.381007 -265.944259)
			(xy 420.417259 -265.905188) (xy 420.45893 -265.871957) (xy 420.505088 -265.845308) (xy 420.554702 -265.825836)
			(xy 420.606664 -265.813976) (xy 420.659814 -265.809993) (xy 420.712964 -265.813976) (xy 420.764926 -265.825836)
			(xy 420.81454 -265.845308) (xy 420.860698 -265.871957) (xy 420.902369 -265.905188) (xy 420.938621 -265.944259)
			(xy 420.968645 -265.988296) (xy 420.991771 -266.036317) (xy 421.007481 -266.087247) (xy 421.015424 -266.139951)
			(xy 421.015922 -266.1666) (xy 421.015424 -266.193249) (xy 435.468004 -266.193249) (xy 435.468004 -266.139951)
			(xy 435.475947 -266.087247) (xy 435.491657 -266.036317) (xy 435.514783 -265.988296) (xy 435.544807 -265.944259)
			(xy 435.581059 -265.905188) (xy 435.62273 -265.871957) (xy 435.668888 -265.845308) (xy 435.718502 -265.825836)
			(xy 435.770464 -265.813976) (xy 435.823614 -265.809993) (xy 435.876764 -265.813976) (xy 435.928726 -265.825836)
			(xy 435.97834 -265.845308) (xy 436.024498 -265.871957) (xy 436.066169 -265.905188) (xy 436.102421 -265.944259)
			(xy 436.132445 -265.988296) (xy 436.155571 -266.036317) (xy 436.171281 -266.087247) (xy 436.179224 -266.139951)
			(xy 436.179722 -266.1666) (xy 436.179224 -266.193249) (xy 450.555604 -266.193249) (xy 450.555604 -266.139951)
			(xy 450.563547 -266.087247) (xy 450.579257 -266.036317) (xy 450.602383 -265.988296) (xy 450.632407 -265.944259)
			(xy 450.668659 -265.905188) (xy 450.71033 -265.871957) (xy 450.756488 -265.845308) (xy 450.806102 -265.825836)
			(xy 450.858064 -265.813976) (xy 450.911214 -265.809993) (xy 450.964364 -265.813976) (xy 451.016326 -265.825836)
			(xy 451.06594 -265.845308) (xy 451.112098 -265.871957) (xy 451.153769 -265.905188) (xy 451.190021 -265.944259)
			(xy 451.220045 -265.988296) (xy 451.243171 -266.036317) (xy 451.258881 -266.087247) (xy 451.266824 -266.139951)
			(xy 451.267322 -266.1666) (xy 451.266824 -266.193249) (xy 451.258881 -266.245953) (xy 451.243171 -266.296883)
			(xy 451.220045 -266.344904) (xy 451.190021 -266.388941) (xy 451.153769 -266.428012) (xy 451.112098 -266.461243)
			(xy 451.06594 -266.487892) (xy 451.016326 -266.507364) (xy 450.964364 -266.519224) (xy 450.911214 -266.523208)
			(xy 450.858064 -266.519224) (xy 450.806102 -266.507364) (xy 450.756488 -266.487892) (xy 450.71033 -266.461243)
			(xy 450.668659 -266.428012) (xy 450.632407 -266.388941) (xy 450.602383 -266.344904) (xy 450.579257 -266.296883)
			(xy 450.563547 -266.245953) (xy 450.555604 -266.193249) (xy 436.179224 -266.193249) (xy 436.171281 -266.245953)
			(xy 436.155571 -266.296883) (xy 436.132445 -266.344904) (xy 436.102421 -266.388941) (xy 436.066169 -266.428012)
			(xy 436.024498 -266.461243) (xy 435.97834 -266.487892) (xy 435.928726 -266.507364) (xy 435.876764 -266.519224)
			(xy 435.823614 -266.523208) (xy 435.770464 -266.519224) (xy 435.718502 -266.507364) (xy 435.668888 -266.487892)
			(xy 435.62273 -266.461243) (xy 435.581059 -266.428012) (xy 435.544807 -266.388941) (xy 435.514783 -266.344904)
			(xy 435.491657 -266.296883) (xy 435.475947 -266.245953) (xy 435.468004 -266.193249) (xy 421.015424 -266.193249)
			(xy 421.007481 -266.245953) (xy 420.991771 -266.296883) (xy 420.968645 -266.344904) (xy 420.938621 -266.388941)
			(xy 420.902369 -266.428012) (xy 420.860698 -266.461243) (xy 420.81454 -266.487892) (xy 420.764926 -266.507364)
			(xy 420.712964 -266.519224) (xy 420.659814 -266.523208) (xy 420.606664 -266.519224) (xy 420.554702 -266.507364)
			(xy 420.505088 -266.487892) (xy 420.45893 -266.461243) (xy 420.417259 -266.428012) (xy 420.381007 -266.388941)
			(xy 420.350983 -266.344904) (xy 420.327857 -266.296883) (xy 420.312147 -266.245953) (xy 420.304204 -266.193249)
			(xy 407.4668 -266.193249) (xy 407.4668 -267.043387) (xy 424.480472 -267.043387) (xy 424.480472 -266.990089)
			(xy 424.488415 -266.937385) (xy 424.504125 -266.886455) (xy 424.527251 -266.838434) (xy 424.557275 -266.794397)
			(xy 424.593527 -266.755326) (xy 424.635198 -266.722095) (xy 424.681356 -266.695446) (xy 424.73097 -266.675974)
			(xy 424.782932 -266.664114) (xy 424.836082 -266.660131) (xy 424.889232 -266.664114) (xy 424.941194 -266.675974)
			(xy 424.990808 -266.695446) (xy 425.036966 -266.722095) (xy 425.078637 -266.755326) (xy 425.114889 -266.794397)
			(xy 425.144913 -266.838434) (xy 425.168039 -266.886455) (xy 425.183749 -266.937385) (xy 425.191692 -266.990089)
			(xy 425.19219 -267.016738) (xy 425.191692 -267.043387) (xy 432.024272 -267.043387) (xy 432.024272 -266.990089)
			(xy 432.032215 -266.937385) (xy 432.047925 -266.886455) (xy 432.071051 -266.838434) (xy 432.101075 -266.794397)
			(xy 432.137327 -266.755326) (xy 432.178998 -266.722095) (xy 432.225156 -266.695446) (xy 432.27477 -266.675974)
			(xy 432.326732 -266.664114) (xy 432.379882 -266.660131) (xy 432.433032 -266.664114) (xy 432.484994 -266.675974)
			(xy 432.534608 -266.695446) (xy 432.580766 -266.722095) (xy 432.622437 -266.755326) (xy 432.658689 -266.794397)
			(xy 432.688713 -266.838434) (xy 432.711839 -266.886455) (xy 432.727549 -266.937385) (xy 432.735492 -266.990089)
			(xy 432.73599 -267.016738) (xy 432.735492 -267.043387) (xy 439.568072 -267.043387) (xy 439.568072 -266.990089)
			(xy 439.576015 -266.937385) (xy 439.591725 -266.886455) (xy 439.614851 -266.838434) (xy 439.644875 -266.794397)
			(xy 439.681127 -266.755326) (xy 439.722798 -266.722095) (xy 439.768956 -266.695446) (xy 439.81857 -266.675974)
			(xy 439.870532 -266.664114) (xy 439.923682 -266.660131) (xy 439.976832 -266.664114) (xy 440.028794 -266.675974)
			(xy 440.078408 -266.695446) (xy 440.124566 -266.722095) (xy 440.166237 -266.755326) (xy 440.202489 -266.794397)
			(xy 440.232513 -266.838434) (xy 440.255639 -266.886455) (xy 440.271349 -266.937385) (xy 440.279292 -266.990089)
			(xy 440.27979 -267.016738) (xy 440.279292 -267.043387) (xy 447.111872 -267.043387) (xy 447.111872 -266.990089)
			(xy 447.119815 -266.937385) (xy 447.135525 -266.886455) (xy 447.158651 -266.838434) (xy 447.188675 -266.794397)
			(xy 447.224927 -266.755326) (xy 447.266598 -266.722095) (xy 447.312756 -266.695446) (xy 447.36237 -266.675974)
			(xy 447.414332 -266.664114) (xy 447.467482 -266.660131) (xy 447.520632 -266.664114) (xy 447.572594 -266.675974)
			(xy 447.622208 -266.695446) (xy 447.668366 -266.722095) (xy 447.710037 -266.755326) (xy 447.746289 -266.794397)
			(xy 447.776313 -266.838434) (xy 447.799439 -266.886455) (xy 447.815149 -266.937385) (xy 447.823092 -266.990089)
			(xy 447.82359 -267.016738) (xy 447.823092 -267.043387) (xy 454.579472 -267.043387) (xy 454.579472 -266.990089)
			(xy 454.587415 -266.937385) (xy 454.603125 -266.886455) (xy 454.626251 -266.838434) (xy 454.656275 -266.794397)
			(xy 454.692527 -266.755326) (xy 454.734198 -266.722095) (xy 454.780356 -266.695446) (xy 454.82997 -266.675974)
			(xy 454.881932 -266.664114) (xy 454.935082 -266.660131) (xy 454.988232 -266.664114) (xy 455.040194 -266.675974)
			(xy 455.089808 -266.695446) (xy 455.135966 -266.722095) (xy 455.177637 -266.755326) (xy 455.213889 -266.794397)
			(xy 455.243913 -266.838434) (xy 455.267039 -266.886455) (xy 455.282749 -266.937385) (xy 455.290692 -266.990089)
			(xy 455.29119 -267.016738) (xy 455.290692 -267.043387) (xy 462.199472 -267.043387) (xy 462.199472 -266.990089)
			(xy 462.207415 -266.937385) (xy 462.223125 -266.886455) (xy 462.246251 -266.838434) (xy 462.276275 -266.794397)
			(xy 462.312527 -266.755326) (xy 462.354198 -266.722095) (xy 462.400356 -266.695446) (xy 462.44997 -266.675974)
			(xy 462.501932 -266.664114) (xy 462.555082 -266.660131) (xy 462.608232 -266.664114) (xy 462.660194 -266.675974)
			(xy 462.709808 -266.695446) (xy 462.755966 -266.722095) (xy 462.797637 -266.755326) (xy 462.833889 -266.794397)
			(xy 462.863913 -266.838434) (xy 462.887039 -266.886455) (xy 462.902749 -266.937385) (xy 462.910692 -266.990089)
			(xy 462.91119 -267.016738) (xy 462.910692 -267.043387) (xy 462.902749 -267.096091) (xy 462.887039 -267.147021)
			(xy 462.863913 -267.195042) (xy 462.833889 -267.239079) (xy 462.797637 -267.27815) (xy 462.755966 -267.311381)
			(xy 462.709808 -267.33803) (xy 462.660194 -267.357502) (xy 462.608232 -267.369362) (xy 462.555082 -267.373346)
			(xy 462.501932 -267.369362) (xy 462.44997 -267.357502) (xy 462.400356 -267.33803) (xy 462.354198 -267.311381)
			(xy 462.312527 -267.27815) (xy 462.276275 -267.239079) (xy 462.246251 -267.195042) (xy 462.223125 -267.147021)
			(xy 462.207415 -267.096091) (xy 462.199472 -267.043387) (xy 455.290692 -267.043387) (xy 455.282749 -267.096091)
			(xy 455.267039 -267.147021) (xy 455.243913 -267.195042) (xy 455.213889 -267.239079) (xy 455.177637 -267.27815)
			(xy 455.135966 -267.311381) (xy 455.089808 -267.33803) (xy 455.040194 -267.357502) (xy 454.988232 -267.369362)
			(xy 454.935082 -267.373346) (xy 454.881932 -267.369362) (xy 454.82997 -267.357502) (xy 454.780356 -267.33803)
			(xy 454.734198 -267.311381) (xy 454.692527 -267.27815) (xy 454.656275 -267.239079) (xy 454.626251 -267.195042)
			(xy 454.603125 -267.147021) (xy 454.587415 -267.096091) (xy 454.579472 -267.043387) (xy 447.823092 -267.043387)
			(xy 447.815149 -267.096091) (xy 447.799439 -267.147021) (xy 447.776313 -267.195042) (xy 447.746289 -267.239079)
			(xy 447.710037 -267.27815) (xy 447.668366 -267.311381) (xy 447.622208 -267.33803) (xy 447.572594 -267.357502)
			(xy 447.520632 -267.369362) (xy 447.467482 -267.373346) (xy 447.414332 -267.369362) (xy 447.36237 -267.357502)
			(xy 447.312756 -267.33803) (xy 447.266598 -267.311381) (xy 447.224927 -267.27815) (xy 447.188675 -267.239079)
			(xy 447.158651 -267.195042) (xy 447.135525 -267.147021) (xy 447.119815 -267.096091) (xy 447.111872 -267.043387)
			(xy 440.279292 -267.043387) (xy 440.271349 -267.096091) (xy 440.255639 -267.147021) (xy 440.232513 -267.195042)
			(xy 440.202489 -267.239079) (xy 440.166237 -267.27815) (xy 440.124566 -267.311381) (xy 440.078408 -267.33803)
			(xy 440.028794 -267.357502) (xy 439.976832 -267.369362) (xy 439.923682 -267.373346) (xy 439.870532 -267.369362)
			(xy 439.81857 -267.357502) (xy 439.768956 -267.33803) (xy 439.722798 -267.311381) (xy 439.681127 -267.27815)
			(xy 439.644875 -267.239079) (xy 439.614851 -267.195042) (xy 439.591725 -267.147021) (xy 439.576015 -267.096091)
			(xy 439.568072 -267.043387) (xy 432.735492 -267.043387) (xy 432.727549 -267.096091) (xy 432.711839 -267.147021)
			(xy 432.688713 -267.195042) (xy 432.658689 -267.239079) (xy 432.622437 -267.27815) (xy 432.580766 -267.311381)
			(xy 432.534608 -267.33803) (xy 432.484994 -267.357502) (xy 432.433032 -267.369362) (xy 432.379882 -267.373346)
			(xy 432.326732 -267.369362) (xy 432.27477 -267.357502) (xy 432.225156 -267.33803) (xy 432.178998 -267.311381)
			(xy 432.137327 -267.27815) (xy 432.101075 -267.239079) (xy 432.071051 -267.195042) (xy 432.047925 -267.147021)
			(xy 432.032215 -267.096091) (xy 432.024272 -267.043387) (xy 425.191692 -267.043387) (xy 425.183749 -267.096091)
			(xy 425.168039 -267.147021) (xy 425.144913 -267.195042) (xy 425.114889 -267.239079) (xy 425.078637 -267.27815)
			(xy 425.036966 -267.311381) (xy 424.990808 -267.33803) (xy 424.941194 -267.357502) (xy 424.889232 -267.369362)
			(xy 424.836082 -267.373346) (xy 424.782932 -267.369362) (xy 424.73097 -267.357502) (xy 424.681356 -267.33803)
			(xy 424.635198 -267.311381) (xy 424.593527 -267.27815) (xy 424.557275 -267.239079) (xy 424.527251 -267.195042)
			(xy 424.504125 -267.147021) (xy 424.488415 -267.096091) (xy 424.480472 -267.043387) (xy 407.4668 -267.043387)
			(xy 407.4668 -267.893271) (xy 420.304204 -267.893271) (xy 420.304204 -267.839973) (xy 420.312147 -267.787269)
			(xy 420.327857 -267.736339) (xy 420.350983 -267.688318) (xy 420.381007 -267.644281) (xy 420.417259 -267.60521)
			(xy 420.45893 -267.571979) (xy 420.505088 -267.54533) (xy 420.554702 -267.525858) (xy 420.606664 -267.513998)
			(xy 420.659814 -267.510015) (xy 420.712964 -267.513998) (xy 420.764926 -267.525858) (xy 420.81454 -267.54533)
			(xy 420.860698 -267.571979) (xy 420.902369 -267.60521) (xy 420.938621 -267.644281) (xy 420.968645 -267.688318)
			(xy 420.991771 -267.736339) (xy 421.007481 -267.787269) (xy 421.015424 -267.839973) (xy 421.015922 -267.866622)
			(xy 421.015424 -267.893271) (xy 427.924204 -267.893271) (xy 427.924204 -267.839973) (xy 427.932147 -267.787269)
			(xy 427.947857 -267.736339) (xy 427.970983 -267.688318) (xy 428.001007 -267.644281) (xy 428.037259 -267.60521)
			(xy 428.07893 -267.571979) (xy 428.125088 -267.54533) (xy 428.174702 -267.525858) (xy 428.226664 -267.513998)
			(xy 428.279814 -267.510015) (xy 428.332964 -267.513998) (xy 428.384926 -267.525858) (xy 428.43454 -267.54533)
			(xy 428.480698 -267.571979) (xy 428.522369 -267.60521) (xy 428.558621 -267.644281) (xy 428.588645 -267.688318)
			(xy 428.611771 -267.736339) (xy 428.627481 -267.787269) (xy 428.635424 -267.839973) (xy 428.635922 -267.866622)
			(xy 428.635424 -267.893271) (xy 435.468004 -267.893271) (xy 435.468004 -267.839973) (xy 435.475947 -267.787269)
			(xy 435.491657 -267.736339) (xy 435.514783 -267.688318) (xy 435.544807 -267.644281) (xy 435.581059 -267.60521)
			(xy 435.62273 -267.571979) (xy 435.668888 -267.54533) (xy 435.718502 -267.525858) (xy 435.770464 -267.513998)
			(xy 435.823614 -267.510015) (xy 435.876764 -267.513998) (xy 435.928726 -267.525858) (xy 435.97834 -267.54533)
			(xy 436.024498 -267.571979) (xy 436.066169 -267.60521) (xy 436.102421 -267.644281) (xy 436.132445 -267.688318)
			(xy 436.155571 -267.736339) (xy 436.171281 -267.787269) (xy 436.179224 -267.839973) (xy 436.179722 -267.866622)
			(xy 436.179224 -267.893271) (xy 443.011804 -267.893271) (xy 443.011804 -267.839973) (xy 443.019747 -267.787269)
			(xy 443.035457 -267.736339) (xy 443.058583 -267.688318) (xy 443.088607 -267.644281) (xy 443.124859 -267.60521)
			(xy 443.16653 -267.571979) (xy 443.212688 -267.54533) (xy 443.262302 -267.525858) (xy 443.314264 -267.513998)
			(xy 443.367414 -267.510015) (xy 443.420564 -267.513998) (xy 443.472526 -267.525858) (xy 443.52214 -267.54533)
			(xy 443.568298 -267.571979) (xy 443.609969 -267.60521) (xy 443.646221 -267.644281) (xy 443.676245 -267.688318)
			(xy 443.699371 -267.736339) (xy 443.715081 -267.787269) (xy 443.723024 -267.839973) (xy 443.723522 -267.866622)
			(xy 443.723024 -267.893271) (xy 450.555604 -267.893271) (xy 450.555604 -267.839973) (xy 450.563547 -267.787269)
			(xy 450.579257 -267.736339) (xy 450.602383 -267.688318) (xy 450.632407 -267.644281) (xy 450.668659 -267.60521)
			(xy 450.71033 -267.571979) (xy 450.756488 -267.54533) (xy 450.806102 -267.525858) (xy 450.858064 -267.513998)
			(xy 450.911214 -267.510015) (xy 450.964364 -267.513998) (xy 451.016326 -267.525858) (xy 451.06594 -267.54533)
			(xy 451.112098 -267.571979) (xy 451.153769 -267.60521) (xy 451.190021 -267.644281) (xy 451.220045 -267.688318)
			(xy 451.243171 -267.736339) (xy 451.258881 -267.787269) (xy 451.266824 -267.839973) (xy 451.267322 -267.866622)
			(xy 451.266824 -267.893271) (xy 458.099404 -267.893271) (xy 458.099404 -267.839973) (xy 458.107347 -267.787269)
			(xy 458.123057 -267.736339) (xy 458.146183 -267.688318) (xy 458.176207 -267.644281) (xy 458.212459 -267.60521)
			(xy 458.25413 -267.571979) (xy 458.300288 -267.54533) (xy 458.349902 -267.525858) (xy 458.401864 -267.513998)
			(xy 458.455014 -267.510015) (xy 458.508164 -267.513998) (xy 458.560126 -267.525858) (xy 458.60974 -267.54533)
			(xy 458.655898 -267.571979) (xy 458.697569 -267.60521) (xy 458.733821 -267.644281) (xy 458.763845 -267.688318)
			(xy 458.786971 -267.736339) (xy 458.802681 -267.787269) (xy 458.810624 -267.839973) (xy 458.811122 -267.866622)
			(xy 458.810624 -267.893271) (xy 458.802681 -267.945975) (xy 458.786971 -267.996905) (xy 458.763845 -268.044926)
			(xy 458.733821 -268.088963) (xy 458.697569 -268.128034) (xy 458.655898 -268.161265) (xy 458.60974 -268.187914)
			(xy 458.560126 -268.207386) (xy 458.508164 -268.219246) (xy 458.455014 -268.22323) (xy 458.401864 -268.219246)
			(xy 458.349902 -268.207386) (xy 458.300288 -268.187914) (xy 458.25413 -268.161265) (xy 458.212459 -268.128034)
			(xy 458.176207 -268.088963) (xy 458.146183 -268.044926) (xy 458.123057 -267.996905) (xy 458.107347 -267.945975)
			(xy 458.099404 -267.893271) (xy 451.266824 -267.893271) (xy 451.258881 -267.945975) (xy 451.243171 -267.996905)
			(xy 451.220045 -268.044926) (xy 451.190021 -268.088963) (xy 451.153769 -268.128034) (xy 451.112098 -268.161265)
			(xy 451.06594 -268.187914) (xy 451.016326 -268.207386) (xy 450.964364 -268.219246) (xy 450.911214 -268.22323)
			(xy 450.858064 -268.219246) (xy 450.806102 -268.207386) (xy 450.756488 -268.187914) (xy 450.71033 -268.161265)
			(xy 450.668659 -268.128034) (xy 450.632407 -268.088963) (xy 450.602383 -268.044926) (xy 450.579257 -267.996905)
			(xy 450.563547 -267.945975) (xy 450.555604 -267.893271) (xy 443.723024 -267.893271) (xy 443.715081 -267.945975)
			(xy 443.699371 -267.996905) (xy 443.676245 -268.044926) (xy 443.646221 -268.088963) (xy 443.609969 -268.128034)
			(xy 443.568298 -268.161265) (xy 443.52214 -268.187914) (xy 443.472526 -268.207386) (xy 443.420564 -268.219246)
			(xy 443.367414 -268.22323) (xy 443.314264 -268.219246) (xy 443.262302 -268.207386) (xy 443.212688 -268.187914)
			(xy 443.16653 -268.161265) (xy 443.124859 -268.128034) (xy 443.088607 -268.088963) (xy 443.058583 -268.044926)
			(xy 443.035457 -267.996905) (xy 443.019747 -267.945975) (xy 443.011804 -267.893271) (xy 436.179224 -267.893271)
			(xy 436.171281 -267.945975) (xy 436.155571 -267.996905) (xy 436.132445 -268.044926) (xy 436.102421 -268.088963)
			(xy 436.066169 -268.128034) (xy 436.024498 -268.161265) (xy 435.97834 -268.187914) (xy 435.928726 -268.207386)
			(xy 435.876764 -268.219246) (xy 435.823614 -268.22323) (xy 435.770464 -268.219246) (xy 435.718502 -268.207386)
			(xy 435.668888 -268.187914) (xy 435.62273 -268.161265) (xy 435.581059 -268.128034) (xy 435.544807 -268.088963)
			(xy 435.514783 -268.044926) (xy 435.491657 -267.996905) (xy 435.475947 -267.945975) (xy 435.468004 -267.893271)
			(xy 428.635424 -267.893271) (xy 428.627481 -267.945975) (xy 428.611771 -267.996905) (xy 428.588645 -268.044926)
			(xy 428.558621 -268.088963) (xy 428.522369 -268.128034) (xy 428.480698 -268.161265) (xy 428.43454 -268.187914)
			(xy 428.384926 -268.207386) (xy 428.332964 -268.219246) (xy 428.279814 -268.22323) (xy 428.226664 -268.219246)
			(xy 428.174702 -268.207386) (xy 428.125088 -268.187914) (xy 428.07893 -268.161265) (xy 428.037259 -268.128034)
			(xy 428.001007 -268.088963) (xy 427.970983 -268.044926) (xy 427.947857 -267.996905) (xy 427.932147 -267.945975)
			(xy 427.924204 -267.893271) (xy 421.015424 -267.893271) (xy 421.007481 -267.945975) (xy 420.991771 -267.996905)
			(xy 420.968645 -268.044926) (xy 420.938621 -268.088963) (xy 420.902369 -268.128034) (xy 420.860698 -268.161265)
			(xy 420.81454 -268.187914) (xy 420.764926 -268.207386) (xy 420.712964 -268.219246) (xy 420.659814 -268.22323)
			(xy 420.606664 -268.219246) (xy 420.554702 -268.207386) (xy 420.505088 -268.187914) (xy 420.45893 -268.161265)
			(xy 420.417259 -268.128034) (xy 420.381007 -268.088963) (xy 420.350983 -268.044926) (xy 420.327857 -267.996905)
			(xy 420.312147 -267.945975) (xy 420.304204 -267.893271) (xy 407.4668 -267.893271) (xy 407.4668 -268.743409)
			(xy 432.024272 -268.743409) (xy 432.024272 -268.690111) (xy 432.032215 -268.637407) (xy 432.047925 -268.586477)
			(xy 432.071051 -268.538456) (xy 432.101075 -268.494419) (xy 432.137327 -268.455348) (xy 432.178998 -268.422117)
			(xy 432.225156 -268.395468) (xy 432.27477 -268.375996) (xy 432.326732 -268.364136) (xy 432.379882 -268.360153)
			(xy 432.433032 -268.364136) (xy 432.484994 -268.375996) (xy 432.534608 -268.395468) (xy 432.580766 -268.422117)
			(xy 432.622437 -268.455348) (xy 432.658689 -268.494419) (xy 432.688713 -268.538456) (xy 432.711839 -268.586477)
			(xy 432.727549 -268.637407) (xy 432.735492 -268.690111) (xy 432.73599 -268.71676) (xy 432.735492 -268.743409)
			(xy 439.491872 -268.743409) (xy 439.491872 -268.690111) (xy 439.499815 -268.637407) (xy 439.515525 -268.586477)
			(xy 439.538651 -268.538456) (xy 439.568675 -268.494419) (xy 439.604927 -268.455348) (xy 439.646598 -268.422117)
			(xy 439.692756 -268.395468) (xy 439.74237 -268.375996) (xy 439.794332 -268.364136) (xy 439.847482 -268.360153)
			(xy 439.900632 -268.364136) (xy 439.952594 -268.375996) (xy 440.002208 -268.395468) (xy 440.048366 -268.422117)
			(xy 440.090037 -268.455348) (xy 440.126289 -268.494419) (xy 440.156313 -268.538456) (xy 440.179439 -268.586477)
			(xy 440.195149 -268.637407) (xy 440.203092 -268.690111) (xy 440.20359 -268.71676) (xy 440.203092 -268.743409)
			(xy 440.195149 -268.796113) (xy 440.179439 -268.847043) (xy 440.156313 -268.895064) (xy 440.126289 -268.939101)
			(xy 440.090037 -268.978172) (xy 440.048366 -269.011403) (xy 440.002208 -269.038052) (xy 439.952594 -269.057524)
			(xy 439.900632 -269.069384) (xy 439.847482 -269.073368) (xy 439.794332 -269.069384) (xy 439.74237 -269.057524)
			(xy 439.692756 -269.038052) (xy 439.646598 -269.011403) (xy 439.604927 -268.978172) (xy 439.568675 -268.939101)
			(xy 439.538651 -268.895064) (xy 439.515525 -268.847043) (xy 439.499815 -268.796113) (xy 439.491872 -268.743409)
			(xy 432.735492 -268.743409) (xy 432.727549 -268.796113) (xy 432.711839 -268.847043) (xy 432.688713 -268.895064)
			(xy 432.658689 -268.939101) (xy 432.622437 -268.978172) (xy 432.580766 -269.011403) (xy 432.534608 -269.038052)
			(xy 432.484994 -269.057524) (xy 432.433032 -269.069384) (xy 432.379882 -269.073368) (xy 432.326732 -269.069384)
			(xy 432.27477 -269.057524) (xy 432.225156 -269.038052) (xy 432.178998 -269.011403) (xy 432.137327 -268.978172)
			(xy 432.101075 -268.939101) (xy 432.071051 -268.895064) (xy 432.047925 -268.847043) (xy 432.032215 -268.796113)
			(xy 432.024272 -268.743409) (xy 407.4668 -268.743409) (xy 407.4668 -269.593293) (xy 420.380404 -269.593293)
			(xy 420.380404 -269.539995) (xy 420.388347 -269.487291) (xy 420.404057 -269.436361) (xy 420.427183 -269.38834)
			(xy 420.457207 -269.344303) (xy 420.493459 -269.305232) (xy 420.53513 -269.272001) (xy 420.581288 -269.245352)
			(xy 420.630902 -269.22588) (xy 420.682864 -269.21402) (xy 420.736014 -269.210037) (xy 420.789164 -269.21402)
			(xy 420.841126 -269.22588) (xy 420.89074 -269.245352) (xy 420.936898 -269.272001) (xy 420.978569 -269.305232)
			(xy 421.014821 -269.344303) (xy 421.044845 -269.38834) (xy 421.067971 -269.436361) (xy 421.083681 -269.487291)
			(xy 421.091624 -269.539995) (xy 421.092122 -269.566644) (xy 421.091624 -269.593293) (xy 435.468004 -269.593293)
			(xy 435.468004 -269.539995) (xy 435.475947 -269.487291) (xy 435.491657 -269.436361) (xy 435.514783 -269.38834)
			(xy 435.544807 -269.344303) (xy 435.581059 -269.305232) (xy 435.62273 -269.272001) (xy 435.668888 -269.245352)
			(xy 435.718502 -269.22588) (xy 435.770464 -269.21402) (xy 435.823614 -269.210037) (xy 435.876764 -269.21402)
			(xy 435.928726 -269.22588) (xy 435.97834 -269.245352) (xy 436.024498 -269.272001) (xy 436.066169 -269.305232)
			(xy 436.102421 -269.344303) (xy 436.132445 -269.38834) (xy 436.155571 -269.436361) (xy 436.171281 -269.487291)
			(xy 436.179224 -269.539995) (xy 436.179722 -269.566644) (xy 436.179224 -269.593293) (xy 450.555604 -269.593293)
			(xy 450.555604 -269.539995) (xy 450.563547 -269.487291) (xy 450.579257 -269.436361) (xy 450.602383 -269.38834)
			(xy 450.632407 -269.344303) (xy 450.668659 -269.305232) (xy 450.71033 -269.272001) (xy 450.756488 -269.245352)
			(xy 450.806102 -269.22588) (xy 450.858064 -269.21402) (xy 450.911214 -269.210037) (xy 450.964364 -269.21402)
			(xy 451.016326 -269.22588) (xy 451.06594 -269.245352) (xy 451.112098 -269.272001) (xy 451.153769 -269.305232)
			(xy 451.190021 -269.344303) (xy 451.220045 -269.38834) (xy 451.243171 -269.436361) (xy 451.258881 -269.487291)
			(xy 451.266824 -269.539995) (xy 451.267322 -269.566644) (xy 451.266824 -269.593293) (xy 451.258881 -269.645997)
			(xy 451.243171 -269.696927) (xy 451.220045 -269.744948) (xy 451.190021 -269.788985) (xy 451.153769 -269.828056)
			(xy 451.112098 -269.861287) (xy 451.06594 -269.887936) (xy 451.016326 -269.907408) (xy 450.964364 -269.919268)
			(xy 450.911214 -269.923252) (xy 450.858064 -269.919268) (xy 450.806102 -269.907408) (xy 450.756488 -269.887936)
			(xy 450.71033 -269.861287) (xy 450.668659 -269.828056) (xy 450.632407 -269.788985) (xy 450.602383 -269.744948)
			(xy 450.579257 -269.696927) (xy 450.563547 -269.645997) (xy 450.555604 -269.593293) (xy 436.179224 -269.593293)
			(xy 436.171281 -269.645997) (xy 436.155571 -269.696927) (xy 436.132445 -269.744948) (xy 436.102421 -269.788985)
			(xy 436.066169 -269.828056) (xy 436.024498 -269.861287) (xy 435.97834 -269.887936) (xy 435.928726 -269.907408)
			(xy 435.876764 -269.919268) (xy 435.823614 -269.923252) (xy 435.770464 -269.919268) (xy 435.718502 -269.907408)
			(xy 435.668888 -269.887936) (xy 435.62273 -269.861287) (xy 435.581059 -269.828056) (xy 435.544807 -269.788985)
			(xy 435.514783 -269.744948) (xy 435.491657 -269.696927) (xy 435.475947 -269.645997) (xy 435.468004 -269.593293)
			(xy 421.091624 -269.593293) (xy 421.083681 -269.645997) (xy 421.067971 -269.696927) (xy 421.044845 -269.744948)
			(xy 421.014821 -269.788985) (xy 420.978569 -269.828056) (xy 420.936898 -269.861287) (xy 420.89074 -269.887936)
			(xy 420.841126 -269.907408) (xy 420.789164 -269.919268) (xy 420.736014 -269.923252) (xy 420.682864 -269.919268)
			(xy 420.630902 -269.907408) (xy 420.581288 -269.887936) (xy 420.53513 -269.861287) (xy 420.493459 -269.828056)
			(xy 420.457207 -269.788985) (xy 420.427183 -269.744948) (xy 420.404057 -269.696927) (xy 420.388347 -269.645997)
			(xy 420.380404 -269.593293) (xy 407.4668 -269.593293) (xy 407.4668 -270.443431) (xy 424.480472 -270.443431)
			(xy 424.480472 -270.390133) (xy 424.488415 -270.337429) (xy 424.504125 -270.286499) (xy 424.527251 -270.238478)
			(xy 424.557275 -270.194441) (xy 424.593527 -270.15537) (xy 424.635198 -270.122139) (xy 424.681356 -270.09549)
			(xy 424.73097 -270.076018) (xy 424.782932 -270.064158) (xy 424.836082 -270.060175) (xy 424.889232 -270.064158)
			(xy 424.941194 -270.076018) (xy 424.990808 -270.09549) (xy 425.036966 -270.122139) (xy 425.078637 -270.15537)
			(xy 425.114889 -270.194441) (xy 425.144913 -270.238478) (xy 425.168039 -270.286499) (xy 425.183749 -270.337429)
			(xy 425.191692 -270.390133) (xy 425.19219 -270.416782) (xy 425.191692 -270.443431) (xy 439.542672 -270.443431)
			(xy 439.542672 -270.390133) (xy 439.550615 -270.337429) (xy 439.566325 -270.286499) (xy 439.589451 -270.238478)
			(xy 439.619475 -270.194441) (xy 439.655727 -270.15537) (xy 439.697398 -270.122139) (xy 439.743556 -270.09549)
			(xy 439.79317 -270.076018) (xy 439.845132 -270.064158) (xy 439.898282 -270.060175) (xy 439.951432 -270.064158)
			(xy 440.003394 -270.076018) (xy 440.053008 -270.09549) (xy 440.099166 -270.122139) (xy 440.140837 -270.15537)
			(xy 440.177089 -270.194441) (xy 440.207113 -270.238478) (xy 440.230239 -270.286499) (xy 440.245949 -270.337429)
			(xy 440.253892 -270.390133) (xy 440.25439 -270.416782) (xy 440.253892 -270.443431) (xy 454.655672 -270.443431)
			(xy 454.655672 -270.390133) (xy 454.663615 -270.337429) (xy 454.679325 -270.286499) (xy 454.702451 -270.238478)
			(xy 454.732475 -270.194441) (xy 454.768727 -270.15537) (xy 454.810398 -270.122139) (xy 454.856556 -270.09549)
			(xy 454.90617 -270.076018) (xy 454.958132 -270.064158) (xy 455.011282 -270.060175) (xy 455.064432 -270.064158)
			(xy 455.116394 -270.076018) (xy 455.166008 -270.09549) (xy 455.212166 -270.122139) (xy 455.253837 -270.15537)
			(xy 455.290089 -270.194441) (xy 455.320113 -270.238478) (xy 455.343239 -270.286499) (xy 455.358949 -270.337429)
			(xy 455.366892 -270.390133) (xy 455.36739 -270.416782) (xy 455.366892 -270.443431) (xy 455.358949 -270.496135)
			(xy 455.343239 -270.547065) (xy 455.320113 -270.595086) (xy 455.290089 -270.639123) (xy 455.253837 -270.678194)
			(xy 455.212166 -270.711425) (xy 455.166008 -270.738074) (xy 455.116394 -270.757546) (xy 455.064432 -270.769406)
			(xy 455.011282 -270.77339) (xy 454.958132 -270.769406) (xy 454.90617 -270.757546) (xy 454.856556 -270.738074)
			(xy 454.810398 -270.711425) (xy 454.768727 -270.678194) (xy 454.732475 -270.639123) (xy 454.702451 -270.595086)
			(xy 454.679325 -270.547065) (xy 454.663615 -270.496135) (xy 454.655672 -270.443431) (xy 440.253892 -270.443431)
			(xy 440.245949 -270.496135) (xy 440.230239 -270.547065) (xy 440.207113 -270.595086) (xy 440.177089 -270.639123)
			(xy 440.140837 -270.678194) (xy 440.099166 -270.711425) (xy 440.053008 -270.738074) (xy 440.003394 -270.757546)
			(xy 439.951432 -270.769406) (xy 439.898282 -270.77339) (xy 439.845132 -270.769406) (xy 439.79317 -270.757546)
			(xy 439.743556 -270.738074) (xy 439.697398 -270.711425) (xy 439.655727 -270.678194) (xy 439.619475 -270.639123)
			(xy 439.589451 -270.595086) (xy 439.566325 -270.547065) (xy 439.550615 -270.496135) (xy 439.542672 -270.443431)
			(xy 425.191692 -270.443431) (xy 425.183749 -270.496135) (xy 425.168039 -270.547065) (xy 425.144913 -270.595086)
			(xy 425.114889 -270.639123) (xy 425.078637 -270.678194) (xy 425.036966 -270.711425) (xy 424.990808 -270.738074)
			(xy 424.941194 -270.757546) (xy 424.889232 -270.769406) (xy 424.836082 -270.77339) (xy 424.782932 -270.769406)
			(xy 424.73097 -270.757546) (xy 424.681356 -270.738074) (xy 424.635198 -270.711425) (xy 424.593527 -270.678194)
			(xy 424.557275 -270.639123) (xy 424.527251 -270.595086) (xy 424.504125 -270.547065) (xy 424.488415 -270.496135)
			(xy 424.480472 -270.443431) (xy 407.4668 -270.443431) (xy 407.4668 -271.293315) (xy 420.380404 -271.293315)
			(xy 420.380404 -271.240017) (xy 420.388347 -271.187313) (xy 420.404057 -271.136383) (xy 420.427183 -271.088362)
			(xy 420.457207 -271.044325) (xy 420.493459 -271.005254) (xy 420.53513 -270.972023) (xy 420.581288 -270.945374)
			(xy 420.630902 -270.925902) (xy 420.682864 -270.914042) (xy 420.736014 -270.910059) (xy 420.789164 -270.914042)
			(xy 420.841126 -270.925902) (xy 420.89074 -270.945374) (xy 420.936898 -270.972023) (xy 420.978569 -271.005254)
			(xy 421.014821 -271.044325) (xy 421.044845 -271.088362) (xy 421.067971 -271.136383) (xy 421.083681 -271.187313)
			(xy 421.091624 -271.240017) (xy 421.092122 -271.266666) (xy 421.091624 -271.293315) (xy 435.468004 -271.293315)
			(xy 435.468004 -271.240017) (xy 435.475947 -271.187313) (xy 435.491657 -271.136383) (xy 435.514783 -271.088362)
			(xy 435.544807 -271.044325) (xy 435.581059 -271.005254) (xy 435.62273 -270.972023) (xy 435.668888 -270.945374)
			(xy 435.718502 -270.925902) (xy 435.770464 -270.914042) (xy 435.823614 -270.910059) (xy 435.876764 -270.914042)
			(xy 435.928726 -270.925902) (xy 435.97834 -270.945374) (xy 436.024498 -270.972023) (xy 436.066169 -271.005254)
			(xy 436.102421 -271.044325) (xy 436.132445 -271.088362) (xy 436.155571 -271.136383) (xy 436.171281 -271.187313)
			(xy 436.179224 -271.240017) (xy 436.179722 -271.266666) (xy 436.179224 -271.293315) (xy 450.555604 -271.293315)
			(xy 450.555604 -271.240017) (xy 450.563547 -271.187313) (xy 450.579257 -271.136383) (xy 450.602383 -271.088362)
			(xy 450.632407 -271.044325) (xy 450.668659 -271.005254) (xy 450.71033 -270.972023) (xy 450.756488 -270.945374)
			(xy 450.806102 -270.925902) (xy 450.858064 -270.914042) (xy 450.911214 -270.910059) (xy 450.964364 -270.914042)
			(xy 451.016326 -270.925902) (xy 451.06594 -270.945374) (xy 451.112098 -270.972023) (xy 451.153769 -271.005254)
			(xy 451.190021 -271.044325) (xy 451.220045 -271.088362) (xy 451.243171 -271.136383) (xy 451.258881 -271.187313)
			(xy 451.266824 -271.240017) (xy 451.267322 -271.266666) (xy 451.266824 -271.293315) (xy 451.258881 -271.346019)
			(xy 451.243171 -271.396949) (xy 451.220045 -271.44497) (xy 451.190021 -271.489007) (xy 451.153769 -271.528078)
			(xy 451.112098 -271.561309) (xy 451.06594 -271.587958) (xy 451.016326 -271.60743) (xy 450.964364 -271.61929)
			(xy 450.911214 -271.623274) (xy 450.858064 -271.61929) (xy 450.806102 -271.60743) (xy 450.756488 -271.587958)
			(xy 450.71033 -271.561309) (xy 450.668659 -271.528078) (xy 450.632407 -271.489007) (xy 450.602383 -271.44497)
			(xy 450.579257 -271.396949) (xy 450.563547 -271.346019) (xy 450.555604 -271.293315) (xy 436.179224 -271.293315)
			(xy 436.171281 -271.346019) (xy 436.155571 -271.396949) (xy 436.132445 -271.44497) (xy 436.102421 -271.489007)
			(xy 436.066169 -271.528078) (xy 436.024498 -271.561309) (xy 435.97834 -271.587958) (xy 435.928726 -271.60743)
			(xy 435.876764 -271.61929) (xy 435.823614 -271.623274) (xy 435.770464 -271.61929) (xy 435.718502 -271.60743)
			(xy 435.668888 -271.587958) (xy 435.62273 -271.561309) (xy 435.581059 -271.528078) (xy 435.544807 -271.489007)
			(xy 435.514783 -271.44497) (xy 435.491657 -271.396949) (xy 435.475947 -271.346019) (xy 435.468004 -271.293315)
			(xy 421.091624 -271.293315) (xy 421.083681 -271.346019) (xy 421.067971 -271.396949) (xy 421.044845 -271.44497)
			(xy 421.014821 -271.489007) (xy 420.978569 -271.528078) (xy 420.936898 -271.561309) (xy 420.89074 -271.587958)
			(xy 420.841126 -271.60743) (xy 420.789164 -271.61929) (xy 420.736014 -271.623274) (xy 420.682864 -271.61929)
			(xy 420.630902 -271.60743) (xy 420.581288 -271.587958) (xy 420.53513 -271.561309) (xy 420.493459 -271.528078)
			(xy 420.457207 -271.489007) (xy 420.427183 -271.44497) (xy 420.404057 -271.396949) (xy 420.388347 -271.346019)
			(xy 420.380404 -271.293315) (xy 407.4668 -271.293315) (xy 407.4668 -272.143199) (xy 424.480472 -272.143199)
			(xy 424.480472 -272.089901) (xy 424.488415 -272.037197) (xy 424.504125 -271.986267) (xy 424.527251 -271.938246)
			(xy 424.557275 -271.894209) (xy 424.593527 -271.855138) (xy 424.635198 -271.821907) (xy 424.681356 -271.795258)
			(xy 424.73097 -271.775786) (xy 424.782932 -271.763926) (xy 424.836082 -271.759943) (xy 424.889232 -271.763926)
			(xy 424.941194 -271.775786) (xy 424.990808 -271.795258) (xy 425.036966 -271.821907) (xy 425.078637 -271.855138)
			(xy 425.114889 -271.894209) (xy 425.144913 -271.938246) (xy 425.168039 -271.986267) (xy 425.183749 -272.037197)
			(xy 425.191692 -272.089901) (xy 425.19219 -272.11655) (xy 425.191692 -272.143199) (xy 425.191654 -272.143453)
			(xy 439.526162 -272.143453) (xy 439.526162 -272.090155) (xy 439.534105 -272.037451) (xy 439.549815 -271.986521)
			(xy 439.572941 -271.9385) (xy 439.602965 -271.894463) (xy 439.639217 -271.855392) (xy 439.680888 -271.822161)
			(xy 439.727046 -271.795512) (xy 439.77666 -271.77604) (xy 439.828622 -271.76418) (xy 439.881772 -271.760197)
			(xy 439.934922 -271.76418) (xy 439.986884 -271.77604) (xy 440.036498 -271.795512) (xy 440.082656 -271.822161)
			(xy 440.124327 -271.855392) (xy 440.160579 -271.894463) (xy 440.190603 -271.9385) (xy 440.213729 -271.986521)
			(xy 440.229439 -272.037451) (xy 440.237382 -272.090155) (xy 440.23788 -272.116804) (xy 440.237387 -272.143199)
			(xy 454.655672 -272.143199) (xy 454.655672 -272.089901) (xy 454.663615 -272.037197) (xy 454.679325 -271.986267)
			(xy 454.702451 -271.938246) (xy 454.732475 -271.894209) (xy 454.768727 -271.855138) (xy 454.810398 -271.821907)
			(xy 454.856556 -271.795258) (xy 454.90617 -271.775786) (xy 454.958132 -271.763926) (xy 455.011282 -271.759943)
			(xy 455.064432 -271.763926) (xy 455.116394 -271.775786) (xy 455.166008 -271.795258) (xy 455.212166 -271.821907)
			(xy 455.253837 -271.855138) (xy 455.290089 -271.894209) (xy 455.320113 -271.938246) (xy 455.343239 -271.986267)
			(xy 455.358949 -272.037197) (xy 455.366892 -272.089901) (xy 455.36739 -272.11655) (xy 455.366892 -272.143199)
			(xy 455.358949 -272.195903) (xy 455.343239 -272.246833) (xy 455.320113 -272.294854) (xy 455.290089 -272.338891)
			(xy 455.253837 -272.377962) (xy 455.212166 -272.411193) (xy 455.166008 -272.437842) (xy 455.116394 -272.457314)
			(xy 455.064432 -272.469174) (xy 455.011282 -272.473158) (xy 454.958132 -272.469174) (xy 454.90617 -272.457314)
			(xy 454.856556 -272.437842) (xy 454.810398 -272.411193) (xy 454.768727 -272.377962) (xy 454.732475 -272.338891)
			(xy 454.702451 -272.294854) (xy 454.679325 -272.246833) (xy 454.663615 -272.195903) (xy 454.655672 -272.143199)
			(xy 440.237387 -272.143199) (xy 440.237382 -272.143453) (xy 440.229439 -272.196157) (xy 440.213729 -272.247087)
			(xy 440.190603 -272.295108) (xy 440.160579 -272.339145) (xy 440.124327 -272.378216) (xy 440.082656 -272.411447)
			(xy 440.036498 -272.438096) (xy 439.986884 -272.457568) (xy 439.934922 -272.469428) (xy 439.881772 -272.473412)
			(xy 439.828622 -272.469428) (xy 439.77666 -272.457568) (xy 439.727046 -272.438096) (xy 439.680888 -272.411447)
			(xy 439.639217 -272.378216) (xy 439.602965 -272.339145) (xy 439.572941 -272.295108) (xy 439.549815 -272.247087)
			(xy 439.534105 -272.196157) (xy 439.526162 -272.143453) (xy 425.191654 -272.143453) (xy 425.183749 -272.195903)
			(xy 425.168039 -272.246833) (xy 425.144913 -272.294854) (xy 425.114889 -272.338891) (xy 425.078637 -272.377962)
			(xy 425.036966 -272.411193) (xy 424.990808 -272.437842) (xy 424.941194 -272.457314) (xy 424.889232 -272.469174)
			(xy 424.836082 -272.473158) (xy 424.782932 -272.469174) (xy 424.73097 -272.457314) (xy 424.681356 -272.437842)
			(xy 424.635198 -272.411193) (xy 424.593527 -272.377962) (xy 424.557275 -272.338891) (xy 424.527251 -272.294854)
			(xy 424.504125 -272.246833) (xy 424.488415 -272.195903) (xy 424.480472 -272.143199) (xy 407.4668 -272.143199)
			(xy 407.4668 -272.993337) (xy 420.380404 -272.993337) (xy 420.380404 -272.940039) (xy 420.388347 -272.887335)
			(xy 420.404057 -272.836405) (xy 420.427183 -272.788384) (xy 420.457207 -272.744347) (xy 420.493459 -272.705276)
			(xy 420.53513 -272.672045) (xy 420.581288 -272.645396) (xy 420.630902 -272.625924) (xy 420.682864 -272.614064)
			(xy 420.736014 -272.610081) (xy 420.789164 -272.614064) (xy 420.841126 -272.625924) (xy 420.89074 -272.645396)
			(xy 420.936898 -272.672045) (xy 420.978569 -272.705276) (xy 421.014821 -272.744347) (xy 421.044845 -272.788384)
			(xy 421.067971 -272.836405) (xy 421.083681 -272.887335) (xy 421.091624 -272.940039) (xy 421.092122 -272.966688)
			(xy 421.091624 -272.993337) (xy 435.468004 -272.993337) (xy 435.468004 -272.940039) (xy 435.475947 -272.887335)
			(xy 435.491657 -272.836405) (xy 435.514783 -272.788384) (xy 435.544807 -272.744347) (xy 435.581059 -272.705276)
			(xy 435.62273 -272.672045) (xy 435.668888 -272.645396) (xy 435.718502 -272.625924) (xy 435.770464 -272.614064)
			(xy 435.823614 -272.610081) (xy 435.876764 -272.614064) (xy 435.928726 -272.625924) (xy 435.97834 -272.645396)
			(xy 436.024498 -272.672045) (xy 436.066169 -272.705276) (xy 436.102421 -272.744347) (xy 436.132445 -272.788384)
			(xy 436.155571 -272.836405) (xy 436.171281 -272.887335) (xy 436.179224 -272.940039) (xy 436.179722 -272.966688)
			(xy 436.179224 -272.993337) (xy 450.555604 -272.993337) (xy 450.555604 -272.940039) (xy 450.563547 -272.887335)
			(xy 450.579257 -272.836405) (xy 450.602383 -272.788384) (xy 450.632407 -272.744347) (xy 450.668659 -272.705276)
			(xy 450.71033 -272.672045) (xy 450.756488 -272.645396) (xy 450.806102 -272.625924) (xy 450.858064 -272.614064)
			(xy 450.911214 -272.610081) (xy 450.964364 -272.614064) (xy 451.016326 -272.625924) (xy 451.06594 -272.645396)
			(xy 451.112098 -272.672045) (xy 451.153769 -272.705276) (xy 451.190021 -272.744347) (xy 451.220045 -272.788384)
			(xy 451.243171 -272.836405) (xy 451.258881 -272.887335) (xy 451.266824 -272.940039) (xy 451.267322 -272.966688)
			(xy 451.266824 -272.993337) (xy 451.258881 -273.046041) (xy 451.243171 -273.096971) (xy 451.220045 -273.144992)
			(xy 451.190021 -273.189029) (xy 451.153769 -273.2281) (xy 451.112098 -273.261331) (xy 451.06594 -273.28798)
			(xy 451.016326 -273.307452) (xy 450.964364 -273.319312) (xy 450.911214 -273.323296) (xy 450.858064 -273.319312)
			(xy 450.806102 -273.307452) (xy 450.756488 -273.28798) (xy 450.71033 -273.261331) (xy 450.668659 -273.2281)
			(xy 450.632407 -273.189029) (xy 450.602383 -273.144992) (xy 450.579257 -273.096971) (xy 450.563547 -273.046041)
			(xy 450.555604 -272.993337) (xy 436.179224 -272.993337) (xy 436.171281 -273.046041) (xy 436.155571 -273.096971)
			(xy 436.132445 -273.144992) (xy 436.102421 -273.189029) (xy 436.066169 -273.2281) (xy 436.024498 -273.261331)
			(xy 435.97834 -273.28798) (xy 435.928726 -273.307452) (xy 435.876764 -273.319312) (xy 435.823614 -273.323296)
			(xy 435.770464 -273.319312) (xy 435.718502 -273.307452) (xy 435.668888 -273.28798) (xy 435.62273 -273.261331)
			(xy 435.581059 -273.2281) (xy 435.544807 -273.189029) (xy 435.514783 -273.144992) (xy 435.491657 -273.096971)
			(xy 435.475947 -273.046041) (xy 435.468004 -272.993337) (xy 421.091624 -272.993337) (xy 421.083681 -273.046041)
			(xy 421.067971 -273.096971) (xy 421.044845 -273.144992) (xy 421.014821 -273.189029) (xy 420.978569 -273.2281)
			(xy 420.936898 -273.261331) (xy 420.89074 -273.28798) (xy 420.841126 -273.307452) (xy 420.789164 -273.319312)
			(xy 420.736014 -273.323296) (xy 420.682864 -273.319312) (xy 420.630902 -273.307452) (xy 420.581288 -273.28798)
			(xy 420.53513 -273.261331) (xy 420.493459 -273.2281) (xy 420.457207 -273.189029) (xy 420.427183 -273.144992)
			(xy 420.404057 -273.096971) (xy 420.388347 -273.046041) (xy 420.380404 -272.993337) (xy 407.4668 -272.993337)
			(xy 407.4668 -273.843221) (xy 424.480472 -273.843221) (xy 424.480472 -273.789923) (xy 424.488415 -273.737219)
			(xy 424.504125 -273.686289) (xy 424.527251 -273.638268) (xy 424.557275 -273.594231) (xy 424.593527 -273.55516)
			(xy 424.635198 -273.521929) (xy 424.681356 -273.49528) (xy 424.73097 -273.475808) (xy 424.782932 -273.463948)
			(xy 424.836082 -273.459965) (xy 424.889232 -273.463948) (xy 424.941194 -273.475808) (xy 424.990808 -273.49528)
			(xy 425.036966 -273.521929) (xy 425.078637 -273.55516) (xy 425.114889 -273.594231) (xy 425.144913 -273.638268)
			(xy 425.168039 -273.686289) (xy 425.183749 -273.737219) (xy 425.191692 -273.789923) (xy 425.19219 -273.816572)
			(xy 425.191692 -273.843221) (xy 439.568072 -273.843221) (xy 439.568072 -273.789923) (xy 439.576015 -273.737219)
			(xy 439.591725 -273.686289) (xy 439.614851 -273.638268) (xy 439.644875 -273.594231) (xy 439.681127 -273.55516)
			(xy 439.722798 -273.521929) (xy 439.768956 -273.49528) (xy 439.81857 -273.475808) (xy 439.870532 -273.463948)
			(xy 439.923682 -273.459965) (xy 439.976832 -273.463948) (xy 440.028794 -273.475808) (xy 440.078408 -273.49528)
			(xy 440.124566 -273.521929) (xy 440.166237 -273.55516) (xy 440.202489 -273.594231) (xy 440.232513 -273.638268)
			(xy 440.255639 -273.686289) (xy 440.271349 -273.737219) (xy 440.279292 -273.789923) (xy 440.27979 -273.816572)
			(xy 440.279292 -273.843221) (xy 454.655672 -273.843221) (xy 454.655672 -273.789923) (xy 454.663615 -273.737219)
			(xy 454.679325 -273.686289) (xy 454.702451 -273.638268) (xy 454.732475 -273.594231) (xy 454.768727 -273.55516)
			(xy 454.810398 -273.521929) (xy 454.856556 -273.49528) (xy 454.90617 -273.475808) (xy 454.958132 -273.463948)
			(xy 455.011282 -273.459965) (xy 455.064432 -273.463948) (xy 455.116394 -273.475808) (xy 455.166008 -273.49528)
			(xy 455.212166 -273.521929) (xy 455.253837 -273.55516) (xy 455.290089 -273.594231) (xy 455.320113 -273.638268)
			(xy 455.343239 -273.686289) (xy 455.358949 -273.737219) (xy 455.366892 -273.789923) (xy 455.36739 -273.816572)
			(xy 455.366892 -273.843221) (xy 455.358949 -273.895925) (xy 455.343239 -273.946855) (xy 455.320113 -273.994876)
			(xy 455.290089 -274.038913) (xy 455.253837 -274.077984) (xy 455.212166 -274.111215) (xy 455.166008 -274.137864)
			(xy 455.116394 -274.157336) (xy 455.064432 -274.169196) (xy 455.011282 -274.17318) (xy 454.958132 -274.169196)
			(xy 454.90617 -274.157336) (xy 454.856556 -274.137864) (xy 454.810398 -274.111215) (xy 454.768727 -274.077984)
			(xy 454.732475 -274.038913) (xy 454.702451 -273.994876) (xy 454.679325 -273.946855) (xy 454.663615 -273.895925)
			(xy 454.655672 -273.843221) (xy 440.279292 -273.843221) (xy 440.271349 -273.895925) (xy 440.255639 -273.946855)
			(xy 440.232513 -273.994876) (xy 440.202489 -274.038913) (xy 440.166237 -274.077984) (xy 440.124566 -274.111215)
			(xy 440.078408 -274.137864) (xy 440.028794 -274.157336) (xy 439.976832 -274.169196) (xy 439.923682 -274.17318)
			(xy 439.870532 -274.169196) (xy 439.81857 -274.157336) (xy 439.768956 -274.137864) (xy 439.722798 -274.111215)
			(xy 439.681127 -274.077984) (xy 439.644875 -274.038913) (xy 439.614851 -273.994876) (xy 439.591725 -273.946855)
			(xy 439.576015 -273.895925) (xy 439.568072 -273.843221) (xy 425.191692 -273.843221) (xy 425.183749 -273.895925)
			(xy 425.168039 -273.946855) (xy 425.144913 -273.994876) (xy 425.114889 -274.038913) (xy 425.078637 -274.077984)
			(xy 425.036966 -274.111215) (xy 424.990808 -274.137864) (xy 424.941194 -274.157336) (xy 424.889232 -274.169196)
			(xy 424.836082 -274.17318) (xy 424.782932 -274.169196) (xy 424.73097 -274.157336) (xy 424.681356 -274.137864)
			(xy 424.635198 -274.111215) (xy 424.593527 -274.077984) (xy 424.557275 -274.038913) (xy 424.527251 -273.994876)
			(xy 424.504125 -273.946855) (xy 424.488415 -273.895925) (xy 424.480472 -273.843221) (xy 407.4668 -273.843221)
			(xy 407.4668 -274.693359) (xy 420.380404 -274.693359) (xy 420.380404 -274.640061) (xy 420.388347 -274.587357)
			(xy 420.404057 -274.536427) (xy 420.427183 -274.488406) (xy 420.457207 -274.444369) (xy 420.493459 -274.405298)
			(xy 420.53513 -274.372067) (xy 420.581288 -274.345418) (xy 420.630902 -274.325946) (xy 420.682864 -274.314086)
			(xy 420.736014 -274.310103) (xy 420.789164 -274.314086) (xy 420.841126 -274.325946) (xy 420.89074 -274.345418)
			(xy 420.936898 -274.372067) (xy 420.978569 -274.405298) (xy 421.014821 -274.444369) (xy 421.044845 -274.488406)
			(xy 421.067971 -274.536427) (xy 421.083681 -274.587357) (xy 421.091624 -274.640061) (xy 421.092122 -274.66671)
			(xy 421.091624 -274.693359) (xy 424.480472 -274.693359) (xy 424.480472 -274.640061) (xy 424.488415 -274.587357)
			(xy 424.504125 -274.536427) (xy 424.527251 -274.488406) (xy 424.557275 -274.444369) (xy 424.593527 -274.405298)
			(xy 424.635198 -274.372067) (xy 424.681356 -274.345418) (xy 424.73097 -274.325946) (xy 424.782932 -274.314086)
			(xy 424.836082 -274.310103) (xy 424.889232 -274.314086) (xy 424.941194 -274.325946) (xy 424.990808 -274.345418)
			(xy 425.036966 -274.372067) (xy 425.078637 -274.405298) (xy 425.114889 -274.444369) (xy 425.144913 -274.488406)
			(xy 425.168039 -274.536427) (xy 425.183749 -274.587357) (xy 425.191692 -274.640061) (xy 425.19219 -274.66671)
			(xy 425.191692 -274.693359) (xy 435.468004 -274.693359) (xy 435.468004 -274.640061) (xy 435.475947 -274.587357)
			(xy 435.491657 -274.536427) (xy 435.514783 -274.488406) (xy 435.544807 -274.444369) (xy 435.581059 -274.405298)
			(xy 435.62273 -274.372067) (xy 435.668888 -274.345418) (xy 435.718502 -274.325946) (xy 435.770464 -274.314086)
			(xy 435.823614 -274.310103) (xy 435.876764 -274.314086) (xy 435.928726 -274.325946) (xy 435.97834 -274.345418)
			(xy 436.024498 -274.372067) (xy 436.066169 -274.405298) (xy 436.102421 -274.444369) (xy 436.132445 -274.488406)
			(xy 436.155571 -274.536427) (xy 436.171281 -274.587357) (xy 436.179224 -274.640061) (xy 436.179722 -274.66671)
			(xy 436.179224 -274.693359) (xy 439.568072 -274.693359) (xy 439.568072 -274.640061) (xy 439.576015 -274.587357)
			(xy 439.591725 -274.536427) (xy 439.614851 -274.488406) (xy 439.644875 -274.444369) (xy 439.681127 -274.405298)
			(xy 439.722798 -274.372067) (xy 439.768956 -274.345418) (xy 439.81857 -274.325946) (xy 439.870532 -274.314086)
			(xy 439.923682 -274.310103) (xy 439.976832 -274.314086) (xy 440.028794 -274.325946) (xy 440.078408 -274.345418)
			(xy 440.124566 -274.372067) (xy 440.166237 -274.405298) (xy 440.202489 -274.444369) (xy 440.232513 -274.488406)
			(xy 440.255639 -274.536427) (xy 440.271349 -274.587357) (xy 440.279292 -274.640061) (xy 440.27979 -274.66671)
			(xy 440.279292 -274.693359) (xy 450.555604 -274.693359) (xy 450.555604 -274.640061) (xy 450.563547 -274.587357)
			(xy 450.579257 -274.536427) (xy 450.602383 -274.488406) (xy 450.632407 -274.444369) (xy 450.668659 -274.405298)
			(xy 450.71033 -274.372067) (xy 450.756488 -274.345418) (xy 450.806102 -274.325946) (xy 450.858064 -274.314086)
			(xy 450.911214 -274.310103) (xy 450.964364 -274.314086) (xy 451.016326 -274.325946) (xy 451.06594 -274.345418)
			(xy 451.112098 -274.372067) (xy 451.153769 -274.405298) (xy 451.190021 -274.444369) (xy 451.220045 -274.488406)
			(xy 451.243171 -274.536427) (xy 451.258881 -274.587357) (xy 451.266824 -274.640061) (xy 451.267322 -274.66671)
			(xy 451.266824 -274.693359) (xy 454.655672 -274.693359) (xy 454.655672 -274.640061) (xy 454.663615 -274.587357)
			(xy 454.679325 -274.536427) (xy 454.702451 -274.488406) (xy 454.732475 -274.444369) (xy 454.768727 -274.405298)
			(xy 454.810398 -274.372067) (xy 454.856556 -274.345418) (xy 454.90617 -274.325946) (xy 454.958132 -274.314086)
			(xy 455.011282 -274.310103) (xy 455.064432 -274.314086) (xy 455.116394 -274.325946) (xy 455.166008 -274.345418)
			(xy 455.212166 -274.372067) (xy 455.253837 -274.405298) (xy 455.290089 -274.444369) (xy 455.320113 -274.488406)
			(xy 455.343239 -274.536427) (xy 455.358949 -274.587357) (xy 455.366892 -274.640061) (xy 455.36739 -274.66671)
			(xy 455.366892 -274.693359) (xy 455.358949 -274.746063) (xy 455.343239 -274.796993) (xy 455.320113 -274.845014)
			(xy 455.290089 -274.889051) (xy 455.253837 -274.928122) (xy 455.212166 -274.961353) (xy 455.166008 -274.988002)
			(xy 455.116394 -275.007474) (xy 455.064432 -275.019334) (xy 455.011282 -275.023318) (xy 454.958132 -275.019334)
			(xy 454.90617 -275.007474) (xy 454.856556 -274.988002) (xy 454.810398 -274.961353) (xy 454.768727 -274.928122)
			(xy 454.732475 -274.889051) (xy 454.702451 -274.845014) (xy 454.679325 -274.796993) (xy 454.663615 -274.746063)
			(xy 454.655672 -274.693359) (xy 451.266824 -274.693359) (xy 451.258881 -274.746063) (xy 451.243171 -274.796993)
			(xy 451.220045 -274.845014) (xy 451.190021 -274.889051) (xy 451.153769 -274.928122) (xy 451.112098 -274.961353)
			(xy 451.06594 -274.988002) (xy 451.016326 -275.007474) (xy 450.964364 -275.019334) (xy 450.911214 -275.023318)
			(xy 450.858064 -275.019334) (xy 450.806102 -275.007474) (xy 450.756488 -274.988002) (xy 450.71033 -274.961353)
			(xy 450.668659 -274.928122) (xy 450.632407 -274.889051) (xy 450.602383 -274.845014) (xy 450.579257 -274.796993)
			(xy 450.563547 -274.746063) (xy 450.555604 -274.693359) (xy 440.279292 -274.693359) (xy 440.271349 -274.746063)
			(xy 440.255639 -274.796993) (xy 440.232513 -274.845014) (xy 440.202489 -274.889051) (xy 440.166237 -274.928122)
			(xy 440.124566 -274.961353) (xy 440.078408 -274.988002) (xy 440.028794 -275.007474) (xy 439.976832 -275.019334)
			(xy 439.923682 -275.023318) (xy 439.870532 -275.019334) (xy 439.81857 -275.007474) (xy 439.768956 -274.988002)
			(xy 439.722798 -274.961353) (xy 439.681127 -274.928122) (xy 439.644875 -274.889051) (xy 439.614851 -274.845014)
			(xy 439.591725 -274.796993) (xy 439.576015 -274.746063) (xy 439.568072 -274.693359) (xy 436.179224 -274.693359)
			(xy 436.171281 -274.746063) (xy 436.155571 -274.796993) (xy 436.132445 -274.845014) (xy 436.102421 -274.889051)
			(xy 436.066169 -274.928122) (xy 436.024498 -274.961353) (xy 435.97834 -274.988002) (xy 435.928726 -275.007474)
			(xy 435.876764 -275.019334) (xy 435.823614 -275.023318) (xy 435.770464 -275.019334) (xy 435.718502 -275.007474)
			(xy 435.668888 -274.988002) (xy 435.62273 -274.961353) (xy 435.581059 -274.928122) (xy 435.544807 -274.889051)
			(xy 435.514783 -274.845014) (xy 435.491657 -274.796993) (xy 435.475947 -274.746063) (xy 435.468004 -274.693359)
			(xy 425.191692 -274.693359) (xy 425.183749 -274.746063) (xy 425.168039 -274.796993) (xy 425.144913 -274.845014)
			(xy 425.114889 -274.889051) (xy 425.078637 -274.928122) (xy 425.036966 -274.961353) (xy 424.990808 -274.988002)
			(xy 424.941194 -275.007474) (xy 424.889232 -275.019334) (xy 424.836082 -275.023318) (xy 424.782932 -275.019334)
			(xy 424.73097 -275.007474) (xy 424.681356 -274.988002) (xy 424.635198 -274.961353) (xy 424.593527 -274.928122)
			(xy 424.557275 -274.889051) (xy 424.527251 -274.845014) (xy 424.504125 -274.796993) (xy 424.488415 -274.746063)
			(xy 424.480472 -274.693359) (xy 421.091624 -274.693359) (xy 421.083681 -274.746063) (xy 421.067971 -274.796993)
			(xy 421.044845 -274.845014) (xy 421.014821 -274.889051) (xy 420.978569 -274.928122) (xy 420.936898 -274.961353)
			(xy 420.89074 -274.988002) (xy 420.841126 -275.007474) (xy 420.789164 -275.019334) (xy 420.736014 -275.023318)
			(xy 420.682864 -275.019334) (xy 420.630902 -275.007474) (xy 420.581288 -274.988002) (xy 420.53513 -274.961353)
			(xy 420.493459 -274.928122) (xy 420.457207 -274.889051) (xy 420.427183 -274.845014) (xy 420.404057 -274.796993)
			(xy 420.388347 -274.746063) (xy 420.380404 -274.693359) (xy 407.4668 -274.693359) (xy 407.4668 -275.543243)
			(xy 420.380404 -275.543243) (xy 420.380404 -275.489945) (xy 420.388347 -275.437241) (xy 420.404057 -275.386311)
			(xy 420.427183 -275.33829) (xy 420.457207 -275.294253) (xy 420.493459 -275.255182) (xy 420.53513 -275.221951)
			(xy 420.581288 -275.195302) (xy 420.630902 -275.17583) (xy 420.682864 -275.16397) (xy 420.736014 -275.159987)
			(xy 420.789164 -275.16397) (xy 420.841126 -275.17583) (xy 420.89074 -275.195302) (xy 420.936898 -275.221951)
			(xy 420.978569 -275.255182) (xy 421.014821 -275.294253) (xy 421.044845 -275.33829) (xy 421.067971 -275.386311)
			(xy 421.083681 -275.437241) (xy 421.091624 -275.489945) (xy 421.092122 -275.516594) (xy 421.091624 -275.543243)
			(xy 435.468004 -275.543243) (xy 435.468004 -275.489945) (xy 435.475947 -275.437241) (xy 435.491657 -275.386311)
			(xy 435.514783 -275.33829) (xy 435.544807 -275.294253) (xy 435.581059 -275.255182) (xy 435.62273 -275.221951)
			(xy 435.668888 -275.195302) (xy 435.718502 -275.17583) (xy 435.770464 -275.16397) (xy 435.823614 -275.159987)
			(xy 435.876764 -275.16397) (xy 435.928726 -275.17583) (xy 435.97834 -275.195302) (xy 436.024498 -275.221951)
			(xy 436.066169 -275.255182) (xy 436.102421 -275.294253) (xy 436.132445 -275.33829) (xy 436.155571 -275.386311)
			(xy 436.171281 -275.437241) (xy 436.179224 -275.489945) (xy 436.179722 -275.516594) (xy 436.179224 -275.543243)
			(xy 450.555604 -275.543243) (xy 450.555604 -275.489945) (xy 450.563547 -275.437241) (xy 450.579257 -275.386311)
			(xy 450.602383 -275.33829) (xy 450.632407 -275.294253) (xy 450.668659 -275.255182) (xy 450.71033 -275.221951)
			(xy 450.756488 -275.195302) (xy 450.806102 -275.17583) (xy 450.858064 -275.16397) (xy 450.911214 -275.159987)
			(xy 450.964364 -275.16397) (xy 451.016326 -275.17583) (xy 451.06594 -275.195302) (xy 451.112098 -275.221951)
			(xy 451.153769 -275.255182) (xy 451.190021 -275.294253) (xy 451.220045 -275.33829) (xy 451.243171 -275.386311)
			(xy 451.258881 -275.437241) (xy 451.266824 -275.489945) (xy 451.267322 -275.516594) (xy 451.266824 -275.543243)
			(xy 451.258881 -275.595947) (xy 451.243171 -275.646877) (xy 451.220045 -275.694898) (xy 451.190021 -275.738935)
			(xy 451.153769 -275.778006) (xy 451.112098 -275.811237) (xy 451.06594 -275.837886) (xy 451.016326 -275.857358)
			(xy 450.964364 -275.869218) (xy 450.911214 -275.873202) (xy 450.858064 -275.869218) (xy 450.806102 -275.857358)
			(xy 450.756488 -275.837886) (xy 450.71033 -275.811237) (xy 450.668659 -275.778006) (xy 450.632407 -275.738935)
			(xy 450.602383 -275.694898) (xy 450.579257 -275.646877) (xy 450.563547 -275.595947) (xy 450.555604 -275.543243)
			(xy 436.179224 -275.543243) (xy 436.171281 -275.595947) (xy 436.155571 -275.646877) (xy 436.132445 -275.694898)
			(xy 436.102421 -275.738935) (xy 436.066169 -275.778006) (xy 436.024498 -275.811237) (xy 435.97834 -275.837886)
			(xy 435.928726 -275.857358) (xy 435.876764 -275.869218) (xy 435.823614 -275.873202) (xy 435.770464 -275.869218)
			(xy 435.718502 -275.857358) (xy 435.668888 -275.837886) (xy 435.62273 -275.811237) (xy 435.581059 -275.778006)
			(xy 435.544807 -275.738935) (xy 435.514783 -275.694898) (xy 435.491657 -275.646877) (xy 435.475947 -275.595947)
			(xy 435.468004 -275.543243) (xy 421.091624 -275.543243) (xy 421.083681 -275.595947) (xy 421.067971 -275.646877)
			(xy 421.044845 -275.694898) (xy 421.014821 -275.738935) (xy 420.978569 -275.778006) (xy 420.936898 -275.811237)
			(xy 420.89074 -275.837886) (xy 420.841126 -275.857358) (xy 420.789164 -275.869218) (xy 420.736014 -275.873202)
			(xy 420.682864 -275.869218) (xy 420.630902 -275.857358) (xy 420.581288 -275.837886) (xy 420.53513 -275.811237)
			(xy 420.493459 -275.778006) (xy 420.457207 -275.738935) (xy 420.427183 -275.694898) (xy 420.404057 -275.646877)
			(xy 420.388347 -275.595947) (xy 420.380404 -275.543243) (xy 407.4668 -275.543243) (xy 407.4668 -276.393381)
			(xy 424.480472 -276.393381) (xy 424.480472 -276.340083) (xy 424.488415 -276.287379) (xy 424.504125 -276.236449)
			(xy 424.527251 -276.188428) (xy 424.557275 -276.144391) (xy 424.593527 -276.10532) (xy 424.635198 -276.072089)
			(xy 424.681356 -276.04544) (xy 424.73097 -276.025968) (xy 424.782932 -276.014108) (xy 424.836082 -276.010125)
			(xy 424.889232 -276.014108) (xy 424.941194 -276.025968) (xy 424.990808 -276.04544) (xy 425.036966 -276.072089)
			(xy 425.078637 -276.10532) (xy 425.114889 -276.144391) (xy 425.144913 -276.188428) (xy 425.168039 -276.236449)
			(xy 425.183749 -276.287379) (xy 425.191692 -276.340083) (xy 425.19219 -276.366732) (xy 425.191692 -276.393381)
			(xy 439.568072 -276.393381) (xy 439.568072 -276.340083) (xy 439.576015 -276.287379) (xy 439.591725 -276.236449)
			(xy 439.614851 -276.188428) (xy 439.644875 -276.144391) (xy 439.681127 -276.10532) (xy 439.722798 -276.072089)
			(xy 439.768956 -276.04544) (xy 439.81857 -276.025968) (xy 439.870532 -276.014108) (xy 439.923682 -276.010125)
			(xy 439.976832 -276.014108) (xy 440.028794 -276.025968) (xy 440.078408 -276.04544) (xy 440.124566 -276.072089)
			(xy 440.166237 -276.10532) (xy 440.202489 -276.144391) (xy 440.232513 -276.188428) (xy 440.255639 -276.236449)
			(xy 440.271349 -276.287379) (xy 440.279292 -276.340083) (xy 440.27979 -276.366732) (xy 440.279292 -276.393381)
			(xy 454.655672 -276.393381) (xy 454.655672 -276.340083) (xy 454.663615 -276.287379) (xy 454.679325 -276.236449)
			(xy 454.702451 -276.188428) (xy 454.732475 -276.144391) (xy 454.768727 -276.10532) (xy 454.810398 -276.072089)
			(xy 454.856556 -276.04544) (xy 454.90617 -276.025968) (xy 454.958132 -276.014108) (xy 455.011282 -276.010125)
			(xy 455.064432 -276.014108) (xy 455.116394 -276.025968) (xy 455.166008 -276.04544) (xy 455.212166 -276.072089)
			(xy 455.253837 -276.10532) (xy 455.290089 -276.144391) (xy 455.320113 -276.188428) (xy 455.343239 -276.236449)
			(xy 455.358949 -276.287379) (xy 455.366892 -276.340083) (xy 455.36739 -276.366732) (xy 455.366892 -276.393381)
			(xy 455.358949 -276.446085) (xy 455.343239 -276.497015) (xy 455.320113 -276.545036) (xy 455.290089 -276.589073)
			(xy 455.253837 -276.628144) (xy 455.212166 -276.661375) (xy 455.166008 -276.688024) (xy 455.116394 -276.707496)
			(xy 455.064432 -276.719356) (xy 455.011282 -276.72334) (xy 454.958132 -276.719356) (xy 454.90617 -276.707496)
			(xy 454.856556 -276.688024) (xy 454.810398 -276.661375) (xy 454.768727 -276.628144) (xy 454.732475 -276.589073)
			(xy 454.702451 -276.545036) (xy 454.679325 -276.497015) (xy 454.663615 -276.446085) (xy 454.655672 -276.393381)
			(xy 440.279292 -276.393381) (xy 440.271349 -276.446085) (xy 440.255639 -276.497015) (xy 440.232513 -276.545036)
			(xy 440.202489 -276.589073) (xy 440.166237 -276.628144) (xy 440.124566 -276.661375) (xy 440.078408 -276.688024)
			(xy 440.028794 -276.707496) (xy 439.976832 -276.719356) (xy 439.923682 -276.72334) (xy 439.870532 -276.719356)
			(xy 439.81857 -276.707496) (xy 439.768956 -276.688024) (xy 439.722798 -276.661375) (xy 439.681127 -276.628144)
			(xy 439.644875 -276.589073) (xy 439.614851 -276.545036) (xy 439.591725 -276.497015) (xy 439.576015 -276.446085)
			(xy 439.568072 -276.393381) (xy 425.191692 -276.393381) (xy 425.183749 -276.446085) (xy 425.168039 -276.497015)
			(xy 425.144913 -276.545036) (xy 425.114889 -276.589073) (xy 425.078637 -276.628144) (xy 425.036966 -276.661375)
			(xy 424.990808 -276.688024) (xy 424.941194 -276.707496) (xy 424.889232 -276.719356) (xy 424.836082 -276.72334)
			(xy 424.782932 -276.719356) (xy 424.73097 -276.707496) (xy 424.681356 -276.688024) (xy 424.635198 -276.661375)
			(xy 424.593527 -276.628144) (xy 424.557275 -276.589073) (xy 424.527251 -276.545036) (xy 424.504125 -276.497015)
			(xy 424.488415 -276.446085) (xy 424.480472 -276.393381) (xy 407.4668 -276.393381) (xy 407.4668 -277.243265)
			(xy 420.380404 -277.243265) (xy 420.380404 -277.189967) (xy 420.388347 -277.137263) (xy 420.404057 -277.086333)
			(xy 420.427183 -277.038312) (xy 420.457207 -276.994275) (xy 420.493459 -276.955204) (xy 420.53513 -276.921973)
			(xy 420.581288 -276.895324) (xy 420.630902 -276.875852) (xy 420.682864 -276.863992) (xy 420.736014 -276.860009)
			(xy 420.789164 -276.863992) (xy 420.841126 -276.875852) (xy 420.89074 -276.895324) (xy 420.936898 -276.921973)
			(xy 420.978569 -276.955204) (xy 421.014821 -276.994275) (xy 421.044845 -277.038312) (xy 421.067971 -277.086333)
			(xy 421.083681 -277.137263) (xy 421.091624 -277.189967) (xy 421.092122 -277.216616) (xy 421.091624 -277.243265)
			(xy 435.468004 -277.243265) (xy 435.468004 -277.189967) (xy 435.475947 -277.137263) (xy 435.491657 -277.086333)
			(xy 435.514783 -277.038312) (xy 435.544807 -276.994275) (xy 435.581059 -276.955204) (xy 435.62273 -276.921973)
			(xy 435.668888 -276.895324) (xy 435.718502 -276.875852) (xy 435.770464 -276.863992) (xy 435.823614 -276.860009)
			(xy 435.876764 -276.863992) (xy 435.928726 -276.875852) (xy 435.97834 -276.895324) (xy 436.024498 -276.921973)
			(xy 436.066169 -276.955204) (xy 436.102421 -276.994275) (xy 436.132445 -277.038312) (xy 436.155571 -277.086333)
			(xy 436.171281 -277.137263) (xy 436.179224 -277.189967) (xy 436.179722 -277.216616) (xy 436.179224 -277.243265)
			(xy 450.555604 -277.243265) (xy 450.555604 -277.189967) (xy 450.563547 -277.137263) (xy 450.579257 -277.086333)
			(xy 450.602383 -277.038312) (xy 450.632407 -276.994275) (xy 450.668659 -276.955204) (xy 450.71033 -276.921973)
			(xy 450.756488 -276.895324) (xy 450.806102 -276.875852) (xy 450.858064 -276.863992) (xy 450.911214 -276.860009)
			(xy 450.964364 -276.863992) (xy 451.016326 -276.875852) (xy 451.06594 -276.895324) (xy 451.112098 -276.921973)
			(xy 451.153769 -276.955204) (xy 451.190021 -276.994275) (xy 451.220045 -277.038312) (xy 451.243171 -277.086333)
			(xy 451.258881 -277.137263) (xy 451.266824 -277.189967) (xy 451.267322 -277.216616) (xy 451.266824 -277.243265)
			(xy 451.258881 -277.295969) (xy 451.243171 -277.346899) (xy 451.220045 -277.39492) (xy 451.190021 -277.438957)
			(xy 451.153769 -277.478028) (xy 451.112098 -277.511259) (xy 451.06594 -277.537908) (xy 451.016326 -277.55738)
			(xy 450.964364 -277.56924) (xy 450.911214 -277.573224) (xy 450.858064 -277.56924) (xy 450.806102 -277.55738)
			(xy 450.756488 -277.537908) (xy 450.71033 -277.511259) (xy 450.668659 -277.478028) (xy 450.632407 -277.438957)
			(xy 450.602383 -277.39492) (xy 450.579257 -277.346899) (xy 450.563547 -277.295969) (xy 450.555604 -277.243265)
			(xy 436.179224 -277.243265) (xy 436.171281 -277.295969) (xy 436.155571 -277.346899) (xy 436.132445 -277.39492)
			(xy 436.102421 -277.438957) (xy 436.066169 -277.478028) (xy 436.024498 -277.511259) (xy 435.97834 -277.537908)
			(xy 435.928726 -277.55738) (xy 435.876764 -277.56924) (xy 435.823614 -277.573224) (xy 435.770464 -277.56924)
			(xy 435.718502 -277.55738) (xy 435.668888 -277.537908) (xy 435.62273 -277.511259) (xy 435.581059 -277.478028)
			(xy 435.544807 -277.438957) (xy 435.514783 -277.39492) (xy 435.491657 -277.346899) (xy 435.475947 -277.295969)
			(xy 435.468004 -277.243265) (xy 421.091624 -277.243265) (xy 421.083681 -277.295969) (xy 421.067971 -277.346899)
			(xy 421.044845 -277.39492) (xy 421.014821 -277.438957) (xy 420.978569 -277.478028) (xy 420.936898 -277.511259)
			(xy 420.89074 -277.537908) (xy 420.841126 -277.55738) (xy 420.789164 -277.56924) (xy 420.736014 -277.573224)
			(xy 420.682864 -277.56924) (xy 420.630902 -277.55738) (xy 420.581288 -277.537908) (xy 420.53513 -277.511259)
			(xy 420.493459 -277.478028) (xy 420.457207 -277.438957) (xy 420.427183 -277.39492) (xy 420.404057 -277.346899)
			(xy 420.388347 -277.295969) (xy 420.380404 -277.243265) (xy 407.4668 -277.243265) (xy 407.4668 -278.093403)
			(xy 424.480472 -278.093403) (xy 424.480472 -278.040105) (xy 424.488415 -277.987401) (xy 424.504125 -277.936471)
			(xy 424.527251 -277.88845) (xy 424.557275 -277.844413) (xy 424.593527 -277.805342) (xy 424.635198 -277.772111)
			(xy 424.681356 -277.745462) (xy 424.73097 -277.72599) (xy 424.782932 -277.71413) (xy 424.836082 -277.710147)
			(xy 424.889232 -277.71413) (xy 424.941194 -277.72599) (xy 424.990808 -277.745462) (xy 425.036966 -277.772111)
			(xy 425.078637 -277.805342) (xy 425.114889 -277.844413) (xy 425.144913 -277.88845) (xy 425.168039 -277.936471)
			(xy 425.183749 -277.987401) (xy 425.191692 -278.040105) (xy 425.19219 -278.066754) (xy 425.191692 -278.093403)
			(xy 439.568072 -278.093403) (xy 439.568072 -278.040105) (xy 439.576015 -277.987401) (xy 439.591725 -277.936471)
			(xy 439.614851 -277.88845) (xy 439.644875 -277.844413) (xy 439.681127 -277.805342) (xy 439.722798 -277.772111)
			(xy 439.768956 -277.745462) (xy 439.81857 -277.72599) (xy 439.870532 -277.71413) (xy 439.923682 -277.710147)
			(xy 439.976832 -277.71413) (xy 440.028794 -277.72599) (xy 440.078408 -277.745462) (xy 440.124566 -277.772111)
			(xy 440.166237 -277.805342) (xy 440.202489 -277.844413) (xy 440.232513 -277.88845) (xy 440.255639 -277.936471)
			(xy 440.271349 -277.987401) (xy 440.279292 -278.040105) (xy 440.27979 -278.066754) (xy 440.279292 -278.093403)
			(xy 454.655672 -278.093403) (xy 454.655672 -278.040105) (xy 454.663615 -277.987401) (xy 454.679325 -277.936471)
			(xy 454.702451 -277.88845) (xy 454.732475 -277.844413) (xy 454.768727 -277.805342) (xy 454.810398 -277.772111)
			(xy 454.856556 -277.745462) (xy 454.90617 -277.72599) (xy 454.958132 -277.71413) (xy 455.011282 -277.710147)
			(xy 455.064432 -277.71413) (xy 455.116394 -277.72599) (xy 455.166008 -277.745462) (xy 455.212166 -277.772111)
			(xy 455.253837 -277.805342) (xy 455.290089 -277.844413) (xy 455.320113 -277.88845) (xy 455.343239 -277.936471)
			(xy 455.358949 -277.987401) (xy 455.366892 -278.040105) (xy 455.36739 -278.066754) (xy 455.366892 -278.093403)
			(xy 455.358949 -278.146107) (xy 455.343239 -278.197037) (xy 455.320113 -278.245058) (xy 455.290089 -278.289095)
			(xy 455.253837 -278.328166) (xy 455.212166 -278.361397) (xy 455.166008 -278.388046) (xy 455.116394 -278.407518)
			(xy 455.064432 -278.419378) (xy 455.011282 -278.423362) (xy 454.958132 -278.419378) (xy 454.90617 -278.407518)
			(xy 454.856556 -278.388046) (xy 454.810398 -278.361397) (xy 454.768727 -278.328166) (xy 454.732475 -278.289095)
			(xy 454.702451 -278.245058) (xy 454.679325 -278.197037) (xy 454.663615 -278.146107) (xy 454.655672 -278.093403)
			(xy 440.279292 -278.093403) (xy 440.271349 -278.146107) (xy 440.255639 -278.197037) (xy 440.232513 -278.245058)
			(xy 440.202489 -278.289095) (xy 440.166237 -278.328166) (xy 440.124566 -278.361397) (xy 440.078408 -278.388046)
			(xy 440.028794 -278.407518) (xy 439.976832 -278.419378) (xy 439.923682 -278.423362) (xy 439.870532 -278.419378)
			(xy 439.81857 -278.407518) (xy 439.768956 -278.388046) (xy 439.722798 -278.361397) (xy 439.681127 -278.328166)
			(xy 439.644875 -278.289095) (xy 439.614851 -278.245058) (xy 439.591725 -278.197037) (xy 439.576015 -278.146107)
			(xy 439.568072 -278.093403) (xy 425.191692 -278.093403) (xy 425.183749 -278.146107) (xy 425.168039 -278.197037)
			(xy 425.144913 -278.245058) (xy 425.114889 -278.289095) (xy 425.078637 -278.328166) (xy 425.036966 -278.361397)
			(xy 424.990808 -278.388046) (xy 424.941194 -278.407518) (xy 424.889232 -278.419378) (xy 424.836082 -278.423362)
			(xy 424.782932 -278.419378) (xy 424.73097 -278.407518) (xy 424.681356 -278.388046) (xy 424.635198 -278.361397)
			(xy 424.593527 -278.328166) (xy 424.557275 -278.289095) (xy 424.527251 -278.245058) (xy 424.504125 -278.197037)
			(xy 424.488415 -278.146107) (xy 424.480472 -278.093403) (xy 407.4668 -278.093403) (xy 407.4668 -278.943287)
			(xy 420.380404 -278.943287) (xy 420.380404 -278.889989) (xy 420.388347 -278.837285) (xy 420.404057 -278.786355)
			(xy 420.427183 -278.738334) (xy 420.457207 -278.694297) (xy 420.493459 -278.655226) (xy 420.53513 -278.621995)
			(xy 420.581288 -278.595346) (xy 420.630902 -278.575874) (xy 420.682864 -278.564014) (xy 420.736014 -278.560031)
			(xy 420.789164 -278.564014) (xy 420.841126 -278.575874) (xy 420.89074 -278.595346) (xy 420.936898 -278.621995)
			(xy 420.978569 -278.655226) (xy 421.014821 -278.694297) (xy 421.044845 -278.738334) (xy 421.067971 -278.786355)
			(xy 421.083681 -278.837285) (xy 421.091624 -278.889989) (xy 421.092122 -278.916638) (xy 421.091624 -278.943287)
			(xy 435.468004 -278.943287) (xy 435.468004 -278.889989) (xy 435.475947 -278.837285) (xy 435.491657 -278.786355)
			(xy 435.514783 -278.738334) (xy 435.544807 -278.694297) (xy 435.581059 -278.655226) (xy 435.62273 -278.621995)
			(xy 435.668888 -278.595346) (xy 435.718502 -278.575874) (xy 435.770464 -278.564014) (xy 435.823614 -278.560031)
			(xy 435.876764 -278.564014) (xy 435.928726 -278.575874) (xy 435.97834 -278.595346) (xy 436.024498 -278.621995)
			(xy 436.066169 -278.655226) (xy 436.102421 -278.694297) (xy 436.132445 -278.738334) (xy 436.155571 -278.786355)
			(xy 436.171281 -278.837285) (xy 436.179224 -278.889989) (xy 436.179722 -278.916638) (xy 436.179224 -278.943287)
			(xy 450.555604 -278.943287) (xy 450.555604 -278.889989) (xy 450.563547 -278.837285) (xy 450.579257 -278.786355)
			(xy 450.602383 -278.738334) (xy 450.632407 -278.694297) (xy 450.668659 -278.655226) (xy 450.71033 -278.621995)
			(xy 450.756488 -278.595346) (xy 450.806102 -278.575874) (xy 450.858064 -278.564014) (xy 450.911214 -278.560031)
			(xy 450.964364 -278.564014) (xy 451.016326 -278.575874) (xy 451.06594 -278.595346) (xy 451.112098 -278.621995)
			(xy 451.153769 -278.655226) (xy 451.190021 -278.694297) (xy 451.220045 -278.738334) (xy 451.243171 -278.786355)
			(xy 451.258881 -278.837285) (xy 451.266824 -278.889989) (xy 451.267322 -278.916638) (xy 451.266824 -278.943287)
			(xy 451.258881 -278.995991) (xy 451.243171 -279.046921) (xy 451.220045 -279.094942) (xy 451.190021 -279.138979)
			(xy 451.153769 -279.17805) (xy 451.112098 -279.211281) (xy 451.06594 -279.23793) (xy 451.016326 -279.257402)
			(xy 450.964364 -279.269262) (xy 450.911214 -279.273246) (xy 450.858064 -279.269262) (xy 450.806102 -279.257402)
			(xy 450.756488 -279.23793) (xy 450.71033 -279.211281) (xy 450.668659 -279.17805) (xy 450.632407 -279.138979)
			(xy 450.602383 -279.094942) (xy 450.579257 -279.046921) (xy 450.563547 -278.995991) (xy 450.555604 -278.943287)
			(xy 436.179224 -278.943287) (xy 436.171281 -278.995991) (xy 436.155571 -279.046921) (xy 436.132445 -279.094942)
			(xy 436.102421 -279.138979) (xy 436.066169 -279.17805) (xy 436.024498 -279.211281) (xy 435.97834 -279.23793)
			(xy 435.928726 -279.257402) (xy 435.876764 -279.269262) (xy 435.823614 -279.273246) (xy 435.770464 -279.269262)
			(xy 435.718502 -279.257402) (xy 435.668888 -279.23793) (xy 435.62273 -279.211281) (xy 435.581059 -279.17805)
			(xy 435.544807 -279.138979) (xy 435.514783 -279.094942) (xy 435.491657 -279.046921) (xy 435.475947 -278.995991)
			(xy 435.468004 -278.943287) (xy 421.091624 -278.943287) (xy 421.083681 -278.995991) (xy 421.067971 -279.046921)
			(xy 421.044845 -279.094942) (xy 421.014821 -279.138979) (xy 420.978569 -279.17805) (xy 420.936898 -279.211281)
			(xy 420.89074 -279.23793) (xy 420.841126 -279.257402) (xy 420.789164 -279.269262) (xy 420.736014 -279.273246)
			(xy 420.682864 -279.269262) (xy 420.630902 -279.257402) (xy 420.581288 -279.23793) (xy 420.53513 -279.211281)
			(xy 420.493459 -279.17805) (xy 420.457207 -279.138979) (xy 420.427183 -279.094942) (xy 420.404057 -279.046921)
			(xy 420.388347 -278.995991) (xy 420.380404 -278.943287) (xy 407.4668 -278.943287) (xy 407.4668 -279.793425)
			(xy 424.480472 -279.793425) (xy 424.480472 -279.740127) (xy 424.488415 -279.687423) (xy 424.504125 -279.636493)
			(xy 424.527251 -279.588472) (xy 424.557275 -279.544435) (xy 424.593527 -279.505364) (xy 424.635198 -279.472133)
			(xy 424.681356 -279.445484) (xy 424.73097 -279.426012) (xy 424.782932 -279.414152) (xy 424.836082 -279.410169)
			(xy 424.889232 -279.414152) (xy 424.941194 -279.426012) (xy 424.990808 -279.445484) (xy 425.036966 -279.472133)
			(xy 425.078637 -279.505364) (xy 425.114889 -279.544435) (xy 425.144913 -279.588472) (xy 425.168039 -279.636493)
			(xy 425.183749 -279.687423) (xy 425.191692 -279.740127) (xy 425.19219 -279.766776) (xy 425.191692 -279.793425)
			(xy 439.568072 -279.793425) (xy 439.568072 -279.740127) (xy 439.576015 -279.687423) (xy 439.591725 -279.636493)
			(xy 439.614851 -279.588472) (xy 439.644875 -279.544435) (xy 439.681127 -279.505364) (xy 439.722798 -279.472133)
			(xy 439.768956 -279.445484) (xy 439.81857 -279.426012) (xy 439.870532 -279.414152) (xy 439.923682 -279.410169)
			(xy 439.976832 -279.414152) (xy 440.028794 -279.426012) (xy 440.078408 -279.445484) (xy 440.124566 -279.472133)
			(xy 440.166237 -279.505364) (xy 440.202489 -279.544435) (xy 440.232513 -279.588472) (xy 440.255639 -279.636493)
			(xy 440.271349 -279.687423) (xy 440.279292 -279.740127) (xy 440.27979 -279.766776) (xy 440.279292 -279.793425)
			(xy 454.655672 -279.793425) (xy 454.655672 -279.740127) (xy 454.663615 -279.687423) (xy 454.679325 -279.636493)
			(xy 454.702451 -279.588472) (xy 454.732475 -279.544435) (xy 454.768727 -279.505364) (xy 454.810398 -279.472133)
			(xy 454.856556 -279.445484) (xy 454.90617 -279.426012) (xy 454.958132 -279.414152) (xy 455.011282 -279.410169)
			(xy 455.064432 -279.414152) (xy 455.116394 -279.426012) (xy 455.166008 -279.445484) (xy 455.212166 -279.472133)
			(xy 455.253837 -279.505364) (xy 455.290089 -279.544435) (xy 455.320113 -279.588472) (xy 455.343239 -279.636493)
			(xy 455.358949 -279.687423) (xy 455.366892 -279.740127) (xy 455.36739 -279.766776) (xy 455.366892 -279.793425)
			(xy 455.358949 -279.846129) (xy 455.343239 -279.897059) (xy 455.320113 -279.94508) (xy 455.290089 -279.989117)
			(xy 455.253837 -280.028188) (xy 455.212166 -280.061419) (xy 455.166008 -280.088068) (xy 455.116394 -280.10754)
			(xy 455.064432 -280.1194) (xy 455.011282 -280.123384) (xy 454.958132 -280.1194) (xy 454.90617 -280.10754)
			(xy 454.856556 -280.088068) (xy 454.810398 -280.061419) (xy 454.768727 -280.028188) (xy 454.732475 -279.989117)
			(xy 454.702451 -279.94508) (xy 454.679325 -279.897059) (xy 454.663615 -279.846129) (xy 454.655672 -279.793425)
			(xy 440.279292 -279.793425) (xy 440.271349 -279.846129) (xy 440.255639 -279.897059) (xy 440.232513 -279.94508)
			(xy 440.202489 -279.989117) (xy 440.166237 -280.028188) (xy 440.124566 -280.061419) (xy 440.078408 -280.088068)
			(xy 440.028794 -280.10754) (xy 439.976832 -280.1194) (xy 439.923682 -280.123384) (xy 439.870532 -280.1194)
			(xy 439.81857 -280.10754) (xy 439.768956 -280.088068) (xy 439.722798 -280.061419) (xy 439.681127 -280.028188)
			(xy 439.644875 -279.989117) (xy 439.614851 -279.94508) (xy 439.591725 -279.897059) (xy 439.576015 -279.846129)
			(xy 439.568072 -279.793425) (xy 425.191692 -279.793425) (xy 425.183749 -279.846129) (xy 425.168039 -279.897059)
			(xy 425.144913 -279.94508) (xy 425.114889 -279.989117) (xy 425.078637 -280.028188) (xy 425.036966 -280.061419)
			(xy 424.990808 -280.088068) (xy 424.941194 -280.10754) (xy 424.889232 -280.1194) (xy 424.836082 -280.123384)
			(xy 424.782932 -280.1194) (xy 424.73097 -280.10754) (xy 424.681356 -280.088068) (xy 424.635198 -280.061419)
			(xy 424.593527 -280.028188) (xy 424.557275 -279.989117) (xy 424.527251 -279.94508) (xy 424.504125 -279.897059)
			(xy 424.488415 -279.846129) (xy 424.480472 -279.793425) (xy 407.4668 -279.793425) (xy 407.4668 -280.643309)
			(xy 420.380404 -280.643309) (xy 420.380404 -280.590011) (xy 420.388347 -280.537307) (xy 420.404057 -280.486377)
			(xy 420.427183 -280.438356) (xy 420.457207 -280.394319) (xy 420.493459 -280.355248) (xy 420.53513 -280.322017)
			(xy 420.581288 -280.295368) (xy 420.630902 -280.275896) (xy 420.682864 -280.264036) (xy 420.736014 -280.260053)
			(xy 420.789164 -280.264036) (xy 420.841126 -280.275896) (xy 420.89074 -280.295368) (xy 420.936898 -280.322017)
			(xy 420.978569 -280.355248) (xy 421.014821 -280.394319) (xy 421.044845 -280.438356) (xy 421.067971 -280.486377)
			(xy 421.083681 -280.537307) (xy 421.091624 -280.590011) (xy 421.092122 -280.61666) (xy 421.091624 -280.643309)
			(xy 435.468004 -280.643309) (xy 435.468004 -280.590011) (xy 435.475947 -280.537307) (xy 435.491657 -280.486377)
			(xy 435.514783 -280.438356) (xy 435.544807 -280.394319) (xy 435.581059 -280.355248) (xy 435.62273 -280.322017)
			(xy 435.668888 -280.295368) (xy 435.718502 -280.275896) (xy 435.770464 -280.264036) (xy 435.823614 -280.260053)
			(xy 435.876764 -280.264036) (xy 435.928726 -280.275896) (xy 435.97834 -280.295368) (xy 436.024498 -280.322017)
			(xy 436.066169 -280.355248) (xy 436.102421 -280.394319) (xy 436.132445 -280.438356) (xy 436.155571 -280.486377)
			(xy 436.171281 -280.537307) (xy 436.179224 -280.590011) (xy 436.179722 -280.61666) (xy 436.179224 -280.643309)
			(xy 450.555604 -280.643309) (xy 450.555604 -280.590011) (xy 450.563547 -280.537307) (xy 450.579257 -280.486377)
			(xy 450.602383 -280.438356) (xy 450.632407 -280.394319) (xy 450.668659 -280.355248) (xy 450.71033 -280.322017)
			(xy 450.756488 -280.295368) (xy 450.806102 -280.275896) (xy 450.858064 -280.264036) (xy 450.911214 -280.260053)
			(xy 450.964364 -280.264036) (xy 451.016326 -280.275896) (xy 451.06594 -280.295368) (xy 451.112098 -280.322017)
			(xy 451.153769 -280.355248) (xy 451.190021 -280.394319) (xy 451.220045 -280.438356) (xy 451.243171 -280.486377)
			(xy 451.258881 -280.537307) (xy 451.266824 -280.590011) (xy 451.267322 -280.61666) (xy 451.266824 -280.643309)
			(xy 451.258881 -280.696013) (xy 451.243171 -280.746943) (xy 451.220045 -280.794964) (xy 451.190021 -280.839001)
			(xy 451.153769 -280.878072) (xy 451.112098 -280.911303) (xy 451.06594 -280.937952) (xy 451.016326 -280.957424)
			(xy 450.964364 -280.969284) (xy 450.911214 -280.973268) (xy 450.858064 -280.969284) (xy 450.806102 -280.957424)
			(xy 450.756488 -280.937952) (xy 450.71033 -280.911303) (xy 450.668659 -280.878072) (xy 450.632407 -280.839001)
			(xy 450.602383 -280.794964) (xy 450.579257 -280.746943) (xy 450.563547 -280.696013) (xy 450.555604 -280.643309)
			(xy 436.179224 -280.643309) (xy 436.171281 -280.696013) (xy 436.155571 -280.746943) (xy 436.132445 -280.794964)
			(xy 436.102421 -280.839001) (xy 436.066169 -280.878072) (xy 436.024498 -280.911303) (xy 435.97834 -280.937952)
			(xy 435.928726 -280.957424) (xy 435.876764 -280.969284) (xy 435.823614 -280.973268) (xy 435.770464 -280.969284)
			(xy 435.718502 -280.957424) (xy 435.668888 -280.937952) (xy 435.62273 -280.911303) (xy 435.581059 -280.878072)
			(xy 435.544807 -280.839001) (xy 435.514783 -280.794964) (xy 435.491657 -280.746943) (xy 435.475947 -280.696013)
			(xy 435.468004 -280.643309) (xy 421.091624 -280.643309) (xy 421.083681 -280.696013) (xy 421.067971 -280.746943)
			(xy 421.044845 -280.794964) (xy 421.014821 -280.839001) (xy 420.978569 -280.878072) (xy 420.936898 -280.911303)
			(xy 420.89074 -280.937952) (xy 420.841126 -280.957424) (xy 420.789164 -280.969284) (xy 420.736014 -280.973268)
			(xy 420.682864 -280.969284) (xy 420.630902 -280.957424) (xy 420.581288 -280.937952) (xy 420.53513 -280.911303)
			(xy 420.493459 -280.878072) (xy 420.457207 -280.839001) (xy 420.427183 -280.794964) (xy 420.404057 -280.746943)
			(xy 420.388347 -280.696013) (xy 420.380404 -280.643309) (xy 407.4668 -280.643309) (xy 407.4668 -281.493193)
			(xy 424.480472 -281.493193) (xy 424.480472 -281.439895) (xy 424.488415 -281.387191) (xy 424.504125 -281.336261)
			(xy 424.527251 -281.28824) (xy 424.557275 -281.244203) (xy 424.593527 -281.205132) (xy 424.635198 -281.171901)
			(xy 424.681356 -281.145252) (xy 424.73097 -281.12578) (xy 424.782932 -281.11392) (xy 424.836082 -281.109937)
			(xy 424.889232 -281.11392) (xy 424.941194 -281.12578) (xy 424.990808 -281.145252) (xy 425.036966 -281.171901)
			(xy 425.078637 -281.205132) (xy 425.114889 -281.244203) (xy 425.144913 -281.28824) (xy 425.168039 -281.336261)
			(xy 425.183749 -281.387191) (xy 425.191692 -281.439895) (xy 425.19219 -281.466544) (xy 425.191692 -281.493193)
			(xy 425.191654 -281.493447) (xy 439.526162 -281.493447) (xy 439.526162 -281.440149) (xy 439.534105 -281.387445)
			(xy 439.549815 -281.336515) (xy 439.572941 -281.288494) (xy 439.602965 -281.244457) (xy 439.639217 -281.205386)
			(xy 439.680888 -281.172155) (xy 439.727046 -281.145506) (xy 439.77666 -281.126034) (xy 439.828622 -281.114174)
			(xy 439.881772 -281.110191) (xy 439.934922 -281.114174) (xy 439.986884 -281.126034) (xy 440.036498 -281.145506)
			(xy 440.082656 -281.172155) (xy 440.124327 -281.205386) (xy 440.160579 -281.244457) (xy 440.190603 -281.288494)
			(xy 440.213729 -281.336515) (xy 440.229439 -281.387445) (xy 440.237382 -281.440149) (xy 440.23788 -281.466798)
			(xy 440.237387 -281.493193) (xy 454.655672 -281.493193) (xy 454.655672 -281.439895) (xy 454.663615 -281.387191)
			(xy 454.679325 -281.336261) (xy 454.702451 -281.28824) (xy 454.732475 -281.244203) (xy 454.768727 -281.205132)
			(xy 454.810398 -281.171901) (xy 454.856556 -281.145252) (xy 454.90617 -281.12578) (xy 454.958132 -281.11392)
			(xy 455.011282 -281.109937) (xy 455.064432 -281.11392) (xy 455.116394 -281.12578) (xy 455.166008 -281.145252)
			(xy 455.212166 -281.171901) (xy 455.253837 -281.205132) (xy 455.290089 -281.244203) (xy 455.320113 -281.28824)
			(xy 455.343239 -281.336261) (xy 455.358949 -281.387191) (xy 455.366892 -281.439895) (xy 455.36739 -281.466544)
			(xy 455.366892 -281.493193) (xy 455.358949 -281.545897) (xy 455.343239 -281.596827) (xy 455.320113 -281.644848)
			(xy 455.290089 -281.688885) (xy 455.253837 -281.727956) (xy 455.212166 -281.761187) (xy 455.166008 -281.787836)
			(xy 455.116394 -281.807308) (xy 455.064432 -281.819168) (xy 455.011282 -281.823152) (xy 454.958132 -281.819168)
			(xy 454.90617 -281.807308) (xy 454.856556 -281.787836) (xy 454.810398 -281.761187) (xy 454.768727 -281.727956)
			(xy 454.732475 -281.688885) (xy 454.702451 -281.644848) (xy 454.679325 -281.596827) (xy 454.663615 -281.545897)
			(xy 454.655672 -281.493193) (xy 440.237387 -281.493193) (xy 440.237382 -281.493447) (xy 440.229439 -281.546151)
			(xy 440.213729 -281.597081) (xy 440.190603 -281.645102) (xy 440.160579 -281.689139) (xy 440.124327 -281.72821)
			(xy 440.082656 -281.761441) (xy 440.036498 -281.78809) (xy 439.986884 -281.807562) (xy 439.934922 -281.819422)
			(xy 439.881772 -281.823406) (xy 439.828622 -281.819422) (xy 439.77666 -281.807562) (xy 439.727046 -281.78809)
			(xy 439.680888 -281.761441) (xy 439.639217 -281.72821) (xy 439.602965 -281.689139) (xy 439.572941 -281.645102)
			(xy 439.549815 -281.597081) (xy 439.534105 -281.546151) (xy 439.526162 -281.493447) (xy 425.191654 -281.493447)
			(xy 425.183749 -281.545897) (xy 425.168039 -281.596827) (xy 425.144913 -281.644848) (xy 425.114889 -281.688885)
			(xy 425.078637 -281.727956) (xy 425.036966 -281.761187) (xy 424.990808 -281.787836) (xy 424.941194 -281.807308)
			(xy 424.889232 -281.819168) (xy 424.836082 -281.823152) (xy 424.782932 -281.819168) (xy 424.73097 -281.807308)
			(xy 424.681356 -281.787836) (xy 424.635198 -281.761187) (xy 424.593527 -281.727956) (xy 424.557275 -281.688885)
			(xy 424.527251 -281.644848) (xy 424.504125 -281.596827) (xy 424.488415 -281.545897) (xy 424.480472 -281.493193)
			(xy 407.4668 -281.493193) (xy 407.4668 -282.343331) (xy 420.380404 -282.343331) (xy 420.380404 -282.290033)
			(xy 420.388347 -282.237329) (xy 420.404057 -282.186399) (xy 420.427183 -282.138378) (xy 420.457207 -282.094341)
			(xy 420.493459 -282.05527) (xy 420.53513 -282.022039) (xy 420.581288 -281.99539) (xy 420.630902 -281.975918)
			(xy 420.682864 -281.964058) (xy 420.736014 -281.960075) (xy 420.789164 -281.964058) (xy 420.841126 -281.975918)
			(xy 420.89074 -281.99539) (xy 420.936898 -282.022039) (xy 420.978569 -282.05527) (xy 421.014821 -282.094341)
			(xy 421.044845 -282.138378) (xy 421.067971 -282.186399) (xy 421.083681 -282.237329) (xy 421.091624 -282.290033)
			(xy 421.092122 -282.316682) (xy 421.091624 -282.343331) (xy 435.468004 -282.343331) (xy 435.468004 -282.290033)
			(xy 435.475947 -282.237329) (xy 435.491657 -282.186399) (xy 435.514783 -282.138378) (xy 435.544807 -282.094341)
			(xy 435.581059 -282.05527) (xy 435.62273 -282.022039) (xy 435.668888 -281.99539) (xy 435.718502 -281.975918)
			(xy 435.770464 -281.964058) (xy 435.823614 -281.960075) (xy 435.876764 -281.964058) (xy 435.928726 -281.975918)
			(xy 435.97834 -281.99539) (xy 436.024498 -282.022039) (xy 436.066169 -282.05527) (xy 436.102421 -282.094341)
			(xy 436.132445 -282.138378) (xy 436.155571 -282.186399) (xy 436.171281 -282.237329) (xy 436.179224 -282.290033)
			(xy 436.179722 -282.316682) (xy 436.179224 -282.343331) (xy 450.555604 -282.343331) (xy 450.555604 -282.290033)
			(xy 450.563547 -282.237329) (xy 450.579257 -282.186399) (xy 450.602383 -282.138378) (xy 450.632407 -282.094341)
			(xy 450.668659 -282.05527) (xy 450.71033 -282.022039) (xy 450.756488 -281.99539) (xy 450.806102 -281.975918)
			(xy 450.858064 -281.964058) (xy 450.911214 -281.960075) (xy 450.964364 -281.964058) (xy 451.016326 -281.975918)
			(xy 451.06594 -281.99539) (xy 451.112098 -282.022039) (xy 451.153769 -282.05527) (xy 451.190021 -282.094341)
			(xy 451.220045 -282.138378) (xy 451.243171 -282.186399) (xy 451.258881 -282.237329) (xy 451.266824 -282.290033)
			(xy 451.267322 -282.316682) (xy 451.266824 -282.343331) (xy 451.258881 -282.396035) (xy 451.243171 -282.446965)
			(xy 451.220045 -282.494986) (xy 451.190021 -282.539023) (xy 451.153769 -282.578094) (xy 451.112098 -282.611325)
			(xy 451.06594 -282.637974) (xy 451.016326 -282.657446) (xy 450.964364 -282.669306) (xy 450.911214 -282.67329)
			(xy 450.858064 -282.669306) (xy 450.806102 -282.657446) (xy 450.756488 -282.637974) (xy 450.71033 -282.611325)
			(xy 450.668659 -282.578094) (xy 450.632407 -282.539023) (xy 450.602383 -282.494986) (xy 450.579257 -282.446965)
			(xy 450.563547 -282.396035) (xy 450.555604 -282.343331) (xy 436.179224 -282.343331) (xy 436.171281 -282.396035)
			(xy 436.155571 -282.446965) (xy 436.132445 -282.494986) (xy 436.102421 -282.539023) (xy 436.066169 -282.578094)
			(xy 436.024498 -282.611325) (xy 435.97834 -282.637974) (xy 435.928726 -282.657446) (xy 435.876764 -282.669306)
			(xy 435.823614 -282.67329) (xy 435.770464 -282.669306) (xy 435.718502 -282.657446) (xy 435.668888 -282.637974)
			(xy 435.62273 -282.611325) (xy 435.581059 -282.578094) (xy 435.544807 -282.539023) (xy 435.514783 -282.494986)
			(xy 435.491657 -282.446965) (xy 435.475947 -282.396035) (xy 435.468004 -282.343331) (xy 421.091624 -282.343331)
			(xy 421.083681 -282.396035) (xy 421.067971 -282.446965) (xy 421.044845 -282.494986) (xy 421.014821 -282.539023)
			(xy 420.978569 -282.578094) (xy 420.936898 -282.611325) (xy 420.89074 -282.637974) (xy 420.841126 -282.657446)
			(xy 420.789164 -282.669306) (xy 420.736014 -282.67329) (xy 420.682864 -282.669306) (xy 420.630902 -282.657446)
			(xy 420.581288 -282.637974) (xy 420.53513 -282.611325) (xy 420.493459 -282.578094) (xy 420.457207 -282.539023)
			(xy 420.427183 -282.494986) (xy 420.404057 -282.446965) (xy 420.388347 -282.396035) (xy 420.380404 -282.343331)
			(xy 407.4668 -282.343331) (xy 407.4668 -283.193215) (xy 424.480472 -283.193215) (xy 424.480472 -283.139917)
			(xy 424.488415 -283.087213) (xy 424.504125 -283.036283) (xy 424.527251 -282.988262) (xy 424.557275 -282.944225)
			(xy 424.593527 -282.905154) (xy 424.635198 -282.871923) (xy 424.681356 -282.845274) (xy 424.73097 -282.825802)
			(xy 424.782932 -282.813942) (xy 424.836082 -282.809959) (xy 424.889232 -282.813942) (xy 424.941194 -282.825802)
			(xy 424.990808 -282.845274) (xy 425.036966 -282.871923) (xy 425.078637 -282.905154) (xy 425.114889 -282.944225)
			(xy 425.144913 -282.988262) (xy 425.168039 -283.036283) (xy 425.183749 -283.087213) (xy 425.191692 -283.139917)
			(xy 425.19219 -283.166566) (xy 425.191692 -283.193215) (xy 439.568072 -283.193215) (xy 439.568072 -283.139917)
			(xy 439.576015 -283.087213) (xy 439.591725 -283.036283) (xy 439.614851 -282.988262) (xy 439.644875 -282.944225)
			(xy 439.681127 -282.905154) (xy 439.722798 -282.871923) (xy 439.768956 -282.845274) (xy 439.81857 -282.825802)
			(xy 439.870532 -282.813942) (xy 439.923682 -282.809959) (xy 439.976832 -282.813942) (xy 440.028794 -282.825802)
			(xy 440.078408 -282.845274) (xy 440.124566 -282.871923) (xy 440.166237 -282.905154) (xy 440.202489 -282.944225)
			(xy 440.232513 -282.988262) (xy 440.255639 -283.036283) (xy 440.271349 -283.087213) (xy 440.279292 -283.139917)
			(xy 440.27979 -283.166566) (xy 440.279292 -283.193215) (xy 454.655672 -283.193215) (xy 454.655672 -283.139917)
			(xy 454.663615 -283.087213) (xy 454.679325 -283.036283) (xy 454.702451 -282.988262) (xy 454.732475 -282.944225)
			(xy 454.768727 -282.905154) (xy 454.810398 -282.871923) (xy 454.856556 -282.845274) (xy 454.90617 -282.825802)
			(xy 454.958132 -282.813942) (xy 455.011282 -282.809959) (xy 455.064432 -282.813942) (xy 455.116394 -282.825802)
			(xy 455.166008 -282.845274) (xy 455.212166 -282.871923) (xy 455.253837 -282.905154) (xy 455.290089 -282.944225)
			(xy 455.320113 -282.988262) (xy 455.343239 -283.036283) (xy 455.358949 -283.087213) (xy 455.366892 -283.139917)
			(xy 455.36739 -283.166566) (xy 455.366892 -283.193215) (xy 455.358949 -283.245919) (xy 455.343239 -283.296849)
			(xy 455.320113 -283.34487) (xy 455.290089 -283.388907) (xy 455.253837 -283.427978) (xy 455.212166 -283.461209)
			(xy 455.166008 -283.487858) (xy 455.116394 -283.50733) (xy 455.064432 -283.51919) (xy 455.011282 -283.523174)
			(xy 454.958132 -283.51919) (xy 454.90617 -283.50733) (xy 454.856556 -283.487858) (xy 454.810398 -283.461209)
			(xy 454.768727 -283.427978) (xy 454.732475 -283.388907) (xy 454.702451 -283.34487) (xy 454.679325 -283.296849)
			(xy 454.663615 -283.245919) (xy 454.655672 -283.193215) (xy 440.279292 -283.193215) (xy 440.271349 -283.245919)
			(xy 440.255639 -283.296849) (xy 440.232513 -283.34487) (xy 440.202489 -283.388907) (xy 440.166237 -283.427978)
			(xy 440.124566 -283.461209) (xy 440.078408 -283.487858) (xy 440.028794 -283.50733) (xy 439.976832 -283.51919)
			(xy 439.923682 -283.523174) (xy 439.870532 -283.51919) (xy 439.81857 -283.50733) (xy 439.768956 -283.487858)
			(xy 439.722798 -283.461209) (xy 439.681127 -283.427978) (xy 439.644875 -283.388907) (xy 439.614851 -283.34487)
			(xy 439.591725 -283.296849) (xy 439.576015 -283.245919) (xy 439.568072 -283.193215) (xy 425.191692 -283.193215)
			(xy 425.183749 -283.245919) (xy 425.168039 -283.296849) (xy 425.144913 -283.34487) (xy 425.114889 -283.388907)
			(xy 425.078637 -283.427978) (xy 425.036966 -283.461209) (xy 424.990808 -283.487858) (xy 424.941194 -283.50733)
			(xy 424.889232 -283.51919) (xy 424.836082 -283.523174) (xy 424.782932 -283.51919) (xy 424.73097 -283.50733)
			(xy 424.681356 -283.487858) (xy 424.635198 -283.461209) (xy 424.593527 -283.427978) (xy 424.557275 -283.388907)
			(xy 424.527251 -283.34487) (xy 424.504125 -283.296849) (xy 424.488415 -283.245919) (xy 424.480472 -283.193215)
			(xy 407.4668 -283.193215) (xy 407.4668 -284.043353) (xy 420.380404 -284.043353) (xy 420.380404 -283.990055)
			(xy 420.388347 -283.937351) (xy 420.404057 -283.886421) (xy 420.427183 -283.8384) (xy 420.457207 -283.794363)
			(xy 420.493459 -283.755292) (xy 420.53513 -283.722061) (xy 420.581288 -283.695412) (xy 420.630902 -283.67594)
			(xy 420.682864 -283.66408) (xy 420.736014 -283.660097) (xy 420.789164 -283.66408) (xy 420.841126 -283.67594)
			(xy 420.89074 -283.695412) (xy 420.936898 -283.722061) (xy 420.978569 -283.755292) (xy 421.014821 -283.794363)
			(xy 421.044845 -283.8384) (xy 421.067971 -283.886421) (xy 421.083681 -283.937351) (xy 421.091624 -283.990055)
			(xy 421.092122 -284.016704) (xy 421.091624 -284.043353) (xy 424.480472 -284.043353) (xy 424.480472 -283.990055)
			(xy 424.488415 -283.937351) (xy 424.504125 -283.886421) (xy 424.527251 -283.8384) (xy 424.557275 -283.794363)
			(xy 424.593527 -283.755292) (xy 424.635198 -283.722061) (xy 424.681356 -283.695412) (xy 424.73097 -283.67594)
			(xy 424.782932 -283.66408) (xy 424.836082 -283.660097) (xy 424.889232 -283.66408) (xy 424.941194 -283.67594)
			(xy 424.990808 -283.695412) (xy 425.036966 -283.722061) (xy 425.078637 -283.755292) (xy 425.114889 -283.794363)
			(xy 425.144913 -283.8384) (xy 425.168039 -283.886421) (xy 425.183749 -283.937351) (xy 425.191692 -283.990055)
			(xy 425.19219 -284.016704) (xy 425.191692 -284.043353) (xy 435.468004 -284.043353) (xy 435.468004 -283.990055)
			(xy 435.475947 -283.937351) (xy 435.491657 -283.886421) (xy 435.514783 -283.8384) (xy 435.544807 -283.794363)
			(xy 435.581059 -283.755292) (xy 435.62273 -283.722061) (xy 435.668888 -283.695412) (xy 435.718502 -283.67594)
			(xy 435.770464 -283.66408) (xy 435.823614 -283.660097) (xy 435.876764 -283.66408) (xy 435.928726 -283.67594)
			(xy 435.97834 -283.695412) (xy 436.024498 -283.722061) (xy 436.066169 -283.755292) (xy 436.102421 -283.794363)
			(xy 436.132445 -283.8384) (xy 436.155571 -283.886421) (xy 436.171281 -283.937351) (xy 436.179224 -283.990055)
			(xy 436.179722 -284.016704) (xy 436.179224 -284.043353) (xy 439.568072 -284.043353) (xy 439.568072 -283.990055)
			(xy 439.576015 -283.937351) (xy 439.591725 -283.886421) (xy 439.614851 -283.8384) (xy 439.644875 -283.794363)
			(xy 439.681127 -283.755292) (xy 439.722798 -283.722061) (xy 439.768956 -283.695412) (xy 439.81857 -283.67594)
			(xy 439.870532 -283.66408) (xy 439.923682 -283.660097) (xy 439.976832 -283.66408) (xy 440.028794 -283.67594)
			(xy 440.078408 -283.695412) (xy 440.124566 -283.722061) (xy 440.166237 -283.755292) (xy 440.202489 -283.794363)
			(xy 440.232513 -283.8384) (xy 440.255639 -283.886421) (xy 440.271349 -283.937351) (xy 440.279292 -283.990055)
			(xy 440.27979 -284.016704) (xy 440.279292 -284.043353) (xy 450.555604 -284.043353) (xy 450.555604 -283.990055)
			(xy 450.563547 -283.937351) (xy 450.579257 -283.886421) (xy 450.602383 -283.8384) (xy 450.632407 -283.794363)
			(xy 450.668659 -283.755292) (xy 450.71033 -283.722061) (xy 450.756488 -283.695412) (xy 450.806102 -283.67594)
			(xy 450.858064 -283.66408) (xy 450.911214 -283.660097) (xy 450.964364 -283.66408) (xy 451.016326 -283.67594)
			(xy 451.06594 -283.695412) (xy 451.112098 -283.722061) (xy 451.153769 -283.755292) (xy 451.190021 -283.794363)
			(xy 451.220045 -283.8384) (xy 451.243171 -283.886421) (xy 451.258881 -283.937351) (xy 451.266824 -283.990055)
			(xy 451.267322 -284.016704) (xy 451.266824 -284.043353) (xy 454.655672 -284.043353) (xy 454.655672 -283.990055)
			(xy 454.663615 -283.937351) (xy 454.679325 -283.886421) (xy 454.702451 -283.8384) (xy 454.732475 -283.794363)
			(xy 454.768727 -283.755292) (xy 454.810398 -283.722061) (xy 454.856556 -283.695412) (xy 454.90617 -283.67594)
			(xy 454.958132 -283.66408) (xy 455.011282 -283.660097) (xy 455.064432 -283.66408) (xy 455.116394 -283.67594)
			(xy 455.166008 -283.695412) (xy 455.212166 -283.722061) (xy 455.253837 -283.755292) (xy 455.290089 -283.794363)
			(xy 455.320113 -283.8384) (xy 455.343239 -283.886421) (xy 455.358949 -283.937351) (xy 455.366892 -283.990055)
			(xy 455.36739 -284.016704) (xy 455.366892 -284.043353) (xy 455.358949 -284.096057) (xy 455.343239 -284.146987)
			(xy 455.320113 -284.195008) (xy 455.290089 -284.239045) (xy 455.253837 -284.278116) (xy 455.212166 -284.311347)
			(xy 455.166008 -284.337996) (xy 455.116394 -284.357468) (xy 455.064432 -284.369328) (xy 455.011282 -284.373312)
			(xy 454.958132 -284.369328) (xy 454.90617 -284.357468) (xy 454.856556 -284.337996) (xy 454.810398 -284.311347)
			(xy 454.768727 -284.278116) (xy 454.732475 -284.239045) (xy 454.702451 -284.195008) (xy 454.679325 -284.146987)
			(xy 454.663615 -284.096057) (xy 454.655672 -284.043353) (xy 451.266824 -284.043353) (xy 451.258881 -284.096057)
			(xy 451.243171 -284.146987) (xy 451.220045 -284.195008) (xy 451.190021 -284.239045) (xy 451.153769 -284.278116)
			(xy 451.112098 -284.311347) (xy 451.06594 -284.337996) (xy 451.016326 -284.357468) (xy 450.964364 -284.369328)
			(xy 450.911214 -284.373312) (xy 450.858064 -284.369328) (xy 450.806102 -284.357468) (xy 450.756488 -284.337996)
			(xy 450.71033 -284.311347) (xy 450.668659 -284.278116) (xy 450.632407 -284.239045) (xy 450.602383 -284.195008)
			(xy 450.579257 -284.146987) (xy 450.563547 -284.096057) (xy 450.555604 -284.043353) (xy 440.279292 -284.043353)
			(xy 440.271349 -284.096057) (xy 440.255639 -284.146987) (xy 440.232513 -284.195008) (xy 440.202489 -284.239045)
			(xy 440.166237 -284.278116) (xy 440.124566 -284.311347) (xy 440.078408 -284.337996) (xy 440.028794 -284.357468)
			(xy 439.976832 -284.369328) (xy 439.923682 -284.373312) (xy 439.870532 -284.369328) (xy 439.81857 -284.357468)
			(xy 439.768956 -284.337996) (xy 439.722798 -284.311347) (xy 439.681127 -284.278116) (xy 439.644875 -284.239045)
			(xy 439.614851 -284.195008) (xy 439.591725 -284.146987) (xy 439.576015 -284.096057) (xy 439.568072 -284.043353)
			(xy 436.179224 -284.043353) (xy 436.171281 -284.096057) (xy 436.155571 -284.146987) (xy 436.132445 -284.195008)
			(xy 436.102421 -284.239045) (xy 436.066169 -284.278116) (xy 436.024498 -284.311347) (xy 435.97834 -284.337996)
			(xy 435.928726 -284.357468) (xy 435.876764 -284.369328) (xy 435.823614 -284.373312) (xy 435.770464 -284.369328)
			(xy 435.718502 -284.357468) (xy 435.668888 -284.337996) (xy 435.62273 -284.311347) (xy 435.581059 -284.278116)
			(xy 435.544807 -284.239045) (xy 435.514783 -284.195008) (xy 435.491657 -284.146987) (xy 435.475947 -284.096057)
			(xy 435.468004 -284.043353) (xy 425.191692 -284.043353) (xy 425.183749 -284.096057) (xy 425.168039 -284.146987)
			(xy 425.144913 -284.195008) (xy 425.114889 -284.239045) (xy 425.078637 -284.278116) (xy 425.036966 -284.311347)
			(xy 424.990808 -284.337996) (xy 424.941194 -284.357468) (xy 424.889232 -284.369328) (xy 424.836082 -284.373312)
			(xy 424.782932 -284.369328) (xy 424.73097 -284.357468) (xy 424.681356 -284.337996) (xy 424.635198 -284.311347)
			(xy 424.593527 -284.278116) (xy 424.557275 -284.239045) (xy 424.527251 -284.195008) (xy 424.504125 -284.146987)
			(xy 424.488415 -284.096057) (xy 424.480472 -284.043353) (xy 421.091624 -284.043353) (xy 421.083681 -284.096057)
			(xy 421.067971 -284.146987) (xy 421.044845 -284.195008) (xy 421.014821 -284.239045) (xy 420.978569 -284.278116)
			(xy 420.936898 -284.311347) (xy 420.89074 -284.337996) (xy 420.841126 -284.357468) (xy 420.789164 -284.369328)
			(xy 420.736014 -284.373312) (xy 420.682864 -284.369328) (xy 420.630902 -284.357468) (xy 420.581288 -284.337996)
			(xy 420.53513 -284.311347) (xy 420.493459 -284.278116) (xy 420.457207 -284.239045) (xy 420.427183 -284.195008)
			(xy 420.404057 -284.146987) (xy 420.388347 -284.096057) (xy 420.380404 -284.043353) (xy 407.4668 -284.043353)
			(xy 407.4668 -284.893237) (xy 420.380404 -284.893237) (xy 420.380404 -284.839939) (xy 420.388347 -284.787235)
			(xy 420.404057 -284.736305) (xy 420.427183 -284.688284) (xy 420.457207 -284.644247) (xy 420.493459 -284.605176)
			(xy 420.53513 -284.571945) (xy 420.581288 -284.545296) (xy 420.630902 -284.525824) (xy 420.682864 -284.513964)
			(xy 420.736014 -284.509981) (xy 420.789164 -284.513964) (xy 420.841126 -284.525824) (xy 420.89074 -284.545296)
			(xy 420.936898 -284.571945) (xy 420.978569 -284.605176) (xy 421.014821 -284.644247) (xy 421.044845 -284.688284)
			(xy 421.067971 -284.736305) (xy 421.083681 -284.787235) (xy 421.091624 -284.839939) (xy 421.092122 -284.866588)
			(xy 421.091624 -284.893237) (xy 435.468004 -284.893237) (xy 435.468004 -284.839939) (xy 435.475947 -284.787235)
			(xy 435.491657 -284.736305) (xy 435.514783 -284.688284) (xy 435.544807 -284.644247) (xy 435.581059 -284.605176)
			(xy 435.62273 -284.571945) (xy 435.668888 -284.545296) (xy 435.718502 -284.525824) (xy 435.770464 -284.513964)
			(xy 435.823614 -284.509981) (xy 435.876764 -284.513964) (xy 435.928726 -284.525824) (xy 435.97834 -284.545296)
			(xy 436.024498 -284.571945) (xy 436.066169 -284.605176) (xy 436.102421 -284.644247) (xy 436.132445 -284.688284)
			(xy 436.155571 -284.736305) (xy 436.171281 -284.787235) (xy 436.179224 -284.839939) (xy 436.179722 -284.866588)
			(xy 436.179224 -284.893237) (xy 450.555604 -284.893237) (xy 450.555604 -284.839939) (xy 450.563547 -284.787235)
			(xy 450.579257 -284.736305) (xy 450.602383 -284.688284) (xy 450.632407 -284.644247) (xy 450.668659 -284.605176)
			(xy 450.71033 -284.571945) (xy 450.756488 -284.545296) (xy 450.806102 -284.525824) (xy 450.858064 -284.513964)
			(xy 450.911214 -284.509981) (xy 450.964364 -284.513964) (xy 451.016326 -284.525824) (xy 451.06594 -284.545296)
			(xy 451.112098 -284.571945) (xy 451.153769 -284.605176) (xy 451.190021 -284.644247) (xy 451.220045 -284.688284)
			(xy 451.243171 -284.736305) (xy 451.258881 -284.787235) (xy 451.266824 -284.839939) (xy 451.267322 -284.866588)
			(xy 451.266824 -284.893237) (xy 451.258881 -284.945941) (xy 451.243171 -284.996871) (xy 451.220045 -285.044892)
			(xy 451.190021 -285.088929) (xy 451.153769 -285.128) (xy 451.112098 -285.161231) (xy 451.06594 -285.18788)
			(xy 451.016326 -285.207352) (xy 450.964364 -285.219212) (xy 450.911214 -285.223196) (xy 450.858064 -285.219212)
			(xy 450.806102 -285.207352) (xy 450.756488 -285.18788) (xy 450.71033 -285.161231) (xy 450.668659 -285.128)
			(xy 450.632407 -285.088929) (xy 450.602383 -285.044892) (xy 450.579257 -284.996871) (xy 450.563547 -284.945941)
			(xy 450.555604 -284.893237) (xy 436.179224 -284.893237) (xy 436.171281 -284.945941) (xy 436.155571 -284.996871)
			(xy 436.132445 -285.044892) (xy 436.102421 -285.088929) (xy 436.066169 -285.128) (xy 436.024498 -285.161231)
			(xy 435.97834 -285.18788) (xy 435.928726 -285.207352) (xy 435.876764 -285.219212) (xy 435.823614 -285.223196)
			(xy 435.770464 -285.219212) (xy 435.718502 -285.207352) (xy 435.668888 -285.18788) (xy 435.62273 -285.161231)
			(xy 435.581059 -285.128) (xy 435.544807 -285.088929) (xy 435.514783 -285.044892) (xy 435.491657 -284.996871)
			(xy 435.475947 -284.945941) (xy 435.468004 -284.893237) (xy 421.091624 -284.893237) (xy 421.083681 -284.945941)
			(xy 421.067971 -284.996871) (xy 421.044845 -285.044892) (xy 421.014821 -285.088929) (xy 420.978569 -285.128)
			(xy 420.936898 -285.161231) (xy 420.89074 -285.18788) (xy 420.841126 -285.207352) (xy 420.789164 -285.219212)
			(xy 420.736014 -285.223196) (xy 420.682864 -285.219212) (xy 420.630902 -285.207352) (xy 420.581288 -285.18788)
			(xy 420.53513 -285.161231) (xy 420.493459 -285.128) (xy 420.457207 -285.088929) (xy 420.427183 -285.044892)
			(xy 420.404057 -284.996871) (xy 420.388347 -284.945941) (xy 420.380404 -284.893237) (xy 407.4668 -284.893237)
			(xy 407.4668 -285.743375) (xy 424.480472 -285.743375) (xy 424.480472 -285.690077) (xy 424.488415 -285.637373)
			(xy 424.504125 -285.586443) (xy 424.527251 -285.538422) (xy 424.557275 -285.494385) (xy 424.593527 -285.455314)
			(xy 424.635198 -285.422083) (xy 424.681356 -285.395434) (xy 424.73097 -285.375962) (xy 424.782932 -285.364102)
			(xy 424.836082 -285.360119) (xy 424.889232 -285.364102) (xy 424.941194 -285.375962) (xy 424.990808 -285.395434)
			(xy 425.036966 -285.422083) (xy 425.078637 -285.455314) (xy 425.114889 -285.494385) (xy 425.144913 -285.538422)
			(xy 425.168039 -285.586443) (xy 425.183749 -285.637373) (xy 425.191692 -285.690077) (xy 425.19219 -285.716726)
			(xy 425.191692 -285.743375) (xy 439.568072 -285.743375) (xy 439.568072 -285.690077) (xy 439.576015 -285.637373)
			(xy 439.591725 -285.586443) (xy 439.614851 -285.538422) (xy 439.644875 -285.494385) (xy 439.681127 -285.455314)
			(xy 439.722798 -285.422083) (xy 439.768956 -285.395434) (xy 439.81857 -285.375962) (xy 439.870532 -285.364102)
			(xy 439.923682 -285.360119) (xy 439.976832 -285.364102) (xy 440.028794 -285.375962) (xy 440.078408 -285.395434)
			(xy 440.124566 -285.422083) (xy 440.166237 -285.455314) (xy 440.202489 -285.494385) (xy 440.232513 -285.538422)
			(xy 440.255639 -285.586443) (xy 440.271349 -285.637373) (xy 440.279292 -285.690077) (xy 440.27979 -285.716726)
			(xy 440.279292 -285.743375) (xy 454.655672 -285.743375) (xy 454.655672 -285.690077) (xy 454.663615 -285.637373)
			(xy 454.679325 -285.586443) (xy 454.702451 -285.538422) (xy 454.732475 -285.494385) (xy 454.768727 -285.455314)
			(xy 454.810398 -285.422083) (xy 454.856556 -285.395434) (xy 454.90617 -285.375962) (xy 454.958132 -285.364102)
			(xy 455.011282 -285.360119) (xy 455.064432 -285.364102) (xy 455.116394 -285.375962) (xy 455.166008 -285.395434)
			(xy 455.212166 -285.422083) (xy 455.253837 -285.455314) (xy 455.290089 -285.494385) (xy 455.320113 -285.538422)
			(xy 455.343239 -285.586443) (xy 455.358949 -285.637373) (xy 455.366892 -285.690077) (xy 455.36739 -285.716726)
			(xy 455.366892 -285.743375) (xy 455.358949 -285.796079) (xy 455.343239 -285.847009) (xy 455.320113 -285.89503)
			(xy 455.290089 -285.939067) (xy 455.253837 -285.978138) (xy 455.212166 -286.011369) (xy 455.166008 -286.038018)
			(xy 455.116394 -286.05749) (xy 455.064432 -286.06935) (xy 455.011282 -286.073334) (xy 454.958132 -286.06935)
			(xy 454.90617 -286.05749) (xy 454.856556 -286.038018) (xy 454.810398 -286.011369) (xy 454.768727 -285.978138)
			(xy 454.732475 -285.939067) (xy 454.702451 -285.89503) (xy 454.679325 -285.847009) (xy 454.663615 -285.796079)
			(xy 454.655672 -285.743375) (xy 440.279292 -285.743375) (xy 440.271349 -285.796079) (xy 440.255639 -285.847009)
			(xy 440.232513 -285.89503) (xy 440.202489 -285.939067) (xy 440.166237 -285.978138) (xy 440.124566 -286.011369)
			(xy 440.078408 -286.038018) (xy 440.028794 -286.05749) (xy 439.976832 -286.06935) (xy 439.923682 -286.073334)
			(xy 439.870532 -286.06935) (xy 439.81857 -286.05749) (xy 439.768956 -286.038018) (xy 439.722798 -286.011369)
			(xy 439.681127 -285.978138) (xy 439.644875 -285.939067) (xy 439.614851 -285.89503) (xy 439.591725 -285.847009)
			(xy 439.576015 -285.796079) (xy 439.568072 -285.743375) (xy 425.191692 -285.743375) (xy 425.183749 -285.796079)
			(xy 425.168039 -285.847009) (xy 425.144913 -285.89503) (xy 425.114889 -285.939067) (xy 425.078637 -285.978138)
			(xy 425.036966 -286.011369) (xy 424.990808 -286.038018) (xy 424.941194 -286.05749) (xy 424.889232 -286.06935)
			(xy 424.836082 -286.073334) (xy 424.782932 -286.06935) (xy 424.73097 -286.05749) (xy 424.681356 -286.038018)
			(xy 424.635198 -286.011369) (xy 424.593527 -285.978138) (xy 424.557275 -285.939067) (xy 424.527251 -285.89503)
			(xy 424.504125 -285.847009) (xy 424.488415 -285.796079) (xy 424.480472 -285.743375) (xy 407.4668 -285.743375)
			(xy 407.4668 -286.593259) (xy 420.380404 -286.593259) (xy 420.380404 -286.539961) (xy 420.388347 -286.487257)
			(xy 420.404057 -286.436327) (xy 420.427183 -286.388306) (xy 420.457207 -286.344269) (xy 420.493459 -286.305198)
			(xy 420.53513 -286.271967) (xy 420.581288 -286.245318) (xy 420.630902 -286.225846) (xy 420.682864 -286.213986)
			(xy 420.736014 -286.210003) (xy 420.789164 -286.213986) (xy 420.841126 -286.225846) (xy 420.89074 -286.245318)
			(xy 420.936898 -286.271967) (xy 420.978569 -286.305198) (xy 421.014821 -286.344269) (xy 421.044845 -286.388306)
			(xy 421.067971 -286.436327) (xy 421.083681 -286.487257) (xy 421.091624 -286.539961) (xy 421.092122 -286.56661)
			(xy 421.091624 -286.593259) (xy 435.468004 -286.593259) (xy 435.468004 -286.539961) (xy 435.475947 -286.487257)
			(xy 435.491657 -286.436327) (xy 435.514783 -286.388306) (xy 435.544807 -286.344269) (xy 435.581059 -286.305198)
			(xy 435.62273 -286.271967) (xy 435.668888 -286.245318) (xy 435.718502 -286.225846) (xy 435.770464 -286.213986)
			(xy 435.823614 -286.210003) (xy 435.876764 -286.213986) (xy 435.928726 -286.225846) (xy 435.97834 -286.245318)
			(xy 436.024498 -286.271967) (xy 436.066169 -286.305198) (xy 436.102421 -286.344269) (xy 436.132445 -286.388306)
			(xy 436.155571 -286.436327) (xy 436.171281 -286.487257) (xy 436.179224 -286.539961) (xy 436.179722 -286.56661)
			(xy 436.179224 -286.593259) (xy 450.555604 -286.593259) (xy 450.555604 -286.539961) (xy 450.563547 -286.487257)
			(xy 450.579257 -286.436327) (xy 450.602383 -286.388306) (xy 450.632407 -286.344269) (xy 450.668659 -286.305198)
			(xy 450.71033 -286.271967) (xy 450.756488 -286.245318) (xy 450.806102 -286.225846) (xy 450.858064 -286.213986)
			(xy 450.911214 -286.210003) (xy 450.964364 -286.213986) (xy 451.016326 -286.225846) (xy 451.06594 -286.245318)
			(xy 451.112098 -286.271967) (xy 451.153769 -286.305198) (xy 451.190021 -286.344269) (xy 451.220045 -286.388306)
			(xy 451.243171 -286.436327) (xy 451.258881 -286.487257) (xy 451.266824 -286.539961) (xy 451.267322 -286.56661)
			(xy 451.266824 -286.593259) (xy 451.258881 -286.645963) (xy 451.243171 -286.696893) (xy 451.220045 -286.744914)
			(xy 451.190021 -286.788951) (xy 451.153769 -286.828022) (xy 451.112098 -286.861253) (xy 451.06594 -286.887902)
			(xy 451.016326 -286.907374) (xy 450.964364 -286.919234) (xy 450.911214 -286.923218) (xy 450.858064 -286.919234)
			(xy 450.806102 -286.907374) (xy 450.756488 -286.887902) (xy 450.71033 -286.861253) (xy 450.668659 -286.828022)
			(xy 450.632407 -286.788951) (xy 450.602383 -286.744914) (xy 450.579257 -286.696893) (xy 450.563547 -286.645963)
			(xy 450.555604 -286.593259) (xy 436.179224 -286.593259) (xy 436.171281 -286.645963) (xy 436.155571 -286.696893)
			(xy 436.132445 -286.744914) (xy 436.102421 -286.788951) (xy 436.066169 -286.828022) (xy 436.024498 -286.861253)
			(xy 435.97834 -286.887902) (xy 435.928726 -286.907374) (xy 435.876764 -286.919234) (xy 435.823614 -286.923218)
			(xy 435.770464 -286.919234) (xy 435.718502 -286.907374) (xy 435.668888 -286.887902) (xy 435.62273 -286.861253)
			(xy 435.581059 -286.828022) (xy 435.544807 -286.788951) (xy 435.514783 -286.744914) (xy 435.491657 -286.696893)
			(xy 435.475947 -286.645963) (xy 435.468004 -286.593259) (xy 421.091624 -286.593259) (xy 421.083681 -286.645963)
			(xy 421.067971 -286.696893) (xy 421.044845 -286.744914) (xy 421.014821 -286.788951) (xy 420.978569 -286.828022)
			(xy 420.936898 -286.861253) (xy 420.89074 -286.887902) (xy 420.841126 -286.907374) (xy 420.789164 -286.919234)
			(xy 420.736014 -286.923218) (xy 420.682864 -286.919234) (xy 420.630902 -286.907374) (xy 420.581288 -286.887902)
			(xy 420.53513 -286.861253) (xy 420.493459 -286.828022) (xy 420.457207 -286.788951) (xy 420.427183 -286.744914)
			(xy 420.404057 -286.696893) (xy 420.388347 -286.645963) (xy 420.380404 -286.593259) (xy 407.4668 -286.593259)
			(xy 407.4668 -287.443397) (xy 424.480472 -287.443397) (xy 424.480472 -287.390099) (xy 424.488415 -287.337395)
			(xy 424.504125 -287.286465) (xy 424.527251 -287.238444) (xy 424.557275 -287.194407) (xy 424.593527 -287.155336)
			(xy 424.635198 -287.122105) (xy 424.681356 -287.095456) (xy 424.73097 -287.075984) (xy 424.782932 -287.064124)
			(xy 424.836082 -287.060141) (xy 424.889232 -287.064124) (xy 424.941194 -287.075984) (xy 424.990808 -287.095456)
			(xy 425.036966 -287.122105) (xy 425.078637 -287.155336) (xy 425.114889 -287.194407) (xy 425.144913 -287.238444)
			(xy 425.168039 -287.286465) (xy 425.183749 -287.337395) (xy 425.191692 -287.390099) (xy 425.19219 -287.416748)
			(xy 425.191692 -287.443397) (xy 439.568072 -287.443397) (xy 439.568072 -287.390099) (xy 439.576015 -287.337395)
			(xy 439.591725 -287.286465) (xy 439.614851 -287.238444) (xy 439.644875 -287.194407) (xy 439.681127 -287.155336)
			(xy 439.722798 -287.122105) (xy 439.768956 -287.095456) (xy 439.81857 -287.075984) (xy 439.870532 -287.064124)
			(xy 439.923682 -287.060141) (xy 439.976832 -287.064124) (xy 440.028794 -287.075984) (xy 440.078408 -287.095456)
			(xy 440.124566 -287.122105) (xy 440.166237 -287.155336) (xy 440.202489 -287.194407) (xy 440.232513 -287.238444)
			(xy 440.255639 -287.286465) (xy 440.271349 -287.337395) (xy 440.279292 -287.390099) (xy 440.27979 -287.416748)
			(xy 440.279292 -287.443397) (xy 454.655672 -287.443397) (xy 454.655672 -287.390099) (xy 454.663615 -287.337395)
			(xy 454.679325 -287.286465) (xy 454.702451 -287.238444) (xy 454.732475 -287.194407) (xy 454.768727 -287.155336)
			(xy 454.810398 -287.122105) (xy 454.856556 -287.095456) (xy 454.90617 -287.075984) (xy 454.958132 -287.064124)
			(xy 455.011282 -287.060141) (xy 455.064432 -287.064124) (xy 455.116394 -287.075984) (xy 455.166008 -287.095456)
			(xy 455.212166 -287.122105) (xy 455.253837 -287.155336) (xy 455.290089 -287.194407) (xy 455.320113 -287.238444)
			(xy 455.343239 -287.286465) (xy 455.358949 -287.337395) (xy 455.366892 -287.390099) (xy 455.36739 -287.416748)
			(xy 455.366892 -287.443397) (xy 455.358949 -287.496101) (xy 455.343239 -287.547031) (xy 455.320113 -287.595052)
			(xy 455.290089 -287.639089) (xy 455.253837 -287.67816) (xy 455.212166 -287.711391) (xy 455.166008 -287.73804)
			(xy 455.116394 -287.757512) (xy 455.064432 -287.769372) (xy 455.011282 -287.773356) (xy 454.958132 -287.769372)
			(xy 454.90617 -287.757512) (xy 454.856556 -287.73804) (xy 454.810398 -287.711391) (xy 454.768727 -287.67816)
			(xy 454.732475 -287.639089) (xy 454.702451 -287.595052) (xy 454.679325 -287.547031) (xy 454.663615 -287.496101)
			(xy 454.655672 -287.443397) (xy 440.279292 -287.443397) (xy 440.271349 -287.496101) (xy 440.255639 -287.547031)
			(xy 440.232513 -287.595052) (xy 440.202489 -287.639089) (xy 440.166237 -287.67816) (xy 440.124566 -287.711391)
			(xy 440.078408 -287.73804) (xy 440.028794 -287.757512) (xy 439.976832 -287.769372) (xy 439.923682 -287.773356)
			(xy 439.870532 -287.769372) (xy 439.81857 -287.757512) (xy 439.768956 -287.73804) (xy 439.722798 -287.711391)
			(xy 439.681127 -287.67816) (xy 439.644875 -287.639089) (xy 439.614851 -287.595052) (xy 439.591725 -287.547031)
			(xy 439.576015 -287.496101) (xy 439.568072 -287.443397) (xy 425.191692 -287.443397) (xy 425.183749 -287.496101)
			(xy 425.168039 -287.547031) (xy 425.144913 -287.595052) (xy 425.114889 -287.639089) (xy 425.078637 -287.67816)
			(xy 425.036966 -287.711391) (xy 424.990808 -287.73804) (xy 424.941194 -287.757512) (xy 424.889232 -287.769372)
			(xy 424.836082 -287.773356) (xy 424.782932 -287.769372) (xy 424.73097 -287.757512) (xy 424.681356 -287.73804)
			(xy 424.635198 -287.711391) (xy 424.593527 -287.67816) (xy 424.557275 -287.639089) (xy 424.527251 -287.595052)
			(xy 424.504125 -287.547031) (xy 424.488415 -287.496101) (xy 424.480472 -287.443397) (xy 407.4668 -287.443397)
			(xy 407.4668 -288.293281) (xy 420.380404 -288.293281) (xy 420.380404 -288.239983) (xy 420.388347 -288.187279)
			(xy 420.404057 -288.136349) (xy 420.427183 -288.088328) (xy 420.457207 -288.044291) (xy 420.493459 -288.00522)
			(xy 420.53513 -287.971989) (xy 420.581288 -287.94534) (xy 420.630902 -287.925868) (xy 420.682864 -287.914008)
			(xy 420.736014 -287.910025) (xy 420.789164 -287.914008) (xy 420.841126 -287.925868) (xy 420.89074 -287.94534)
			(xy 420.936898 -287.971989) (xy 420.978569 -288.00522) (xy 421.014821 -288.044291) (xy 421.044845 -288.088328)
			(xy 421.067971 -288.136349) (xy 421.083681 -288.187279) (xy 421.091624 -288.239983) (xy 421.092122 -288.266632)
			(xy 421.091624 -288.293281) (xy 435.468004 -288.293281) (xy 435.468004 -288.239983) (xy 435.475947 -288.187279)
			(xy 435.491657 -288.136349) (xy 435.514783 -288.088328) (xy 435.544807 -288.044291) (xy 435.581059 -288.00522)
			(xy 435.62273 -287.971989) (xy 435.668888 -287.94534) (xy 435.718502 -287.925868) (xy 435.770464 -287.914008)
			(xy 435.823614 -287.910025) (xy 435.876764 -287.914008) (xy 435.928726 -287.925868) (xy 435.97834 -287.94534)
			(xy 436.024498 -287.971989) (xy 436.066169 -288.00522) (xy 436.102421 -288.044291) (xy 436.132445 -288.088328)
			(xy 436.155571 -288.136349) (xy 436.171281 -288.187279) (xy 436.179224 -288.239983) (xy 436.179722 -288.266632)
			(xy 436.179224 -288.293281) (xy 450.555604 -288.293281) (xy 450.555604 -288.239983) (xy 450.563547 -288.187279)
			(xy 450.579257 -288.136349) (xy 450.602383 -288.088328) (xy 450.632407 -288.044291) (xy 450.668659 -288.00522)
			(xy 450.71033 -287.971989) (xy 450.756488 -287.94534) (xy 450.806102 -287.925868) (xy 450.858064 -287.914008)
			(xy 450.911214 -287.910025) (xy 450.964364 -287.914008) (xy 451.016326 -287.925868) (xy 451.06594 -287.94534)
			(xy 451.112098 -287.971989) (xy 451.153769 -288.00522) (xy 451.190021 -288.044291) (xy 451.220045 -288.088328)
			(xy 451.243171 -288.136349) (xy 451.258881 -288.187279) (xy 451.266824 -288.239983) (xy 451.267322 -288.266632)
			(xy 451.266824 -288.293281) (xy 451.258881 -288.345985) (xy 451.243171 -288.396915) (xy 451.220045 -288.444936)
			(xy 451.190021 -288.488973) (xy 451.153769 -288.528044) (xy 451.112098 -288.561275) (xy 451.06594 -288.587924)
			(xy 451.016326 -288.607396) (xy 450.964364 -288.619256) (xy 450.911214 -288.62324) (xy 450.858064 -288.619256)
			(xy 450.806102 -288.607396) (xy 450.756488 -288.587924) (xy 450.71033 -288.561275) (xy 450.668659 -288.528044)
			(xy 450.632407 -288.488973) (xy 450.602383 -288.444936) (xy 450.579257 -288.396915) (xy 450.563547 -288.345985)
			(xy 450.555604 -288.293281) (xy 436.179224 -288.293281) (xy 436.171281 -288.345985) (xy 436.155571 -288.396915)
			(xy 436.132445 -288.444936) (xy 436.102421 -288.488973) (xy 436.066169 -288.528044) (xy 436.024498 -288.561275)
			(xy 435.97834 -288.587924) (xy 435.928726 -288.607396) (xy 435.876764 -288.619256) (xy 435.823614 -288.62324)
			(xy 435.770464 -288.619256) (xy 435.718502 -288.607396) (xy 435.668888 -288.587924) (xy 435.62273 -288.561275)
			(xy 435.581059 -288.528044) (xy 435.544807 -288.488973) (xy 435.514783 -288.444936) (xy 435.491657 -288.396915)
			(xy 435.475947 -288.345985) (xy 435.468004 -288.293281) (xy 421.091624 -288.293281) (xy 421.083681 -288.345985)
			(xy 421.067971 -288.396915) (xy 421.044845 -288.444936) (xy 421.014821 -288.488973) (xy 420.978569 -288.528044)
			(xy 420.936898 -288.561275) (xy 420.89074 -288.587924) (xy 420.841126 -288.607396) (xy 420.789164 -288.619256)
			(xy 420.736014 -288.62324) (xy 420.682864 -288.619256) (xy 420.630902 -288.607396) (xy 420.581288 -288.587924)
			(xy 420.53513 -288.561275) (xy 420.493459 -288.528044) (xy 420.457207 -288.488973) (xy 420.427183 -288.444936)
			(xy 420.404057 -288.396915) (xy 420.388347 -288.345985) (xy 420.380404 -288.293281) (xy 407.4668 -288.293281)
			(xy 407.4668 -289.143419) (xy 424.480472 -289.143419) (xy 424.480472 -289.090121) (xy 424.488415 -289.037417)
			(xy 424.504125 -288.986487) (xy 424.527251 -288.938466) (xy 424.557275 -288.894429) (xy 424.593527 -288.855358)
			(xy 424.635198 -288.822127) (xy 424.681356 -288.795478) (xy 424.73097 -288.776006) (xy 424.782932 -288.764146)
			(xy 424.836082 -288.760163) (xy 424.889232 -288.764146) (xy 424.941194 -288.776006) (xy 424.990808 -288.795478)
			(xy 425.036966 -288.822127) (xy 425.078637 -288.855358) (xy 425.114889 -288.894429) (xy 425.144913 -288.938466)
			(xy 425.168039 -288.986487) (xy 425.183749 -289.037417) (xy 425.191692 -289.090121) (xy 425.19219 -289.11677)
			(xy 425.191692 -289.143419) (xy 439.568072 -289.143419) (xy 439.568072 -289.090121) (xy 439.576015 -289.037417)
			(xy 439.591725 -288.986487) (xy 439.614851 -288.938466) (xy 439.644875 -288.894429) (xy 439.681127 -288.855358)
			(xy 439.722798 -288.822127) (xy 439.768956 -288.795478) (xy 439.81857 -288.776006) (xy 439.870532 -288.764146)
			(xy 439.923682 -288.760163) (xy 439.976832 -288.764146) (xy 440.028794 -288.776006) (xy 440.078408 -288.795478)
			(xy 440.124566 -288.822127) (xy 440.166237 -288.855358) (xy 440.202489 -288.894429) (xy 440.232513 -288.938466)
			(xy 440.255639 -288.986487) (xy 440.271349 -289.037417) (xy 440.279292 -289.090121) (xy 440.27979 -289.11677)
			(xy 440.279292 -289.143419) (xy 454.655672 -289.143419) (xy 454.655672 -289.090121) (xy 454.663615 -289.037417)
			(xy 454.679325 -288.986487) (xy 454.702451 -288.938466) (xy 454.732475 -288.894429) (xy 454.768727 -288.855358)
			(xy 454.810398 -288.822127) (xy 454.856556 -288.795478) (xy 454.90617 -288.776006) (xy 454.958132 -288.764146)
			(xy 455.011282 -288.760163) (xy 455.064432 -288.764146) (xy 455.116394 -288.776006) (xy 455.166008 -288.795478)
			(xy 455.212166 -288.822127) (xy 455.253837 -288.855358) (xy 455.290089 -288.894429) (xy 455.320113 -288.938466)
			(xy 455.343239 -288.986487) (xy 455.358949 -289.037417) (xy 455.366892 -289.090121) (xy 455.36739 -289.11677)
			(xy 455.366892 -289.143419) (xy 455.358949 -289.196123) (xy 455.343239 -289.247053) (xy 455.320113 -289.295074)
			(xy 455.290089 -289.339111) (xy 455.253837 -289.378182) (xy 455.212166 -289.411413) (xy 455.166008 -289.438062)
			(xy 455.116394 -289.457534) (xy 455.064432 -289.469394) (xy 455.011282 -289.473378) (xy 454.958132 -289.469394)
			(xy 454.90617 -289.457534) (xy 454.856556 -289.438062) (xy 454.810398 -289.411413) (xy 454.768727 -289.378182)
			(xy 454.732475 -289.339111) (xy 454.702451 -289.295074) (xy 454.679325 -289.247053) (xy 454.663615 -289.196123)
			(xy 454.655672 -289.143419) (xy 440.279292 -289.143419) (xy 440.271349 -289.196123) (xy 440.255639 -289.247053)
			(xy 440.232513 -289.295074) (xy 440.202489 -289.339111) (xy 440.166237 -289.378182) (xy 440.124566 -289.411413)
			(xy 440.078408 -289.438062) (xy 440.028794 -289.457534) (xy 439.976832 -289.469394) (xy 439.923682 -289.473378)
			(xy 439.870532 -289.469394) (xy 439.81857 -289.457534) (xy 439.768956 -289.438062) (xy 439.722798 -289.411413)
			(xy 439.681127 -289.378182) (xy 439.644875 -289.339111) (xy 439.614851 -289.295074) (xy 439.591725 -289.247053)
			(xy 439.576015 -289.196123) (xy 439.568072 -289.143419) (xy 425.191692 -289.143419) (xy 425.183749 -289.196123)
			(xy 425.168039 -289.247053) (xy 425.144913 -289.295074) (xy 425.114889 -289.339111) (xy 425.078637 -289.378182)
			(xy 425.036966 -289.411413) (xy 424.990808 -289.438062) (xy 424.941194 -289.457534) (xy 424.889232 -289.469394)
			(xy 424.836082 -289.473378) (xy 424.782932 -289.469394) (xy 424.73097 -289.457534) (xy 424.681356 -289.438062)
			(xy 424.635198 -289.411413) (xy 424.593527 -289.378182) (xy 424.557275 -289.339111) (xy 424.527251 -289.295074)
			(xy 424.504125 -289.247053) (xy 424.488415 -289.196123) (xy 424.480472 -289.143419) (xy 407.4668 -289.143419)
			(xy 407.4668 -289.993303) (xy 420.380404 -289.993303) (xy 420.380404 -289.940005) (xy 420.388347 -289.887301)
			(xy 420.404057 -289.836371) (xy 420.427183 -289.78835) (xy 420.457207 -289.744313) (xy 420.493459 -289.705242)
			(xy 420.53513 -289.672011) (xy 420.581288 -289.645362) (xy 420.630902 -289.62589) (xy 420.682864 -289.61403)
			(xy 420.736014 -289.610047) (xy 420.789164 -289.61403) (xy 420.841126 -289.62589) (xy 420.89074 -289.645362)
			(xy 420.936898 -289.672011) (xy 420.978569 -289.705242) (xy 421.014821 -289.744313) (xy 421.044845 -289.78835)
			(xy 421.067971 -289.836371) (xy 421.083681 -289.887301) (xy 421.091624 -289.940005) (xy 421.092122 -289.966654)
			(xy 421.091624 -289.993303) (xy 435.468004 -289.993303) (xy 435.468004 -289.940005) (xy 435.475947 -289.887301)
			(xy 435.491657 -289.836371) (xy 435.514783 -289.78835) (xy 435.544807 -289.744313) (xy 435.581059 -289.705242)
			(xy 435.62273 -289.672011) (xy 435.668888 -289.645362) (xy 435.718502 -289.62589) (xy 435.770464 -289.61403)
			(xy 435.823614 -289.610047) (xy 435.876764 -289.61403) (xy 435.928726 -289.62589) (xy 435.97834 -289.645362)
			(xy 436.024498 -289.672011) (xy 436.066169 -289.705242) (xy 436.102421 -289.744313) (xy 436.132445 -289.78835)
			(xy 436.155571 -289.836371) (xy 436.171281 -289.887301) (xy 436.179224 -289.940005) (xy 436.179722 -289.966654)
			(xy 436.179224 -289.993303) (xy 450.555604 -289.993303) (xy 450.555604 -289.940005) (xy 450.563547 -289.887301)
			(xy 450.579257 -289.836371) (xy 450.602383 -289.78835) (xy 450.632407 -289.744313) (xy 450.668659 -289.705242)
			(xy 450.71033 -289.672011) (xy 450.756488 -289.645362) (xy 450.806102 -289.62589) (xy 450.858064 -289.61403)
			(xy 450.911214 -289.610047) (xy 450.964364 -289.61403) (xy 451.016326 -289.62589) (xy 451.06594 -289.645362)
			(xy 451.112098 -289.672011) (xy 451.153769 -289.705242) (xy 451.190021 -289.744313) (xy 451.220045 -289.78835)
			(xy 451.243171 -289.836371) (xy 451.258881 -289.887301) (xy 451.266824 -289.940005) (xy 451.267322 -289.966654)
			(xy 451.266824 -289.993303) (xy 451.258881 -290.046007) (xy 451.243171 -290.096937) (xy 451.220045 -290.144958)
			(xy 451.190021 -290.188995) (xy 451.153769 -290.228066) (xy 451.112098 -290.261297) (xy 451.06594 -290.287946)
			(xy 451.016326 -290.307418) (xy 450.964364 -290.319278) (xy 450.911214 -290.323262) (xy 450.858064 -290.319278)
			(xy 450.806102 -290.307418) (xy 450.756488 -290.287946) (xy 450.71033 -290.261297) (xy 450.668659 -290.228066)
			(xy 450.632407 -290.188995) (xy 450.602383 -290.144958) (xy 450.579257 -290.096937) (xy 450.563547 -290.046007)
			(xy 450.555604 -289.993303) (xy 436.179224 -289.993303) (xy 436.171281 -290.046007) (xy 436.155571 -290.096937)
			(xy 436.132445 -290.144958) (xy 436.102421 -290.188995) (xy 436.066169 -290.228066) (xy 436.024498 -290.261297)
			(xy 435.97834 -290.287946) (xy 435.928726 -290.307418) (xy 435.876764 -290.319278) (xy 435.823614 -290.323262)
			(xy 435.770464 -290.319278) (xy 435.718502 -290.307418) (xy 435.668888 -290.287946) (xy 435.62273 -290.261297)
			(xy 435.581059 -290.228066) (xy 435.544807 -290.188995) (xy 435.514783 -290.144958) (xy 435.491657 -290.096937)
			(xy 435.475947 -290.046007) (xy 435.468004 -289.993303) (xy 421.091624 -289.993303) (xy 421.083681 -290.046007)
			(xy 421.067971 -290.096937) (xy 421.044845 -290.144958) (xy 421.014821 -290.188995) (xy 420.978569 -290.228066)
			(xy 420.936898 -290.261297) (xy 420.89074 -290.287946) (xy 420.841126 -290.307418) (xy 420.789164 -290.319278)
			(xy 420.736014 -290.323262) (xy 420.682864 -290.319278) (xy 420.630902 -290.307418) (xy 420.581288 -290.287946)
			(xy 420.53513 -290.261297) (xy 420.493459 -290.228066) (xy 420.457207 -290.188995) (xy 420.427183 -290.144958)
			(xy 420.404057 -290.096937) (xy 420.388347 -290.046007) (xy 420.380404 -289.993303) (xy 407.4668 -289.993303)
			(xy 407.4668 -290.843187) (xy 424.480472 -290.843187) (xy 424.480472 -290.789889) (xy 424.488415 -290.737185)
			(xy 424.504125 -290.686255) (xy 424.527251 -290.638234) (xy 424.557275 -290.594197) (xy 424.593527 -290.555126)
			(xy 424.635198 -290.521895) (xy 424.681356 -290.495246) (xy 424.73097 -290.475774) (xy 424.782932 -290.463914)
			(xy 424.836082 -290.459931) (xy 424.889232 -290.463914) (xy 424.941194 -290.475774) (xy 424.990808 -290.495246)
			(xy 425.036966 -290.521895) (xy 425.078637 -290.555126) (xy 425.114889 -290.594197) (xy 425.144913 -290.638234)
			(xy 425.168039 -290.686255) (xy 425.183749 -290.737185) (xy 425.191692 -290.789889) (xy 425.19219 -290.816538)
			(xy 425.191692 -290.843187) (xy 439.568072 -290.843187) (xy 439.568072 -290.789889) (xy 439.576015 -290.737185)
			(xy 439.591725 -290.686255) (xy 439.614851 -290.638234) (xy 439.644875 -290.594197) (xy 439.681127 -290.555126)
			(xy 439.722798 -290.521895) (xy 439.768956 -290.495246) (xy 439.81857 -290.475774) (xy 439.870532 -290.463914)
			(xy 439.923682 -290.459931) (xy 439.976832 -290.463914) (xy 440.028794 -290.475774) (xy 440.078408 -290.495246)
			(xy 440.124566 -290.521895) (xy 440.166237 -290.555126) (xy 440.202489 -290.594197) (xy 440.232513 -290.638234)
			(xy 440.255639 -290.686255) (xy 440.271349 -290.737185) (xy 440.279292 -290.789889) (xy 440.27979 -290.816538)
			(xy 440.279292 -290.843187) (xy 454.655672 -290.843187) (xy 454.655672 -290.789889) (xy 454.663615 -290.737185)
			(xy 454.679325 -290.686255) (xy 454.702451 -290.638234) (xy 454.732475 -290.594197) (xy 454.768727 -290.555126)
			(xy 454.810398 -290.521895) (xy 454.856556 -290.495246) (xy 454.90617 -290.475774) (xy 454.958132 -290.463914)
			(xy 455.011282 -290.459931) (xy 455.064432 -290.463914) (xy 455.116394 -290.475774) (xy 455.166008 -290.495246)
			(xy 455.212166 -290.521895) (xy 455.253837 -290.555126) (xy 455.290089 -290.594197) (xy 455.320113 -290.638234)
			(xy 455.343239 -290.686255) (xy 455.358949 -290.737185) (xy 455.366892 -290.789889) (xy 455.36739 -290.816538)
			(xy 455.366892 -290.843187) (xy 455.358949 -290.895891) (xy 455.343239 -290.946821) (xy 455.320113 -290.994842)
			(xy 455.290089 -291.038879) (xy 455.253837 -291.07795) (xy 455.212166 -291.111181) (xy 455.166008 -291.13783)
			(xy 455.116394 -291.157302) (xy 455.064432 -291.169162) (xy 455.011282 -291.173146) (xy 454.958132 -291.169162)
			(xy 454.90617 -291.157302) (xy 454.856556 -291.13783) (xy 454.810398 -291.111181) (xy 454.768727 -291.07795)
			(xy 454.732475 -291.038879) (xy 454.702451 -290.994842) (xy 454.679325 -290.946821) (xy 454.663615 -290.895891)
			(xy 454.655672 -290.843187) (xy 440.279292 -290.843187) (xy 440.271349 -290.895891) (xy 440.255639 -290.946821)
			(xy 440.232513 -290.994842) (xy 440.202489 -291.038879) (xy 440.166237 -291.07795) (xy 440.124566 -291.111181)
			(xy 440.078408 -291.13783) (xy 440.028794 -291.157302) (xy 439.976832 -291.169162) (xy 439.923682 -291.173146)
			(xy 439.870532 -291.169162) (xy 439.81857 -291.157302) (xy 439.768956 -291.13783) (xy 439.722798 -291.111181)
			(xy 439.681127 -291.07795) (xy 439.644875 -291.038879) (xy 439.614851 -290.994842) (xy 439.591725 -290.946821)
			(xy 439.576015 -290.895891) (xy 439.568072 -290.843187) (xy 425.191692 -290.843187) (xy 425.183749 -290.895891)
			(xy 425.168039 -290.946821) (xy 425.144913 -290.994842) (xy 425.114889 -291.038879) (xy 425.078637 -291.07795)
			(xy 425.036966 -291.111181) (xy 424.990808 -291.13783) (xy 424.941194 -291.157302) (xy 424.889232 -291.169162)
			(xy 424.836082 -291.173146) (xy 424.782932 -291.169162) (xy 424.73097 -291.157302) (xy 424.681356 -291.13783)
			(xy 424.635198 -291.111181) (xy 424.593527 -291.07795) (xy 424.557275 -291.038879) (xy 424.527251 -290.994842)
			(xy 424.504125 -290.946821) (xy 424.488415 -290.895891) (xy 424.480472 -290.843187) (xy 407.4668 -290.843187)
			(xy 407.4668 -291.693325) (xy 420.380404 -291.693325) (xy 420.380404 -291.640027) (xy 420.388347 -291.587323)
			(xy 420.404057 -291.536393) (xy 420.427183 -291.488372) (xy 420.457207 -291.444335) (xy 420.493459 -291.405264)
			(xy 420.53513 -291.372033) (xy 420.581288 -291.345384) (xy 420.630902 -291.325912) (xy 420.682864 -291.314052)
			(xy 420.736014 -291.310069) (xy 420.789164 -291.314052) (xy 420.841126 -291.325912) (xy 420.89074 -291.345384)
			(xy 420.936898 -291.372033) (xy 420.978569 -291.405264) (xy 421.014821 -291.444335) (xy 421.044845 -291.488372)
			(xy 421.067971 -291.536393) (xy 421.083681 -291.587323) (xy 421.091624 -291.640027) (xy 421.092122 -291.666676)
			(xy 421.091624 -291.693325) (xy 435.468004 -291.693325) (xy 435.468004 -291.640027) (xy 435.475947 -291.587323)
			(xy 435.491657 -291.536393) (xy 435.514783 -291.488372) (xy 435.544807 -291.444335) (xy 435.581059 -291.405264)
			(xy 435.62273 -291.372033) (xy 435.668888 -291.345384) (xy 435.718502 -291.325912) (xy 435.770464 -291.314052)
			(xy 435.823614 -291.310069) (xy 435.876764 -291.314052) (xy 435.928726 -291.325912) (xy 435.97834 -291.345384)
			(xy 436.024498 -291.372033) (xy 436.066169 -291.405264) (xy 436.102421 -291.444335) (xy 436.132445 -291.488372)
			(xy 436.155571 -291.536393) (xy 436.171281 -291.587323) (xy 436.179224 -291.640027) (xy 436.179722 -291.666676)
			(xy 436.179224 -291.693325) (xy 450.555604 -291.693325) (xy 450.555604 -291.640027) (xy 450.563547 -291.587323)
			(xy 450.579257 -291.536393) (xy 450.602383 -291.488372) (xy 450.632407 -291.444335) (xy 450.668659 -291.405264)
			(xy 450.71033 -291.372033) (xy 450.756488 -291.345384) (xy 450.806102 -291.325912) (xy 450.858064 -291.314052)
			(xy 450.911214 -291.310069) (xy 450.964364 -291.314052) (xy 451.016326 -291.325912) (xy 451.06594 -291.345384)
			(xy 451.112098 -291.372033) (xy 451.153769 -291.405264) (xy 451.190021 -291.444335) (xy 451.220045 -291.488372)
			(xy 451.243171 -291.536393) (xy 451.258881 -291.587323) (xy 451.266824 -291.640027) (xy 451.267322 -291.666676)
			(xy 451.266824 -291.693325) (xy 451.258881 -291.746029) (xy 451.243171 -291.796959) (xy 451.220045 -291.84498)
			(xy 451.190021 -291.889017) (xy 451.153769 -291.928088) (xy 451.112098 -291.961319) (xy 451.06594 -291.987968)
			(xy 451.016326 -292.00744) (xy 450.964364 -292.0193) (xy 450.911214 -292.023284) (xy 450.858064 -292.0193)
			(xy 450.806102 -292.00744) (xy 450.756488 -291.987968) (xy 450.71033 -291.961319) (xy 450.668659 -291.928088)
			(xy 450.632407 -291.889017) (xy 450.602383 -291.84498) (xy 450.579257 -291.796959) (xy 450.563547 -291.746029)
			(xy 450.555604 -291.693325) (xy 436.179224 -291.693325) (xy 436.171281 -291.746029) (xy 436.155571 -291.796959)
			(xy 436.132445 -291.84498) (xy 436.102421 -291.889017) (xy 436.066169 -291.928088) (xy 436.024498 -291.961319)
			(xy 435.97834 -291.987968) (xy 435.928726 -292.00744) (xy 435.876764 -292.0193) (xy 435.823614 -292.023284)
			(xy 435.770464 -292.0193) (xy 435.718502 -292.00744) (xy 435.668888 -291.987968) (xy 435.62273 -291.961319)
			(xy 435.581059 -291.928088) (xy 435.544807 -291.889017) (xy 435.514783 -291.84498) (xy 435.491657 -291.796959)
			(xy 435.475947 -291.746029) (xy 435.468004 -291.693325) (xy 421.091624 -291.693325) (xy 421.083681 -291.746029)
			(xy 421.067971 -291.796959) (xy 421.044845 -291.84498) (xy 421.014821 -291.889017) (xy 420.978569 -291.928088)
			(xy 420.936898 -291.961319) (xy 420.89074 -291.987968) (xy 420.841126 -292.00744) (xy 420.789164 -292.0193)
			(xy 420.736014 -292.023284) (xy 420.682864 -292.0193) (xy 420.630902 -292.00744) (xy 420.581288 -291.987968)
			(xy 420.53513 -291.961319) (xy 420.493459 -291.928088) (xy 420.457207 -291.889017) (xy 420.427183 -291.84498)
			(xy 420.404057 -291.796959) (xy 420.388347 -291.746029) (xy 420.380404 -291.693325) (xy 407.4668 -291.693325)
			(xy 407.4668 -292.543209) (xy 424.480472 -292.543209) (xy 424.480472 -292.489911) (xy 424.488415 -292.437207)
			(xy 424.504125 -292.386277) (xy 424.527251 -292.338256) (xy 424.557275 -292.294219) (xy 424.593527 -292.255148)
			(xy 424.635198 -292.221917) (xy 424.681356 -292.195268) (xy 424.73097 -292.175796) (xy 424.782932 -292.163936)
			(xy 424.836082 -292.159953) (xy 424.889232 -292.163936) (xy 424.941194 -292.175796) (xy 424.990808 -292.195268)
			(xy 425.036966 -292.221917) (xy 425.078637 -292.255148) (xy 425.114889 -292.294219) (xy 425.144913 -292.338256)
			(xy 425.168039 -292.386277) (xy 425.183749 -292.437207) (xy 425.191692 -292.489911) (xy 425.19219 -292.51656)
			(xy 425.191692 -292.543209) (xy 439.568072 -292.543209) (xy 439.568072 -292.489911) (xy 439.576015 -292.437207)
			(xy 439.591725 -292.386277) (xy 439.614851 -292.338256) (xy 439.644875 -292.294219) (xy 439.681127 -292.255148)
			(xy 439.722798 -292.221917) (xy 439.768956 -292.195268) (xy 439.81857 -292.175796) (xy 439.870532 -292.163936)
			(xy 439.923682 -292.159953) (xy 439.976832 -292.163936) (xy 440.028794 -292.175796) (xy 440.078408 -292.195268)
			(xy 440.124566 -292.221917) (xy 440.166237 -292.255148) (xy 440.202489 -292.294219) (xy 440.232513 -292.338256)
			(xy 440.255639 -292.386277) (xy 440.271349 -292.437207) (xy 440.279292 -292.489911) (xy 440.27979 -292.51656)
			(xy 440.279292 -292.543209) (xy 454.655672 -292.543209) (xy 454.655672 -292.489911) (xy 454.663615 -292.437207)
			(xy 454.679325 -292.386277) (xy 454.702451 -292.338256) (xy 454.732475 -292.294219) (xy 454.768727 -292.255148)
			(xy 454.810398 -292.221917) (xy 454.856556 -292.195268) (xy 454.90617 -292.175796) (xy 454.958132 -292.163936)
			(xy 455.011282 -292.159953) (xy 455.064432 -292.163936) (xy 455.116394 -292.175796) (xy 455.166008 -292.195268)
			(xy 455.212166 -292.221917) (xy 455.253837 -292.255148) (xy 455.290089 -292.294219) (xy 455.320113 -292.338256)
			(xy 455.343239 -292.386277) (xy 455.358949 -292.437207) (xy 455.366892 -292.489911) (xy 455.36739 -292.51656)
			(xy 455.366892 -292.543209) (xy 455.358949 -292.595913) (xy 455.343239 -292.646843) (xy 455.320113 -292.694864)
			(xy 455.290089 -292.738901) (xy 455.253837 -292.777972) (xy 455.212166 -292.811203) (xy 455.166008 -292.837852)
			(xy 455.116394 -292.857324) (xy 455.064432 -292.869184) (xy 455.011282 -292.873168) (xy 454.958132 -292.869184)
			(xy 454.90617 -292.857324) (xy 454.856556 -292.837852) (xy 454.810398 -292.811203) (xy 454.768727 -292.777972)
			(xy 454.732475 -292.738901) (xy 454.702451 -292.694864) (xy 454.679325 -292.646843) (xy 454.663615 -292.595913)
			(xy 454.655672 -292.543209) (xy 440.279292 -292.543209) (xy 440.271349 -292.595913) (xy 440.255639 -292.646843)
			(xy 440.232513 -292.694864) (xy 440.202489 -292.738901) (xy 440.166237 -292.777972) (xy 440.124566 -292.811203)
			(xy 440.078408 -292.837852) (xy 440.028794 -292.857324) (xy 439.976832 -292.869184) (xy 439.923682 -292.873168)
			(xy 439.870532 -292.869184) (xy 439.81857 -292.857324) (xy 439.768956 -292.837852) (xy 439.722798 -292.811203)
			(xy 439.681127 -292.777972) (xy 439.644875 -292.738901) (xy 439.614851 -292.694864) (xy 439.591725 -292.646843)
			(xy 439.576015 -292.595913) (xy 439.568072 -292.543209) (xy 425.191692 -292.543209) (xy 425.183749 -292.595913)
			(xy 425.168039 -292.646843) (xy 425.144913 -292.694864) (xy 425.114889 -292.738901) (xy 425.078637 -292.777972)
			(xy 425.036966 -292.811203) (xy 424.990808 -292.837852) (xy 424.941194 -292.857324) (xy 424.889232 -292.869184)
			(xy 424.836082 -292.873168) (xy 424.782932 -292.869184) (xy 424.73097 -292.857324) (xy 424.681356 -292.837852)
			(xy 424.635198 -292.811203) (xy 424.593527 -292.777972) (xy 424.557275 -292.738901) (xy 424.527251 -292.694864)
			(xy 424.504125 -292.646843) (xy 424.488415 -292.595913) (xy 424.480472 -292.543209) (xy 407.4668 -292.543209)
			(xy 407.4668 -293.393347) (xy 420.380404 -293.393347) (xy 420.380404 -293.340049) (xy 420.388347 -293.287345)
			(xy 420.404057 -293.236415) (xy 420.427183 -293.188394) (xy 420.457207 -293.144357) (xy 420.493459 -293.105286)
			(xy 420.53513 -293.072055) (xy 420.581288 -293.045406) (xy 420.630902 -293.025934) (xy 420.682864 -293.014074)
			(xy 420.736014 -293.010091) (xy 420.789164 -293.014074) (xy 420.841126 -293.025934) (xy 420.89074 -293.045406)
			(xy 420.936898 -293.072055) (xy 420.978569 -293.105286) (xy 421.014821 -293.144357) (xy 421.044845 -293.188394)
			(xy 421.067971 -293.236415) (xy 421.083681 -293.287345) (xy 421.091624 -293.340049) (xy 421.092122 -293.366698)
			(xy 421.091624 -293.393347) (xy 424.480472 -293.393347) (xy 424.480472 -293.340049) (xy 424.488415 -293.287345)
			(xy 424.504125 -293.236415) (xy 424.527251 -293.188394) (xy 424.557275 -293.144357) (xy 424.593527 -293.105286)
			(xy 424.635198 -293.072055) (xy 424.681356 -293.045406) (xy 424.73097 -293.025934) (xy 424.782932 -293.014074)
			(xy 424.836082 -293.010091) (xy 424.889232 -293.014074) (xy 424.941194 -293.025934) (xy 424.990808 -293.045406)
			(xy 425.036966 -293.072055) (xy 425.078637 -293.105286) (xy 425.114889 -293.144357) (xy 425.144913 -293.188394)
			(xy 425.168039 -293.236415) (xy 425.183749 -293.287345) (xy 425.191692 -293.340049) (xy 425.19219 -293.366698)
			(xy 425.191692 -293.393347) (xy 435.468004 -293.393347) (xy 435.468004 -293.340049) (xy 435.475947 -293.287345)
			(xy 435.491657 -293.236415) (xy 435.514783 -293.188394) (xy 435.544807 -293.144357) (xy 435.581059 -293.105286)
			(xy 435.62273 -293.072055) (xy 435.668888 -293.045406) (xy 435.718502 -293.025934) (xy 435.770464 -293.014074)
			(xy 435.823614 -293.010091) (xy 435.876764 -293.014074) (xy 435.928726 -293.025934) (xy 435.97834 -293.045406)
			(xy 436.024498 -293.072055) (xy 436.066169 -293.105286) (xy 436.102421 -293.144357) (xy 436.132445 -293.188394)
			(xy 436.155571 -293.236415) (xy 436.171281 -293.287345) (xy 436.179224 -293.340049) (xy 436.179722 -293.366698)
			(xy 436.179224 -293.393347) (xy 439.568072 -293.393347) (xy 439.568072 -293.340049) (xy 439.576015 -293.287345)
			(xy 439.591725 -293.236415) (xy 439.614851 -293.188394) (xy 439.644875 -293.144357) (xy 439.681127 -293.105286)
			(xy 439.722798 -293.072055) (xy 439.768956 -293.045406) (xy 439.81857 -293.025934) (xy 439.870532 -293.014074)
			(xy 439.923682 -293.010091) (xy 439.976832 -293.014074) (xy 440.028794 -293.025934) (xy 440.078408 -293.045406)
			(xy 440.124566 -293.072055) (xy 440.166237 -293.105286) (xy 440.202489 -293.144357) (xy 440.232513 -293.188394)
			(xy 440.255639 -293.236415) (xy 440.271349 -293.287345) (xy 440.279292 -293.340049) (xy 440.27979 -293.366698)
			(xy 440.279292 -293.393347) (xy 450.555604 -293.393347) (xy 450.555604 -293.340049) (xy 450.563547 -293.287345)
			(xy 450.579257 -293.236415) (xy 450.602383 -293.188394) (xy 450.632407 -293.144357) (xy 450.668659 -293.105286)
			(xy 450.71033 -293.072055) (xy 450.756488 -293.045406) (xy 450.806102 -293.025934) (xy 450.858064 -293.014074)
			(xy 450.911214 -293.010091) (xy 450.964364 -293.014074) (xy 451.016326 -293.025934) (xy 451.06594 -293.045406)
			(xy 451.112098 -293.072055) (xy 451.153769 -293.105286) (xy 451.190021 -293.144357) (xy 451.220045 -293.188394)
			(xy 451.243171 -293.236415) (xy 451.258881 -293.287345) (xy 451.266824 -293.340049) (xy 451.267322 -293.366698)
			(xy 451.266824 -293.393347) (xy 454.655672 -293.393347) (xy 454.655672 -293.340049) (xy 454.663615 -293.287345)
			(xy 454.679325 -293.236415) (xy 454.702451 -293.188394) (xy 454.732475 -293.144357) (xy 454.768727 -293.105286)
			(xy 454.810398 -293.072055) (xy 454.856556 -293.045406) (xy 454.90617 -293.025934) (xy 454.958132 -293.014074)
			(xy 455.011282 -293.010091) (xy 455.064432 -293.014074) (xy 455.116394 -293.025934) (xy 455.166008 -293.045406)
			(xy 455.212166 -293.072055) (xy 455.253837 -293.105286) (xy 455.290089 -293.144357) (xy 455.320113 -293.188394)
			(xy 455.343239 -293.236415) (xy 455.358949 -293.287345) (xy 455.366892 -293.340049) (xy 455.36739 -293.366698)
			(xy 455.366892 -293.393347) (xy 455.358949 -293.446051) (xy 455.343239 -293.496981) (xy 455.320113 -293.545002)
			(xy 455.290089 -293.589039) (xy 455.253837 -293.62811) (xy 455.212166 -293.661341) (xy 455.166008 -293.68799)
			(xy 455.116394 -293.707462) (xy 455.064432 -293.719322) (xy 455.011282 -293.723306) (xy 454.958132 -293.719322)
			(xy 454.90617 -293.707462) (xy 454.856556 -293.68799) (xy 454.810398 -293.661341) (xy 454.768727 -293.62811)
			(xy 454.732475 -293.589039) (xy 454.702451 -293.545002) (xy 454.679325 -293.496981) (xy 454.663615 -293.446051)
			(xy 454.655672 -293.393347) (xy 451.266824 -293.393347) (xy 451.258881 -293.446051) (xy 451.243171 -293.496981)
			(xy 451.220045 -293.545002) (xy 451.190021 -293.589039) (xy 451.153769 -293.62811) (xy 451.112098 -293.661341)
			(xy 451.06594 -293.68799) (xy 451.016326 -293.707462) (xy 450.964364 -293.719322) (xy 450.911214 -293.723306)
			(xy 450.858064 -293.719322) (xy 450.806102 -293.707462) (xy 450.756488 -293.68799) (xy 450.71033 -293.661341)
			(xy 450.668659 -293.62811) (xy 450.632407 -293.589039) (xy 450.602383 -293.545002) (xy 450.579257 -293.496981)
			(xy 450.563547 -293.446051) (xy 450.555604 -293.393347) (xy 440.279292 -293.393347) (xy 440.271349 -293.446051)
			(xy 440.255639 -293.496981) (xy 440.232513 -293.545002) (xy 440.202489 -293.589039) (xy 440.166237 -293.62811)
			(xy 440.124566 -293.661341) (xy 440.078408 -293.68799) (xy 440.028794 -293.707462) (xy 439.976832 -293.719322)
			(xy 439.923682 -293.723306) (xy 439.870532 -293.719322) (xy 439.81857 -293.707462) (xy 439.768956 -293.68799)
			(xy 439.722798 -293.661341) (xy 439.681127 -293.62811) (xy 439.644875 -293.589039) (xy 439.614851 -293.545002)
			(xy 439.591725 -293.496981) (xy 439.576015 -293.446051) (xy 439.568072 -293.393347) (xy 436.179224 -293.393347)
			(xy 436.171281 -293.446051) (xy 436.155571 -293.496981) (xy 436.132445 -293.545002) (xy 436.102421 -293.589039)
			(xy 436.066169 -293.62811) (xy 436.024498 -293.661341) (xy 435.97834 -293.68799) (xy 435.928726 -293.707462)
			(xy 435.876764 -293.719322) (xy 435.823614 -293.723306) (xy 435.770464 -293.719322) (xy 435.718502 -293.707462)
			(xy 435.668888 -293.68799) (xy 435.62273 -293.661341) (xy 435.581059 -293.62811) (xy 435.544807 -293.589039)
			(xy 435.514783 -293.545002) (xy 435.491657 -293.496981) (xy 435.475947 -293.446051) (xy 435.468004 -293.393347)
			(xy 425.191692 -293.393347) (xy 425.183749 -293.446051) (xy 425.168039 -293.496981) (xy 425.144913 -293.545002)
			(xy 425.114889 -293.589039) (xy 425.078637 -293.62811) (xy 425.036966 -293.661341) (xy 424.990808 -293.68799)
			(xy 424.941194 -293.707462) (xy 424.889232 -293.719322) (xy 424.836082 -293.723306) (xy 424.782932 -293.719322)
			(xy 424.73097 -293.707462) (xy 424.681356 -293.68799) (xy 424.635198 -293.661341) (xy 424.593527 -293.62811)
			(xy 424.557275 -293.589039) (xy 424.527251 -293.545002) (xy 424.504125 -293.496981) (xy 424.488415 -293.446051)
			(xy 424.480472 -293.393347) (xy 421.091624 -293.393347) (xy 421.083681 -293.446051) (xy 421.067971 -293.496981)
			(xy 421.044845 -293.545002) (xy 421.014821 -293.589039) (xy 420.978569 -293.62811) (xy 420.936898 -293.661341)
			(xy 420.89074 -293.68799) (xy 420.841126 -293.707462) (xy 420.789164 -293.719322) (xy 420.736014 -293.723306)
			(xy 420.682864 -293.719322) (xy 420.630902 -293.707462) (xy 420.581288 -293.68799) (xy 420.53513 -293.661341)
			(xy 420.493459 -293.62811) (xy 420.457207 -293.589039) (xy 420.427183 -293.545002) (xy 420.404057 -293.496981)
			(xy 420.388347 -293.446051) (xy 420.380404 -293.393347) (xy 407.4668 -293.393347) (xy 407.4668 -294.243231)
			(xy 420.380404 -294.243231) (xy 420.380404 -294.189933) (xy 420.388347 -294.137229) (xy 420.404057 -294.086299)
			(xy 420.427183 -294.038278) (xy 420.457207 -293.994241) (xy 420.493459 -293.95517) (xy 420.53513 -293.921939)
			(xy 420.581288 -293.89529) (xy 420.630902 -293.875818) (xy 420.682864 -293.863958) (xy 420.736014 -293.859975)
			(xy 420.789164 -293.863958) (xy 420.841126 -293.875818) (xy 420.89074 -293.89529) (xy 420.936898 -293.921939)
			(xy 420.978569 -293.95517) (xy 421.014821 -293.994241) (xy 421.044845 -294.038278) (xy 421.067971 -294.086299)
			(xy 421.083681 -294.137229) (xy 421.091624 -294.189933) (xy 421.092122 -294.216582) (xy 421.091624 -294.243231)
			(xy 435.468004 -294.243231) (xy 435.468004 -294.189933) (xy 435.475947 -294.137229) (xy 435.491657 -294.086299)
			(xy 435.514783 -294.038278) (xy 435.544807 -293.994241) (xy 435.581059 -293.95517) (xy 435.62273 -293.921939)
			(xy 435.668888 -293.89529) (xy 435.718502 -293.875818) (xy 435.770464 -293.863958) (xy 435.823614 -293.859975)
			(xy 435.876764 -293.863958) (xy 435.928726 -293.875818) (xy 435.97834 -293.89529) (xy 436.024498 -293.921939)
			(xy 436.066169 -293.95517) (xy 436.102421 -293.994241) (xy 436.132445 -294.038278) (xy 436.155571 -294.086299)
			(xy 436.171281 -294.137229) (xy 436.179224 -294.189933) (xy 436.179722 -294.216582) (xy 436.179224 -294.243231)
			(xy 450.555604 -294.243231) (xy 450.555604 -294.189933) (xy 450.563547 -294.137229) (xy 450.579257 -294.086299)
			(xy 450.602383 -294.038278) (xy 450.632407 -293.994241) (xy 450.668659 -293.95517) (xy 450.71033 -293.921939)
			(xy 450.756488 -293.89529) (xy 450.806102 -293.875818) (xy 450.858064 -293.863958) (xy 450.911214 -293.859975)
			(xy 450.964364 -293.863958) (xy 451.016326 -293.875818) (xy 451.06594 -293.89529) (xy 451.112098 -293.921939)
			(xy 451.153769 -293.95517) (xy 451.190021 -293.994241) (xy 451.220045 -294.038278) (xy 451.243171 -294.086299)
			(xy 451.258881 -294.137229) (xy 451.266824 -294.189933) (xy 451.267322 -294.216582) (xy 451.266824 -294.243231)
			(xy 451.258881 -294.295935) (xy 451.243171 -294.346865) (xy 451.220045 -294.394886) (xy 451.190021 -294.438923)
			(xy 451.153769 -294.477994) (xy 451.112098 -294.511225) (xy 451.06594 -294.537874) (xy 451.016326 -294.557346)
			(xy 450.964364 -294.569206) (xy 450.911214 -294.57319) (xy 450.858064 -294.569206) (xy 450.806102 -294.557346)
			(xy 450.756488 -294.537874) (xy 450.71033 -294.511225) (xy 450.668659 -294.477994) (xy 450.632407 -294.438923)
			(xy 450.602383 -294.394886) (xy 450.579257 -294.346865) (xy 450.563547 -294.295935) (xy 450.555604 -294.243231)
			(xy 436.179224 -294.243231) (xy 436.171281 -294.295935) (xy 436.155571 -294.346865) (xy 436.132445 -294.394886)
			(xy 436.102421 -294.438923) (xy 436.066169 -294.477994) (xy 436.024498 -294.511225) (xy 435.97834 -294.537874)
			(xy 435.928726 -294.557346) (xy 435.876764 -294.569206) (xy 435.823614 -294.57319) (xy 435.770464 -294.569206)
			(xy 435.718502 -294.557346) (xy 435.668888 -294.537874) (xy 435.62273 -294.511225) (xy 435.581059 -294.477994)
			(xy 435.544807 -294.438923) (xy 435.514783 -294.394886) (xy 435.491657 -294.346865) (xy 435.475947 -294.295935)
			(xy 435.468004 -294.243231) (xy 421.091624 -294.243231) (xy 421.083681 -294.295935) (xy 421.067971 -294.346865)
			(xy 421.044845 -294.394886) (xy 421.014821 -294.438923) (xy 420.978569 -294.477994) (xy 420.936898 -294.511225)
			(xy 420.89074 -294.537874) (xy 420.841126 -294.557346) (xy 420.789164 -294.569206) (xy 420.736014 -294.57319)
			(xy 420.682864 -294.569206) (xy 420.630902 -294.557346) (xy 420.581288 -294.537874) (xy 420.53513 -294.511225)
			(xy 420.493459 -294.477994) (xy 420.457207 -294.438923) (xy 420.427183 -294.394886) (xy 420.404057 -294.346865)
			(xy 420.388347 -294.295935) (xy 420.380404 -294.243231) (xy 407.4668 -294.243231) (xy 407.4668 -295.093369)
			(xy 424.480472 -295.093369) (xy 424.480472 -295.040071) (xy 424.488415 -294.987367) (xy 424.504125 -294.936437)
			(xy 424.527251 -294.888416) (xy 424.557275 -294.844379) (xy 424.593527 -294.805308) (xy 424.635198 -294.772077)
			(xy 424.681356 -294.745428) (xy 424.73097 -294.725956) (xy 424.782932 -294.714096) (xy 424.836082 -294.710113)
			(xy 424.889232 -294.714096) (xy 424.941194 -294.725956) (xy 424.990808 -294.745428) (xy 425.036966 -294.772077)
			(xy 425.078637 -294.805308) (xy 425.114889 -294.844379) (xy 425.144913 -294.888416) (xy 425.168039 -294.936437)
			(xy 425.183749 -294.987367) (xy 425.191692 -295.040071) (xy 425.19219 -295.06672) (xy 425.191692 -295.093369)
			(xy 439.568072 -295.093369) (xy 439.568072 -295.040071) (xy 439.576015 -294.987367) (xy 439.591725 -294.936437)
			(xy 439.614851 -294.888416) (xy 439.644875 -294.844379) (xy 439.681127 -294.805308) (xy 439.722798 -294.772077)
			(xy 439.768956 -294.745428) (xy 439.81857 -294.725956) (xy 439.870532 -294.714096) (xy 439.923682 -294.710113)
			(xy 439.976832 -294.714096) (xy 440.028794 -294.725956) (xy 440.078408 -294.745428) (xy 440.124566 -294.772077)
			(xy 440.166237 -294.805308) (xy 440.202489 -294.844379) (xy 440.232513 -294.888416) (xy 440.255639 -294.936437)
			(xy 440.271349 -294.987367) (xy 440.279292 -295.040071) (xy 440.27979 -295.06672) (xy 440.279292 -295.093369)
			(xy 454.655672 -295.093369) (xy 454.655672 -295.040071) (xy 454.663615 -294.987367) (xy 454.679325 -294.936437)
			(xy 454.702451 -294.888416) (xy 454.732475 -294.844379) (xy 454.768727 -294.805308) (xy 454.810398 -294.772077)
			(xy 454.856556 -294.745428) (xy 454.90617 -294.725956) (xy 454.958132 -294.714096) (xy 455.011282 -294.710113)
			(xy 455.064432 -294.714096) (xy 455.116394 -294.725956) (xy 455.166008 -294.745428) (xy 455.212166 -294.772077)
			(xy 455.253837 -294.805308) (xy 455.290089 -294.844379) (xy 455.320113 -294.888416) (xy 455.343239 -294.936437)
			(xy 455.358949 -294.987367) (xy 455.366892 -295.040071) (xy 455.36739 -295.06672) (xy 455.366892 -295.093369)
			(xy 455.358949 -295.146073) (xy 455.343239 -295.197003) (xy 455.320113 -295.245024) (xy 455.290089 -295.289061)
			(xy 455.253837 -295.328132) (xy 455.212166 -295.361363) (xy 455.166008 -295.388012) (xy 455.116394 -295.407484)
			(xy 455.064432 -295.419344) (xy 455.011282 -295.423328) (xy 454.958132 -295.419344) (xy 454.90617 -295.407484)
			(xy 454.856556 -295.388012) (xy 454.810398 -295.361363) (xy 454.768727 -295.328132) (xy 454.732475 -295.289061)
			(xy 454.702451 -295.245024) (xy 454.679325 -295.197003) (xy 454.663615 -295.146073) (xy 454.655672 -295.093369)
			(xy 440.279292 -295.093369) (xy 440.271349 -295.146073) (xy 440.255639 -295.197003) (xy 440.232513 -295.245024)
			(xy 440.202489 -295.289061) (xy 440.166237 -295.328132) (xy 440.124566 -295.361363) (xy 440.078408 -295.388012)
			(xy 440.028794 -295.407484) (xy 439.976832 -295.419344) (xy 439.923682 -295.423328) (xy 439.870532 -295.419344)
			(xy 439.81857 -295.407484) (xy 439.768956 -295.388012) (xy 439.722798 -295.361363) (xy 439.681127 -295.328132)
			(xy 439.644875 -295.289061) (xy 439.614851 -295.245024) (xy 439.591725 -295.197003) (xy 439.576015 -295.146073)
			(xy 439.568072 -295.093369) (xy 425.191692 -295.093369) (xy 425.183749 -295.146073) (xy 425.168039 -295.197003)
			(xy 425.144913 -295.245024) (xy 425.114889 -295.289061) (xy 425.078637 -295.328132) (xy 425.036966 -295.361363)
			(xy 424.990808 -295.388012) (xy 424.941194 -295.407484) (xy 424.889232 -295.419344) (xy 424.836082 -295.423328)
			(xy 424.782932 -295.419344) (xy 424.73097 -295.407484) (xy 424.681356 -295.388012) (xy 424.635198 -295.361363)
			(xy 424.593527 -295.328132) (xy 424.557275 -295.289061) (xy 424.527251 -295.245024) (xy 424.504125 -295.197003)
			(xy 424.488415 -295.146073) (xy 424.480472 -295.093369) (xy 407.4668 -295.093369) (xy 407.4668 -295.943253)
			(xy 420.380404 -295.943253) (xy 420.380404 -295.889955) (xy 420.388347 -295.837251) (xy 420.404057 -295.786321)
			(xy 420.427183 -295.7383) (xy 420.457207 -295.694263) (xy 420.493459 -295.655192) (xy 420.53513 -295.621961)
			(xy 420.581288 -295.595312) (xy 420.630902 -295.57584) (xy 420.682864 -295.56398) (xy 420.736014 -295.559997)
			(xy 420.789164 -295.56398) (xy 420.841126 -295.57584) (xy 420.89074 -295.595312) (xy 420.936898 -295.621961)
			(xy 420.978569 -295.655192) (xy 421.014821 -295.694263) (xy 421.044845 -295.7383) (xy 421.067971 -295.786321)
			(xy 421.083681 -295.837251) (xy 421.091624 -295.889955) (xy 421.092122 -295.916604) (xy 421.091624 -295.943253)
			(xy 435.468004 -295.943253) (xy 435.468004 -295.889955) (xy 435.475947 -295.837251) (xy 435.491657 -295.786321)
			(xy 435.514783 -295.7383) (xy 435.544807 -295.694263) (xy 435.581059 -295.655192) (xy 435.62273 -295.621961)
			(xy 435.668888 -295.595312) (xy 435.718502 -295.57584) (xy 435.770464 -295.56398) (xy 435.823614 -295.559997)
			(xy 435.876764 -295.56398) (xy 435.928726 -295.57584) (xy 435.97834 -295.595312) (xy 436.024498 -295.621961)
			(xy 436.066169 -295.655192) (xy 436.102421 -295.694263) (xy 436.132445 -295.7383) (xy 436.155571 -295.786321)
			(xy 436.171281 -295.837251) (xy 436.179224 -295.889955) (xy 436.179722 -295.916604) (xy 436.179224 -295.943253)
			(xy 450.555604 -295.943253) (xy 450.555604 -295.889955) (xy 450.563547 -295.837251) (xy 450.579257 -295.786321)
			(xy 450.602383 -295.7383) (xy 450.632407 -295.694263) (xy 450.668659 -295.655192) (xy 450.71033 -295.621961)
			(xy 450.756488 -295.595312) (xy 450.806102 -295.57584) (xy 450.858064 -295.56398) (xy 450.911214 -295.559997)
			(xy 450.964364 -295.56398) (xy 451.016326 -295.57584) (xy 451.06594 -295.595312) (xy 451.112098 -295.621961)
			(xy 451.153769 -295.655192) (xy 451.190021 -295.694263) (xy 451.220045 -295.7383) (xy 451.243171 -295.786321)
			(xy 451.258881 -295.837251) (xy 451.266824 -295.889955) (xy 451.267322 -295.916604) (xy 451.266824 -295.943253)
			(xy 451.258881 -295.995957) (xy 451.243171 -296.046887) (xy 451.220045 -296.094908) (xy 451.190021 -296.138945)
			(xy 451.153769 -296.178016) (xy 451.112098 -296.211247) (xy 451.06594 -296.237896) (xy 451.016326 -296.257368)
			(xy 450.964364 -296.269228) (xy 450.911214 -296.273212) (xy 450.858064 -296.269228) (xy 450.806102 -296.257368)
			(xy 450.756488 -296.237896) (xy 450.71033 -296.211247) (xy 450.668659 -296.178016) (xy 450.632407 -296.138945)
			(xy 450.602383 -296.094908) (xy 450.579257 -296.046887) (xy 450.563547 -295.995957) (xy 450.555604 -295.943253)
			(xy 436.179224 -295.943253) (xy 436.171281 -295.995957) (xy 436.155571 -296.046887) (xy 436.132445 -296.094908)
			(xy 436.102421 -296.138945) (xy 436.066169 -296.178016) (xy 436.024498 -296.211247) (xy 435.97834 -296.237896)
			(xy 435.928726 -296.257368) (xy 435.876764 -296.269228) (xy 435.823614 -296.273212) (xy 435.770464 -296.269228)
			(xy 435.718502 -296.257368) (xy 435.668888 -296.237896) (xy 435.62273 -296.211247) (xy 435.581059 -296.178016)
			(xy 435.544807 -296.138945) (xy 435.514783 -296.094908) (xy 435.491657 -296.046887) (xy 435.475947 -295.995957)
			(xy 435.468004 -295.943253) (xy 421.091624 -295.943253) (xy 421.083681 -295.995957) (xy 421.067971 -296.046887)
			(xy 421.044845 -296.094908) (xy 421.014821 -296.138945) (xy 420.978569 -296.178016) (xy 420.936898 -296.211247)
			(xy 420.89074 -296.237896) (xy 420.841126 -296.257368) (xy 420.789164 -296.269228) (xy 420.736014 -296.273212)
			(xy 420.682864 -296.269228) (xy 420.630902 -296.257368) (xy 420.581288 -296.237896) (xy 420.53513 -296.211247)
			(xy 420.493459 -296.178016) (xy 420.457207 -296.138945) (xy 420.427183 -296.094908) (xy 420.404057 -296.046887)
			(xy 420.388347 -295.995957) (xy 420.380404 -295.943253) (xy 407.4668 -295.943253) (xy 407.4668 -296.793391)
			(xy 424.480472 -296.793391) (xy 424.480472 -296.740093) (xy 424.488415 -296.687389) (xy 424.504125 -296.636459)
			(xy 424.527251 -296.588438) (xy 424.557275 -296.544401) (xy 424.593527 -296.50533) (xy 424.635198 -296.472099)
			(xy 424.681356 -296.44545) (xy 424.73097 -296.425978) (xy 424.782932 -296.414118) (xy 424.836082 -296.410135)
			(xy 424.889232 -296.414118) (xy 424.941194 -296.425978) (xy 424.990808 -296.44545) (xy 425.036966 -296.472099)
			(xy 425.078637 -296.50533) (xy 425.114889 -296.544401) (xy 425.144913 -296.588438) (xy 425.168039 -296.636459)
			(xy 425.183749 -296.687389) (xy 425.191692 -296.740093) (xy 425.19219 -296.766742) (xy 425.191692 -296.793391)
			(xy 439.568072 -296.793391) (xy 439.568072 -296.740093) (xy 439.576015 -296.687389) (xy 439.591725 -296.636459)
			(xy 439.614851 -296.588438) (xy 439.644875 -296.544401) (xy 439.681127 -296.50533) (xy 439.722798 -296.472099)
			(xy 439.768956 -296.44545) (xy 439.81857 -296.425978) (xy 439.870532 -296.414118) (xy 439.923682 -296.410135)
			(xy 439.976832 -296.414118) (xy 440.028794 -296.425978) (xy 440.078408 -296.44545) (xy 440.124566 -296.472099)
			(xy 440.166237 -296.50533) (xy 440.202489 -296.544401) (xy 440.232513 -296.588438) (xy 440.255639 -296.636459)
			(xy 440.271349 -296.687389) (xy 440.279292 -296.740093) (xy 440.27979 -296.766742) (xy 440.279292 -296.793391)
			(xy 454.655672 -296.793391) (xy 454.655672 -296.740093) (xy 454.663615 -296.687389) (xy 454.679325 -296.636459)
			(xy 454.702451 -296.588438) (xy 454.732475 -296.544401) (xy 454.768727 -296.50533) (xy 454.810398 -296.472099)
			(xy 454.856556 -296.44545) (xy 454.90617 -296.425978) (xy 454.958132 -296.414118) (xy 455.011282 -296.410135)
			(xy 455.064432 -296.414118) (xy 455.116394 -296.425978) (xy 455.166008 -296.44545) (xy 455.212166 -296.472099)
			(xy 455.253837 -296.50533) (xy 455.290089 -296.544401) (xy 455.320113 -296.588438) (xy 455.343239 -296.636459)
			(xy 455.358949 -296.687389) (xy 455.366892 -296.740093) (xy 455.36739 -296.766742) (xy 455.366892 -296.793391)
			(xy 455.358949 -296.846095) (xy 455.343239 -296.897025) (xy 455.320113 -296.945046) (xy 455.290089 -296.989083)
			(xy 455.253837 -297.028154) (xy 455.212166 -297.061385) (xy 455.166008 -297.088034) (xy 455.116394 -297.107506)
			(xy 455.064432 -297.119366) (xy 455.011282 -297.12335) (xy 454.958132 -297.119366) (xy 454.90617 -297.107506)
			(xy 454.856556 -297.088034) (xy 454.810398 -297.061385) (xy 454.768727 -297.028154) (xy 454.732475 -296.989083)
			(xy 454.702451 -296.945046) (xy 454.679325 -296.897025) (xy 454.663615 -296.846095) (xy 454.655672 -296.793391)
			(xy 440.279292 -296.793391) (xy 440.271349 -296.846095) (xy 440.255639 -296.897025) (xy 440.232513 -296.945046)
			(xy 440.202489 -296.989083) (xy 440.166237 -297.028154) (xy 440.124566 -297.061385) (xy 440.078408 -297.088034)
			(xy 440.028794 -297.107506) (xy 439.976832 -297.119366) (xy 439.923682 -297.12335) (xy 439.870532 -297.119366)
			(xy 439.81857 -297.107506) (xy 439.768956 -297.088034) (xy 439.722798 -297.061385) (xy 439.681127 -297.028154)
			(xy 439.644875 -296.989083) (xy 439.614851 -296.945046) (xy 439.591725 -296.897025) (xy 439.576015 -296.846095)
			(xy 439.568072 -296.793391) (xy 425.191692 -296.793391) (xy 425.183749 -296.846095) (xy 425.168039 -296.897025)
			(xy 425.144913 -296.945046) (xy 425.114889 -296.989083) (xy 425.078637 -297.028154) (xy 425.036966 -297.061385)
			(xy 424.990808 -297.088034) (xy 424.941194 -297.107506) (xy 424.889232 -297.119366) (xy 424.836082 -297.12335)
			(xy 424.782932 -297.119366) (xy 424.73097 -297.107506) (xy 424.681356 -297.088034) (xy 424.635198 -297.061385)
			(xy 424.593527 -297.028154) (xy 424.557275 -296.989083) (xy 424.527251 -296.945046) (xy 424.504125 -296.897025)
			(xy 424.488415 -296.846095) (xy 424.480472 -296.793391) (xy 407.4668 -296.793391) (xy 407.4668 -297.643275)
			(xy 420.380404 -297.643275) (xy 420.380404 -297.589977) (xy 420.388347 -297.537273) (xy 420.404057 -297.486343)
			(xy 420.427183 -297.438322) (xy 420.457207 -297.394285) (xy 420.493459 -297.355214) (xy 420.53513 -297.321983)
			(xy 420.581288 -297.295334) (xy 420.630902 -297.275862) (xy 420.682864 -297.264002) (xy 420.736014 -297.260019)
			(xy 420.789164 -297.264002) (xy 420.841126 -297.275862) (xy 420.89074 -297.295334) (xy 420.936898 -297.321983)
			(xy 420.978569 -297.355214) (xy 421.014821 -297.394285) (xy 421.044845 -297.438322) (xy 421.067971 -297.486343)
			(xy 421.083681 -297.537273) (xy 421.091624 -297.589977) (xy 421.092122 -297.616626) (xy 421.091624 -297.643275)
			(xy 435.468004 -297.643275) (xy 435.468004 -297.589977) (xy 435.475947 -297.537273) (xy 435.491657 -297.486343)
			(xy 435.514783 -297.438322) (xy 435.544807 -297.394285) (xy 435.581059 -297.355214) (xy 435.62273 -297.321983)
			(xy 435.668888 -297.295334) (xy 435.718502 -297.275862) (xy 435.770464 -297.264002) (xy 435.823614 -297.260019)
			(xy 435.876764 -297.264002) (xy 435.928726 -297.275862) (xy 435.97834 -297.295334) (xy 436.024498 -297.321983)
			(xy 436.066169 -297.355214) (xy 436.102421 -297.394285) (xy 436.132445 -297.438322) (xy 436.155571 -297.486343)
			(xy 436.171281 -297.537273) (xy 436.179224 -297.589977) (xy 436.179722 -297.616626) (xy 436.179224 -297.643275)
			(xy 450.555604 -297.643275) (xy 450.555604 -297.589977) (xy 450.563547 -297.537273) (xy 450.579257 -297.486343)
			(xy 450.602383 -297.438322) (xy 450.632407 -297.394285) (xy 450.668659 -297.355214) (xy 450.71033 -297.321983)
			(xy 450.756488 -297.295334) (xy 450.806102 -297.275862) (xy 450.858064 -297.264002) (xy 450.911214 -297.260019)
			(xy 450.964364 -297.264002) (xy 451.016326 -297.275862) (xy 451.06594 -297.295334) (xy 451.112098 -297.321983)
			(xy 451.153769 -297.355214) (xy 451.190021 -297.394285) (xy 451.220045 -297.438322) (xy 451.243171 -297.486343)
			(xy 451.258881 -297.537273) (xy 451.266824 -297.589977) (xy 451.267322 -297.616626) (xy 451.266824 -297.643275)
			(xy 451.258881 -297.695979) (xy 451.243171 -297.746909) (xy 451.220045 -297.79493) (xy 451.190021 -297.838967)
			(xy 451.153769 -297.878038) (xy 451.112098 -297.911269) (xy 451.06594 -297.937918) (xy 451.016326 -297.95739)
			(xy 450.964364 -297.96925) (xy 450.911214 -297.973234) (xy 450.858064 -297.96925) (xy 450.806102 -297.95739)
			(xy 450.756488 -297.937918) (xy 450.71033 -297.911269) (xy 450.668659 -297.878038) (xy 450.632407 -297.838967)
			(xy 450.602383 -297.79493) (xy 450.579257 -297.746909) (xy 450.563547 -297.695979) (xy 450.555604 -297.643275)
			(xy 436.179224 -297.643275) (xy 436.171281 -297.695979) (xy 436.155571 -297.746909) (xy 436.132445 -297.79493)
			(xy 436.102421 -297.838967) (xy 436.066169 -297.878038) (xy 436.024498 -297.911269) (xy 435.97834 -297.937918)
			(xy 435.928726 -297.95739) (xy 435.876764 -297.96925) (xy 435.823614 -297.973234) (xy 435.770464 -297.96925)
			(xy 435.718502 -297.95739) (xy 435.668888 -297.937918) (xy 435.62273 -297.911269) (xy 435.581059 -297.878038)
			(xy 435.544807 -297.838967) (xy 435.514783 -297.79493) (xy 435.491657 -297.746909) (xy 435.475947 -297.695979)
			(xy 435.468004 -297.643275) (xy 421.091624 -297.643275) (xy 421.083681 -297.695979) (xy 421.067971 -297.746909)
			(xy 421.044845 -297.79493) (xy 421.014821 -297.838967) (xy 420.978569 -297.878038) (xy 420.936898 -297.911269)
			(xy 420.89074 -297.937918) (xy 420.841126 -297.95739) (xy 420.789164 -297.96925) (xy 420.736014 -297.973234)
			(xy 420.682864 -297.96925) (xy 420.630902 -297.95739) (xy 420.581288 -297.937918) (xy 420.53513 -297.911269)
			(xy 420.493459 -297.878038) (xy 420.457207 -297.838967) (xy 420.427183 -297.79493) (xy 420.404057 -297.746909)
			(xy 420.388347 -297.695979) (xy 420.380404 -297.643275) (xy 407.4668 -297.643275) (xy 407.4668 -298.493413)
			(xy 409.367472 -298.493413) (xy 409.367472 -298.440115) (xy 409.375415 -298.387411) (xy 409.391125 -298.336481)
			(xy 409.414251 -298.28846) (xy 409.444275 -298.244423) (xy 409.480527 -298.205352) (xy 409.522198 -298.172121)
			(xy 409.568356 -298.145472) (xy 409.61797 -298.126) (xy 409.669932 -298.11414) (xy 409.723082 -298.110157)
			(xy 409.776232 -298.11414) (xy 409.828194 -298.126) (xy 409.877808 -298.145472) (xy 409.923966 -298.172121)
			(xy 409.965637 -298.205352) (xy 410.001889 -298.244423) (xy 410.031913 -298.28846) (xy 410.055039 -298.336481)
			(xy 410.070749 -298.387411) (xy 410.078692 -298.440115) (xy 410.07919 -298.466764) (xy 410.078692 -298.493413)
			(xy 424.480472 -298.493413) (xy 424.480472 -298.440115) (xy 424.488415 -298.387411) (xy 424.504125 -298.336481)
			(xy 424.527251 -298.28846) (xy 424.557275 -298.244423) (xy 424.593527 -298.205352) (xy 424.635198 -298.172121)
			(xy 424.681356 -298.145472) (xy 424.73097 -298.126) (xy 424.782932 -298.11414) (xy 424.836082 -298.110157)
			(xy 424.889232 -298.11414) (xy 424.941194 -298.126) (xy 424.990808 -298.145472) (xy 425.036966 -298.172121)
			(xy 425.078637 -298.205352) (xy 425.114889 -298.244423) (xy 425.144913 -298.28846) (xy 425.168039 -298.336481)
			(xy 425.183749 -298.387411) (xy 425.191692 -298.440115) (xy 425.19219 -298.466764) (xy 425.191692 -298.493413)
			(xy 439.568072 -298.493413) (xy 439.568072 -298.440115) (xy 439.576015 -298.387411) (xy 439.591725 -298.336481)
			(xy 439.614851 -298.28846) (xy 439.644875 -298.244423) (xy 439.681127 -298.205352) (xy 439.722798 -298.172121)
			(xy 439.768956 -298.145472) (xy 439.81857 -298.126) (xy 439.870532 -298.11414) (xy 439.923682 -298.110157)
			(xy 439.976832 -298.11414) (xy 440.028794 -298.126) (xy 440.078408 -298.145472) (xy 440.124566 -298.172121)
			(xy 440.166237 -298.205352) (xy 440.202489 -298.244423) (xy 440.232513 -298.28846) (xy 440.255639 -298.336481)
			(xy 440.271349 -298.387411) (xy 440.279292 -298.440115) (xy 440.27979 -298.466764) (xy 440.279292 -298.493413)
			(xy 454.655672 -298.493413) (xy 454.655672 -298.440115) (xy 454.663615 -298.387411) (xy 454.679325 -298.336481)
			(xy 454.702451 -298.28846) (xy 454.732475 -298.244423) (xy 454.768727 -298.205352) (xy 454.810398 -298.172121)
			(xy 454.856556 -298.145472) (xy 454.90617 -298.126) (xy 454.958132 -298.11414) (xy 455.011282 -298.110157)
			(xy 455.064432 -298.11414) (xy 455.116394 -298.126) (xy 455.166008 -298.145472) (xy 455.212166 -298.172121)
			(xy 455.253837 -298.205352) (xy 455.290089 -298.244423) (xy 455.320113 -298.28846) (xy 455.343239 -298.336481)
			(xy 455.358949 -298.387411) (xy 455.366892 -298.440115) (xy 455.36739 -298.466764) (xy 455.366892 -298.493413)
			(xy 455.358949 -298.546117) (xy 455.343239 -298.597047) (xy 455.320113 -298.645068) (xy 455.290089 -298.689105)
			(xy 455.253837 -298.728176) (xy 455.212166 -298.761407) (xy 455.166008 -298.788056) (xy 455.116394 -298.807528)
			(xy 455.064432 -298.819388) (xy 455.011282 -298.823372) (xy 454.958132 -298.819388) (xy 454.90617 -298.807528)
			(xy 454.856556 -298.788056) (xy 454.810398 -298.761407) (xy 454.768727 -298.728176) (xy 454.732475 -298.689105)
			(xy 454.702451 -298.645068) (xy 454.679325 -298.597047) (xy 454.663615 -298.546117) (xy 454.655672 -298.493413)
			(xy 440.279292 -298.493413) (xy 440.271349 -298.546117) (xy 440.255639 -298.597047) (xy 440.232513 -298.645068)
			(xy 440.202489 -298.689105) (xy 440.166237 -298.728176) (xy 440.124566 -298.761407) (xy 440.078408 -298.788056)
			(xy 440.028794 -298.807528) (xy 439.976832 -298.819388) (xy 439.923682 -298.823372) (xy 439.870532 -298.819388)
			(xy 439.81857 -298.807528) (xy 439.768956 -298.788056) (xy 439.722798 -298.761407) (xy 439.681127 -298.728176)
			(xy 439.644875 -298.689105) (xy 439.614851 -298.645068) (xy 439.591725 -298.597047) (xy 439.576015 -298.546117)
			(xy 439.568072 -298.493413) (xy 425.191692 -298.493413) (xy 425.183749 -298.546117) (xy 425.168039 -298.597047)
			(xy 425.144913 -298.645068) (xy 425.114889 -298.689105) (xy 425.078637 -298.728176) (xy 425.036966 -298.761407)
			(xy 424.990808 -298.788056) (xy 424.941194 -298.807528) (xy 424.889232 -298.819388) (xy 424.836082 -298.823372)
			(xy 424.782932 -298.819388) (xy 424.73097 -298.807528) (xy 424.681356 -298.788056) (xy 424.635198 -298.761407)
			(xy 424.593527 -298.728176) (xy 424.557275 -298.689105) (xy 424.527251 -298.645068) (xy 424.504125 -298.597047)
			(xy 424.488415 -298.546117) (xy 424.480472 -298.493413) (xy 410.078692 -298.493413) (xy 410.070749 -298.546117)
			(xy 410.055039 -298.597047) (xy 410.031913 -298.645068) (xy 410.001889 -298.689105) (xy 409.965637 -298.728176)
			(xy 409.923966 -298.761407) (xy 409.877808 -298.788056) (xy 409.828194 -298.807528) (xy 409.776232 -298.819388)
			(xy 409.723082 -298.823372) (xy 409.669932 -298.819388) (xy 409.61797 -298.807528) (xy 409.568356 -298.788056)
			(xy 409.522198 -298.761407) (xy 409.480527 -298.728176) (xy 409.444275 -298.689105) (xy 409.414251 -298.645068)
			(xy 409.391125 -298.597047) (xy 409.375415 -298.546117) (xy 409.367472 -298.493413) (xy 407.4668 -298.493413)
			(xy 407.4668 -299.343297) (xy 420.380404 -299.343297) (xy 420.380404 -299.289999) (xy 420.388347 -299.237295)
			(xy 420.404057 -299.186365) (xy 420.427183 -299.138344) (xy 420.457207 -299.094307) (xy 420.493459 -299.055236)
			(xy 420.53513 -299.022005) (xy 420.581288 -298.995356) (xy 420.630902 -298.975884) (xy 420.682864 -298.964024)
			(xy 420.736014 -298.960041) (xy 420.789164 -298.964024) (xy 420.841126 -298.975884) (xy 420.89074 -298.995356)
			(xy 420.936898 -299.022005) (xy 420.978569 -299.055236) (xy 421.014821 -299.094307) (xy 421.044845 -299.138344)
			(xy 421.067971 -299.186365) (xy 421.083681 -299.237295) (xy 421.091624 -299.289999) (xy 421.092122 -299.316648)
			(xy 421.091624 -299.343297) (xy 435.468004 -299.343297) (xy 435.468004 -299.289999) (xy 435.475947 -299.237295)
			(xy 435.491657 -299.186365) (xy 435.514783 -299.138344) (xy 435.544807 -299.094307) (xy 435.581059 -299.055236)
			(xy 435.62273 -299.022005) (xy 435.668888 -298.995356) (xy 435.718502 -298.975884) (xy 435.770464 -298.964024)
			(xy 435.823614 -298.960041) (xy 435.876764 -298.964024) (xy 435.928726 -298.975884) (xy 435.97834 -298.995356)
			(xy 436.024498 -299.022005) (xy 436.066169 -299.055236) (xy 436.102421 -299.094307) (xy 436.132445 -299.138344)
			(xy 436.155571 -299.186365) (xy 436.171281 -299.237295) (xy 436.179224 -299.289999) (xy 436.179722 -299.316648)
			(xy 436.179224 -299.343297) (xy 450.555604 -299.343297) (xy 450.555604 -299.289999) (xy 450.563547 -299.237295)
			(xy 450.579257 -299.186365) (xy 450.602383 -299.138344) (xy 450.632407 -299.094307) (xy 450.668659 -299.055236)
			(xy 450.71033 -299.022005) (xy 450.756488 -298.995356) (xy 450.806102 -298.975884) (xy 450.858064 -298.964024)
			(xy 450.911214 -298.960041) (xy 450.964364 -298.964024) (xy 451.016326 -298.975884) (xy 451.06594 -298.995356)
			(xy 451.112098 -299.022005) (xy 451.153769 -299.055236) (xy 451.190021 -299.094307) (xy 451.220045 -299.138344)
			(xy 451.243171 -299.186365) (xy 451.258881 -299.237295) (xy 451.266824 -299.289999) (xy 451.267322 -299.316648)
			(xy 451.266824 -299.343297) (xy 451.258881 -299.396001) (xy 451.243171 -299.446931) (xy 451.220045 -299.494952)
			(xy 451.190021 -299.538989) (xy 451.153769 -299.57806) (xy 451.112098 -299.611291) (xy 451.06594 -299.63794)
			(xy 451.016326 -299.657412) (xy 450.964364 -299.669272) (xy 450.911214 -299.673256) (xy 450.858064 -299.669272)
			(xy 450.806102 -299.657412) (xy 450.756488 -299.63794) (xy 450.71033 -299.611291) (xy 450.668659 -299.57806)
			(xy 450.632407 -299.538989) (xy 450.602383 -299.494952) (xy 450.579257 -299.446931) (xy 450.563547 -299.396001)
			(xy 450.555604 -299.343297) (xy 436.179224 -299.343297) (xy 436.171281 -299.396001) (xy 436.155571 -299.446931)
			(xy 436.132445 -299.494952) (xy 436.102421 -299.538989) (xy 436.066169 -299.57806) (xy 436.024498 -299.611291)
			(xy 435.97834 -299.63794) (xy 435.928726 -299.657412) (xy 435.876764 -299.669272) (xy 435.823614 -299.673256)
			(xy 435.770464 -299.669272) (xy 435.718502 -299.657412) (xy 435.668888 -299.63794) (xy 435.62273 -299.611291)
			(xy 435.581059 -299.57806) (xy 435.544807 -299.538989) (xy 435.514783 -299.494952) (xy 435.491657 -299.446931)
			(xy 435.475947 -299.396001) (xy 435.468004 -299.343297) (xy 421.091624 -299.343297) (xy 421.083681 -299.396001)
			(xy 421.067971 -299.446931) (xy 421.044845 -299.494952) (xy 421.014821 -299.538989) (xy 420.978569 -299.57806)
			(xy 420.936898 -299.611291) (xy 420.89074 -299.63794) (xy 420.841126 -299.657412) (xy 420.789164 -299.669272)
			(xy 420.736014 -299.673256) (xy 420.682864 -299.669272) (xy 420.630902 -299.657412) (xy 420.581288 -299.63794)
			(xy 420.53513 -299.611291) (xy 420.493459 -299.57806) (xy 420.457207 -299.538989) (xy 420.427183 -299.494952)
			(xy 420.404057 -299.446931) (xy 420.388347 -299.396001) (xy 420.380404 -299.343297) (xy 407.4668 -299.343297)
			(xy 407.4668 -300.193435) (xy 409.367472 -300.193435) (xy 409.367472 -300.140137) (xy 409.375415 -300.087433)
			(xy 409.391125 -300.036503) (xy 409.414251 -299.988482) (xy 409.444275 -299.944445) (xy 409.480527 -299.905374)
			(xy 409.522198 -299.872143) (xy 409.568356 -299.845494) (xy 409.61797 -299.826022) (xy 409.669932 -299.814162)
			(xy 409.723082 -299.810179) (xy 409.776232 -299.814162) (xy 409.828194 -299.826022) (xy 409.877808 -299.845494)
			(xy 409.923966 -299.872143) (xy 409.965637 -299.905374) (xy 410.001889 -299.944445) (xy 410.031913 -299.988482)
			(xy 410.055039 -300.036503) (xy 410.070749 -300.087433) (xy 410.078692 -300.140137) (xy 410.07919 -300.166786)
			(xy 410.078697 -300.193181) (xy 424.480472 -300.193181) (xy 424.480472 -300.139883) (xy 424.488415 -300.087179)
			(xy 424.504125 -300.036249) (xy 424.527251 -299.988228) (xy 424.557275 -299.944191) (xy 424.593527 -299.90512)
			(xy 424.635198 -299.871889) (xy 424.681356 -299.84524) (xy 424.73097 -299.825768) (xy 424.782932 -299.813908)
			(xy 424.836082 -299.809925) (xy 424.889232 -299.813908) (xy 424.941194 -299.825768) (xy 424.990808 -299.84524)
			(xy 425.036966 -299.871889) (xy 425.078637 -299.90512) (xy 425.114889 -299.944191) (xy 425.144913 -299.988228)
			(xy 425.168039 -300.036249) (xy 425.183749 -300.087179) (xy 425.191692 -300.139883) (xy 425.19219 -300.166532)
			(xy 425.191692 -300.193181) (xy 425.191654 -300.193435) (xy 439.526162 -300.193435) (xy 439.526162 -300.140137)
			(xy 439.534105 -300.087433) (xy 439.549815 -300.036503) (xy 439.572941 -299.988482) (xy 439.602965 -299.944445)
			(xy 439.639217 -299.905374) (xy 439.680888 -299.872143) (xy 439.727046 -299.845494) (xy 439.77666 -299.826022)
			(xy 439.828622 -299.814162) (xy 439.881772 -299.810179) (xy 439.934922 -299.814162) (xy 439.986884 -299.826022)
			(xy 440.036498 -299.845494) (xy 440.082656 -299.872143) (xy 440.124327 -299.905374) (xy 440.160579 -299.944445)
			(xy 440.190603 -299.988482) (xy 440.213729 -300.036503) (xy 440.229439 -300.087433) (xy 440.237382 -300.140137)
			(xy 440.23788 -300.166786) (xy 440.237387 -300.193181) (xy 454.655672 -300.193181) (xy 454.655672 -300.139883)
			(xy 454.663615 -300.087179) (xy 454.679325 -300.036249) (xy 454.702451 -299.988228) (xy 454.732475 -299.944191)
			(xy 454.768727 -299.90512) (xy 454.810398 -299.871889) (xy 454.856556 -299.84524) (xy 454.90617 -299.825768)
			(xy 454.958132 -299.813908) (xy 455.011282 -299.809925) (xy 455.064432 -299.813908) (xy 455.116394 -299.825768)
			(xy 455.166008 -299.84524) (xy 455.212166 -299.871889) (xy 455.253837 -299.90512) (xy 455.290089 -299.944191)
			(xy 455.320113 -299.988228) (xy 455.343239 -300.036249) (xy 455.358949 -300.087179) (xy 455.366892 -300.139883)
			(xy 455.36739 -300.166532) (xy 455.366892 -300.193181) (xy 455.358949 -300.245885) (xy 455.343239 -300.296815)
			(xy 455.320113 -300.344836) (xy 455.290089 -300.388873) (xy 455.253837 -300.427944) (xy 455.212166 -300.461175)
			(xy 455.166008 -300.487824) (xy 455.116394 -300.507296) (xy 455.064432 -300.519156) (xy 455.011282 -300.52314)
			(xy 454.958132 -300.519156) (xy 454.90617 -300.507296) (xy 454.856556 -300.487824) (xy 454.810398 -300.461175)
			(xy 454.768727 -300.427944) (xy 454.732475 -300.388873) (xy 454.702451 -300.344836) (xy 454.679325 -300.296815)
			(xy 454.663615 -300.245885) (xy 454.655672 -300.193181) (xy 440.237387 -300.193181) (xy 440.237382 -300.193435)
			(xy 440.229439 -300.246139) (xy 440.213729 -300.297069) (xy 440.190603 -300.34509) (xy 440.160579 -300.389127)
			(xy 440.124327 -300.428198) (xy 440.082656 -300.461429) (xy 440.036498 -300.488078) (xy 439.986884 -300.50755)
			(xy 439.934922 -300.51941) (xy 439.881772 -300.523394) (xy 439.828622 -300.51941) (xy 439.77666 -300.50755)
			(xy 439.727046 -300.488078) (xy 439.680888 -300.461429) (xy 439.639217 -300.428198) (xy 439.602965 -300.389127)
			(xy 439.572941 -300.34509) (xy 439.549815 -300.297069) (xy 439.534105 -300.246139) (xy 439.526162 -300.193435)
			(xy 425.191654 -300.193435) (xy 425.183749 -300.245885) (xy 425.168039 -300.296815) (xy 425.144913 -300.344836)
			(xy 425.114889 -300.388873) (xy 425.078637 -300.427944) (xy 425.036966 -300.461175) (xy 424.990808 -300.487824)
			(xy 424.941194 -300.507296) (xy 424.889232 -300.519156) (xy 424.836082 -300.52314) (xy 424.782932 -300.519156)
			(xy 424.73097 -300.507296) (xy 424.681356 -300.487824) (xy 424.635198 -300.461175) (xy 424.593527 -300.427944)
			(xy 424.557275 -300.388873) (xy 424.527251 -300.344836) (xy 424.504125 -300.296815) (xy 424.488415 -300.245885)
			(xy 424.480472 -300.193181) (xy 410.078697 -300.193181) (xy 410.078692 -300.193435) (xy 410.070749 -300.246139)
			(xy 410.055039 -300.297069) (xy 410.031913 -300.34509) (xy 410.001889 -300.389127) (xy 409.965637 -300.428198)
			(xy 409.923966 -300.461429) (xy 409.877808 -300.488078) (xy 409.828194 -300.50755) (xy 409.776232 -300.51941)
			(xy 409.723082 -300.523394) (xy 409.669932 -300.51941) (xy 409.61797 -300.50755) (xy 409.568356 -300.488078)
			(xy 409.522198 -300.461429) (xy 409.480527 -300.428198) (xy 409.444275 -300.389127) (xy 409.414251 -300.34509)
			(xy 409.391125 -300.297069) (xy 409.375415 -300.246139) (xy 409.367472 -300.193435) (xy 407.4668 -300.193435)
			(xy 407.4668 -301.043319) (xy 420.380404 -301.043319) (xy 420.380404 -300.990021) (xy 420.388347 -300.937317)
			(xy 420.404057 -300.886387) (xy 420.427183 -300.838366) (xy 420.457207 -300.794329) (xy 420.493459 -300.755258)
			(xy 420.53513 -300.722027) (xy 420.581288 -300.695378) (xy 420.630902 -300.675906) (xy 420.682864 -300.664046)
			(xy 420.736014 -300.660063) (xy 420.789164 -300.664046) (xy 420.841126 -300.675906) (xy 420.89074 -300.695378)
			(xy 420.936898 -300.722027) (xy 420.978569 -300.755258) (xy 421.014821 -300.794329) (xy 421.044845 -300.838366)
			(xy 421.067971 -300.886387) (xy 421.083681 -300.937317) (xy 421.091624 -300.990021) (xy 421.092122 -301.01667)
			(xy 421.091624 -301.043319) (xy 435.468004 -301.043319) (xy 435.468004 -300.990021) (xy 435.475947 -300.937317)
			(xy 435.491657 -300.886387) (xy 435.514783 -300.838366) (xy 435.544807 -300.794329) (xy 435.581059 -300.755258)
			(xy 435.62273 -300.722027) (xy 435.668888 -300.695378) (xy 435.718502 -300.675906) (xy 435.770464 -300.664046)
			(xy 435.823614 -300.660063) (xy 435.876764 -300.664046) (xy 435.928726 -300.675906) (xy 435.97834 -300.695378)
			(xy 436.024498 -300.722027) (xy 436.066169 -300.755258) (xy 436.102421 -300.794329) (xy 436.132445 -300.838366)
			(xy 436.155571 -300.886387) (xy 436.171281 -300.937317) (xy 436.179224 -300.990021) (xy 436.179722 -301.01667)
			(xy 436.179224 -301.043319) (xy 450.555604 -301.043319) (xy 450.555604 -300.990021) (xy 450.563547 -300.937317)
			(xy 450.579257 -300.886387) (xy 450.602383 -300.838366) (xy 450.632407 -300.794329) (xy 450.668659 -300.755258)
			(xy 450.71033 -300.722027) (xy 450.756488 -300.695378) (xy 450.806102 -300.675906) (xy 450.858064 -300.664046)
			(xy 450.911214 -300.660063) (xy 450.964364 -300.664046) (xy 451.016326 -300.675906) (xy 451.06594 -300.695378)
			(xy 451.112098 -300.722027) (xy 451.153769 -300.755258) (xy 451.190021 -300.794329) (xy 451.220045 -300.838366)
			(xy 451.243171 -300.886387) (xy 451.258881 -300.937317) (xy 451.266824 -300.990021) (xy 451.267322 -301.01667)
			(xy 451.266824 -301.043319) (xy 451.258881 -301.096023) (xy 451.243171 -301.146953) (xy 451.220045 -301.194974)
			(xy 451.190021 -301.239011) (xy 451.153769 -301.278082) (xy 451.112098 -301.311313) (xy 451.06594 -301.337962)
			(xy 451.016326 -301.357434) (xy 450.964364 -301.369294) (xy 450.911214 -301.373278) (xy 450.858064 -301.369294)
			(xy 450.806102 -301.357434) (xy 450.756488 -301.337962) (xy 450.71033 -301.311313) (xy 450.668659 -301.278082)
			(xy 450.632407 -301.239011) (xy 450.602383 -301.194974) (xy 450.579257 -301.146953) (xy 450.563547 -301.096023)
			(xy 450.555604 -301.043319) (xy 436.179224 -301.043319) (xy 436.171281 -301.096023) (xy 436.155571 -301.146953)
			(xy 436.132445 -301.194974) (xy 436.102421 -301.239011) (xy 436.066169 -301.278082) (xy 436.024498 -301.311313)
			(xy 435.97834 -301.337962) (xy 435.928726 -301.357434) (xy 435.876764 -301.369294) (xy 435.823614 -301.373278)
			(xy 435.770464 -301.369294) (xy 435.718502 -301.357434) (xy 435.668888 -301.337962) (xy 435.62273 -301.311313)
			(xy 435.581059 -301.278082) (xy 435.544807 -301.239011) (xy 435.514783 -301.194974) (xy 435.491657 -301.146953)
			(xy 435.475947 -301.096023) (xy 435.468004 -301.043319) (xy 421.091624 -301.043319) (xy 421.083681 -301.096023)
			(xy 421.067971 -301.146953) (xy 421.044845 -301.194974) (xy 421.014821 -301.239011) (xy 420.978569 -301.278082)
			(xy 420.936898 -301.311313) (xy 420.89074 -301.337962) (xy 420.841126 -301.357434) (xy 420.789164 -301.369294)
			(xy 420.736014 -301.373278) (xy 420.682864 -301.369294) (xy 420.630902 -301.357434) (xy 420.581288 -301.337962)
			(xy 420.53513 -301.311313) (xy 420.493459 -301.278082) (xy 420.457207 -301.239011) (xy 420.427183 -301.194974)
			(xy 420.404057 -301.146953) (xy 420.388347 -301.096023) (xy 420.380404 -301.043319) (xy 407.4668 -301.043319)
			(xy 407.4668 -301.893203) (xy 409.367472 -301.893203) (xy 409.367472 -301.839905) (xy 409.375415 -301.787201)
			(xy 409.391125 -301.736271) (xy 409.414251 -301.68825) (xy 409.444275 -301.644213) (xy 409.480527 -301.605142)
			(xy 409.522198 -301.571911) (xy 409.568356 -301.545262) (xy 409.61797 -301.52579) (xy 409.669932 -301.51393)
			(xy 409.723082 -301.509947) (xy 409.776232 -301.51393) (xy 409.828194 -301.52579) (xy 409.877808 -301.545262)
			(xy 409.923966 -301.571911) (xy 409.965637 -301.605142) (xy 410.001889 -301.644213) (xy 410.031913 -301.68825)
			(xy 410.055039 -301.736271) (xy 410.070749 -301.787201) (xy 410.078692 -301.839905) (xy 410.07919 -301.866554)
			(xy 410.078692 -301.893203) (xy 424.480472 -301.893203) (xy 424.480472 -301.839905) (xy 424.488415 -301.787201)
			(xy 424.504125 -301.736271) (xy 424.527251 -301.68825) (xy 424.557275 -301.644213) (xy 424.593527 -301.605142)
			(xy 424.635198 -301.571911) (xy 424.681356 -301.545262) (xy 424.73097 -301.52579) (xy 424.782932 -301.51393)
			(xy 424.836082 -301.509947) (xy 424.889232 -301.51393) (xy 424.941194 -301.52579) (xy 424.990808 -301.545262)
			(xy 425.036966 -301.571911) (xy 425.078637 -301.605142) (xy 425.114889 -301.644213) (xy 425.144913 -301.68825)
			(xy 425.168039 -301.736271) (xy 425.183749 -301.787201) (xy 425.191692 -301.839905) (xy 425.19219 -301.866554)
			(xy 425.191692 -301.893203) (xy 425.191654 -301.893457) (xy 439.526162 -301.893457) (xy 439.526162 -301.840159)
			(xy 439.534105 -301.787455) (xy 439.549815 -301.736525) (xy 439.572941 -301.688504) (xy 439.602965 -301.644467)
			(xy 439.639217 -301.605396) (xy 439.680888 -301.572165) (xy 439.727046 -301.545516) (xy 439.77666 -301.526044)
			(xy 439.828622 -301.514184) (xy 439.881772 -301.510201) (xy 439.934922 -301.514184) (xy 439.986884 -301.526044)
			(xy 440.036498 -301.545516) (xy 440.082656 -301.572165) (xy 440.124327 -301.605396) (xy 440.160579 -301.644467)
			(xy 440.190603 -301.688504) (xy 440.213729 -301.736525) (xy 440.229439 -301.787455) (xy 440.237382 -301.840159)
			(xy 440.23788 -301.866808) (xy 440.237387 -301.893203) (xy 454.655672 -301.893203) (xy 454.655672 -301.839905)
			(xy 454.663615 -301.787201) (xy 454.679325 -301.736271) (xy 454.702451 -301.68825) (xy 454.732475 -301.644213)
			(xy 454.768727 -301.605142) (xy 454.810398 -301.571911) (xy 454.856556 -301.545262) (xy 454.90617 -301.52579)
			(xy 454.958132 -301.51393) (xy 455.011282 -301.509947) (xy 455.064432 -301.51393) (xy 455.116394 -301.52579)
			(xy 455.166008 -301.545262) (xy 455.212166 -301.571911) (xy 455.253837 -301.605142) (xy 455.290089 -301.644213)
			(xy 455.320113 -301.68825) (xy 455.343239 -301.736271) (xy 455.358949 -301.787201) (xy 455.366892 -301.839905)
			(xy 455.36739 -301.866554) (xy 455.366892 -301.893203) (xy 455.358949 -301.945907) (xy 455.343239 -301.996837)
			(xy 455.320113 -302.044858) (xy 455.290089 -302.088895) (xy 455.253837 -302.127966) (xy 455.212166 -302.161197)
			(xy 455.166008 -302.187846) (xy 455.116394 -302.207318) (xy 455.064432 -302.219178) (xy 455.011282 -302.223162)
			(xy 454.958132 -302.219178) (xy 454.90617 -302.207318) (xy 454.856556 -302.187846) (xy 454.810398 -302.161197)
			(xy 454.768727 -302.127966) (xy 454.732475 -302.088895) (xy 454.702451 -302.044858) (xy 454.679325 -301.996837)
			(xy 454.663615 -301.945907) (xy 454.655672 -301.893203) (xy 440.237387 -301.893203) (xy 440.237382 -301.893457)
			(xy 440.229439 -301.946161) (xy 440.213729 -301.997091) (xy 440.190603 -302.045112) (xy 440.160579 -302.089149)
			(xy 440.124327 -302.12822) (xy 440.082656 -302.161451) (xy 440.036498 -302.1881) (xy 439.986884 -302.207572)
			(xy 439.934922 -302.219432) (xy 439.881772 -302.223416) (xy 439.828622 -302.219432) (xy 439.77666 -302.207572)
			(xy 439.727046 -302.1881) (xy 439.680888 -302.161451) (xy 439.639217 -302.12822) (xy 439.602965 -302.089149)
			(xy 439.572941 -302.045112) (xy 439.549815 -301.997091) (xy 439.534105 -301.946161) (xy 439.526162 -301.893457)
			(xy 425.191654 -301.893457) (xy 425.183749 -301.945907) (xy 425.168039 -301.996837) (xy 425.144913 -302.044858)
			(xy 425.114889 -302.088895) (xy 425.078637 -302.127966) (xy 425.036966 -302.161197) (xy 424.990808 -302.187846)
			(xy 424.941194 -302.207318) (xy 424.889232 -302.219178) (xy 424.836082 -302.223162) (xy 424.782932 -302.219178)
			(xy 424.73097 -302.207318) (xy 424.681356 -302.187846) (xy 424.635198 -302.161197) (xy 424.593527 -302.127966)
			(xy 424.557275 -302.088895) (xy 424.527251 -302.044858) (xy 424.504125 -301.996837) (xy 424.488415 -301.945907)
			(xy 424.480472 -301.893203) (xy 410.078692 -301.893203) (xy 410.070749 -301.945907) (xy 410.055039 -301.996837)
			(xy 410.031913 -302.044858) (xy 410.001889 -302.088895) (xy 409.965637 -302.127966) (xy 409.923966 -302.161197)
			(xy 409.877808 -302.187846) (xy 409.828194 -302.207318) (xy 409.776232 -302.219178) (xy 409.723082 -302.223162)
			(xy 409.669932 -302.219178) (xy 409.61797 -302.207318) (xy 409.568356 -302.187846) (xy 409.522198 -302.161197)
			(xy 409.480527 -302.127966) (xy 409.444275 -302.088895) (xy 409.414251 -302.044858) (xy 409.391125 -301.996837)
			(xy 409.375415 -301.945907) (xy 409.367472 -301.893203) (xy 407.4668 -301.893203) (xy 407.4668 -302.743341)
			(xy 409.367472 -302.743341) (xy 409.367472 -302.690043) (xy 409.375415 -302.637339) (xy 409.391125 -302.586409)
			(xy 409.414251 -302.538388) (xy 409.444275 -302.494351) (xy 409.480527 -302.45528) (xy 409.522198 -302.422049)
			(xy 409.568356 -302.3954) (xy 409.61797 -302.375928) (xy 409.669932 -302.364068) (xy 409.723082 -302.360085)
			(xy 409.776232 -302.364068) (xy 409.828194 -302.375928) (xy 409.877808 -302.3954) (xy 409.923966 -302.422049)
			(xy 409.965637 -302.45528) (xy 410.001889 -302.494351) (xy 410.031913 -302.538388) (xy 410.055039 -302.586409)
			(xy 410.070749 -302.637339) (xy 410.078692 -302.690043) (xy 410.07919 -302.716692) (xy 410.078692 -302.743341)
			(xy 420.380404 -302.743341) (xy 420.380404 -302.690043) (xy 420.388347 -302.637339) (xy 420.404057 -302.586409)
			(xy 420.427183 -302.538388) (xy 420.457207 -302.494351) (xy 420.493459 -302.45528) (xy 420.53513 -302.422049)
			(xy 420.581288 -302.3954) (xy 420.630902 -302.375928) (xy 420.682864 -302.364068) (xy 420.736014 -302.360085)
			(xy 420.789164 -302.364068) (xy 420.841126 -302.375928) (xy 420.89074 -302.3954) (xy 420.936898 -302.422049)
			(xy 420.978569 -302.45528) (xy 421.014821 -302.494351) (xy 421.044845 -302.538388) (xy 421.067971 -302.586409)
			(xy 421.083681 -302.637339) (xy 421.091624 -302.690043) (xy 421.092122 -302.716692) (xy 421.091624 -302.743341)
			(xy 424.480472 -302.743341) (xy 424.480472 -302.690043) (xy 424.488415 -302.637339) (xy 424.504125 -302.586409)
			(xy 424.527251 -302.538388) (xy 424.557275 -302.494351) (xy 424.593527 -302.45528) (xy 424.635198 -302.422049)
			(xy 424.681356 -302.3954) (xy 424.73097 -302.375928) (xy 424.782932 -302.364068) (xy 424.836082 -302.360085)
			(xy 424.889232 -302.364068) (xy 424.941194 -302.375928) (xy 424.990808 -302.3954) (xy 425.036966 -302.422049)
			(xy 425.078637 -302.45528) (xy 425.114889 -302.494351) (xy 425.144913 -302.538388) (xy 425.168039 -302.586409)
			(xy 425.183749 -302.637339) (xy 425.191692 -302.690043) (xy 425.19219 -302.716692) (xy 425.191692 -302.743341)
			(xy 435.468004 -302.743341) (xy 435.468004 -302.690043) (xy 435.475947 -302.637339) (xy 435.491657 -302.586409)
			(xy 435.514783 -302.538388) (xy 435.544807 -302.494351) (xy 435.581059 -302.45528) (xy 435.62273 -302.422049)
			(xy 435.668888 -302.3954) (xy 435.718502 -302.375928) (xy 435.770464 -302.364068) (xy 435.823614 -302.360085)
			(xy 435.876764 -302.364068) (xy 435.928726 -302.375928) (xy 435.97834 -302.3954) (xy 436.024498 -302.422049)
			(xy 436.066169 -302.45528) (xy 436.102421 -302.494351) (xy 436.132445 -302.538388) (xy 436.155571 -302.586409)
			(xy 436.171281 -302.637339) (xy 436.179224 -302.690043) (xy 436.179722 -302.716692) (xy 436.179224 -302.743341)
			(xy 439.568072 -302.743341) (xy 439.568072 -302.690043) (xy 439.576015 -302.637339) (xy 439.591725 -302.586409)
			(xy 439.614851 -302.538388) (xy 439.644875 -302.494351) (xy 439.681127 -302.45528) (xy 439.722798 -302.422049)
			(xy 439.768956 -302.3954) (xy 439.81857 -302.375928) (xy 439.870532 -302.364068) (xy 439.923682 -302.360085)
			(xy 439.976832 -302.364068) (xy 440.028794 -302.375928) (xy 440.078408 -302.3954) (xy 440.124566 -302.422049)
			(xy 440.166237 -302.45528) (xy 440.202489 -302.494351) (xy 440.232513 -302.538388) (xy 440.255639 -302.586409)
			(xy 440.271349 -302.637339) (xy 440.279292 -302.690043) (xy 440.27979 -302.716692) (xy 440.279292 -302.743341)
			(xy 450.555604 -302.743341) (xy 450.555604 -302.690043) (xy 450.563547 -302.637339) (xy 450.579257 -302.586409)
			(xy 450.602383 -302.538388) (xy 450.632407 -302.494351) (xy 450.668659 -302.45528) (xy 450.71033 -302.422049)
			(xy 450.756488 -302.3954) (xy 450.806102 -302.375928) (xy 450.858064 -302.364068) (xy 450.911214 -302.360085)
			(xy 450.964364 -302.364068) (xy 451.016326 -302.375928) (xy 451.06594 -302.3954) (xy 451.112098 -302.422049)
			(xy 451.153769 -302.45528) (xy 451.190021 -302.494351) (xy 451.220045 -302.538388) (xy 451.243171 -302.586409)
			(xy 451.258881 -302.637339) (xy 451.266824 -302.690043) (xy 451.267322 -302.716692) (xy 451.266824 -302.743341)
			(xy 454.655672 -302.743341) (xy 454.655672 -302.690043) (xy 454.663615 -302.637339) (xy 454.679325 -302.586409)
			(xy 454.702451 -302.538388) (xy 454.732475 -302.494351) (xy 454.768727 -302.45528) (xy 454.810398 -302.422049)
			(xy 454.856556 -302.3954) (xy 454.90617 -302.375928) (xy 454.958132 -302.364068) (xy 455.011282 -302.360085)
			(xy 455.064432 -302.364068) (xy 455.116394 -302.375928) (xy 455.166008 -302.3954) (xy 455.212166 -302.422049)
			(xy 455.253837 -302.45528) (xy 455.290089 -302.494351) (xy 455.320113 -302.538388) (xy 455.343239 -302.586409)
			(xy 455.358949 -302.637339) (xy 455.366892 -302.690043) (xy 455.36739 -302.716692) (xy 455.366892 -302.743341)
			(xy 455.358949 -302.796045) (xy 455.343239 -302.846975) (xy 455.320113 -302.894996) (xy 455.290089 -302.939033)
			(xy 455.253837 -302.978104) (xy 455.212166 -303.011335) (xy 455.166008 -303.037984) (xy 455.116394 -303.057456)
			(xy 455.064432 -303.069316) (xy 455.011282 -303.0733) (xy 454.958132 -303.069316) (xy 454.90617 -303.057456)
			(xy 454.856556 -303.037984) (xy 454.810398 -303.011335) (xy 454.768727 -302.978104) (xy 454.732475 -302.939033)
			(xy 454.702451 -302.894996) (xy 454.679325 -302.846975) (xy 454.663615 -302.796045) (xy 454.655672 -302.743341)
			(xy 451.266824 -302.743341) (xy 451.258881 -302.796045) (xy 451.243171 -302.846975) (xy 451.220045 -302.894996)
			(xy 451.190021 -302.939033) (xy 451.153769 -302.978104) (xy 451.112098 -303.011335) (xy 451.06594 -303.037984)
			(xy 451.016326 -303.057456) (xy 450.964364 -303.069316) (xy 450.911214 -303.0733) (xy 450.858064 -303.069316)
			(xy 450.806102 -303.057456) (xy 450.756488 -303.037984) (xy 450.71033 -303.011335) (xy 450.668659 -302.978104)
			(xy 450.632407 -302.939033) (xy 450.602383 -302.894996) (xy 450.579257 -302.846975) (xy 450.563547 -302.796045)
			(xy 450.555604 -302.743341) (xy 440.279292 -302.743341) (xy 440.271349 -302.796045) (xy 440.255639 -302.846975)
			(xy 440.232513 -302.894996) (xy 440.202489 -302.939033) (xy 440.166237 -302.978104) (xy 440.124566 -303.011335)
			(xy 440.078408 -303.037984) (xy 440.028794 -303.057456) (xy 439.976832 -303.069316) (xy 439.923682 -303.0733)
			(xy 439.870532 -303.069316) (xy 439.81857 -303.057456) (xy 439.768956 -303.037984) (xy 439.722798 -303.011335)
			(xy 439.681127 -302.978104) (xy 439.644875 -302.939033) (xy 439.614851 -302.894996) (xy 439.591725 -302.846975)
			(xy 439.576015 -302.796045) (xy 439.568072 -302.743341) (xy 436.179224 -302.743341) (xy 436.171281 -302.796045)
			(xy 436.155571 -302.846975) (xy 436.132445 -302.894996) (xy 436.102421 -302.939033) (xy 436.066169 -302.978104)
			(xy 436.024498 -303.011335) (xy 435.97834 -303.037984) (xy 435.928726 -303.057456) (xy 435.876764 -303.069316)
			(xy 435.823614 -303.0733) (xy 435.770464 -303.069316) (xy 435.718502 -303.057456) (xy 435.668888 -303.037984)
			(xy 435.62273 -303.011335) (xy 435.581059 -302.978104) (xy 435.544807 -302.939033) (xy 435.514783 -302.894996)
			(xy 435.491657 -302.846975) (xy 435.475947 -302.796045) (xy 435.468004 -302.743341) (xy 425.191692 -302.743341)
			(xy 425.183749 -302.796045) (xy 425.168039 -302.846975) (xy 425.144913 -302.894996) (xy 425.114889 -302.939033)
			(xy 425.078637 -302.978104) (xy 425.036966 -303.011335) (xy 424.990808 -303.037984) (xy 424.941194 -303.057456)
			(xy 424.889232 -303.069316) (xy 424.836082 -303.0733) (xy 424.782932 -303.069316) (xy 424.73097 -303.057456)
			(xy 424.681356 -303.037984) (xy 424.635198 -303.011335) (xy 424.593527 -302.978104) (xy 424.557275 -302.939033)
			(xy 424.527251 -302.894996) (xy 424.504125 -302.846975) (xy 424.488415 -302.796045) (xy 424.480472 -302.743341)
			(xy 421.091624 -302.743341) (xy 421.083681 -302.796045) (xy 421.067971 -302.846975) (xy 421.044845 -302.894996)
			(xy 421.014821 -302.939033) (xy 420.978569 -302.978104) (xy 420.936898 -303.011335) (xy 420.89074 -303.037984)
			(xy 420.841126 -303.057456) (xy 420.789164 -303.069316) (xy 420.736014 -303.0733) (xy 420.682864 -303.069316)
			(xy 420.630902 -303.057456) (xy 420.581288 -303.037984) (xy 420.53513 -303.011335) (xy 420.493459 -302.978104)
			(xy 420.457207 -302.939033) (xy 420.427183 -302.894996) (xy 420.404057 -302.846975) (xy 420.388347 -302.796045)
			(xy 420.380404 -302.743341) (xy 410.078692 -302.743341) (xy 410.070749 -302.796045) (xy 410.055039 -302.846975)
			(xy 410.031913 -302.894996) (xy 410.001889 -302.939033) (xy 409.965637 -302.978104) (xy 409.923966 -303.011335)
			(xy 409.877808 -303.037984) (xy 409.828194 -303.057456) (xy 409.776232 -303.069316) (xy 409.723082 -303.0733)
			(xy 409.669932 -303.069316) (xy 409.61797 -303.057456) (xy 409.568356 -303.037984) (xy 409.522198 -303.011335)
			(xy 409.480527 -302.978104) (xy 409.444275 -302.939033) (xy 409.414251 -302.894996) (xy 409.391125 -302.846975)
			(xy 409.375415 -302.796045) (xy 409.367472 -302.743341) (xy 407.4668 -302.743341) (xy 407.4668 -303.593225)
			(xy 420.380404 -303.593225) (xy 420.380404 -303.539927) (xy 420.388347 -303.487223) (xy 420.404057 -303.436293)
			(xy 420.427183 -303.388272) (xy 420.457207 -303.344235) (xy 420.493459 -303.305164) (xy 420.53513 -303.271933)
			(xy 420.581288 -303.245284) (xy 420.630902 -303.225812) (xy 420.682864 -303.213952) (xy 420.736014 -303.209969)
			(xy 420.789164 -303.213952) (xy 420.841126 -303.225812) (xy 420.89074 -303.245284) (xy 420.936898 -303.271933)
			(xy 420.978569 -303.305164) (xy 421.014821 -303.344235) (xy 421.044845 -303.388272) (xy 421.067971 -303.436293)
			(xy 421.083681 -303.487223) (xy 421.091624 -303.539927) (xy 421.092122 -303.566576) (xy 421.091624 -303.593225)
			(xy 435.468004 -303.593225) (xy 435.468004 -303.539927) (xy 435.475947 -303.487223) (xy 435.491657 -303.436293)
			(xy 435.514783 -303.388272) (xy 435.544807 -303.344235) (xy 435.581059 -303.305164) (xy 435.62273 -303.271933)
			(xy 435.668888 -303.245284) (xy 435.718502 -303.225812) (xy 435.770464 -303.213952) (xy 435.823614 -303.209969)
			(xy 435.876764 -303.213952) (xy 435.928726 -303.225812) (xy 435.97834 -303.245284) (xy 436.024498 -303.271933)
			(xy 436.066169 -303.305164) (xy 436.102421 -303.344235) (xy 436.132445 -303.388272) (xy 436.155571 -303.436293)
			(xy 436.171281 -303.487223) (xy 436.179224 -303.539927) (xy 436.179722 -303.566576) (xy 436.179224 -303.593225)
			(xy 450.555604 -303.593225) (xy 450.555604 -303.539927) (xy 450.563547 -303.487223) (xy 450.579257 -303.436293)
			(xy 450.602383 -303.388272) (xy 450.632407 -303.344235) (xy 450.668659 -303.305164) (xy 450.71033 -303.271933)
			(xy 450.756488 -303.245284) (xy 450.806102 -303.225812) (xy 450.858064 -303.213952) (xy 450.911214 -303.209969)
			(xy 450.964364 -303.213952) (xy 451.016326 -303.225812) (xy 451.06594 -303.245284) (xy 451.112098 -303.271933)
			(xy 451.153769 -303.305164) (xy 451.190021 -303.344235) (xy 451.220045 -303.388272) (xy 451.243171 -303.436293)
			(xy 451.258881 -303.487223) (xy 451.266824 -303.539927) (xy 451.267322 -303.566576) (xy 451.266824 -303.593225)
			(xy 451.258881 -303.645929) (xy 451.243171 -303.696859) (xy 451.220045 -303.74488) (xy 451.190021 -303.788917)
			(xy 451.153769 -303.827988) (xy 451.112098 -303.861219) (xy 451.06594 -303.887868) (xy 451.016326 -303.90734)
			(xy 450.964364 -303.9192) (xy 450.911214 -303.923184) (xy 450.858064 -303.9192) (xy 450.806102 -303.90734)
			(xy 450.756488 -303.887868) (xy 450.71033 -303.861219) (xy 450.668659 -303.827988) (xy 450.632407 -303.788917)
			(xy 450.602383 -303.74488) (xy 450.579257 -303.696859) (xy 450.563547 -303.645929) (xy 450.555604 -303.593225)
			(xy 436.179224 -303.593225) (xy 436.171281 -303.645929) (xy 436.155571 -303.696859) (xy 436.132445 -303.74488)
			(xy 436.102421 -303.788917) (xy 436.066169 -303.827988) (xy 436.024498 -303.861219) (xy 435.97834 -303.887868)
			(xy 435.928726 -303.90734) (xy 435.876764 -303.9192) (xy 435.823614 -303.923184) (xy 435.770464 -303.9192)
			(xy 435.718502 -303.90734) (xy 435.668888 -303.887868) (xy 435.62273 -303.861219) (xy 435.581059 -303.827988)
			(xy 435.544807 -303.788917) (xy 435.514783 -303.74488) (xy 435.491657 -303.696859) (xy 435.475947 -303.645929)
			(xy 435.468004 -303.593225) (xy 421.091624 -303.593225) (xy 421.083681 -303.645929) (xy 421.067971 -303.696859)
			(xy 421.044845 -303.74488) (xy 421.014821 -303.788917) (xy 420.978569 -303.827988) (xy 420.936898 -303.861219)
			(xy 420.89074 -303.887868) (xy 420.841126 -303.90734) (xy 420.789164 -303.9192) (xy 420.736014 -303.923184)
			(xy 420.682864 -303.9192) (xy 420.630902 -303.90734) (xy 420.581288 -303.887868) (xy 420.53513 -303.861219)
			(xy 420.493459 -303.827988) (xy 420.457207 -303.788917) (xy 420.427183 -303.74488) (xy 420.404057 -303.696859)
			(xy 420.388347 -303.645929) (xy 420.380404 -303.593225) (xy 407.4668 -303.593225) (xy 407.4668 -304.443363)
			(xy 409.367472 -304.443363) (xy 409.367472 -304.390065) (xy 409.375415 -304.337361) (xy 409.391125 -304.286431)
			(xy 409.414251 -304.23841) (xy 409.444275 -304.194373) (xy 409.480527 -304.155302) (xy 409.522198 -304.122071)
			(xy 409.568356 -304.095422) (xy 409.61797 -304.07595) (xy 409.669932 -304.06409) (xy 409.723082 -304.060107)
			(xy 409.776232 -304.06409) (xy 409.828194 -304.07595) (xy 409.877808 -304.095422) (xy 409.923966 -304.122071)
			(xy 409.965637 -304.155302) (xy 410.001889 -304.194373) (xy 410.031913 -304.23841) (xy 410.055039 -304.286431)
			(xy 410.070749 -304.337361) (xy 410.078692 -304.390065) (xy 410.07919 -304.416714) (xy 410.078692 -304.443363)
			(xy 424.480472 -304.443363) (xy 424.480472 -304.390065) (xy 424.488415 -304.337361) (xy 424.504125 -304.286431)
			(xy 424.527251 -304.23841) (xy 424.557275 -304.194373) (xy 424.593527 -304.155302) (xy 424.635198 -304.122071)
			(xy 424.681356 -304.095422) (xy 424.73097 -304.07595) (xy 424.782932 -304.06409) (xy 424.836082 -304.060107)
			(xy 424.889232 -304.06409) (xy 424.941194 -304.07595) (xy 424.990808 -304.095422) (xy 425.036966 -304.122071)
			(xy 425.078637 -304.155302) (xy 425.114889 -304.194373) (xy 425.144913 -304.23841) (xy 425.168039 -304.286431)
			(xy 425.183749 -304.337361) (xy 425.191692 -304.390065) (xy 425.19219 -304.416714) (xy 425.191692 -304.443363)
			(xy 439.568072 -304.443363) (xy 439.568072 -304.390065) (xy 439.576015 -304.337361) (xy 439.591725 -304.286431)
			(xy 439.614851 -304.23841) (xy 439.644875 -304.194373) (xy 439.681127 -304.155302) (xy 439.722798 -304.122071)
			(xy 439.768956 -304.095422) (xy 439.81857 -304.07595) (xy 439.870532 -304.06409) (xy 439.923682 -304.060107)
			(xy 439.976832 -304.06409) (xy 440.028794 -304.07595) (xy 440.078408 -304.095422) (xy 440.124566 -304.122071)
			(xy 440.166237 -304.155302) (xy 440.202489 -304.194373) (xy 440.232513 -304.23841) (xy 440.255639 -304.286431)
			(xy 440.271349 -304.337361) (xy 440.279292 -304.390065) (xy 440.27979 -304.416714) (xy 440.279292 -304.443363)
			(xy 454.655672 -304.443363) (xy 454.655672 -304.390065) (xy 454.663615 -304.337361) (xy 454.679325 -304.286431)
			(xy 454.702451 -304.23841) (xy 454.732475 -304.194373) (xy 454.768727 -304.155302) (xy 454.810398 -304.122071)
			(xy 454.856556 -304.095422) (xy 454.90617 -304.07595) (xy 454.958132 -304.06409) (xy 455.011282 -304.060107)
			(xy 455.064432 -304.06409) (xy 455.116394 -304.07595) (xy 455.166008 -304.095422) (xy 455.212166 -304.122071)
			(xy 455.253837 -304.155302) (xy 455.290089 -304.194373) (xy 455.320113 -304.23841) (xy 455.343239 -304.286431)
			(xy 455.358949 -304.337361) (xy 455.366892 -304.390065) (xy 455.36739 -304.416714) (xy 455.366892 -304.443363)
			(xy 455.358949 -304.496067) (xy 455.343239 -304.546997) (xy 455.320113 -304.595018) (xy 455.290089 -304.639055)
			(xy 455.253837 -304.678126) (xy 455.212166 -304.711357) (xy 455.166008 -304.738006) (xy 455.116394 -304.757478)
			(xy 455.064432 -304.769338) (xy 455.011282 -304.773322) (xy 454.958132 -304.769338) (xy 454.90617 -304.757478)
			(xy 454.856556 -304.738006) (xy 454.810398 -304.711357) (xy 454.768727 -304.678126) (xy 454.732475 -304.639055)
			(xy 454.702451 -304.595018) (xy 454.679325 -304.546997) (xy 454.663615 -304.496067) (xy 454.655672 -304.443363)
			(xy 440.279292 -304.443363) (xy 440.271349 -304.496067) (xy 440.255639 -304.546997) (xy 440.232513 -304.595018)
			(xy 440.202489 -304.639055) (xy 440.166237 -304.678126) (xy 440.124566 -304.711357) (xy 440.078408 -304.738006)
			(xy 440.028794 -304.757478) (xy 439.976832 -304.769338) (xy 439.923682 -304.773322) (xy 439.870532 -304.769338)
			(xy 439.81857 -304.757478) (xy 439.768956 -304.738006) (xy 439.722798 -304.711357) (xy 439.681127 -304.678126)
			(xy 439.644875 -304.639055) (xy 439.614851 -304.595018) (xy 439.591725 -304.546997) (xy 439.576015 -304.496067)
			(xy 439.568072 -304.443363) (xy 425.191692 -304.443363) (xy 425.183749 -304.496067) (xy 425.168039 -304.546997)
			(xy 425.144913 -304.595018) (xy 425.114889 -304.639055) (xy 425.078637 -304.678126) (xy 425.036966 -304.711357)
			(xy 424.990808 -304.738006) (xy 424.941194 -304.757478) (xy 424.889232 -304.769338) (xy 424.836082 -304.773322)
			(xy 424.782932 -304.769338) (xy 424.73097 -304.757478) (xy 424.681356 -304.738006) (xy 424.635198 -304.711357)
			(xy 424.593527 -304.678126) (xy 424.557275 -304.639055) (xy 424.527251 -304.595018) (xy 424.504125 -304.546997)
			(xy 424.488415 -304.496067) (xy 424.480472 -304.443363) (xy 410.078692 -304.443363) (xy 410.070749 -304.496067)
			(xy 410.055039 -304.546997) (xy 410.031913 -304.595018) (xy 410.001889 -304.639055) (xy 409.965637 -304.678126)
			(xy 409.923966 -304.711357) (xy 409.877808 -304.738006) (xy 409.828194 -304.757478) (xy 409.776232 -304.769338)
			(xy 409.723082 -304.773322) (xy 409.669932 -304.769338) (xy 409.61797 -304.757478) (xy 409.568356 -304.738006)
			(xy 409.522198 -304.711357) (xy 409.480527 -304.678126) (xy 409.444275 -304.639055) (xy 409.414251 -304.595018)
			(xy 409.391125 -304.546997) (xy 409.375415 -304.496067) (xy 409.367472 -304.443363) (xy 407.4668 -304.443363)
			(xy 407.4668 -305.293247) (xy 420.380404 -305.293247) (xy 420.380404 -305.239949) (xy 420.388347 -305.187245)
			(xy 420.404057 -305.136315) (xy 420.427183 -305.088294) (xy 420.457207 -305.044257) (xy 420.493459 -305.005186)
			(xy 420.53513 -304.971955) (xy 420.581288 -304.945306) (xy 420.630902 -304.925834) (xy 420.682864 -304.913974)
			(xy 420.736014 -304.909991) (xy 420.789164 -304.913974) (xy 420.841126 -304.925834) (xy 420.89074 -304.945306)
			(xy 420.936898 -304.971955) (xy 420.978569 -305.005186) (xy 421.014821 -305.044257) (xy 421.044845 -305.088294)
			(xy 421.067971 -305.136315) (xy 421.083681 -305.187245) (xy 421.091624 -305.239949) (xy 421.092122 -305.266598)
			(xy 421.091624 -305.293247) (xy 435.468004 -305.293247) (xy 435.468004 -305.239949) (xy 435.475947 -305.187245)
			(xy 435.491657 -305.136315) (xy 435.514783 -305.088294) (xy 435.544807 -305.044257) (xy 435.581059 -305.005186)
			(xy 435.62273 -304.971955) (xy 435.668888 -304.945306) (xy 435.718502 -304.925834) (xy 435.770464 -304.913974)
			(xy 435.823614 -304.909991) (xy 435.876764 -304.913974) (xy 435.928726 -304.925834) (xy 435.97834 -304.945306)
			(xy 436.024498 -304.971955) (xy 436.066169 -305.005186) (xy 436.102421 -305.044257) (xy 436.132445 -305.088294)
			(xy 436.155571 -305.136315) (xy 436.171281 -305.187245) (xy 436.179224 -305.239949) (xy 436.179722 -305.266598)
			(xy 436.179224 -305.293247) (xy 450.555604 -305.293247) (xy 450.555604 -305.239949) (xy 450.563547 -305.187245)
			(xy 450.579257 -305.136315) (xy 450.602383 -305.088294) (xy 450.632407 -305.044257) (xy 450.668659 -305.005186)
			(xy 450.71033 -304.971955) (xy 450.756488 -304.945306) (xy 450.806102 -304.925834) (xy 450.858064 -304.913974)
			(xy 450.911214 -304.909991) (xy 450.964364 -304.913974) (xy 451.016326 -304.925834) (xy 451.06594 -304.945306)
			(xy 451.112098 -304.971955) (xy 451.153769 -305.005186) (xy 451.190021 -305.044257) (xy 451.220045 -305.088294)
			(xy 451.243171 -305.136315) (xy 451.258881 -305.187245) (xy 451.266824 -305.239949) (xy 451.267322 -305.266598)
			(xy 451.266824 -305.293247) (xy 451.258881 -305.345951) (xy 451.243171 -305.396881) (xy 451.220045 -305.444902)
			(xy 451.190021 -305.488939) (xy 451.153769 -305.52801) (xy 451.112098 -305.561241) (xy 451.06594 -305.58789)
			(xy 451.016326 -305.607362) (xy 450.964364 -305.619222) (xy 450.911214 -305.623206) (xy 450.858064 -305.619222)
			(xy 450.806102 -305.607362) (xy 450.756488 -305.58789) (xy 450.71033 -305.561241) (xy 450.668659 -305.52801)
			(xy 450.632407 -305.488939) (xy 450.602383 -305.444902) (xy 450.579257 -305.396881) (xy 450.563547 -305.345951)
			(xy 450.555604 -305.293247) (xy 436.179224 -305.293247) (xy 436.171281 -305.345951) (xy 436.155571 -305.396881)
			(xy 436.132445 -305.444902) (xy 436.102421 -305.488939) (xy 436.066169 -305.52801) (xy 436.024498 -305.561241)
			(xy 435.97834 -305.58789) (xy 435.928726 -305.607362) (xy 435.876764 -305.619222) (xy 435.823614 -305.623206)
			(xy 435.770464 -305.619222) (xy 435.718502 -305.607362) (xy 435.668888 -305.58789) (xy 435.62273 -305.561241)
			(xy 435.581059 -305.52801) (xy 435.544807 -305.488939) (xy 435.514783 -305.444902) (xy 435.491657 -305.396881)
			(xy 435.475947 -305.345951) (xy 435.468004 -305.293247) (xy 421.091624 -305.293247) (xy 421.083681 -305.345951)
			(xy 421.067971 -305.396881) (xy 421.044845 -305.444902) (xy 421.014821 -305.488939) (xy 420.978569 -305.52801)
			(xy 420.936898 -305.561241) (xy 420.89074 -305.58789) (xy 420.841126 -305.607362) (xy 420.789164 -305.619222)
			(xy 420.736014 -305.623206) (xy 420.682864 -305.619222) (xy 420.630902 -305.607362) (xy 420.581288 -305.58789)
			(xy 420.53513 -305.561241) (xy 420.493459 -305.52801) (xy 420.457207 -305.488939) (xy 420.427183 -305.444902)
			(xy 420.404057 -305.396881) (xy 420.388347 -305.345951) (xy 420.380404 -305.293247) (xy 407.4668 -305.293247)
			(xy 407.4668 -306.143385) (xy 409.367472 -306.143385) (xy 409.367472 -306.090087) (xy 409.375415 -306.037383)
			(xy 409.391125 -305.986453) (xy 409.414251 -305.938432) (xy 409.444275 -305.894395) (xy 409.480527 -305.855324)
			(xy 409.522198 -305.822093) (xy 409.568356 -305.795444) (xy 409.61797 -305.775972) (xy 409.669932 -305.764112)
			(xy 409.723082 -305.760129) (xy 409.776232 -305.764112) (xy 409.828194 -305.775972) (xy 409.877808 -305.795444)
			(xy 409.923966 -305.822093) (xy 409.965637 -305.855324) (xy 410.001889 -305.894395) (xy 410.031913 -305.938432)
			(xy 410.055039 -305.986453) (xy 410.070749 -306.037383) (xy 410.078692 -306.090087) (xy 410.07919 -306.116736)
			(xy 410.078692 -306.143385) (xy 424.480472 -306.143385) (xy 424.480472 -306.090087) (xy 424.488415 -306.037383)
			(xy 424.504125 -305.986453) (xy 424.527251 -305.938432) (xy 424.557275 -305.894395) (xy 424.593527 -305.855324)
			(xy 424.635198 -305.822093) (xy 424.681356 -305.795444) (xy 424.73097 -305.775972) (xy 424.782932 -305.764112)
			(xy 424.836082 -305.760129) (xy 424.889232 -305.764112) (xy 424.941194 -305.775972) (xy 424.990808 -305.795444)
			(xy 425.036966 -305.822093) (xy 425.078637 -305.855324) (xy 425.114889 -305.894395) (xy 425.144913 -305.938432)
			(xy 425.168039 -305.986453) (xy 425.183749 -306.037383) (xy 425.191692 -306.090087) (xy 425.19219 -306.116736)
			(xy 425.191692 -306.143385) (xy 439.568072 -306.143385) (xy 439.568072 -306.090087) (xy 439.576015 -306.037383)
			(xy 439.591725 -305.986453) (xy 439.614851 -305.938432) (xy 439.644875 -305.894395) (xy 439.681127 -305.855324)
			(xy 439.722798 -305.822093) (xy 439.768956 -305.795444) (xy 439.81857 -305.775972) (xy 439.870532 -305.764112)
			(xy 439.923682 -305.760129) (xy 439.976832 -305.764112) (xy 440.028794 -305.775972) (xy 440.078408 -305.795444)
			(xy 440.124566 -305.822093) (xy 440.166237 -305.855324) (xy 440.202489 -305.894395) (xy 440.232513 -305.938432)
			(xy 440.255639 -305.986453) (xy 440.271349 -306.037383) (xy 440.279292 -306.090087) (xy 440.27979 -306.116736)
			(xy 440.279292 -306.143385) (xy 454.655672 -306.143385) (xy 454.655672 -306.090087) (xy 454.663615 -306.037383)
			(xy 454.679325 -305.986453) (xy 454.702451 -305.938432) (xy 454.732475 -305.894395) (xy 454.768727 -305.855324)
			(xy 454.810398 -305.822093) (xy 454.856556 -305.795444) (xy 454.90617 -305.775972) (xy 454.958132 -305.764112)
			(xy 455.011282 -305.760129) (xy 455.064432 -305.764112) (xy 455.116394 -305.775972) (xy 455.166008 -305.795444)
			(xy 455.212166 -305.822093) (xy 455.253837 -305.855324) (xy 455.290089 -305.894395) (xy 455.320113 -305.938432)
			(xy 455.343239 -305.986453) (xy 455.358949 -306.037383) (xy 455.366892 -306.090087) (xy 455.36739 -306.116736)
			(xy 455.366892 -306.143385) (xy 455.358949 -306.196089) (xy 455.343239 -306.247019) (xy 455.320113 -306.29504)
			(xy 455.290089 -306.339077) (xy 455.253837 -306.378148) (xy 455.212166 -306.411379) (xy 455.166008 -306.438028)
			(xy 455.116394 -306.4575) (xy 455.064432 -306.46936) (xy 455.011282 -306.473344) (xy 454.958132 -306.46936)
			(xy 454.90617 -306.4575) (xy 454.856556 -306.438028) (xy 454.810398 -306.411379) (xy 454.768727 -306.378148)
			(xy 454.732475 -306.339077) (xy 454.702451 -306.29504) (xy 454.679325 -306.247019) (xy 454.663615 -306.196089)
			(xy 454.655672 -306.143385) (xy 440.279292 -306.143385) (xy 440.271349 -306.196089) (xy 440.255639 -306.247019)
			(xy 440.232513 -306.29504) (xy 440.202489 -306.339077) (xy 440.166237 -306.378148) (xy 440.124566 -306.411379)
			(xy 440.078408 -306.438028) (xy 440.028794 -306.4575) (xy 439.976832 -306.46936) (xy 439.923682 -306.473344)
			(xy 439.870532 -306.46936) (xy 439.81857 -306.4575) (xy 439.768956 -306.438028) (xy 439.722798 -306.411379)
			(xy 439.681127 -306.378148) (xy 439.644875 -306.339077) (xy 439.614851 -306.29504) (xy 439.591725 -306.247019)
			(xy 439.576015 -306.196089) (xy 439.568072 -306.143385) (xy 425.191692 -306.143385) (xy 425.183749 -306.196089)
			(xy 425.168039 -306.247019) (xy 425.144913 -306.29504) (xy 425.114889 -306.339077) (xy 425.078637 -306.378148)
			(xy 425.036966 -306.411379) (xy 424.990808 -306.438028) (xy 424.941194 -306.4575) (xy 424.889232 -306.46936)
			(xy 424.836082 -306.473344) (xy 424.782932 -306.46936) (xy 424.73097 -306.4575) (xy 424.681356 -306.438028)
			(xy 424.635198 -306.411379) (xy 424.593527 -306.378148) (xy 424.557275 -306.339077) (xy 424.527251 -306.29504)
			(xy 424.504125 -306.247019) (xy 424.488415 -306.196089) (xy 424.480472 -306.143385) (xy 410.078692 -306.143385)
			(xy 410.070749 -306.196089) (xy 410.055039 -306.247019) (xy 410.031913 -306.29504) (xy 410.001889 -306.339077)
			(xy 409.965637 -306.378148) (xy 409.923966 -306.411379) (xy 409.877808 -306.438028) (xy 409.828194 -306.4575)
			(xy 409.776232 -306.46936) (xy 409.723082 -306.473344) (xy 409.669932 -306.46936) (xy 409.61797 -306.4575)
			(xy 409.568356 -306.438028) (xy 409.522198 -306.411379) (xy 409.480527 -306.378148) (xy 409.444275 -306.339077)
			(xy 409.414251 -306.29504) (xy 409.391125 -306.247019) (xy 409.375415 -306.196089) (xy 409.367472 -306.143385)
			(xy 407.4668 -306.143385) (xy 407.4668 -306.993269) (xy 420.380404 -306.993269) (xy 420.380404 -306.939971)
			(xy 420.388347 -306.887267) (xy 420.404057 -306.836337) (xy 420.427183 -306.788316) (xy 420.457207 -306.744279)
			(xy 420.493459 -306.705208) (xy 420.53513 -306.671977) (xy 420.581288 -306.645328) (xy 420.630902 -306.625856)
			(xy 420.682864 -306.613996) (xy 420.736014 -306.610013) (xy 420.789164 -306.613996) (xy 420.841126 -306.625856)
			(xy 420.89074 -306.645328) (xy 420.936898 -306.671977) (xy 420.978569 -306.705208) (xy 421.014821 -306.744279)
			(xy 421.044845 -306.788316) (xy 421.067971 -306.836337) (xy 421.083681 -306.887267) (xy 421.091624 -306.939971)
			(xy 421.092122 -306.96662) (xy 421.091624 -306.993269) (xy 435.468004 -306.993269) (xy 435.468004 -306.939971)
			(xy 435.475947 -306.887267) (xy 435.491657 -306.836337) (xy 435.514783 -306.788316) (xy 435.544807 -306.744279)
			(xy 435.581059 -306.705208) (xy 435.62273 -306.671977) (xy 435.668888 -306.645328) (xy 435.718502 -306.625856)
			(xy 435.770464 -306.613996) (xy 435.823614 -306.610013) (xy 435.876764 -306.613996) (xy 435.928726 -306.625856)
			(xy 435.97834 -306.645328) (xy 436.024498 -306.671977) (xy 436.066169 -306.705208) (xy 436.102421 -306.744279)
			(xy 436.132445 -306.788316) (xy 436.155571 -306.836337) (xy 436.171281 -306.887267) (xy 436.179224 -306.939971)
			(xy 436.179722 -306.96662) (xy 436.179224 -306.993269) (xy 450.555604 -306.993269) (xy 450.555604 -306.939971)
			(xy 450.563547 -306.887267) (xy 450.579257 -306.836337) (xy 450.602383 -306.788316) (xy 450.632407 -306.744279)
			(xy 450.668659 -306.705208) (xy 450.71033 -306.671977) (xy 450.756488 -306.645328) (xy 450.806102 -306.625856)
			(xy 450.858064 -306.613996) (xy 450.911214 -306.610013) (xy 450.964364 -306.613996) (xy 451.016326 -306.625856)
			(xy 451.06594 -306.645328) (xy 451.112098 -306.671977) (xy 451.153769 -306.705208) (xy 451.190021 -306.744279)
			(xy 451.220045 -306.788316) (xy 451.243171 -306.836337) (xy 451.258881 -306.887267) (xy 451.266824 -306.939971)
			(xy 451.267322 -306.96662) (xy 451.266824 -306.993269) (xy 451.258881 -307.045973) (xy 451.243171 -307.096903)
			(xy 451.220045 -307.144924) (xy 451.190021 -307.188961) (xy 451.153769 -307.228032) (xy 451.112098 -307.261263)
			(xy 451.06594 -307.287912) (xy 451.016326 -307.307384) (xy 450.964364 -307.319244) (xy 450.911214 -307.323228)
			(xy 450.858064 -307.319244) (xy 450.806102 -307.307384) (xy 450.756488 -307.287912) (xy 450.71033 -307.261263)
			(xy 450.668659 -307.228032) (xy 450.632407 -307.188961) (xy 450.602383 -307.144924) (xy 450.579257 -307.096903)
			(xy 450.563547 -307.045973) (xy 450.555604 -306.993269) (xy 436.179224 -306.993269) (xy 436.171281 -307.045973)
			(xy 436.155571 -307.096903) (xy 436.132445 -307.144924) (xy 436.102421 -307.188961) (xy 436.066169 -307.228032)
			(xy 436.024498 -307.261263) (xy 435.97834 -307.287912) (xy 435.928726 -307.307384) (xy 435.876764 -307.319244)
			(xy 435.823614 -307.323228) (xy 435.770464 -307.319244) (xy 435.718502 -307.307384) (xy 435.668888 -307.287912)
			(xy 435.62273 -307.261263) (xy 435.581059 -307.228032) (xy 435.544807 -307.188961) (xy 435.514783 -307.144924)
			(xy 435.491657 -307.096903) (xy 435.475947 -307.045973) (xy 435.468004 -306.993269) (xy 421.091624 -306.993269)
			(xy 421.083681 -307.045973) (xy 421.067971 -307.096903) (xy 421.044845 -307.144924) (xy 421.014821 -307.188961)
			(xy 420.978569 -307.228032) (xy 420.936898 -307.261263) (xy 420.89074 -307.287912) (xy 420.841126 -307.307384)
			(xy 420.789164 -307.319244) (xy 420.736014 -307.323228) (xy 420.682864 -307.319244) (xy 420.630902 -307.307384)
			(xy 420.581288 -307.287912) (xy 420.53513 -307.261263) (xy 420.493459 -307.228032) (xy 420.457207 -307.188961)
			(xy 420.427183 -307.144924) (xy 420.404057 -307.096903) (xy 420.388347 -307.045973) (xy 420.380404 -306.993269)
			(xy 407.4668 -306.993269) (xy 407.4668 -307.843407) (xy 424.480472 -307.843407) (xy 424.480472 -307.790109)
			(xy 424.488415 -307.737405) (xy 424.504125 -307.686475) (xy 424.527251 -307.638454) (xy 424.557275 -307.594417)
			(xy 424.593527 -307.555346) (xy 424.635198 -307.522115) (xy 424.681356 -307.495466) (xy 424.73097 -307.475994)
			(xy 424.782932 -307.464134) (xy 424.836082 -307.460151) (xy 424.889232 -307.464134) (xy 424.941194 -307.475994)
			(xy 424.990808 -307.495466) (xy 425.036966 -307.522115) (xy 425.078637 -307.555346) (xy 425.114889 -307.594417)
			(xy 425.144913 -307.638454) (xy 425.168039 -307.686475) (xy 425.183749 -307.737405) (xy 425.191692 -307.790109)
			(xy 425.19219 -307.816758) (xy 425.191692 -307.843407) (xy 439.568072 -307.843407) (xy 439.568072 -307.790109)
			(xy 439.576015 -307.737405) (xy 439.591725 -307.686475) (xy 439.614851 -307.638454) (xy 439.644875 -307.594417)
			(xy 439.681127 -307.555346) (xy 439.722798 -307.522115) (xy 439.768956 -307.495466) (xy 439.81857 -307.475994)
			(xy 439.870532 -307.464134) (xy 439.923682 -307.460151) (xy 439.976832 -307.464134) (xy 440.028794 -307.475994)
			(xy 440.078408 -307.495466) (xy 440.124566 -307.522115) (xy 440.166237 -307.555346) (xy 440.202489 -307.594417)
			(xy 440.232513 -307.638454) (xy 440.255639 -307.686475) (xy 440.271349 -307.737405) (xy 440.279292 -307.790109)
			(xy 440.27979 -307.816758) (xy 440.279292 -307.843407) (xy 454.655672 -307.843407) (xy 454.655672 -307.790109)
			(xy 454.663615 -307.737405) (xy 454.679325 -307.686475) (xy 454.702451 -307.638454) (xy 454.732475 -307.594417)
			(xy 454.768727 -307.555346) (xy 454.810398 -307.522115) (xy 454.856556 -307.495466) (xy 454.90617 -307.475994)
			(xy 454.958132 -307.464134) (xy 455.011282 -307.460151) (xy 455.064432 -307.464134) (xy 455.116394 -307.475994)
			(xy 455.166008 -307.495466) (xy 455.212166 -307.522115) (xy 455.253837 -307.555346) (xy 455.290089 -307.594417)
			(xy 455.320113 -307.638454) (xy 455.343239 -307.686475) (xy 455.358949 -307.737405) (xy 455.366892 -307.790109)
			(xy 455.36739 -307.816758) (xy 455.366892 -307.843407) (xy 455.358949 -307.896111) (xy 455.343239 -307.947041)
			(xy 455.320113 -307.995062) (xy 455.290089 -308.039099) (xy 455.253837 -308.07817) (xy 455.212166 -308.111401)
			(xy 455.166008 -308.13805) (xy 455.116394 -308.157522) (xy 455.064432 -308.169382) (xy 455.011282 -308.173366)
			(xy 454.958132 -308.169382) (xy 454.90617 -308.157522) (xy 454.856556 -308.13805) (xy 454.810398 -308.111401)
			(xy 454.768727 -308.07817) (xy 454.732475 -308.039099) (xy 454.702451 -307.995062) (xy 454.679325 -307.947041)
			(xy 454.663615 -307.896111) (xy 454.655672 -307.843407) (xy 440.279292 -307.843407) (xy 440.271349 -307.896111)
			(xy 440.255639 -307.947041) (xy 440.232513 -307.995062) (xy 440.202489 -308.039099) (xy 440.166237 -308.07817)
			(xy 440.124566 -308.111401) (xy 440.078408 -308.13805) (xy 440.028794 -308.157522) (xy 439.976832 -308.169382)
			(xy 439.923682 -308.173366) (xy 439.870532 -308.169382) (xy 439.81857 -308.157522) (xy 439.768956 -308.13805)
			(xy 439.722798 -308.111401) (xy 439.681127 -308.07817) (xy 439.644875 -308.039099) (xy 439.614851 -307.995062)
			(xy 439.591725 -307.947041) (xy 439.576015 -307.896111) (xy 439.568072 -307.843407) (xy 425.191692 -307.843407)
			(xy 425.183749 -307.896111) (xy 425.168039 -307.947041) (xy 425.144913 -307.995062) (xy 425.114889 -308.039099)
			(xy 425.078637 -308.07817) (xy 425.036966 -308.111401) (xy 424.990808 -308.13805) (xy 424.941194 -308.157522)
			(xy 424.889232 -308.169382) (xy 424.836082 -308.173366) (xy 424.782932 -308.169382) (xy 424.73097 -308.157522)
			(xy 424.681356 -308.13805) (xy 424.635198 -308.111401) (xy 424.593527 -308.07817) (xy 424.557275 -308.039099)
			(xy 424.527251 -307.995062) (xy 424.504125 -307.947041) (xy 424.488415 -307.896111) (xy 424.480472 -307.843407)
			(xy 407.4668 -307.843407) (xy 407.4668 -308.693291) (xy 420.380404 -308.693291) (xy 420.380404 -308.639993)
			(xy 420.388347 -308.587289) (xy 420.404057 -308.536359) (xy 420.427183 -308.488338) (xy 420.457207 -308.444301)
			(xy 420.493459 -308.40523) (xy 420.53513 -308.371999) (xy 420.581288 -308.34535) (xy 420.630902 -308.325878)
			(xy 420.682864 -308.314018) (xy 420.736014 -308.310035) (xy 420.789164 -308.314018) (xy 420.841126 -308.325878)
			(xy 420.89074 -308.34535) (xy 420.936898 -308.371999) (xy 420.978569 -308.40523) (xy 421.014821 -308.444301)
			(xy 421.044845 -308.488338) (xy 421.067971 -308.536359) (xy 421.083681 -308.587289) (xy 421.091624 -308.639993)
			(xy 421.092122 -308.666642) (xy 421.091624 -308.693291) (xy 435.468004 -308.693291) (xy 435.468004 -308.639993)
			(xy 435.475947 -308.587289) (xy 435.491657 -308.536359) (xy 435.514783 -308.488338) (xy 435.544807 -308.444301)
			(xy 435.581059 -308.40523) (xy 435.62273 -308.371999) (xy 435.668888 -308.34535) (xy 435.718502 -308.325878)
			(xy 435.770464 -308.314018) (xy 435.823614 -308.310035) (xy 435.876764 -308.314018) (xy 435.928726 -308.325878)
			(xy 435.97834 -308.34535) (xy 436.024498 -308.371999) (xy 436.066169 -308.40523) (xy 436.102421 -308.444301)
			(xy 436.132445 -308.488338) (xy 436.155571 -308.536359) (xy 436.171281 -308.587289) (xy 436.179224 -308.639993)
			(xy 436.179722 -308.666642) (xy 436.179224 -308.693291) (xy 450.555604 -308.693291) (xy 450.555604 -308.639993)
			(xy 450.563547 -308.587289) (xy 450.579257 -308.536359) (xy 450.602383 -308.488338) (xy 450.632407 -308.444301)
			(xy 450.668659 -308.40523) (xy 450.71033 -308.371999) (xy 450.756488 -308.34535) (xy 450.806102 -308.325878)
			(xy 450.858064 -308.314018) (xy 450.911214 -308.310035) (xy 450.964364 -308.314018) (xy 451.016326 -308.325878)
			(xy 451.06594 -308.34535) (xy 451.112098 -308.371999) (xy 451.153769 -308.40523) (xy 451.190021 -308.444301)
			(xy 451.220045 -308.488338) (xy 451.243171 -308.536359) (xy 451.258881 -308.587289) (xy 451.266824 -308.639993)
			(xy 451.267322 -308.666642) (xy 451.266824 -308.693291) (xy 451.258881 -308.745995) (xy 451.243171 -308.796925)
			(xy 451.220045 -308.844946) (xy 451.190021 -308.888983) (xy 451.153769 -308.928054) (xy 451.112098 -308.961285)
			(xy 451.06594 -308.987934) (xy 451.016326 -309.007406) (xy 450.964364 -309.019266) (xy 450.911214 -309.02325)
			(xy 450.858064 -309.019266) (xy 450.806102 -309.007406) (xy 450.756488 -308.987934) (xy 450.71033 -308.961285)
			(xy 450.668659 -308.928054) (xy 450.632407 -308.888983) (xy 450.602383 -308.844946) (xy 450.579257 -308.796925)
			(xy 450.563547 -308.745995) (xy 450.555604 -308.693291) (xy 436.179224 -308.693291) (xy 436.171281 -308.745995)
			(xy 436.155571 -308.796925) (xy 436.132445 -308.844946) (xy 436.102421 -308.888983) (xy 436.066169 -308.928054)
			(xy 436.024498 -308.961285) (xy 435.97834 -308.987934) (xy 435.928726 -309.007406) (xy 435.876764 -309.019266)
			(xy 435.823614 -309.02325) (xy 435.770464 -309.019266) (xy 435.718502 -309.007406) (xy 435.668888 -308.987934)
			(xy 435.62273 -308.961285) (xy 435.581059 -308.928054) (xy 435.544807 -308.888983) (xy 435.514783 -308.844946)
			(xy 435.491657 -308.796925) (xy 435.475947 -308.745995) (xy 435.468004 -308.693291) (xy 421.091624 -308.693291)
			(xy 421.083681 -308.745995) (xy 421.067971 -308.796925) (xy 421.044845 -308.844946) (xy 421.014821 -308.888983)
			(xy 420.978569 -308.928054) (xy 420.936898 -308.961285) (xy 420.89074 -308.987934) (xy 420.841126 -309.007406)
			(xy 420.789164 -309.019266) (xy 420.736014 -309.02325) (xy 420.682864 -309.019266) (xy 420.630902 -309.007406)
			(xy 420.581288 -308.987934) (xy 420.53513 -308.961285) (xy 420.493459 -308.928054) (xy 420.457207 -308.888983)
			(xy 420.427183 -308.844946) (xy 420.404057 -308.796925) (xy 420.388347 -308.745995) (xy 420.380404 -308.693291)
			(xy 407.4668 -308.693291) (xy 407.4668 -309.543175) (xy 424.480472 -309.543175) (xy 424.480472 -309.489877)
			(xy 424.488415 -309.437173) (xy 424.504125 -309.386243) (xy 424.527251 -309.338222) (xy 424.557275 -309.294185)
			(xy 424.593527 -309.255114) (xy 424.635198 -309.221883) (xy 424.681356 -309.195234) (xy 424.73097 -309.175762)
			(xy 424.782932 -309.163902) (xy 424.836082 -309.159919) (xy 424.889232 -309.163902) (xy 424.941194 -309.175762)
			(xy 424.990808 -309.195234) (xy 425.036966 -309.221883) (xy 425.078637 -309.255114) (xy 425.114889 -309.294185)
			(xy 425.144913 -309.338222) (xy 425.168039 -309.386243) (xy 425.183749 -309.437173) (xy 425.191692 -309.489877)
			(xy 425.19219 -309.516526) (xy 425.191692 -309.543175) (xy 439.568072 -309.543175) (xy 439.568072 -309.489877)
			(xy 439.576015 -309.437173) (xy 439.591725 -309.386243) (xy 439.614851 -309.338222) (xy 439.644875 -309.294185)
			(xy 439.681127 -309.255114) (xy 439.722798 -309.221883) (xy 439.768956 -309.195234) (xy 439.81857 -309.175762)
			(xy 439.870532 -309.163902) (xy 439.923682 -309.159919) (xy 439.976832 -309.163902) (xy 440.028794 -309.175762)
			(xy 440.078408 -309.195234) (xy 440.124566 -309.221883) (xy 440.166237 -309.255114) (xy 440.202489 -309.294185)
			(xy 440.232513 -309.338222) (xy 440.255639 -309.386243) (xy 440.271349 -309.437173) (xy 440.279292 -309.489877)
			(xy 440.27979 -309.516526) (xy 440.279292 -309.543175) (xy 440.279254 -309.543429) (xy 454.655672 -309.543429)
			(xy 454.655672 -309.490131) (xy 454.663615 -309.437427) (xy 454.679325 -309.386497) (xy 454.702451 -309.338476)
			(xy 454.732475 -309.294439) (xy 454.768727 -309.255368) (xy 454.810398 -309.222137) (xy 454.856556 -309.195488)
			(xy 454.90617 -309.176016) (xy 454.958132 -309.164156) (xy 455.011282 -309.160173) (xy 455.064432 -309.164156)
			(xy 455.116394 -309.176016) (xy 455.166008 -309.195488) (xy 455.212166 -309.222137) (xy 455.253837 -309.255368)
			(xy 455.290089 -309.294439) (xy 455.320113 -309.338476) (xy 455.343239 -309.386497) (xy 455.358949 -309.437427)
			(xy 455.366892 -309.490131) (xy 455.36739 -309.51678) (xy 455.366892 -309.543429) (xy 455.358949 -309.596133)
			(xy 455.343239 -309.647063) (xy 455.320113 -309.695084) (xy 455.290089 -309.739121) (xy 455.253837 -309.778192)
			(xy 455.212166 -309.811423) (xy 455.166008 -309.838072) (xy 455.116394 -309.857544) (xy 455.064432 -309.869404)
			(xy 455.011282 -309.873388) (xy 454.958132 -309.869404) (xy 454.90617 -309.857544) (xy 454.856556 -309.838072)
			(xy 454.810398 -309.811423) (xy 454.768727 -309.778192) (xy 454.732475 -309.739121) (xy 454.702451 -309.695084)
			(xy 454.679325 -309.647063) (xy 454.663615 -309.596133) (xy 454.655672 -309.543429) (xy 440.279254 -309.543429)
			(xy 440.271349 -309.595879) (xy 440.255639 -309.646809) (xy 440.232513 -309.69483) (xy 440.202489 -309.738867)
			(xy 440.166237 -309.777938) (xy 440.124566 -309.811169) (xy 440.078408 -309.837818) (xy 440.028794 -309.85729)
			(xy 439.976832 -309.86915) (xy 439.923682 -309.873134) (xy 439.870532 -309.86915) (xy 439.81857 -309.85729)
			(xy 439.768956 -309.837818) (xy 439.722798 -309.811169) (xy 439.681127 -309.777938) (xy 439.644875 -309.738867)
			(xy 439.614851 -309.69483) (xy 439.591725 -309.646809) (xy 439.576015 -309.595879) (xy 439.568072 -309.543175)
			(xy 425.191692 -309.543175) (xy 425.183749 -309.595879) (xy 425.168039 -309.646809) (xy 425.144913 -309.69483)
			(xy 425.114889 -309.738867) (xy 425.078637 -309.777938) (xy 425.036966 -309.811169) (xy 424.990808 -309.837818)
			(xy 424.941194 -309.85729) (xy 424.889232 -309.86915) (xy 424.836082 -309.873134) (xy 424.782932 -309.86915)
			(xy 424.73097 -309.85729) (xy 424.681356 -309.837818) (xy 424.635198 -309.811169) (xy 424.593527 -309.777938)
			(xy 424.557275 -309.738867) (xy 424.527251 -309.69483) (xy 424.504125 -309.646809) (xy 424.488415 -309.595879)
			(xy 424.480472 -309.543175) (xy 407.4668 -309.543175) (xy 407.4668 -310.393313) (xy 420.380404 -310.393313)
			(xy 420.380404 -310.340015) (xy 420.388347 -310.287311) (xy 420.404057 -310.236381) (xy 420.427183 -310.18836)
			(xy 420.457207 -310.144323) (xy 420.493459 -310.105252) (xy 420.53513 -310.072021) (xy 420.581288 -310.045372)
			(xy 420.630902 -310.0259) (xy 420.682864 -310.01404) (xy 420.736014 -310.010057) (xy 420.789164 -310.01404)
			(xy 420.841126 -310.0259) (xy 420.89074 -310.045372) (xy 420.936898 -310.072021) (xy 420.978569 -310.105252)
			(xy 421.014821 -310.144323) (xy 421.044845 -310.18836) (xy 421.067971 -310.236381) (xy 421.083681 -310.287311)
			(xy 421.091624 -310.340015) (xy 421.092122 -310.366664) (xy 421.091624 -310.393313) (xy 435.468004 -310.393313)
			(xy 435.468004 -310.340015) (xy 435.475947 -310.287311) (xy 435.491657 -310.236381) (xy 435.514783 -310.18836)
			(xy 435.544807 -310.144323) (xy 435.581059 -310.105252) (xy 435.62273 -310.072021) (xy 435.668888 -310.045372)
			(xy 435.718502 -310.0259) (xy 435.770464 -310.01404) (xy 435.823614 -310.010057) (xy 435.876764 -310.01404)
			(xy 435.928726 -310.0259) (xy 435.97834 -310.045372) (xy 436.024498 -310.072021) (xy 436.066169 -310.105252)
			(xy 436.102421 -310.144323) (xy 436.132445 -310.18836) (xy 436.155571 -310.236381) (xy 436.171281 -310.287311)
			(xy 436.179224 -310.340015) (xy 436.179722 -310.366664) (xy 436.179224 -310.393313) (xy 450.555604 -310.393313)
			(xy 450.555604 -310.340015) (xy 450.563547 -310.287311) (xy 450.579257 -310.236381) (xy 450.602383 -310.18836)
			(xy 450.632407 -310.144323) (xy 450.668659 -310.105252) (xy 450.71033 -310.072021) (xy 450.756488 -310.045372)
			(xy 450.806102 -310.0259) (xy 450.858064 -310.01404) (xy 450.911214 -310.010057) (xy 450.964364 -310.01404)
			(xy 451.016326 -310.0259) (xy 451.06594 -310.045372) (xy 451.112098 -310.072021) (xy 451.153769 -310.105252)
			(xy 451.190021 -310.144323) (xy 451.220045 -310.18836) (xy 451.243171 -310.236381) (xy 451.258881 -310.287311)
			(xy 451.266824 -310.340015) (xy 451.267322 -310.366664) (xy 451.266824 -310.393313) (xy 451.258881 -310.446017)
			(xy 451.243171 -310.496947) (xy 451.220045 -310.544968) (xy 451.190021 -310.589005) (xy 451.153769 -310.628076)
			(xy 451.112098 -310.661307) (xy 451.06594 -310.687956) (xy 451.016326 -310.707428) (xy 450.964364 -310.719288)
			(xy 450.911214 -310.723272) (xy 450.858064 -310.719288) (xy 450.806102 -310.707428) (xy 450.756488 -310.687956)
			(xy 450.71033 -310.661307) (xy 450.668659 -310.628076) (xy 450.632407 -310.589005) (xy 450.602383 -310.544968)
			(xy 450.579257 -310.496947) (xy 450.563547 -310.446017) (xy 450.555604 -310.393313) (xy 436.179224 -310.393313)
			(xy 436.171281 -310.446017) (xy 436.155571 -310.496947) (xy 436.132445 -310.544968) (xy 436.102421 -310.589005)
			(xy 436.066169 -310.628076) (xy 436.024498 -310.661307) (xy 435.97834 -310.687956) (xy 435.928726 -310.707428)
			(xy 435.876764 -310.719288) (xy 435.823614 -310.723272) (xy 435.770464 -310.719288) (xy 435.718502 -310.707428)
			(xy 435.668888 -310.687956) (xy 435.62273 -310.661307) (xy 435.581059 -310.628076) (xy 435.544807 -310.589005)
			(xy 435.514783 -310.544968) (xy 435.491657 -310.496947) (xy 435.475947 -310.446017) (xy 435.468004 -310.393313)
			(xy 421.091624 -310.393313) (xy 421.083681 -310.446017) (xy 421.067971 -310.496947) (xy 421.044845 -310.544968)
			(xy 421.014821 -310.589005) (xy 420.978569 -310.628076) (xy 420.936898 -310.661307) (xy 420.89074 -310.687956)
			(xy 420.841126 -310.707428) (xy 420.789164 -310.719288) (xy 420.736014 -310.723272) (xy 420.682864 -310.719288)
			(xy 420.630902 -310.707428) (xy 420.581288 -310.687956) (xy 420.53513 -310.661307) (xy 420.493459 -310.628076)
			(xy 420.457207 -310.589005) (xy 420.427183 -310.544968) (xy 420.404057 -310.496947) (xy 420.388347 -310.446017)
			(xy 420.380404 -310.393313) (xy 407.4668 -310.393313) (xy 407.4668 -311.243197) (xy 424.480472 -311.243197)
			(xy 424.480472 -311.189899) (xy 424.488415 -311.137195) (xy 424.504125 -311.086265) (xy 424.527251 -311.038244)
			(xy 424.557275 -310.994207) (xy 424.593527 -310.955136) (xy 424.635198 -310.921905) (xy 424.681356 -310.895256)
			(xy 424.73097 -310.875784) (xy 424.782932 -310.863924) (xy 424.836082 -310.859941) (xy 424.889232 -310.863924)
			(xy 424.941194 -310.875784) (xy 424.990808 -310.895256) (xy 425.036966 -310.921905) (xy 425.078637 -310.955136)
			(xy 425.114889 -310.994207) (xy 425.144913 -311.038244) (xy 425.168039 -311.086265) (xy 425.183749 -311.137195)
			(xy 425.191692 -311.189899) (xy 425.19219 -311.216548) (xy 425.191692 -311.243197) (xy 439.568072 -311.243197)
			(xy 439.568072 -311.189899) (xy 439.576015 -311.137195) (xy 439.591725 -311.086265) (xy 439.614851 -311.038244)
			(xy 439.644875 -310.994207) (xy 439.681127 -310.955136) (xy 439.722798 -310.921905) (xy 439.768956 -310.895256)
			(xy 439.81857 -310.875784) (xy 439.870532 -310.863924) (xy 439.923682 -310.859941) (xy 439.976832 -310.863924)
			(xy 440.028794 -310.875784) (xy 440.078408 -310.895256) (xy 440.124566 -310.921905) (xy 440.166237 -310.955136)
			(xy 440.202489 -310.994207) (xy 440.232513 -311.038244) (xy 440.255639 -311.086265) (xy 440.271349 -311.137195)
			(xy 440.279292 -311.189899) (xy 440.27979 -311.216548) (xy 440.279292 -311.243197) (xy 440.279254 -311.243451)
			(xy 454.655672 -311.243451) (xy 454.655672 -311.190153) (xy 454.663615 -311.137449) (xy 454.679325 -311.086519)
			(xy 454.702451 -311.038498) (xy 454.732475 -310.994461) (xy 454.768727 -310.95539) (xy 454.810398 -310.922159)
			(xy 454.856556 -310.89551) (xy 454.90617 -310.876038) (xy 454.958132 -310.864178) (xy 455.011282 -310.860195)
			(xy 455.064432 -310.864178) (xy 455.116394 -310.876038) (xy 455.166008 -310.89551) (xy 455.212166 -310.922159)
			(xy 455.253837 -310.95539) (xy 455.290089 -310.994461) (xy 455.320113 -311.038498) (xy 455.343239 -311.086519)
			(xy 455.358949 -311.137449) (xy 455.366892 -311.190153) (xy 455.36739 -311.216802) (xy 455.366892 -311.243451)
			(xy 455.358949 -311.296155) (xy 455.343239 -311.347085) (xy 455.320113 -311.395106) (xy 455.290089 -311.439143)
			(xy 455.253837 -311.478214) (xy 455.212166 -311.511445) (xy 455.166008 -311.538094) (xy 455.116394 -311.557566)
			(xy 455.064432 -311.569426) (xy 455.011282 -311.57341) (xy 454.958132 -311.569426) (xy 454.90617 -311.557566)
			(xy 454.856556 -311.538094) (xy 454.810398 -311.511445) (xy 454.768727 -311.478214) (xy 454.732475 -311.439143)
			(xy 454.702451 -311.395106) (xy 454.679325 -311.347085) (xy 454.663615 -311.296155) (xy 454.655672 -311.243451)
			(xy 440.279254 -311.243451) (xy 440.271349 -311.295901) (xy 440.255639 -311.346831) (xy 440.232513 -311.394852)
			(xy 440.202489 -311.438889) (xy 440.166237 -311.47796) (xy 440.124566 -311.511191) (xy 440.078408 -311.53784)
			(xy 440.028794 -311.557312) (xy 439.976832 -311.569172) (xy 439.923682 -311.573156) (xy 439.870532 -311.569172)
			(xy 439.81857 -311.557312) (xy 439.768956 -311.53784) (xy 439.722798 -311.511191) (xy 439.681127 -311.47796)
			(xy 439.644875 -311.438889) (xy 439.614851 -311.394852) (xy 439.591725 -311.346831) (xy 439.576015 -311.295901)
			(xy 439.568072 -311.243197) (xy 425.191692 -311.243197) (xy 425.183749 -311.295901) (xy 425.168039 -311.346831)
			(xy 425.144913 -311.394852) (xy 425.114889 -311.438889) (xy 425.078637 -311.47796) (xy 425.036966 -311.511191)
			(xy 424.990808 -311.53784) (xy 424.941194 -311.557312) (xy 424.889232 -311.569172) (xy 424.836082 -311.573156)
			(xy 424.782932 -311.569172) (xy 424.73097 -311.557312) (xy 424.681356 -311.53784) (xy 424.635198 -311.511191)
			(xy 424.593527 -311.47796) (xy 424.557275 -311.438889) (xy 424.527251 -311.394852) (xy 424.504125 -311.346831)
			(xy 424.488415 -311.295901) (xy 424.480472 -311.243197) (xy 407.4668 -311.243197) (xy 407.4668 -312.093335)
			(xy 420.380404 -312.093335) (xy 420.380404 -312.040037) (xy 420.388347 -311.987333) (xy 420.404057 -311.936403)
			(xy 420.427183 -311.888382) (xy 420.457207 -311.844345) (xy 420.493459 -311.805274) (xy 420.53513 -311.772043)
			(xy 420.581288 -311.745394) (xy 420.630902 -311.725922) (xy 420.682864 -311.714062) (xy 420.736014 -311.710079)
			(xy 420.789164 -311.714062) (xy 420.841126 -311.725922) (xy 420.89074 -311.745394) (xy 420.936898 -311.772043)
			(xy 420.978569 -311.805274) (xy 421.014821 -311.844345) (xy 421.044845 -311.888382) (xy 421.067971 -311.936403)
			(xy 421.083681 -311.987333) (xy 421.091624 -312.040037) (xy 421.092122 -312.066686) (xy 421.091624 -312.093335)
			(xy 424.480472 -312.093335) (xy 424.480472 -312.040037) (xy 424.488415 -311.987333) (xy 424.504125 -311.936403)
			(xy 424.527251 -311.888382) (xy 424.557275 -311.844345) (xy 424.593527 -311.805274) (xy 424.635198 -311.772043)
			(xy 424.681356 -311.745394) (xy 424.73097 -311.725922) (xy 424.782932 -311.714062) (xy 424.836082 -311.710079)
			(xy 424.889232 -311.714062) (xy 424.941194 -311.725922) (xy 424.990808 -311.745394) (xy 425.036966 -311.772043)
			(xy 425.078637 -311.805274) (xy 425.114889 -311.844345) (xy 425.144913 -311.888382) (xy 425.168039 -311.936403)
			(xy 425.183749 -311.987333) (xy 425.191692 -312.040037) (xy 425.19219 -312.066686) (xy 425.191692 -312.093335)
			(xy 435.468004 -312.093335) (xy 435.468004 -312.040037) (xy 435.475947 -311.987333) (xy 435.491657 -311.936403)
			(xy 435.514783 -311.888382) (xy 435.544807 -311.844345) (xy 435.581059 -311.805274) (xy 435.62273 -311.772043)
			(xy 435.668888 -311.745394) (xy 435.718502 -311.725922) (xy 435.770464 -311.714062) (xy 435.823614 -311.710079)
			(xy 435.876764 -311.714062) (xy 435.928726 -311.725922) (xy 435.97834 -311.745394) (xy 436.024498 -311.772043)
			(xy 436.066169 -311.805274) (xy 436.102421 -311.844345) (xy 436.132445 -311.888382) (xy 436.155571 -311.936403)
			(xy 436.171281 -311.987333) (xy 436.179224 -312.040037) (xy 436.179722 -312.066686) (xy 436.179224 -312.093335)
			(xy 439.568072 -312.093335) (xy 439.568072 -312.040037) (xy 439.576015 -311.987333) (xy 439.591725 -311.936403)
			(xy 439.614851 -311.888382) (xy 439.644875 -311.844345) (xy 439.681127 -311.805274) (xy 439.722798 -311.772043)
			(xy 439.768956 -311.745394) (xy 439.81857 -311.725922) (xy 439.870532 -311.714062) (xy 439.923682 -311.710079)
			(xy 439.976832 -311.714062) (xy 440.028794 -311.725922) (xy 440.078408 -311.745394) (xy 440.124566 -311.772043)
			(xy 440.166237 -311.805274) (xy 440.202489 -311.844345) (xy 440.232513 -311.888382) (xy 440.255639 -311.936403)
			(xy 440.271349 -311.987333) (xy 440.279292 -312.040037) (xy 440.27979 -312.066686) (xy 440.279292 -312.093335)
			(xy 450.555604 -312.093335) (xy 450.555604 -312.040037) (xy 450.563547 -311.987333) (xy 450.579257 -311.936403)
			(xy 450.602383 -311.888382) (xy 450.632407 -311.844345) (xy 450.668659 -311.805274) (xy 450.71033 -311.772043)
			(xy 450.756488 -311.745394) (xy 450.806102 -311.725922) (xy 450.858064 -311.714062) (xy 450.911214 -311.710079)
			(xy 450.964364 -311.714062) (xy 451.016326 -311.725922) (xy 451.06594 -311.745394) (xy 451.112098 -311.772043)
			(xy 451.153769 -311.805274) (xy 451.190021 -311.844345) (xy 451.220045 -311.888382) (xy 451.243171 -311.936403)
			(xy 451.258881 -311.987333) (xy 451.266824 -312.040037) (xy 451.267322 -312.066686) (xy 451.266824 -312.093335)
			(xy 454.655672 -312.093335) (xy 454.655672 -312.040037) (xy 454.663615 -311.987333) (xy 454.679325 -311.936403)
			(xy 454.702451 -311.888382) (xy 454.732475 -311.844345) (xy 454.768727 -311.805274) (xy 454.810398 -311.772043)
			(xy 454.856556 -311.745394) (xy 454.90617 -311.725922) (xy 454.958132 -311.714062) (xy 455.011282 -311.710079)
			(xy 455.064432 -311.714062) (xy 455.116394 -311.725922) (xy 455.166008 -311.745394) (xy 455.212166 -311.772043)
			(xy 455.253837 -311.805274) (xy 455.290089 -311.844345) (xy 455.320113 -311.888382) (xy 455.343239 -311.936403)
			(xy 455.358949 -311.987333) (xy 455.366892 -312.040037) (xy 455.36739 -312.066686) (xy 455.366892 -312.093335)
			(xy 455.358949 -312.146039) (xy 455.343239 -312.196969) (xy 455.320113 -312.24499) (xy 455.290089 -312.289027)
			(xy 455.253837 -312.328098) (xy 455.212166 -312.361329) (xy 455.166008 -312.387978) (xy 455.116394 -312.40745)
			(xy 455.064432 -312.41931) (xy 455.011282 -312.423294) (xy 454.958132 -312.41931) (xy 454.90617 -312.40745)
			(xy 454.856556 -312.387978) (xy 454.810398 -312.361329) (xy 454.768727 -312.328098) (xy 454.732475 -312.289027)
			(xy 454.702451 -312.24499) (xy 454.679325 -312.196969) (xy 454.663615 -312.146039) (xy 454.655672 -312.093335)
			(xy 451.266824 -312.093335) (xy 451.258881 -312.146039) (xy 451.243171 -312.196969) (xy 451.220045 -312.24499)
			(xy 451.190021 -312.289027) (xy 451.153769 -312.328098) (xy 451.112098 -312.361329) (xy 451.06594 -312.387978)
			(xy 451.016326 -312.40745) (xy 450.964364 -312.41931) (xy 450.911214 -312.423294) (xy 450.858064 -312.41931)
			(xy 450.806102 -312.40745) (xy 450.756488 -312.387978) (xy 450.71033 -312.361329) (xy 450.668659 -312.328098)
			(xy 450.632407 -312.289027) (xy 450.602383 -312.24499) (xy 450.579257 -312.196969) (xy 450.563547 -312.146039)
			(xy 450.555604 -312.093335) (xy 440.279292 -312.093335) (xy 440.271349 -312.146039) (xy 440.255639 -312.196969)
			(xy 440.232513 -312.24499) (xy 440.202489 -312.289027) (xy 440.166237 -312.328098) (xy 440.124566 -312.361329)
			(xy 440.078408 -312.387978) (xy 440.028794 -312.40745) (xy 439.976832 -312.41931) (xy 439.923682 -312.423294)
			(xy 439.870532 -312.41931) (xy 439.81857 -312.40745) (xy 439.768956 -312.387978) (xy 439.722798 -312.361329)
			(xy 439.681127 -312.328098) (xy 439.644875 -312.289027) (xy 439.614851 -312.24499) (xy 439.591725 -312.196969)
			(xy 439.576015 -312.146039) (xy 439.568072 -312.093335) (xy 436.179224 -312.093335) (xy 436.171281 -312.146039)
			(xy 436.155571 -312.196969) (xy 436.132445 -312.24499) (xy 436.102421 -312.289027) (xy 436.066169 -312.328098)
			(xy 436.024498 -312.361329) (xy 435.97834 -312.387978) (xy 435.928726 -312.40745) (xy 435.876764 -312.41931)
			(xy 435.823614 -312.423294) (xy 435.770464 -312.41931) (xy 435.718502 -312.40745) (xy 435.668888 -312.387978)
			(xy 435.62273 -312.361329) (xy 435.581059 -312.328098) (xy 435.544807 -312.289027) (xy 435.514783 -312.24499)
			(xy 435.491657 -312.196969) (xy 435.475947 -312.146039) (xy 435.468004 -312.093335) (xy 425.191692 -312.093335)
			(xy 425.183749 -312.146039) (xy 425.168039 -312.196969) (xy 425.144913 -312.24499) (xy 425.114889 -312.289027)
			(xy 425.078637 -312.328098) (xy 425.036966 -312.361329) (xy 424.990808 -312.387978) (xy 424.941194 -312.40745)
			(xy 424.889232 -312.41931) (xy 424.836082 -312.423294) (xy 424.782932 -312.41931) (xy 424.73097 -312.40745)
			(xy 424.681356 -312.387978) (xy 424.635198 -312.361329) (xy 424.593527 -312.328098) (xy 424.557275 -312.289027)
			(xy 424.527251 -312.24499) (xy 424.504125 -312.196969) (xy 424.488415 -312.146039) (xy 424.480472 -312.093335)
			(xy 421.091624 -312.093335) (xy 421.083681 -312.146039) (xy 421.067971 -312.196969) (xy 421.044845 -312.24499)
			(xy 421.014821 -312.289027) (xy 420.978569 -312.328098) (xy 420.936898 -312.361329) (xy 420.89074 -312.387978)
			(xy 420.841126 -312.40745) (xy 420.789164 -312.41931) (xy 420.736014 -312.423294) (xy 420.682864 -312.41931)
			(xy 420.630902 -312.40745) (xy 420.581288 -312.387978) (xy 420.53513 -312.361329) (xy 420.493459 -312.328098)
			(xy 420.457207 -312.289027) (xy 420.427183 -312.24499) (xy 420.404057 -312.196969) (xy 420.388347 -312.146039)
			(xy 420.380404 -312.093335) (xy 407.4668 -312.093335) (xy 407.4668 -312.943219) (xy 420.380404 -312.943219)
			(xy 420.380404 -312.889921) (xy 420.388347 -312.837217) (xy 420.404057 -312.786287) (xy 420.427183 -312.738266)
			(xy 420.457207 -312.694229) (xy 420.493459 -312.655158) (xy 420.53513 -312.621927) (xy 420.581288 -312.595278)
			(xy 420.630902 -312.575806) (xy 420.682864 -312.563946) (xy 420.736014 -312.559963) (xy 420.789164 -312.563946)
			(xy 420.841126 -312.575806) (xy 420.89074 -312.595278) (xy 420.936898 -312.621927) (xy 420.978569 -312.655158)
			(xy 421.014821 -312.694229) (xy 421.044845 -312.738266) (xy 421.067971 -312.786287) (xy 421.083681 -312.837217)
			(xy 421.091624 -312.889921) (xy 421.092122 -312.91657) (xy 421.091624 -312.943219) (xy 435.468004 -312.943219)
			(xy 435.468004 -312.889921) (xy 435.475947 -312.837217) (xy 435.491657 -312.786287) (xy 435.514783 -312.738266)
			(xy 435.544807 -312.694229) (xy 435.581059 -312.655158) (xy 435.62273 -312.621927) (xy 435.668888 -312.595278)
			(xy 435.718502 -312.575806) (xy 435.770464 -312.563946) (xy 435.823614 -312.559963) (xy 435.876764 -312.563946)
			(xy 435.928726 -312.575806) (xy 435.97834 -312.595278) (xy 436.024498 -312.621927) (xy 436.066169 -312.655158)
			(xy 436.102421 -312.694229) (xy 436.132445 -312.738266) (xy 436.155571 -312.786287) (xy 436.171281 -312.837217)
			(xy 436.179224 -312.889921) (xy 436.179722 -312.91657) (xy 436.179224 -312.943219) (xy 450.555604 -312.943219)
			(xy 450.555604 -312.889921) (xy 450.563547 -312.837217) (xy 450.579257 -312.786287) (xy 450.602383 -312.738266)
			(xy 450.632407 -312.694229) (xy 450.668659 -312.655158) (xy 450.71033 -312.621927) (xy 450.756488 -312.595278)
			(xy 450.806102 -312.575806) (xy 450.858064 -312.563946) (xy 450.911214 -312.559963) (xy 450.964364 -312.563946)
			(xy 451.016326 -312.575806) (xy 451.06594 -312.595278) (xy 451.112098 -312.621927) (xy 451.153769 -312.655158)
			(xy 451.190021 -312.694229) (xy 451.220045 -312.738266) (xy 451.243171 -312.786287) (xy 451.258881 -312.837217)
			(xy 451.266824 -312.889921) (xy 451.267322 -312.91657) (xy 451.266824 -312.943219) (xy 451.258881 -312.995923)
			(xy 451.243171 -313.046853) (xy 451.220045 -313.094874) (xy 451.190021 -313.138911) (xy 451.153769 -313.177982)
			(xy 451.112098 -313.211213) (xy 451.071225 -313.234811) (xy 460.670392 -313.234811) (xy 460.670392 -313.181513)
			(xy 460.678335 -313.128809) (xy 460.694045 -313.077879) (xy 460.717171 -313.029858) (xy 460.747195 -312.985821)
			(xy 460.783447 -312.94675) (xy 460.825118 -312.913519) (xy 460.871276 -312.88687) (xy 460.92089 -312.867398)
			(xy 460.972852 -312.855538) (xy 461.026002 -312.851555) (xy 461.079152 -312.855538) (xy 461.131114 -312.867398)
			(xy 461.180728 -312.88687) (xy 461.226886 -312.913519) (xy 461.268557 -312.94675) (xy 461.304809 -312.985821)
			(xy 461.334833 -313.029858) (xy 461.357959 -313.077879) (xy 461.373669 -313.128809) (xy 461.381612 -313.181513)
			(xy 461.38211 -313.208162) (xy 461.381612 -313.234811) (xy 461.373669 -313.287515) (xy 461.357959 -313.338445)
			(xy 461.334833 -313.386466) (xy 461.304809 -313.430503) (xy 461.268557 -313.469574) (xy 461.226886 -313.502805)
			(xy 461.180728 -313.529454) (xy 461.131114 -313.548926) (xy 461.079152 -313.560786) (xy 461.026002 -313.56477)
			(xy 460.972852 -313.560786) (xy 460.92089 -313.548926) (xy 460.871276 -313.529454) (xy 460.825118 -313.502805)
			(xy 460.783447 -313.469574) (xy 460.747195 -313.430503) (xy 460.717171 -313.386466) (xy 460.694045 -313.338445)
			(xy 460.678335 -313.287515) (xy 460.670392 -313.234811) (xy 451.071225 -313.234811) (xy 451.06594 -313.237862)
			(xy 451.016326 -313.257334) (xy 450.964364 -313.269194) (xy 450.911214 -313.273178) (xy 450.858064 -313.269194)
			(xy 450.806102 -313.257334) (xy 450.756488 -313.237862) (xy 450.71033 -313.211213) (xy 450.668659 -313.177982)
			(xy 450.632407 -313.138911) (xy 450.602383 -313.094874) (xy 450.579257 -313.046853) (xy 450.563547 -312.995923)
			(xy 450.555604 -312.943219) (xy 436.179224 -312.943219) (xy 436.171281 -312.995923) (xy 436.155571 -313.046853)
			(xy 436.132445 -313.094874) (xy 436.102421 -313.138911) (xy 436.066169 -313.177982) (xy 436.024498 -313.211213)
			(xy 435.97834 -313.237862) (xy 435.928726 -313.257334) (xy 435.876764 -313.269194) (xy 435.823614 -313.273178)
			(xy 435.770464 -313.269194) (xy 435.718502 -313.257334) (xy 435.668888 -313.237862) (xy 435.62273 -313.211213)
			(xy 435.581059 -313.177982) (xy 435.544807 -313.138911) (xy 435.514783 -313.094874) (xy 435.491657 -313.046853)
			(xy 435.475947 -312.995923) (xy 435.468004 -312.943219) (xy 421.091624 -312.943219) (xy 421.083681 -312.995923)
			(xy 421.067971 -313.046853) (xy 421.044845 -313.094874) (xy 421.014821 -313.138911) (xy 420.978569 -313.177982)
			(xy 420.936898 -313.211213) (xy 420.89074 -313.237862) (xy 420.841126 -313.257334) (xy 420.789164 -313.269194)
			(xy 420.736014 -313.273178) (xy 420.682864 -313.269194) (xy 420.630902 -313.257334) (xy 420.581288 -313.237862)
			(xy 420.53513 -313.211213) (xy 420.493459 -313.177982) (xy 420.457207 -313.138911) (xy 420.427183 -313.094874)
			(xy 420.404057 -313.046853) (xy 420.388347 -312.995923) (xy 420.380404 -312.943219) (xy 407.4668 -312.943219)
			(xy 407.4668 -313.793357) (xy 424.480472 -313.793357) (xy 424.480472 -313.740059) (xy 424.488415 -313.687355)
			(xy 424.504125 -313.636425) (xy 424.527251 -313.588404) (xy 424.557275 -313.544367) (xy 424.593527 -313.505296)
			(xy 424.635198 -313.472065) (xy 424.681356 -313.445416) (xy 424.73097 -313.425944) (xy 424.782932 -313.414084)
			(xy 424.836082 -313.410101) (xy 424.889232 -313.414084) (xy 424.941194 -313.425944) (xy 424.990808 -313.445416)
			(xy 425.036966 -313.472065) (xy 425.078637 -313.505296) (xy 425.114889 -313.544367) (xy 425.144913 -313.588404)
			(xy 425.168039 -313.636425) (xy 425.183749 -313.687355) (xy 425.191692 -313.740059) (xy 425.19219 -313.766708)
			(xy 425.191692 -313.793357) (xy 439.568072 -313.793357) (xy 439.568072 -313.740059) (xy 439.576015 -313.687355)
			(xy 439.591725 -313.636425) (xy 439.614851 -313.588404) (xy 439.644875 -313.544367) (xy 439.681127 -313.505296)
			(xy 439.722798 -313.472065) (xy 439.768956 -313.445416) (xy 439.81857 -313.425944) (xy 439.870532 -313.414084)
			(xy 439.923682 -313.410101) (xy 439.976832 -313.414084) (xy 440.028794 -313.425944) (xy 440.078408 -313.445416)
			(xy 440.124566 -313.472065) (xy 440.166237 -313.505296) (xy 440.202489 -313.544367) (xy 440.232513 -313.588404)
			(xy 440.255639 -313.636425) (xy 440.271349 -313.687355) (xy 440.279292 -313.740059) (xy 440.27979 -313.766708)
			(xy 440.279292 -313.793357) (xy 454.655672 -313.793357) (xy 454.655672 -313.740059) (xy 454.663615 -313.687355)
			(xy 454.679325 -313.636425) (xy 454.702451 -313.588404) (xy 454.732475 -313.544367) (xy 454.768727 -313.505296)
			(xy 454.810398 -313.472065) (xy 454.856556 -313.445416) (xy 454.90617 -313.425944) (xy 454.958132 -313.414084)
			(xy 455.011282 -313.410101) (xy 455.064432 -313.414084) (xy 455.116394 -313.425944) (xy 455.166008 -313.445416)
			(xy 455.212166 -313.472065) (xy 455.253837 -313.505296) (xy 455.290089 -313.544367) (xy 455.320113 -313.588404)
			(xy 455.343239 -313.636425) (xy 455.358949 -313.687355) (xy 455.366892 -313.740059) (xy 455.36739 -313.766708)
			(xy 455.366892 -313.793357) (xy 455.358949 -313.846061) (xy 455.343239 -313.896991) (xy 455.320113 -313.945012)
			(xy 455.290089 -313.989049) (xy 455.253837 -314.02812) (xy 455.212166 -314.061351) (xy 455.166008 -314.088)
			(xy 455.116394 -314.107472) (xy 455.064432 -314.119332) (xy 455.011282 -314.123316) (xy 454.958132 -314.119332)
			(xy 454.90617 -314.107472) (xy 454.856556 -314.088) (xy 454.810398 -314.061351) (xy 454.768727 -314.02812)
			(xy 454.732475 -313.989049) (xy 454.702451 -313.945012) (xy 454.679325 -313.896991) (xy 454.663615 -313.846061)
			(xy 454.655672 -313.793357) (xy 440.279292 -313.793357) (xy 440.271349 -313.846061) (xy 440.255639 -313.896991)
			(xy 440.232513 -313.945012) (xy 440.202489 -313.989049) (xy 440.166237 -314.02812) (xy 440.124566 -314.061351)
			(xy 440.078408 -314.088) (xy 440.028794 -314.107472) (xy 439.976832 -314.119332) (xy 439.923682 -314.123316)
			(xy 439.870532 -314.119332) (xy 439.81857 -314.107472) (xy 439.768956 -314.088) (xy 439.722798 -314.061351)
			(xy 439.681127 -314.02812) (xy 439.644875 -313.989049) (xy 439.614851 -313.945012) (xy 439.591725 -313.896991)
			(xy 439.576015 -313.846061) (xy 439.568072 -313.793357) (xy 425.191692 -313.793357) (xy 425.183749 -313.846061)
			(xy 425.168039 -313.896991) (xy 425.144913 -313.945012) (xy 425.114889 -313.989049) (xy 425.078637 -314.02812)
			(xy 425.036966 -314.061351) (xy 424.990808 -314.088) (xy 424.941194 -314.107472) (xy 424.889232 -314.119332)
			(xy 424.836082 -314.123316) (xy 424.782932 -314.119332) (xy 424.73097 -314.107472) (xy 424.681356 -314.088)
			(xy 424.635198 -314.061351) (xy 424.593527 -314.02812) (xy 424.557275 -313.989049) (xy 424.527251 -313.945012)
			(xy 424.504125 -313.896991) (xy 424.488415 -313.846061) (xy 424.480472 -313.793357) (xy 407.4668 -313.793357)
			(xy 407.4668 -314.643241) (xy 420.380404 -314.643241) (xy 420.380404 -314.589943) (xy 420.388347 -314.537239)
			(xy 420.404057 -314.486309) (xy 420.427183 -314.438288) (xy 420.457207 -314.394251) (xy 420.493459 -314.35518)
			(xy 420.53513 -314.321949) (xy 420.581288 -314.2953) (xy 420.630902 -314.275828) (xy 420.682864 -314.263968)
			(xy 420.736014 -314.259985) (xy 420.789164 -314.263968) (xy 420.841126 -314.275828) (xy 420.89074 -314.2953)
			(xy 420.936898 -314.321949) (xy 420.978569 -314.35518) (xy 421.014821 -314.394251) (xy 421.044845 -314.438288)
			(xy 421.067971 -314.486309) (xy 421.083681 -314.537239) (xy 421.091624 -314.589943) (xy 421.092122 -314.616592)
			(xy 421.091624 -314.643241) (xy 435.468004 -314.643241) (xy 435.468004 -314.589943) (xy 435.475947 -314.537239)
			(xy 435.491657 -314.486309) (xy 435.514783 -314.438288) (xy 435.544807 -314.394251) (xy 435.581059 -314.35518)
			(xy 435.62273 -314.321949) (xy 435.668888 -314.2953) (xy 435.718502 -314.275828) (xy 435.770464 -314.263968)
			(xy 435.823614 -314.259985) (xy 435.876764 -314.263968) (xy 435.928726 -314.275828) (xy 435.97834 -314.2953)
			(xy 436.024498 -314.321949) (xy 436.066169 -314.35518) (xy 436.102421 -314.394251) (xy 436.132445 -314.438288)
			(xy 436.155571 -314.486309) (xy 436.171281 -314.537239) (xy 436.179224 -314.589943) (xy 436.179722 -314.616592)
			(xy 436.179224 -314.643241) (xy 450.555604 -314.643241) (xy 450.555604 -314.589943) (xy 450.563547 -314.537239)
			(xy 450.579257 -314.486309) (xy 450.602383 -314.438288) (xy 450.632407 -314.394251) (xy 450.668659 -314.35518)
			(xy 450.71033 -314.321949) (xy 450.756488 -314.2953) (xy 450.806102 -314.275828) (xy 450.858064 -314.263968)
			(xy 450.911214 -314.259985) (xy 450.964364 -314.263968) (xy 451.016326 -314.275828) (xy 451.06594 -314.2953)
			(xy 451.112098 -314.321949) (xy 451.153769 -314.35518) (xy 451.190021 -314.394251) (xy 451.220045 -314.438288)
			(xy 451.243171 -314.486309) (xy 451.258881 -314.537239) (xy 451.266824 -314.589943) (xy 451.267322 -314.616592)
			(xy 451.266824 -314.643241) (xy 451.258881 -314.695945) (xy 451.243171 -314.746875) (xy 451.220045 -314.794896)
			(xy 451.190021 -314.838933) (xy 451.153769 -314.878004) (xy 451.112098 -314.911235) (xy 451.06594 -314.937884)
			(xy 451.016326 -314.957356) (xy 450.964364 -314.969216) (xy 450.911214 -314.9732) (xy 450.858064 -314.969216)
			(xy 450.806102 -314.957356) (xy 450.756488 -314.937884) (xy 450.71033 -314.911235) (xy 450.668659 -314.878004)
			(xy 450.632407 -314.838933) (xy 450.602383 -314.794896) (xy 450.579257 -314.746875) (xy 450.563547 -314.695945)
			(xy 450.555604 -314.643241) (xy 436.179224 -314.643241) (xy 436.171281 -314.695945) (xy 436.155571 -314.746875)
			(xy 436.132445 -314.794896) (xy 436.102421 -314.838933) (xy 436.066169 -314.878004) (xy 436.024498 -314.911235)
			(xy 435.97834 -314.937884) (xy 435.928726 -314.957356) (xy 435.876764 -314.969216) (xy 435.823614 -314.9732)
			(xy 435.770464 -314.969216) (xy 435.718502 -314.957356) (xy 435.668888 -314.937884) (xy 435.62273 -314.911235)
			(xy 435.581059 -314.878004) (xy 435.544807 -314.838933) (xy 435.514783 -314.794896) (xy 435.491657 -314.746875)
			(xy 435.475947 -314.695945) (xy 435.468004 -314.643241) (xy 421.091624 -314.643241) (xy 421.083681 -314.695945)
			(xy 421.067971 -314.746875) (xy 421.044845 -314.794896) (xy 421.014821 -314.838933) (xy 420.978569 -314.878004)
			(xy 420.936898 -314.911235) (xy 420.89074 -314.937884) (xy 420.841126 -314.957356) (xy 420.789164 -314.969216)
			(xy 420.736014 -314.9732) (xy 420.682864 -314.969216) (xy 420.630902 -314.957356) (xy 420.581288 -314.937884)
			(xy 420.53513 -314.911235) (xy 420.493459 -314.878004) (xy 420.457207 -314.838933) (xy 420.427183 -314.794896)
			(xy 420.404057 -314.746875) (xy 420.388347 -314.695945) (xy 420.380404 -314.643241) (xy 407.4668 -314.643241)
			(xy 407.4668 -315.493379) (xy 424.480472 -315.493379) (xy 424.480472 -315.440081) (xy 424.488415 -315.387377)
			(xy 424.504125 -315.336447) (xy 424.527251 -315.288426) (xy 424.557275 -315.244389) (xy 424.593527 -315.205318)
			(xy 424.635198 -315.172087) (xy 424.681356 -315.145438) (xy 424.73097 -315.125966) (xy 424.782932 -315.114106)
			(xy 424.836082 -315.110123) (xy 424.889232 -315.114106) (xy 424.941194 -315.125966) (xy 424.990808 -315.145438)
			(xy 425.036966 -315.172087) (xy 425.078637 -315.205318) (xy 425.114889 -315.244389) (xy 425.144913 -315.288426)
			(xy 425.168039 -315.336447) (xy 425.183749 -315.387377) (xy 425.191692 -315.440081) (xy 425.19219 -315.46673)
			(xy 425.191692 -315.493379) (xy 439.568072 -315.493379) (xy 439.568072 -315.440081) (xy 439.576015 -315.387377)
			(xy 439.591725 -315.336447) (xy 439.614851 -315.288426) (xy 439.644875 -315.244389) (xy 439.681127 -315.205318)
			(xy 439.722798 -315.172087) (xy 439.768956 -315.145438) (xy 439.81857 -315.125966) (xy 439.870532 -315.114106)
			(xy 439.923682 -315.110123) (xy 439.976832 -315.114106) (xy 440.028794 -315.125966) (xy 440.078408 -315.145438)
			(xy 440.124566 -315.172087) (xy 440.166237 -315.205318) (xy 440.202489 -315.244389) (xy 440.232513 -315.288426)
			(xy 440.255639 -315.336447) (xy 440.271349 -315.387377) (xy 440.274653 -315.4093) (xy 453.890094 -315.4093)
			(xy 453.894078 -315.356147) (xy 453.905939 -315.304181) (xy 453.925414 -315.254564) (xy 453.952067 -315.208403)
			(xy 453.985303 -315.166732) (xy 454.024379 -315.130479) (xy 454.068421 -315.100456) (xy 454.116447 -315.077333)
			(xy 454.167383 -315.061627) (xy 454.220091 -315.053688) (xy 454.246742 -315.053218) (xy 454.273906 -315.053764)
			(xy 454.327601 -315.062035) (xy 454.379418 -315.078361) (xy 454.428155 -315.102366) (xy 454.472683 -315.133493)
			(xy 454.511968 -315.171019) (xy 454.5451 -315.214075) (xy 454.558654 -315.237622) (xy 454.566017 -315.250054)
			(xy 454.586453 -315.270463) (xy 454.611789 -315.284327) (xy 454.639996 -315.290535) (xy 454.668812 -315.288589)
			(xy 454.695928 -315.278646) (xy 454.719171 -315.261501) (xy 454.728326 -315.250322) (xy 454.745301 -315.228992)
			(xy 454.784653 -315.191271) (xy 454.829289 -315.15998) (xy 454.878168 -315.13585) (xy 454.930151 -315.119443)
			(xy 454.984026 -315.111141) (xy 455.011282 -315.110622) (xy 455.037936 -315.111034) (xy 455.09065 -315.118977)
			(xy 455.14159 -315.134688) (xy 455.189621 -315.157816) (xy 455.233667 -315.187844) (xy 455.272746 -315.224102)
			(xy 455.305984 -315.265779) (xy 455.332639 -315.311946) (xy 455.352115 -315.361569) (xy 455.363978 -315.413541)
			(xy 455.367962 -315.4667) (xy 455.363978 -315.519859) (xy 455.352115 -315.571831) (xy 455.332639 -315.621454)
			(xy 455.305984 -315.667621) (xy 455.272746 -315.709298) (xy 455.233667 -315.745556) (xy 455.189621 -315.775584)
			(xy 455.14159 -315.798712) (xy 455.09065 -315.814423) (xy 455.037936 -315.822366) (xy 455.011282 -315.822838)
			(xy 454.984118 -315.822295) (xy 454.930421 -315.814027) (xy 454.878603 -315.797702) (xy 454.829865 -315.773696)
			(xy 454.785337 -315.742569) (xy 454.746052 -315.705041) (xy 454.712922 -315.661982) (xy 454.69937 -315.638434)
			(xy 454.691976 -315.626024) (xy 454.671543 -315.605624) (xy 454.646214 -315.591766) (xy 454.618016 -315.585558)
			(xy 454.589208 -315.587499) (xy 454.562098 -315.597432) (xy 454.538855 -315.614562) (xy 454.529698 -315.625734)
			(xy 454.512698 -315.647043) (xy 454.473353 -315.684768) (xy 454.428722 -315.716062) (xy 454.379848 -315.740196)
			(xy 454.327868 -315.756608) (xy 454.273996 -315.764913) (xy 454.246742 -315.765434) (xy 454.220091 -315.764912)
			(xy 454.167383 -315.756973) (xy 454.116447 -315.741267) (xy 454.068421 -315.718144) (xy 454.024379 -315.688121)
			(xy 453.985303 -315.651868) (xy 453.952067 -315.610197) (xy 453.925414 -315.564036) (xy 453.905939 -315.514419)
			(xy 453.894078 -315.462453) (xy 453.890094 -315.4093) (xy 440.274653 -315.4093) (xy 440.279292 -315.440081)
			(xy 440.27979 -315.46673) (xy 440.279292 -315.493379) (xy 440.271349 -315.546083) (xy 440.255639 -315.597013)
			(xy 440.232513 -315.645034) (xy 440.202489 -315.689071) (xy 440.166237 -315.728142) (xy 440.124566 -315.761373)
			(xy 440.078408 -315.788022) (xy 440.028794 -315.807494) (xy 439.976832 -315.819354) (xy 439.923682 -315.823338)
			(xy 439.870532 -315.819354) (xy 439.81857 -315.807494) (xy 439.768956 -315.788022) (xy 439.722798 -315.761373)
			(xy 439.681127 -315.728142) (xy 439.644875 -315.689071) (xy 439.614851 -315.645034) (xy 439.591725 -315.597013)
			(xy 439.576015 -315.546083) (xy 439.568072 -315.493379) (xy 425.191692 -315.493379) (xy 425.183749 -315.546083)
			(xy 425.168039 -315.597013) (xy 425.144913 -315.645034) (xy 425.114889 -315.689071) (xy 425.078637 -315.728142)
			(xy 425.036966 -315.761373) (xy 424.990808 -315.788022) (xy 424.941194 -315.807494) (xy 424.889232 -315.819354)
			(xy 424.836082 -315.823338) (xy 424.782932 -315.819354) (xy 424.73097 -315.807494) (xy 424.681356 -315.788022)
			(xy 424.635198 -315.761373) (xy 424.593527 -315.728142) (xy 424.557275 -315.689071) (xy 424.527251 -315.645034)
			(xy 424.504125 -315.597013) (xy 424.488415 -315.546083) (xy 424.480472 -315.493379) (xy 407.4668 -315.493379)
			(xy 407.4668 -316.343263) (xy 420.380404 -316.343263) (xy 420.380404 -316.289965) (xy 420.388347 -316.237261)
			(xy 420.404057 -316.186331) (xy 420.427183 -316.13831) (xy 420.457207 -316.094273) (xy 420.493459 -316.055202)
			(xy 420.53513 -316.021971) (xy 420.581288 -315.995322) (xy 420.630902 -315.97585) (xy 420.682864 -315.96399)
			(xy 420.736014 -315.960007) (xy 420.789164 -315.96399) (xy 420.841126 -315.97585) (xy 420.89074 -315.995322)
			(xy 420.936898 -316.021971) (xy 420.978569 -316.055202) (xy 421.014821 -316.094273) (xy 421.044845 -316.13831)
			(xy 421.067971 -316.186331) (xy 421.083681 -316.237261) (xy 421.091624 -316.289965) (xy 421.092122 -316.316614)
			(xy 421.091624 -316.343263) (xy 421.088676 -316.362821) (xy 431.406798 -316.362821) (xy 431.406798 -316.309523)
			(xy 431.414741 -316.256819) (xy 431.430451 -316.205889) (xy 431.453577 -316.157868) (xy 431.483601 -316.113831)
			(xy 431.519853 -316.07476) (xy 431.561524 -316.041529) (xy 431.607682 -316.01488) (xy 431.657296 -315.995408)
			(xy 431.709258 -315.983548) (xy 431.762408 -315.979565) (xy 431.815558 -315.983548) (xy 431.86752 -315.995408)
			(xy 431.917134 -316.01488) (xy 431.963292 -316.041529) (xy 432.004963 -316.07476) (xy 432.041215 -316.113831)
			(xy 432.071239 -316.157868) (xy 432.094365 -316.205889) (xy 432.110075 -316.256819) (xy 432.118018 -316.309523)
			(xy 432.118516 -316.336172) (xy 432.118383 -316.343263) (xy 435.468004 -316.343263) (xy 435.468004 -316.289965)
			(xy 435.475947 -316.237261) (xy 435.491657 -316.186331) (xy 435.514783 -316.13831) (xy 435.544807 -316.094273)
			(xy 435.581059 -316.055202) (xy 435.62273 -316.021971) (xy 435.668888 -315.995322) (xy 435.718502 -315.97585)
			(xy 435.770464 -315.96399) (xy 435.823614 -315.960007) (xy 435.876764 -315.96399) (xy 435.928726 -315.97585)
			(xy 435.97834 -315.995322) (xy 436.024498 -316.021971) (xy 436.066169 -316.055202) (xy 436.102421 -316.094273)
			(xy 436.132445 -316.13831) (xy 436.155571 -316.186331) (xy 436.171281 -316.237261) (xy 436.179224 -316.289965)
			(xy 436.179722 -316.316614) (xy 436.179224 -316.343263) (xy 450.555604 -316.343263) (xy 450.555604 -316.289965)
			(xy 450.563547 -316.237261) (xy 450.579257 -316.186331) (xy 450.602383 -316.13831) (xy 450.632407 -316.094273)
			(xy 450.668659 -316.055202) (xy 450.71033 -316.021971) (xy 450.756488 -315.995322) (xy 450.806102 -315.97585)
			(xy 450.858064 -315.96399) (xy 450.911214 -315.960007) (xy 450.964364 -315.96399) (xy 451.016326 -315.97585)
			(xy 451.06594 -315.995322) (xy 451.112098 -316.021971) (xy 451.153769 -316.055202) (xy 451.190021 -316.094273)
			(xy 451.220045 -316.13831) (xy 451.243171 -316.186331) (xy 451.258881 -316.237261) (xy 451.266824 -316.289965)
			(xy 451.267322 -316.316614) (xy 451.266824 -316.343263) (xy 451.258881 -316.395967) (xy 451.243171 -316.446897)
			(xy 451.220045 -316.494918) (xy 451.190021 -316.538955) (xy 451.153769 -316.578026) (xy 451.112098 -316.611257)
			(xy 451.06594 -316.637906) (xy 451.016326 -316.657378) (xy 450.964364 -316.669238) (xy 450.911214 -316.673222)
			(xy 450.858064 -316.669238) (xy 450.806102 -316.657378) (xy 450.756488 -316.637906) (xy 450.71033 -316.611257)
			(xy 450.668659 -316.578026) (xy 450.632407 -316.538955) (xy 450.602383 -316.494918) (xy 450.579257 -316.446897)
			(xy 450.563547 -316.395967) (xy 450.555604 -316.343263) (xy 436.179224 -316.343263) (xy 436.171281 -316.395967)
			(xy 436.155571 -316.446897) (xy 436.132445 -316.494918) (xy 436.102421 -316.538955) (xy 436.066169 -316.578026)
			(xy 436.024498 -316.611257) (xy 435.97834 -316.637906) (xy 435.928726 -316.657378) (xy 435.876764 -316.669238)
			(xy 435.823614 -316.673222) (xy 435.770464 -316.669238) (xy 435.718502 -316.657378) (xy 435.668888 -316.637906)
			(xy 435.62273 -316.611257) (xy 435.581059 -316.578026) (xy 435.544807 -316.538955) (xy 435.514783 -316.494918)
			(xy 435.491657 -316.446897) (xy 435.475947 -316.395967) (xy 435.468004 -316.343263) (xy 432.118383 -316.343263)
			(xy 432.118018 -316.362821) (xy 432.110075 -316.415525) (xy 432.094365 -316.466455) (xy 432.071239 -316.514476)
			(xy 432.041215 -316.558513) (xy 432.004963 -316.597584) (xy 431.963292 -316.630815) (xy 431.917134 -316.657464)
			(xy 431.86752 -316.676936) (xy 431.815558 -316.688796) (xy 431.762408 -316.69278) (xy 431.709258 -316.688796)
			(xy 431.657296 -316.676936) (xy 431.607682 -316.657464) (xy 431.561524 -316.630815) (xy 431.519853 -316.597584)
			(xy 431.483601 -316.558513) (xy 431.453577 -316.514476) (xy 431.430451 -316.466455) (xy 431.414741 -316.415525)
			(xy 431.406798 -316.362821) (xy 421.088676 -316.362821) (xy 421.083681 -316.395967) (xy 421.067971 -316.446897)
			(xy 421.044845 -316.494918) (xy 421.014821 -316.538955) (xy 420.978569 -316.578026) (xy 420.936898 -316.611257)
			(xy 420.89074 -316.637906) (xy 420.841126 -316.657378) (xy 420.789164 -316.669238) (xy 420.736014 -316.673222)
			(xy 420.682864 -316.669238) (xy 420.630902 -316.657378) (xy 420.581288 -316.637906) (xy 420.53513 -316.611257)
			(xy 420.493459 -316.578026) (xy 420.457207 -316.538955) (xy 420.427183 -316.494918) (xy 420.404057 -316.446897)
			(xy 420.388347 -316.395967) (xy 420.380404 -316.343263) (xy 407.4668 -316.343263) (xy 407.4668 -317.223119)
			(xy 409.353248 -317.223119) (xy 409.353248 -317.169821) (xy 409.361191 -317.117117) (xy 409.376901 -317.066187)
			(xy 409.400027 -317.018166) (xy 409.430051 -316.974129) (xy 409.466303 -316.935058) (xy 409.507974 -316.901827)
			(xy 409.554132 -316.875178) (xy 409.603746 -316.855706) (xy 409.655708 -316.843846) (xy 409.708858 -316.839863)
			(xy 409.762008 -316.843846) (xy 409.81397 -316.855706) (xy 409.863584 -316.875178) (xy 409.909742 -316.901827)
			(xy 409.951413 -316.935058) (xy 409.987665 -316.974129) (xy 410.017689 -317.018166) (xy 410.040815 -317.066187)
			(xy 410.056525 -317.117117) (xy 410.064468 -317.169821) (xy 410.064966 -317.19647) (xy 410.064468 -317.223119)
			(xy 410.061406 -317.243439) (xy 419.170856 -317.243439) (xy 419.170856 -317.190141) (xy 419.178799 -317.137437)
			(xy 419.194509 -317.086507) (xy 419.217635 -317.038486) (xy 419.247659 -316.994449) (xy 419.283911 -316.955378)
			(xy 419.325582 -316.922147) (xy 419.37174 -316.895498) (xy 419.421354 -316.876026) (xy 419.473316 -316.864166)
			(xy 419.526466 -316.860183) (xy 419.579616 -316.864166) (xy 419.631578 -316.876026) (xy 419.681192 -316.895498)
			(xy 419.72735 -316.922147) (xy 419.769021 -316.955378) (xy 419.805273 -316.994449) (xy 419.835297 -317.038486)
			(xy 419.858423 -317.086507) (xy 419.874133 -317.137437) (xy 419.882076 -317.190141) (xy 419.882137 -317.193401)
			(xy 424.480472 -317.193401) (xy 424.480472 -317.140103) (xy 424.488415 -317.087399) (xy 424.504125 -317.036469)
			(xy 424.527251 -316.988448) (xy 424.557275 -316.944411) (xy 424.593527 -316.90534) (xy 424.635198 -316.872109)
			(xy 424.681356 -316.84546) (xy 424.73097 -316.825988) (xy 424.782932 -316.814128) (xy 424.836082 -316.810145)
			(xy 424.889232 -316.814128) (xy 424.941194 -316.825988) (xy 424.990808 -316.84546) (xy 425.036966 -316.872109)
			(xy 425.078637 -316.90534) (xy 425.114889 -316.944411) (xy 425.144913 -316.988448) (xy 425.168039 -317.036469)
			(xy 425.183749 -317.087399) (xy 425.191692 -317.140103) (xy 425.19219 -317.166752) (xy 425.191692 -317.193401)
			(xy 432.024272 -317.193401) (xy 432.024272 -317.140103) (xy 432.032215 -317.087399) (xy 432.047925 -317.036469)
			(xy 432.071051 -316.988448) (xy 432.101075 -316.944411) (xy 432.137327 -316.90534) (xy 432.178998 -316.872109)
			(xy 432.225156 -316.84546) (xy 432.27477 -316.825988) (xy 432.326732 -316.814128) (xy 432.379882 -316.810145)
			(xy 432.433032 -316.814128) (xy 432.484994 -316.825988) (xy 432.534608 -316.84546) (xy 432.580766 -316.872109)
			(xy 432.622437 -316.90534) (xy 432.658689 -316.944411) (xy 432.688713 -316.988448) (xy 432.711839 -317.036469)
			(xy 432.727549 -317.087399) (xy 432.735492 -317.140103) (xy 432.73599 -317.166752) (xy 432.735492 -317.193401)
			(xy 438.312804 -317.193401) (xy 438.312804 -317.140103) (xy 438.320747 -317.087399) (xy 438.336457 -317.036469)
			(xy 438.359583 -316.988448) (xy 438.389607 -316.944411) (xy 438.425859 -316.90534) (xy 438.46753 -316.872109)
			(xy 438.513688 -316.84546) (xy 438.563302 -316.825988) (xy 438.615264 -316.814128) (xy 438.668414 -316.810145)
			(xy 438.721564 -316.814128) (xy 438.773526 -316.825988) (xy 438.82314 -316.84546) (xy 438.869298 -316.872109)
			(xy 438.910969 -316.90534) (xy 438.947221 -316.944411) (xy 438.977245 -316.988448) (xy 439.000371 -317.036469)
			(xy 439.016081 -317.087399) (xy 439.024024 -317.140103) (xy 439.024522 -317.166752) (xy 439.024024 -317.193401)
			(xy 439.568072 -317.193401) (xy 439.568072 -317.140103) (xy 439.576015 -317.087399) (xy 439.591725 -317.036469)
			(xy 439.614851 -316.988448) (xy 439.644875 -316.944411) (xy 439.681127 -316.90534) (xy 439.722798 -316.872109)
			(xy 439.768956 -316.84546) (xy 439.81857 -316.825988) (xy 439.870532 -316.814128) (xy 439.923682 -316.810145)
			(xy 439.976832 -316.814128) (xy 440.028794 -316.825988) (xy 440.078408 -316.84546) (xy 440.124566 -316.872109)
			(xy 440.166237 -316.90534) (xy 440.184643 -316.925177) (xy 445.902578 -316.925177) (xy 445.902578 -316.871879)
			(xy 445.910521 -316.819175) (xy 445.926231 -316.768245) (xy 445.949357 -316.720224) (xy 445.979381 -316.676187)
			(xy 446.015633 -316.637116) (xy 446.057304 -316.603885) (xy 446.103462 -316.577236) (xy 446.153076 -316.557764)
			(xy 446.205038 -316.545904) (xy 446.258188 -316.541921) (xy 446.311338 -316.545904) (xy 446.3633 -316.557764)
			(xy 446.412914 -316.577236) (xy 446.459072 -316.603885) (xy 446.500743 -316.637116) (xy 446.536995 -316.676187)
			(xy 446.567019 -316.720224) (xy 446.590145 -316.768245) (xy 446.605855 -316.819175) (xy 446.613798 -316.871879)
			(xy 446.614296 -316.898528) (xy 446.613798 -316.925177) (xy 446.605855 -316.977881) (xy 446.590145 -317.028811)
			(xy 446.567019 -317.076832) (xy 446.536995 -317.120869) (xy 446.500743 -317.15994) (xy 446.459072 -317.193171)
			(xy 446.458674 -317.193401) (xy 447.111872 -317.193401) (xy 447.111872 -317.140103) (xy 447.119815 -317.087399)
			(xy 447.135525 -317.036469) (xy 447.158651 -316.988448) (xy 447.188675 -316.944411) (xy 447.224927 -316.90534)
			(xy 447.266598 -316.872109) (xy 447.312756 -316.84546) (xy 447.36237 -316.825988) (xy 447.414332 -316.814128)
			(xy 447.467482 -316.810145) (xy 447.520632 -316.814128) (xy 447.572594 -316.825988) (xy 447.622208 -316.84546)
			(xy 447.668366 -316.872109) (xy 447.710037 -316.90534) (xy 447.746289 -316.944411) (xy 447.776313 -316.988448)
			(xy 447.799439 -317.036469) (xy 447.815149 -317.087399) (xy 447.823092 -317.140103) (xy 447.82359 -317.166752)
			(xy 447.823092 -317.193401) (xy 454.655672 -317.193401) (xy 454.655672 -317.140103) (xy 454.663615 -317.087399)
			(xy 454.679325 -317.036469) (xy 454.702451 -316.988448) (xy 454.732475 -316.944411) (xy 454.768727 -316.90534)
			(xy 454.810398 -316.872109) (xy 454.856556 -316.84546) (xy 454.90617 -316.825988) (xy 454.958132 -316.814128)
			(xy 455.011282 -316.810145) (xy 455.064432 -316.814128) (xy 455.116394 -316.825988) (xy 455.166008 -316.84546)
			(xy 455.212166 -316.872109) (xy 455.253837 -316.90534) (xy 455.290089 -316.944411) (xy 455.320113 -316.988448)
			(xy 455.343239 -317.036469) (xy 455.347536 -317.050399) (xy 456.952848 -317.050399) (xy 456.952848 -316.997101)
			(xy 456.960791 -316.944397) (xy 456.976501 -316.893467) (xy 456.999627 -316.845446) (xy 457.029651 -316.801409)
			(xy 457.065903 -316.762338) (xy 457.107574 -316.729107) (xy 457.153732 -316.702458) (xy 457.203346 -316.682986)
			(xy 457.255308 -316.671126) (xy 457.308458 -316.667143) (xy 457.361608 -316.671126) (xy 457.41357 -316.682986)
			(xy 457.463184 -316.702458) (xy 457.509342 -316.729107) (xy 457.551013 -316.762338) (xy 457.587265 -316.801409)
			(xy 457.617289 -316.845446) (xy 457.640415 -316.893467) (xy 457.656125 -316.944397) (xy 457.664068 -316.997101)
			(xy 457.664566 -317.02375) (xy 457.664068 -317.050399) (xy 457.66292 -317.058019) (xy 462.213696 -317.058019)
			(xy 462.213696 -317.004721) (xy 462.221639 -316.952017) (xy 462.237349 -316.901087) (xy 462.260475 -316.853066)
			(xy 462.290499 -316.809029) (xy 462.326751 -316.769958) (xy 462.368422 -316.736727) (xy 462.41458 -316.710078)
			(xy 462.464194 -316.690606) (xy 462.516156 -316.678746) (xy 462.569306 -316.674763) (xy 462.622456 -316.678746)
			(xy 462.674418 -316.690606) (xy 462.724032 -316.710078) (xy 462.77019 -316.736727) (xy 462.811861 -316.769958)
			(xy 462.848113 -316.809029) (xy 462.878137 -316.853066) (xy 462.901263 -316.901087) (xy 462.916973 -316.952017)
			(xy 462.924916 -317.004721) (xy 462.925414 -317.03137) (xy 462.924916 -317.058019) (xy 462.916973 -317.110723)
			(xy 462.901263 -317.161653) (xy 462.878137 -317.209674) (xy 462.848113 -317.253711) (xy 462.811861 -317.292782)
			(xy 462.77019 -317.326013) (xy 462.724032 -317.352662) (xy 462.674418 -317.372134) (xy 462.622456 -317.383994)
			(xy 462.569306 -317.387978) (xy 462.516156 -317.383994) (xy 462.464194 -317.372134) (xy 462.41458 -317.352662)
			(xy 462.368422 -317.326013) (xy 462.326751 -317.292782) (xy 462.290499 -317.253711) (xy 462.260475 -317.209674)
			(xy 462.237349 -317.161653) (xy 462.221639 -317.110723) (xy 462.213696 -317.058019) (xy 457.66292 -317.058019)
			(xy 457.656125 -317.103103) (xy 457.640415 -317.154033) (xy 457.617289 -317.202054) (xy 457.587265 -317.246091)
			(xy 457.551013 -317.285162) (xy 457.509342 -317.318393) (xy 457.463184 -317.345042) (xy 457.41357 -317.364514)
			(xy 457.361608 -317.376374) (xy 457.308458 -317.380358) (xy 457.255308 -317.376374) (xy 457.203346 -317.364514)
			(xy 457.153732 -317.345042) (xy 457.107574 -317.318393) (xy 457.065903 -317.285162) (xy 457.029651 -317.246091)
			(xy 456.999627 -317.202054) (xy 456.976501 -317.154033) (xy 456.960791 -317.103103) (xy 456.952848 -317.050399)
			(xy 455.347536 -317.050399) (xy 455.358949 -317.087399) (xy 455.366892 -317.140103) (xy 455.36739 -317.166752)
			(xy 455.366892 -317.193401) (xy 455.358949 -317.246105) (xy 455.343239 -317.297035) (xy 455.320113 -317.345056)
			(xy 455.290089 -317.389093) (xy 455.253837 -317.428164) (xy 455.212166 -317.461395) (xy 455.166008 -317.488044)
			(xy 455.116394 -317.507516) (xy 455.064432 -317.519376) (xy 455.011282 -317.52336) (xy 454.958132 -317.519376)
			(xy 454.90617 -317.507516) (xy 454.856556 -317.488044) (xy 454.810398 -317.461395) (xy 454.768727 -317.428164)
			(xy 454.732475 -317.389093) (xy 454.702451 -317.345056) (xy 454.679325 -317.297035) (xy 454.663615 -317.246105)
			(xy 454.655672 -317.193401) (xy 447.823092 -317.193401) (xy 447.815149 -317.246105) (xy 447.799439 -317.297035)
			(xy 447.776313 -317.345056) (xy 447.746289 -317.389093) (xy 447.710037 -317.428164) (xy 447.668366 -317.461395)
			(xy 447.622208 -317.488044) (xy 447.572594 -317.507516) (xy 447.520632 -317.519376) (xy 447.467482 -317.52336)
			(xy 447.414332 -317.519376) (xy 447.36237 -317.507516) (xy 447.312756 -317.488044) (xy 447.266598 -317.461395)
			(xy 447.224927 -317.428164) (xy 447.188675 -317.389093) (xy 447.158651 -317.345056) (xy 447.135525 -317.297035)
			(xy 447.119815 -317.246105) (xy 447.111872 -317.193401) (xy 446.458674 -317.193401) (xy 446.412914 -317.21982)
			(xy 446.3633 -317.239292) (xy 446.311338 -317.251152) (xy 446.258188 -317.255136) (xy 446.205038 -317.251152)
			(xy 446.153076 -317.239292) (xy 446.103462 -317.21982) (xy 446.057304 -317.193171) (xy 446.015633 -317.15994)
			(xy 445.979381 -317.120869) (xy 445.949357 -317.076832) (xy 445.926231 -317.028811) (xy 445.910521 -316.977881)
			(xy 445.902578 -316.925177) (xy 440.184643 -316.925177) (xy 440.202489 -316.944411) (xy 440.232513 -316.988448)
			(xy 440.255639 -317.036469) (xy 440.271349 -317.087399) (xy 440.279292 -317.140103) (xy 440.27979 -317.166752)
			(xy 440.279292 -317.193401) (xy 440.271349 -317.246105) (xy 440.255639 -317.297035) (xy 440.232513 -317.345056)
			(xy 440.202489 -317.389093) (xy 440.166237 -317.428164) (xy 440.124566 -317.461395) (xy 440.078408 -317.488044)
			(xy 440.028794 -317.507516) (xy 439.976832 -317.519376) (xy 439.923682 -317.52336) (xy 439.870532 -317.519376)
			(xy 439.81857 -317.507516) (xy 439.768956 -317.488044) (xy 439.722798 -317.461395) (xy 439.681127 -317.428164)
			(xy 439.644875 -317.389093) (xy 439.614851 -317.345056) (xy 439.591725 -317.297035) (xy 439.576015 -317.246105)
			(xy 439.568072 -317.193401) (xy 439.024024 -317.193401) (xy 439.016081 -317.246105) (xy 439.000371 -317.297035)
			(xy 438.977245 -317.345056) (xy 438.947221 -317.389093) (xy 438.910969 -317.428164) (xy 438.869298 -317.461395)
			(xy 438.82314 -317.488044) (xy 438.773526 -317.507516) (xy 438.721564 -317.519376) (xy 438.668414 -317.52336)
			(xy 438.615264 -317.519376) (xy 438.563302 -317.507516) (xy 438.513688 -317.488044) (xy 438.46753 -317.461395)
			(xy 438.425859 -317.428164) (xy 438.389607 -317.389093) (xy 438.359583 -317.345056) (xy 438.336457 -317.297035)
			(xy 438.320747 -317.246105) (xy 438.312804 -317.193401) (xy 432.735492 -317.193401) (xy 432.727549 -317.246105)
			(xy 432.711839 -317.297035) (xy 432.688713 -317.345056) (xy 432.658689 -317.389093) (xy 432.622437 -317.428164)
			(xy 432.580766 -317.461395) (xy 432.534608 -317.488044) (xy 432.484994 -317.507516) (xy 432.433032 -317.519376)
			(xy 432.379882 -317.52336) (xy 432.326732 -317.519376) (xy 432.27477 -317.507516) (xy 432.225156 -317.488044)
			(xy 432.178998 -317.461395) (xy 432.137327 -317.428164) (xy 432.101075 -317.389093) (xy 432.071051 -317.345056)
			(xy 432.047925 -317.297035) (xy 432.032215 -317.246105) (xy 432.024272 -317.193401) (xy 425.191692 -317.193401)
			(xy 425.183749 -317.246105) (xy 425.168039 -317.297035) (xy 425.144913 -317.345056) (xy 425.114889 -317.389093)
			(xy 425.078637 -317.428164) (xy 425.036966 -317.461395) (xy 424.990808 -317.488044) (xy 424.941194 -317.507516)
			(xy 424.889232 -317.519376) (xy 424.836082 -317.52336) (xy 424.782932 -317.519376) (xy 424.73097 -317.507516)
			(xy 424.681356 -317.488044) (xy 424.635198 -317.461395) (xy 424.593527 -317.428164) (xy 424.557275 -317.389093)
			(xy 424.527251 -317.345056) (xy 424.504125 -317.297035) (xy 424.488415 -317.246105) (xy 424.480472 -317.193401)
			(xy 419.882137 -317.193401) (xy 419.882574 -317.21679) (xy 419.882076 -317.243439) (xy 419.874133 -317.296143)
			(xy 419.858423 -317.347073) (xy 419.835297 -317.395094) (xy 419.805273 -317.439131) (xy 419.769021 -317.478202)
			(xy 419.72735 -317.511433) (xy 419.681192 -317.538082) (xy 419.631578 -317.557554) (xy 419.579616 -317.569414)
			(xy 419.526466 -317.573398) (xy 419.473316 -317.569414) (xy 419.421354 -317.557554) (xy 419.37174 -317.538082)
			(xy 419.325582 -317.511433) (xy 419.283911 -317.478202) (xy 419.247659 -317.439131) (xy 419.217635 -317.395094)
			(xy 419.194509 -317.347073) (xy 419.178799 -317.296143) (xy 419.170856 -317.243439) (xy 410.061406 -317.243439)
			(xy 410.056525 -317.275823) (xy 410.040815 -317.326753) (xy 410.017689 -317.374774) (xy 409.987665 -317.418811)
			(xy 409.951413 -317.457882) (xy 409.909742 -317.491113) (xy 409.863584 -317.517762) (xy 409.81397 -317.537234)
			(xy 409.762008 -317.549094) (xy 409.708858 -317.553078) (xy 409.655708 -317.549094) (xy 409.603746 -317.537234)
			(xy 409.554132 -317.517762) (xy 409.507974 -317.491113) (xy 409.466303 -317.457882) (xy 409.430051 -317.418811)
			(xy 409.400027 -317.374774) (xy 409.376901 -317.326753) (xy 409.361191 -317.275823) (xy 409.353248 -317.223119)
			(xy 407.4668 -317.223119) (xy 407.4668 -317.679557) (xy 408.344614 -317.679557) (xy 408.344614 -317.626259)
			(xy 408.352557 -317.573555) (xy 408.368267 -317.522625) (xy 408.391393 -317.474604) (xy 408.421417 -317.430567)
			(xy 408.457669 -317.391496) (xy 408.49934 -317.358265) (xy 408.545498 -317.331616) (xy 408.595112 -317.312144)
			(xy 408.647074 -317.300284) (xy 408.700224 -317.296301) (xy 408.753374 -317.300284) (xy 408.805336 -317.312144)
			(xy 408.85495 -317.331616) (xy 408.901108 -317.358265) (xy 408.942779 -317.391496) (xy 408.979031 -317.430567)
			(xy 409.009055 -317.474604) (xy 409.032181 -317.522625) (xy 409.047891 -317.573555) (xy 409.055834 -317.626259)
			(xy 409.056332 -317.652908) (xy 409.055834 -317.679557) (xy 409.047891 -317.732261) (xy 409.032181 -317.783191)
			(xy 409.009055 -317.831212) (xy 408.979031 -317.875249) (xy 408.942779 -317.91432) (xy 408.901108 -317.947551)
			(xy 408.85495 -317.9742) (xy 408.805336 -317.993672) (xy 408.753374 -318.005532) (xy 408.700224 -318.009516)
			(xy 408.647074 -318.005532) (xy 408.595112 -317.993672) (xy 408.545498 -317.9742) (xy 408.49934 -317.947551)
			(xy 408.457669 -317.91432) (xy 408.421417 -317.875249) (xy 408.391393 -317.831212) (xy 408.368267 -317.783191)
			(xy 408.352557 -317.732261) (xy 408.344614 -317.679557) (xy 407.4668 -317.679557) (xy 407.4668 -318.043285)
			(xy 409.392872 -318.043285) (xy 409.392872 -317.989987) (xy 409.400815 -317.937283) (xy 409.416525 -317.886353)
			(xy 409.439651 -317.838332) (xy 409.469675 -317.794295) (xy 409.505927 -317.755224) (xy 409.547598 -317.721993)
			(xy 409.593756 -317.695344) (xy 409.64337 -317.675872) (xy 409.695332 -317.664012) (xy 409.748482 -317.660029)
			(xy 409.801632 -317.664012) (xy 409.853594 -317.675872) (xy 409.903208 -317.695344) (xy 409.949366 -317.721993)
			(xy 409.991037 -317.755224) (xy 410.027289 -317.794295) (xy 410.057313 -317.838332) (xy 410.080439 -317.886353)
			(xy 410.096149 -317.937283) (xy 410.104092 -317.989987) (xy 410.10459 -318.016636) (xy 410.104092 -318.043285)
			(xy 410.096149 -318.095989) (xy 410.09611 -318.096117) (xy 412.12261 -318.096117) (xy 412.12261 -318.042819)
			(xy 412.130553 -317.990115) (xy 412.146263 -317.939185) (xy 412.169389 -317.891164) (xy 412.199413 -317.847127)
			(xy 412.235665 -317.808056) (xy 412.277336 -317.774825) (xy 412.323494 -317.748176) (xy 412.373108 -317.728704)
			(xy 412.42507 -317.716844) (xy 412.47822 -317.712861) (xy 412.53137 -317.716844) (xy 412.583332 -317.728704)
			(xy 412.632946 -317.748176) (xy 412.679104 -317.774825) (xy 412.720775 -317.808056) (xy 412.757027 -317.847127)
			(xy 412.787051 -317.891164) (xy 412.810177 -317.939185) (xy 412.825887 -317.990115) (xy 412.83383 -318.042819)
			(xy 412.833839 -318.043285) (xy 416.936672 -318.043285) (xy 416.936672 -317.989987) (xy 416.944615 -317.937283)
			(xy 416.960325 -317.886353) (xy 416.983451 -317.838332) (xy 417.013475 -317.794295) (xy 417.049727 -317.755224)
			(xy 417.091398 -317.721993) (xy 417.137556 -317.695344) (xy 417.18717 -317.675872) (xy 417.239132 -317.664012)
			(xy 417.292282 -317.660029) (xy 417.345432 -317.664012) (xy 417.397394 -317.675872) (xy 417.447008 -317.695344)
			(xy 417.493166 -317.721993) (xy 417.534837 -317.755224) (xy 417.571089 -317.794295) (xy 417.601113 -317.838332)
			(xy 417.624239 -317.886353) (xy 417.639949 -317.937283) (xy 417.647892 -317.989987) (xy 417.64822 -318.007532)
			(xy 426.663017 -318.007532) (xy 426.668501 -317.953655) (xy 426.682081 -317.90123) (xy 426.703442 -317.851465)
			(xy 426.732093 -317.80551) (xy 426.767372 -317.764422) (xy 426.808466 -317.729151) (xy 426.854428 -317.700509)
			(xy 426.904196 -317.679158) (xy 426.956624 -317.665589) (xy 427.010502 -317.660116) (xy 427.064587 -317.662864)
			(xy 427.117633 -317.67377) (xy 427.168415 -317.692584) (xy 427.215763 -317.71887) (xy 427.258584 -317.752023)
			(xy 427.295892 -317.791278) (xy 427.326824 -317.83573) (xy 427.350669 -317.884353) (xy 427.366876 -317.936027)
			(xy 427.375071 -317.989558) (xy 427.375574 -318.016636) (xy 427.375574 -318.02578) (xy 427.375695 -318.039824)
			(xy 427.376589 -318.043285) (xy 434.266076 -318.043285) (xy 434.266076 -317.989987) (xy 434.274019 -317.937283)
			(xy 434.289729 -317.886353) (xy 434.312855 -317.838332) (xy 434.342879 -317.794295) (xy 434.379131 -317.755224)
			(xy 434.420802 -317.721993) (xy 434.46696 -317.695344) (xy 434.516574 -317.675872) (xy 434.568536 -317.664012)
			(xy 434.621686 -317.660029) (xy 434.674836 -317.664012) (xy 434.726798 -317.675872) (xy 434.776412 -317.695344)
			(xy 434.82257 -317.721993) (xy 434.864241 -317.755224) (xy 434.900493 -317.794295) (xy 434.930517 -317.838332)
			(xy 434.953643 -317.886353) (xy 434.969353 -317.937283) (xy 434.977296 -317.989987) (xy 434.977794 -318.016636)
			(xy 434.977296 -318.043285) (xy 439.568072 -318.043285) (xy 439.568072 -317.989987) (xy 439.576015 -317.937283)
			(xy 439.591725 -317.886353) (xy 439.614851 -317.838332) (xy 439.644875 -317.794295) (xy 439.681127 -317.755224)
			(xy 439.722798 -317.721993) (xy 439.768956 -317.695344) (xy 439.81857 -317.675872) (xy 439.870532 -317.664012)
			(xy 439.923682 -317.660029) (xy 439.976832 -317.664012) (xy 440.028794 -317.675872) (xy 440.078408 -317.695344)
			(xy 440.124566 -317.721993) (xy 440.166237 -317.755224) (xy 440.202489 -317.794295) (xy 440.232513 -317.838332)
			(xy 440.255639 -317.886353) (xy 440.271349 -317.937283) (xy 440.279292 -317.989987) (xy 440.27979 -318.016636)
			(xy 440.279292 -318.043285) (xy 440.271349 -318.095989) (xy 440.266765 -318.110849) (xy 442.197988 -318.110849)
			(xy 442.197988 -318.057551) (xy 442.205931 -318.004847) (xy 442.221641 -317.953917) (xy 442.244767 -317.905896)
			(xy 442.274791 -317.861859) (xy 442.311043 -317.822788) (xy 442.352714 -317.789557) (xy 442.398872 -317.762908)
			(xy 442.448486 -317.743436) (xy 442.500448 -317.731576) (xy 442.553598 -317.727593) (xy 442.606748 -317.731576)
			(xy 442.65871 -317.743436) (xy 442.708324 -317.762908) (xy 442.754482 -317.789557) (xy 442.796153 -317.822788)
			(xy 442.832405 -317.861859) (xy 442.862429 -317.905896) (xy 442.885555 -317.953917) (xy 442.901265 -318.004847)
			(xy 442.907058 -318.043285) (xy 449.300336 -318.043285) (xy 449.300336 -317.989987) (xy 449.308279 -317.937283)
			(xy 449.323989 -317.886353) (xy 449.347115 -317.838332) (xy 449.377139 -317.794295) (xy 449.413391 -317.755224)
			(xy 449.455062 -317.721993) (xy 449.50122 -317.695344) (xy 449.550834 -317.675872) (xy 449.602796 -317.664012)
			(xy 449.655946 -317.660029) (xy 449.709096 -317.664012) (xy 449.761058 -317.675872) (xy 449.810672 -317.695344)
			(xy 449.85683 -317.721993) (xy 449.898501 -317.755224) (xy 449.934753 -317.794295) (xy 449.964777 -317.838332)
			(xy 449.987903 -317.886353) (xy 450.003613 -317.937283) (xy 450.011556 -317.989987) (xy 450.012054 -318.016636)
			(xy 450.011556 -318.043285) (xy 456.849216 -318.043285) (xy 456.849216 -317.989987) (xy 456.857159 -317.937283)
			(xy 456.872869 -317.886353) (xy 456.895995 -317.838332) (xy 456.926019 -317.794295) (xy 456.962271 -317.755224)
			(xy 457.003942 -317.721993) (xy 457.0501 -317.695344) (xy 457.099714 -317.675872) (xy 457.151676 -317.664012)
			(xy 457.204826 -317.660029) (xy 457.257976 -317.664012) (xy 457.309938 -317.675872) (xy 457.359552 -317.695344)
			(xy 457.40571 -317.721993) (xy 457.447381 -317.755224) (xy 457.483633 -317.794295) (xy 457.513657 -317.838332)
			(xy 457.536783 -317.886353) (xy 457.552493 -317.937283) (xy 457.560436 -317.989987) (xy 457.560934 -318.016636)
			(xy 457.560436 -318.043285) (xy 462.199472 -318.043285) (xy 462.199472 -317.989987) (xy 462.207415 -317.937283)
			(xy 462.223125 -317.886353) (xy 462.246251 -317.838332) (xy 462.276275 -317.794295) (xy 462.312527 -317.755224)
			(xy 462.354198 -317.721993) (xy 462.400356 -317.695344) (xy 462.44997 -317.675872) (xy 462.501932 -317.664012)
			(xy 462.555082 -317.660029) (xy 462.608232 -317.664012) (xy 462.660194 -317.675872) (xy 462.709808 -317.695344)
			(xy 462.755966 -317.721993) (xy 462.797637 -317.755224) (xy 462.833889 -317.794295) (xy 462.863913 -317.838332)
			(xy 462.887039 -317.886353) (xy 462.902749 -317.937283) (xy 462.910692 -317.989987) (xy 462.91119 -318.016636)
			(xy 462.910692 -318.043285) (xy 462.902749 -318.095989) (xy 462.887039 -318.146919) (xy 462.863913 -318.19494)
			(xy 462.833889 -318.238977) (xy 462.797637 -318.278048) (xy 462.755966 -318.311279) (xy 462.709808 -318.337928)
			(xy 462.660194 -318.3574) (xy 462.608232 -318.36926) (xy 462.555082 -318.373244) (xy 462.501932 -318.36926)
			(xy 462.44997 -318.3574) (xy 462.400356 -318.337928) (xy 462.354198 -318.311279) (xy 462.312527 -318.278048)
			(xy 462.276275 -318.238977) (xy 462.246251 -318.19494) (xy 462.223125 -318.146919) (xy 462.207415 -318.095989)
			(xy 462.199472 -318.043285) (xy 457.560436 -318.043285) (xy 457.552493 -318.095989) (xy 457.536783 -318.146919)
			(xy 457.513657 -318.19494) (xy 457.483633 -318.238977) (xy 457.447381 -318.278048) (xy 457.40571 -318.311279)
			(xy 457.359552 -318.337928) (xy 457.309938 -318.3574) (xy 457.257976 -318.36926) (xy 457.204826 -318.373244)
			(xy 457.151676 -318.36926) (xy 457.099714 -318.3574) (xy 457.0501 -318.337928) (xy 457.003942 -318.311279)
			(xy 456.962271 -318.278048) (xy 456.926019 -318.238977) (xy 456.895995 -318.19494) (xy 456.872869 -318.146919)
			(xy 456.857159 -318.095989) (xy 456.849216 -318.043285) (xy 450.011556 -318.043285) (xy 450.003613 -318.095989)
			(xy 449.987903 -318.146919) (xy 449.964777 -318.19494) (xy 449.934753 -318.238977) (xy 449.898501 -318.278048)
			(xy 449.85683 -318.311279) (xy 449.810672 -318.337928) (xy 449.761058 -318.3574) (xy 449.709096 -318.36926)
			(xy 449.655946 -318.373244) (xy 449.602796 -318.36926) (xy 449.550834 -318.3574) (xy 449.50122 -318.337928)
			(xy 449.455062 -318.311279) (xy 449.413391 -318.278048) (xy 449.377139 -318.238977) (xy 449.347115 -318.19494)
			(xy 449.323989 -318.146919) (xy 449.308279 -318.095989) (xy 449.300336 -318.043285) (xy 442.907058 -318.043285)
			(xy 442.909208 -318.057551) (xy 442.909706 -318.0842) (xy 442.909208 -318.110849) (xy 442.901265 -318.163553)
			(xy 442.885555 -318.214483) (xy 442.862429 -318.262504) (xy 442.832405 -318.306541) (xy 442.796153 -318.345612)
			(xy 442.754482 -318.378843) (xy 442.708324 -318.405492) (xy 442.65871 -318.424964) (xy 442.606748 -318.436824)
			(xy 442.553598 -318.440808) (xy 442.500448 -318.436824) (xy 442.448486 -318.424964) (xy 442.398872 -318.405492)
			(xy 442.352714 -318.378843) (xy 442.311043 -318.345612) (xy 442.274791 -318.306541) (xy 442.244767 -318.262504)
			(xy 442.221641 -318.214483) (xy 442.205931 -318.163553) (xy 442.197988 -318.110849) (xy 440.266765 -318.110849)
			(xy 440.255639 -318.146919) (xy 440.232513 -318.19494) (xy 440.202489 -318.238977) (xy 440.166237 -318.278048)
			(xy 440.124566 -318.311279) (xy 440.078408 -318.337928) (xy 440.028794 -318.3574) (xy 439.976832 -318.36926)
			(xy 439.923682 -318.373244) (xy 439.870532 -318.36926) (xy 439.81857 -318.3574) (xy 439.768956 -318.337928)
			(xy 439.722798 -318.311279) (xy 439.681127 -318.278048) (xy 439.644875 -318.238977) (xy 439.614851 -318.19494)
			(xy 439.591725 -318.146919) (xy 439.576015 -318.095989) (xy 439.568072 -318.043285) (xy 434.977296 -318.043285)
			(xy 434.969353 -318.095989) (xy 434.953643 -318.146919) (xy 434.930517 -318.19494) (xy 434.900493 -318.238977)
			(xy 434.864241 -318.278048) (xy 434.82257 -318.311279) (xy 434.776412 -318.337928) (xy 434.726798 -318.3574)
			(xy 434.674836 -318.36926) (xy 434.621686 -318.373244) (xy 434.568536 -318.36926) (xy 434.516574 -318.3574)
			(xy 434.46696 -318.337928) (xy 434.420802 -318.311279) (xy 434.379131 -318.278048) (xy 434.342879 -318.238977)
			(xy 434.312855 -318.19494) (xy 434.289729 -318.146919) (xy 434.274019 -318.095989) (xy 434.266076 -318.043285)
			(xy 427.376589 -318.043285) (xy 427.382718 -318.067007) (xy 427.396873 -318.091253) (xy 427.417093 -318.110731)
			(xy 427.441851 -318.12397) (xy 427.469277 -318.129972) (xy 427.497301 -318.128283) (xy 427.510702 -318.124078)
			(xy 427.539328 -318.114715) (xy 427.5987 -318.104623) (xy 427.628812 -318.104012) (xy 427.655891 -318.10451)
			(xy 427.709423 -318.112713) (xy 427.761097 -318.128927) (xy 427.809719 -318.152779) (xy 427.854169 -318.183719)
			(xy 427.893421 -318.221032) (xy 427.926571 -318.263859) (xy 427.952853 -318.311212) (xy 427.971661 -318.361998)
			(xy 427.982563 -318.415047) (xy 427.985067 -318.464417) (xy 450.10831 -318.464417) (xy 450.10831 -318.411119)
			(xy 450.116253 -318.358415) (xy 450.131963 -318.307485) (xy 450.155089 -318.259464) (xy 450.185113 -318.215427)
			(xy 450.221365 -318.176356) (xy 450.263036 -318.143125) (xy 450.309194 -318.116476) (xy 450.358808 -318.097004)
			(xy 450.41077 -318.085144) (xy 450.46392 -318.081161) (xy 450.51707 -318.085144) (xy 450.569032 -318.097004)
			(xy 450.618646 -318.116476) (xy 450.664804 -318.143125) (xy 450.706475 -318.176356) (xy 450.742727 -318.215427)
			(xy 450.772751 -318.259464) (xy 450.795877 -318.307485) (xy 450.811587 -318.358415) (xy 450.81953 -318.411119)
			(xy 450.820028 -318.437768) (xy 450.81953 -318.464417) (xy 450.811587 -318.517121) (xy 450.795877 -318.568051)
			(xy 450.772751 -318.616072) (xy 450.742727 -318.660109) (xy 450.706475 -318.69918) (xy 450.682034 -318.718671)
			(xy 460.353146 -318.718671) (xy 460.353146 -318.665373) (xy 460.361089 -318.612669) (xy 460.376799 -318.561739)
			(xy 460.399925 -318.513718) (xy 460.429949 -318.469681) (xy 460.466201 -318.43061) (xy 460.507872 -318.397379)
			(xy 460.55403 -318.37073) (xy 460.603644 -318.351258) (xy 460.655606 -318.339398) (xy 460.708756 -318.335415)
			(xy 460.761906 -318.339398) (xy 460.813868 -318.351258) (xy 460.863482 -318.37073) (xy 460.90964 -318.397379)
			(xy 460.951311 -318.43061) (xy 460.987563 -318.469681) (xy 461.017587 -318.513718) (xy 461.040713 -318.561739)
			(xy 461.056423 -318.612669) (xy 461.064366 -318.665373) (xy 461.064864 -318.692022) (xy 461.064366 -318.718671)
			(xy 461.056423 -318.771375) (xy 461.040713 -318.822305) (xy 461.017587 -318.870326) (xy 460.987563 -318.914363)
			(xy 460.951311 -318.953434) (xy 460.90964 -318.986665) (xy 460.863482 -319.013314) (xy 460.813868 -319.032786)
			(xy 460.761906 -319.044646) (xy 460.708756 -319.04863) (xy 460.655606 -319.044646) (xy 460.603644 -319.032786)
			(xy 460.55403 -319.013314) (xy 460.507872 -318.986665) (xy 460.466201 -318.953434) (xy 460.429949 -318.914363)
			(xy 460.399925 -318.870326) (xy 460.376799 -318.822305) (xy 460.361089 -318.771375) (xy 460.353146 -318.718671)
			(xy 450.682034 -318.718671) (xy 450.664804 -318.732411) (xy 450.618646 -318.75906) (xy 450.569032 -318.778532)
			(xy 450.51707 -318.790392) (xy 450.46392 -318.794376) (xy 450.41077 -318.790392) (xy 450.358808 -318.778532)
			(xy 450.309194 -318.75906) (xy 450.263036 -318.732411) (xy 450.221365 -318.69918) (xy 450.185113 -318.660109)
			(xy 450.155089 -318.616072) (xy 450.131963 -318.568051) (xy 450.116253 -318.517121) (xy 450.10831 -318.464417)
			(xy 427.985067 -318.464417) (xy 427.985306 -318.469135) (xy 427.979826 -318.523015) (xy 427.966252 -318.575444)
			(xy 427.944895 -318.625212) (xy 427.916248 -318.671173) (xy 427.880971 -318.712266) (xy 427.839879 -318.747543)
			(xy 427.793919 -318.776191) (xy 427.744151 -318.797549) (xy 427.691723 -318.811125) (xy 427.637843 -318.816605)
			(xy 427.583755 -318.813864) (xy 427.530706 -318.802964) (xy 427.479919 -318.784156) (xy 427.432566 -318.757875)
			(xy 427.389738 -318.724727) (xy 427.352424 -318.685475) (xy 427.321483 -318.641026) (xy 427.29763 -318.592404)
			(xy 427.281415 -318.540731) (xy 427.273211 -318.487199) (xy 427.272704 -318.46012) (xy 427.272704 -318.450976)
			(xy 427.272649 -318.436929) (xy 427.265614 -318.409741) (xy 427.251447 -318.385493) (xy 427.231216 -318.366015)
			(xy 427.206448 -318.352777) (xy 427.179013 -318.346778) (xy 427.15098 -318.348471) (xy 427.137576 -318.352678)
			(xy 427.108951 -318.362045) (xy 427.049578 -318.372135) (xy 427.019466 -318.372744) (xy 426.992388 -318.372166)
			(xy 426.938858 -318.36396) (xy 426.887188 -318.347743) (xy 426.83857 -318.323889) (xy 426.794124 -318.292947)
			(xy 426.754876 -318.255632) (xy 426.721732 -318.212805) (xy 426.695455 -318.165451) (xy 426.676651 -318.114665)
			(xy 426.665755 -318.061618) (xy 426.663017 -318.007532) (xy 417.64822 -318.007532) (xy 417.64839 -318.016636)
			(xy 417.647892 -318.043285) (xy 417.639949 -318.095989) (xy 417.624239 -318.146919) (xy 417.601113 -318.19494)
			(xy 417.571089 -318.238977) (xy 417.534837 -318.278048) (xy 417.493166 -318.311279) (xy 417.447008 -318.337928)
			(xy 417.397394 -318.3574) (xy 417.345432 -318.36926) (xy 417.292282 -318.373244) (xy 417.239132 -318.36926)
			(xy 417.18717 -318.3574) (xy 417.137556 -318.337928) (xy 417.091398 -318.311279) (xy 417.049727 -318.278048)
			(xy 417.013475 -318.238977) (xy 416.983451 -318.19494) (xy 416.960325 -318.146919) (xy 416.944615 -318.095989)
			(xy 416.936672 -318.043285) (xy 412.833839 -318.043285) (xy 412.834328 -318.069468) (xy 412.83383 -318.096117)
			(xy 412.825887 -318.148821) (xy 412.810177 -318.199751) (xy 412.787051 -318.247772) (xy 412.757027 -318.291809)
			(xy 412.720775 -318.33088) (xy 412.679104 -318.364111) (xy 412.632946 -318.39076) (xy 412.583332 -318.410232)
			(xy 412.53137 -318.422092) (xy 412.47822 -318.426076) (xy 412.42507 -318.422092) (xy 412.373108 -318.410232)
			(xy 412.323494 -318.39076) (xy 412.277336 -318.364111) (xy 412.235665 -318.33088) (xy 412.199413 -318.291809)
			(xy 412.169389 -318.247772) (xy 412.146263 -318.199751) (xy 412.130553 -318.148821) (xy 412.12261 -318.096117)
			(xy 410.09611 -318.096117) (xy 410.080439 -318.146919) (xy 410.057313 -318.19494) (xy 410.027289 -318.238977)
			(xy 409.991037 -318.278048) (xy 409.949366 -318.311279) (xy 409.903208 -318.337928) (xy 409.853594 -318.3574)
			(xy 409.801632 -318.36926) (xy 409.748482 -318.373244) (xy 409.695332 -318.36926) (xy 409.64337 -318.3574)
			(xy 409.593756 -318.337928) (xy 409.547598 -318.311279) (xy 409.505927 -318.278048) (xy 409.469675 -318.238977)
			(xy 409.439651 -318.19494) (xy 409.416525 -318.146919) (xy 409.400815 -318.095989) (xy 409.392872 -318.043285)
			(xy 407.4668 -318.043285) (xy 407.4668 -318.893423) (xy 416.936672 -318.893423) (xy 416.936672 -318.840125)
			(xy 416.944615 -318.787421) (xy 416.960325 -318.736491) (xy 416.983451 -318.68847) (xy 417.013475 -318.644433)
			(xy 417.049727 -318.605362) (xy 417.091398 -318.572131) (xy 417.137556 -318.545482) (xy 417.18717 -318.52601)
			(xy 417.239132 -318.51415) (xy 417.292282 -318.510167) (xy 417.345432 -318.51415) (xy 417.397394 -318.52601)
			(xy 417.447008 -318.545482) (xy 417.493166 -318.572131) (xy 417.534837 -318.605362) (xy 417.571089 -318.644433)
			(xy 417.601113 -318.68847) (xy 417.624239 -318.736491) (xy 417.639949 -318.787421) (xy 417.647892 -318.840125)
			(xy 417.64839 -318.866774) (xy 417.647892 -318.893423) (xy 424.480472 -318.893423) (xy 424.480472 -318.840125)
			(xy 424.488415 -318.787421) (xy 424.504125 -318.736491) (xy 424.527251 -318.68847) (xy 424.557275 -318.644433)
			(xy 424.593527 -318.605362) (xy 424.635198 -318.572131) (xy 424.681356 -318.545482) (xy 424.73097 -318.52601)
			(xy 424.782932 -318.51415) (xy 424.836082 -318.510167) (xy 424.889232 -318.51415) (xy 424.941194 -318.52601)
			(xy 424.990808 -318.545482) (xy 425.036966 -318.572131) (xy 425.078637 -318.605362) (xy 425.114889 -318.644433)
			(xy 425.144913 -318.68847) (xy 425.168039 -318.736491) (xy 425.183749 -318.787421) (xy 425.191692 -318.840125)
			(xy 425.19219 -318.866774) (xy 425.191692 -318.893423) (xy 435.11215 -318.893423) (xy 435.11215 -318.840125)
			(xy 435.120093 -318.787421) (xy 435.135803 -318.736491) (xy 435.158929 -318.68847) (xy 435.188953 -318.644433)
			(xy 435.225205 -318.605362) (xy 435.266876 -318.572131) (xy 435.313034 -318.545482) (xy 435.362648 -318.52601)
			(xy 435.41461 -318.51415) (xy 435.46776 -318.510167) (xy 435.52091 -318.51415) (xy 435.572872 -318.52601)
			(xy 435.622486 -318.545482) (xy 435.668644 -318.572131) (xy 435.710315 -318.605362) (xy 435.746567 -318.644433)
			(xy 435.776591 -318.68847) (xy 435.799717 -318.736491) (xy 435.815427 -318.787421) (xy 435.82337 -318.840125)
			(xy 435.823868 -318.866774) (xy 435.82337 -318.893423) (xy 439.568072 -318.893423) (xy 439.568072 -318.840125)
			(xy 439.576015 -318.787421) (xy 439.591725 -318.736491) (xy 439.614851 -318.68847) (xy 439.644875 -318.644433)
			(xy 439.681127 -318.605362) (xy 439.722798 -318.572131) (xy 439.768956 -318.545482) (xy 439.81857 -318.52601)
			(xy 439.870532 -318.51415) (xy 439.923682 -318.510167) (xy 439.976832 -318.51415) (xy 440.028794 -318.52601)
			(xy 440.078408 -318.545482) (xy 440.124566 -318.572131) (xy 440.166237 -318.605362) (xy 440.202489 -318.644433)
			(xy 440.232513 -318.68847) (xy 440.255639 -318.736491) (xy 440.271349 -318.787421) (xy 440.279292 -318.840125)
			(xy 440.27979 -318.866774) (xy 440.279292 -318.893423) (xy 447.111872 -318.893423) (xy 447.111872 -318.840125)
			(xy 447.119815 -318.787421) (xy 447.135525 -318.736491) (xy 447.158651 -318.68847) (xy 447.188675 -318.644433)
			(xy 447.224927 -318.605362) (xy 447.266598 -318.572131) (xy 447.312756 -318.545482) (xy 447.36237 -318.52601)
			(xy 447.414332 -318.51415) (xy 447.467482 -318.510167) (xy 447.520632 -318.51415) (xy 447.572594 -318.52601)
			(xy 447.622208 -318.545482) (xy 447.668366 -318.572131) (xy 447.710037 -318.605362) (xy 447.746289 -318.644433)
			(xy 447.776313 -318.68847) (xy 447.799439 -318.736491) (xy 447.815149 -318.787421) (xy 447.823092 -318.840125)
			(xy 447.82359 -318.866774) (xy 447.823092 -318.893423) (xy 447.815149 -318.946127) (xy 447.799439 -318.997057)
			(xy 447.776313 -319.045078) (xy 447.746289 -319.089115) (xy 447.710037 -319.128186) (xy 447.668366 -319.161417)
			(xy 447.622208 -319.188066) (xy 447.572594 -319.207538) (xy 447.520632 -319.219398) (xy 447.467482 -319.223382)
			(xy 447.414332 -319.219398) (xy 447.36237 -319.207538) (xy 447.312756 -319.188066) (xy 447.266598 -319.161417)
			(xy 447.224927 -319.128186) (xy 447.188675 -319.089115) (xy 447.158651 -319.045078) (xy 447.135525 -318.997057)
			(xy 447.119815 -318.946127) (xy 447.111872 -318.893423) (xy 440.279292 -318.893423) (xy 440.271349 -318.946127)
			(xy 440.255639 -318.997057) (xy 440.232513 -319.045078) (xy 440.202489 -319.089115) (xy 440.166237 -319.128186)
			(xy 440.124566 -319.161417) (xy 440.078408 -319.188066) (xy 440.028794 -319.207538) (xy 439.976832 -319.219398)
			(xy 439.923682 -319.223382) (xy 439.870532 -319.219398) (xy 439.81857 -319.207538) (xy 439.768956 -319.188066)
			(xy 439.722798 -319.161417) (xy 439.681127 -319.128186) (xy 439.644875 -319.089115) (xy 439.614851 -319.045078)
			(xy 439.591725 -318.997057) (xy 439.576015 -318.946127) (xy 439.568072 -318.893423) (xy 435.82337 -318.893423)
			(xy 435.815427 -318.946127) (xy 435.799717 -318.997057) (xy 435.776591 -319.045078) (xy 435.746567 -319.089115)
			(xy 435.710315 -319.128186) (xy 435.668644 -319.161417) (xy 435.622486 -319.188066) (xy 435.572872 -319.207538)
			(xy 435.52091 -319.219398) (xy 435.46776 -319.223382) (xy 435.41461 -319.219398) (xy 435.362648 -319.207538)
			(xy 435.313034 -319.188066) (xy 435.266876 -319.161417) (xy 435.225205 -319.128186) (xy 435.188953 -319.089115)
			(xy 435.158929 -319.045078) (xy 435.135803 -318.997057) (xy 435.120093 -318.946127) (xy 435.11215 -318.893423)
			(xy 425.191692 -318.893423) (xy 425.183749 -318.946127) (xy 425.168039 -318.997057) (xy 425.144913 -319.045078)
			(xy 425.114889 -319.089115) (xy 425.078637 -319.128186) (xy 425.036966 -319.161417) (xy 424.990808 -319.188066)
			(xy 424.941194 -319.207538) (xy 424.889232 -319.219398) (xy 424.836082 -319.223382) (xy 424.782932 -319.219398)
			(xy 424.73097 -319.207538) (xy 424.681356 -319.188066) (xy 424.635198 -319.161417) (xy 424.593527 -319.128186)
			(xy 424.557275 -319.089115) (xy 424.527251 -319.045078) (xy 424.504125 -318.997057) (xy 424.488415 -318.946127)
			(xy 424.480472 -318.893423) (xy 417.647892 -318.893423) (xy 417.639949 -318.946127) (xy 417.624239 -318.997057)
			(xy 417.601113 -319.045078) (xy 417.571089 -319.089115) (xy 417.534837 -319.128186) (xy 417.493166 -319.161417)
			(xy 417.447008 -319.188066) (xy 417.397394 -319.207538) (xy 417.345432 -319.219398) (xy 417.292282 -319.223382)
			(xy 417.239132 -319.219398) (xy 417.18717 -319.207538) (xy 417.137556 -319.188066) (xy 417.091398 -319.161417)
			(xy 417.049727 -319.128186) (xy 417.013475 -319.089115) (xy 416.983451 -319.045078) (xy 416.960325 -318.997057)
			(xy 416.944615 -318.946127) (xy 416.936672 -318.893423) (xy 407.4668 -318.893423) (xy 407.4668 -319.723495)
			(xy 407.690564 -319.723495) (xy 407.690564 -319.670197) (xy 407.698507 -319.617493) (xy 407.714217 -319.566563)
			(xy 407.737343 -319.518542) (xy 407.767367 -319.474505) (xy 407.803619 -319.435434) (xy 407.84529 -319.402203)
			(xy 407.891448 -319.375554) (xy 407.941062 -319.356082) (xy 407.993024 -319.344222) (xy 408.046174 -319.340239)
			(xy 408.099324 -319.344222) (xy 408.151286 -319.356082) (xy 408.2009 -319.375554) (xy 408.247058 -319.402203)
			(xy 408.288729 -319.435434) (xy 408.324981 -319.474505) (xy 408.355005 -319.518542) (xy 408.378131 -319.566563)
			(xy 408.393841 -319.617493) (xy 408.401784 -319.670197) (xy 408.402282 -319.696846) (xy 408.401784 -319.723495)
			(xy 408.393841 -319.776199) (xy 408.378131 -319.827129) (xy 408.370171 -319.843658) (xy 408.958542 -319.843658)
			(xy 408.95904 -319.817009) (xy 408.966983 -319.764305) (xy 408.982693 -319.713375) (xy 409.005819 -319.665354)
			(xy 409.035843 -319.621317) (xy 409.072095 -319.582246) (xy 409.113766 -319.549015) (xy 409.159924 -319.522366)
			(xy 409.209538 -319.502894) (xy 409.2615 -319.491034) (xy 409.31465 -319.487051) (xy 409.3678 -319.491034)
			(xy 409.419762 -319.502894) (xy 409.469376 -319.522366) (xy 409.515534 -319.549015) (xy 409.557205 -319.582246)
			(xy 409.593457 -319.621317) (xy 409.623481 -319.665354) (xy 409.646607 -319.713375) (xy 409.65584 -319.743307)
			(xy 411.628072 -319.743307) (xy 411.628072 -319.690009) (xy 411.636015 -319.637305) (xy 411.651725 -319.586375)
			(xy 411.674851 -319.538354) (xy 411.704875 -319.494317) (xy 411.741127 -319.455246) (xy 411.782798 -319.422015)
			(xy 411.828956 -319.395366) (xy 411.87857 -319.375894) (xy 411.930532 -319.364034) (xy 411.983682 -319.360051)
			(xy 412.036832 -319.364034) (xy 412.088794 -319.375894) (xy 412.138408 -319.395366) (xy 412.184566 -319.422015)
			(xy 412.226237 -319.455246) (xy 412.262489 -319.494317) (xy 412.292513 -319.538354) (xy 412.315639 -319.586375)
			(xy 412.331349 -319.637305) (xy 412.339292 -319.690009) (xy 412.33979 -319.716658) (xy 412.339292 -319.743307)
			(xy 412.836604 -319.743307) (xy 412.836604 -319.690009) (xy 412.844547 -319.637305) (xy 412.860257 -319.586375)
			(xy 412.883383 -319.538354) (xy 412.913407 -319.494317) (xy 412.949659 -319.455246) (xy 412.99133 -319.422015)
			(xy 413.037488 -319.395366) (xy 413.087102 -319.375894) (xy 413.139064 -319.364034) (xy 413.192214 -319.360051)
			(xy 413.245364 -319.364034) (xy 413.297326 -319.375894) (xy 413.34694 -319.395366) (xy 413.393098 -319.422015)
			(xy 413.434769 -319.455246) (xy 413.471021 -319.494317) (xy 413.501045 -319.538354) (xy 413.524171 -319.586375)
			(xy 413.539881 -319.637305) (xy 413.547824 -319.690009) (xy 413.548322 -319.716658) (xy 413.547824 -319.743307)
			(xy 416.936672 -319.743307) (xy 416.936672 -319.690009) (xy 416.944615 -319.637305) (xy 416.960325 -319.586375)
			(xy 416.983451 -319.538354) (xy 417.013475 -319.494317) (xy 417.049727 -319.455246) (xy 417.091398 -319.422015)
			(xy 417.137556 -319.395366) (xy 417.18717 -319.375894) (xy 417.239132 -319.364034) (xy 417.292282 -319.360051)
			(xy 417.345432 -319.364034) (xy 417.397394 -319.375894) (xy 417.447008 -319.395366) (xy 417.493166 -319.422015)
			(xy 417.534837 -319.455246) (xy 417.571089 -319.494317) (xy 417.591052 -319.523597) (xy 419.54195 -319.523597)
			(xy 419.54195 -319.470299) (xy 419.549893 -319.417595) (xy 419.565603 -319.366665) (xy 419.588729 -319.318644)
			(xy 419.618753 -319.274607) (xy 419.655005 -319.235536) (xy 419.696676 -319.202305) (xy 419.742834 -319.175656)
			(xy 419.792448 -319.156184) (xy 419.84441 -319.144324) (xy 419.89756 -319.140341) (xy 419.95071 -319.144324)
			(xy 420.002672 -319.156184) (xy 420.052286 -319.175656) (xy 420.098444 -319.202305) (xy 420.140115 -319.235536)
			(xy 420.176367 -319.274607) (xy 420.206391 -319.318644) (xy 420.229517 -319.366665) (xy 420.245227 -319.417595)
			(xy 420.25317 -319.470299) (xy 420.253668 -319.496948) (xy 420.25317 -319.523597) (xy 420.245227 -319.576301)
			(xy 420.229517 -319.627231) (xy 420.206391 -319.675252) (xy 420.176367 -319.719289) (xy 420.154082 -319.743307)
			(xy 424.480472 -319.743307) (xy 424.480472 -319.690009) (xy 424.488415 -319.637305) (xy 424.504125 -319.586375)
			(xy 424.527251 -319.538354) (xy 424.557275 -319.494317) (xy 424.593527 -319.455246) (xy 424.635198 -319.422015)
			(xy 424.681356 -319.395366) (xy 424.73097 -319.375894) (xy 424.782932 -319.364034) (xy 424.836082 -319.360051)
			(xy 424.889232 -319.364034) (xy 424.941194 -319.375894) (xy 424.990808 -319.395366) (xy 425.036966 -319.422015)
			(xy 425.078637 -319.455246) (xy 425.114889 -319.494317) (xy 425.144913 -319.538354) (xy 425.168039 -319.586375)
			(xy 425.183749 -319.637305) (xy 425.191692 -319.690009) (xy 425.19219 -319.716658) (xy 425.191692 -319.743307)
			(xy 427.924204 -319.743307) (xy 427.924204 -319.690009) (xy 427.932147 -319.637305) (xy 427.947857 -319.586375)
			(xy 427.970983 -319.538354) (xy 428.001007 -319.494317) (xy 428.037259 -319.455246) (xy 428.07893 -319.422015)
			(xy 428.125088 -319.395366) (xy 428.174702 -319.375894) (xy 428.226664 -319.364034) (xy 428.279814 -319.360051)
			(xy 428.332964 -319.364034) (xy 428.384926 -319.375894) (xy 428.43454 -319.395366) (xy 428.480698 -319.422015)
			(xy 428.522369 -319.455246) (xy 428.558621 -319.494317) (xy 428.588645 -319.538354) (xy 428.611771 -319.586375)
			(xy 428.627481 -319.637305) (xy 428.635424 -319.690009) (xy 428.635922 -319.716658) (xy 428.635424 -319.743307)
			(xy 428.631022 -319.772517) (xy 431.212996 -319.772517) (xy 431.212996 -319.719219) (xy 431.220939 -319.666515)
			(xy 431.236649 -319.615585) (xy 431.259775 -319.567564) (xy 431.289799 -319.523527) (xy 431.326051 -319.484456)
			(xy 431.367722 -319.451225) (xy 431.41388 -319.424576) (xy 431.463494 -319.405104) (xy 431.515456 -319.393244)
			(xy 431.568606 -319.389261) (xy 431.621756 -319.393244) (xy 431.673718 -319.405104) (xy 431.723332 -319.424576)
			(xy 431.76949 -319.451225) (xy 431.811161 -319.484456) (xy 431.847413 -319.523527) (xy 431.877437 -319.567564)
			(xy 431.900563 -319.615585) (xy 431.916273 -319.666515) (xy 431.919616 -319.688697) (xy 434.90387 -319.688697)
			(xy 434.90387 -319.635399) (xy 434.911813 -319.582695) (xy 434.927523 -319.531765) (xy 434.950649 -319.483744)
			(xy 434.980673 -319.439707) (xy 435.016925 -319.400636) (xy 435.058596 -319.367405) (xy 435.104754 -319.340756)
			(xy 435.154368 -319.321284) (xy 435.20633 -319.309424) (xy 435.25948 -319.305441) (xy 435.31263 -319.309424)
			(xy 435.364592 -319.321284) (xy 435.414206 -319.340756) (xy 435.460364 -319.367405) (xy 435.502035 -319.400636)
			(xy 435.538287 -319.439707) (xy 435.568311 -319.483744) (xy 435.591437 -319.531765) (xy 435.607147 -319.582695)
			(xy 435.61509 -319.635399) (xy 435.615588 -319.662048) (xy 435.61509 -319.688697) (xy 435.607147 -319.741401)
			(xy 435.606559 -319.743307) (xy 439.568072 -319.743307) (xy 439.568072 -319.690009) (xy 439.576015 -319.637305)
			(xy 439.591725 -319.586375) (xy 439.614851 -319.538354) (xy 439.644875 -319.494317) (xy 439.681127 -319.455246)
			(xy 439.722798 -319.422015) (xy 439.768956 -319.395366) (xy 439.81857 -319.375894) (xy 439.870532 -319.364034)
			(xy 439.923682 -319.360051) (xy 439.976832 -319.364034) (xy 440.028794 -319.375894) (xy 440.078408 -319.395366)
			(xy 440.124566 -319.422015) (xy 440.166237 -319.455246) (xy 440.202489 -319.494317) (xy 440.232513 -319.538354)
			(xy 440.255639 -319.586375) (xy 440.271349 -319.637305) (xy 440.279292 -319.690009) (xy 440.27979 -319.716658)
			(xy 440.279292 -319.743307) (xy 443.011804 -319.743307) (xy 443.011804 -319.690009) (xy 443.019747 -319.637305)
			(xy 443.035457 -319.586375) (xy 443.058583 -319.538354) (xy 443.088607 -319.494317) (xy 443.124859 -319.455246)
			(xy 443.16653 -319.422015) (xy 443.212688 -319.395366) (xy 443.262302 -319.375894) (xy 443.314264 -319.364034)
			(xy 443.367414 -319.360051) (xy 443.420564 -319.364034) (xy 443.472526 -319.375894) (xy 443.52214 -319.395366)
			(xy 443.568298 -319.422015) (xy 443.609969 -319.455246) (xy 443.646221 -319.494317) (xy 443.676245 -319.538354)
			(xy 443.699371 -319.586375) (xy 443.715081 -319.637305) (xy 443.723024 -319.690009) (xy 443.723522 -319.716658)
			(xy 443.723024 -319.743307) (xy 447.111872 -319.743307) (xy 447.111872 -319.690009) (xy 447.119815 -319.637305)
			(xy 447.135525 -319.586375) (xy 447.158651 -319.538354) (xy 447.188675 -319.494317) (xy 447.224927 -319.455246)
			(xy 447.266598 -319.422015) (xy 447.312756 -319.395366) (xy 447.36237 -319.375894) (xy 447.414332 -319.364034)
			(xy 447.467482 -319.360051) (xy 447.520632 -319.364034) (xy 447.572594 -319.375894) (xy 447.622208 -319.395366)
			(xy 447.668366 -319.422015) (xy 447.710037 -319.455246) (xy 447.746289 -319.494317) (xy 447.776313 -319.538354)
			(xy 447.799439 -319.586375) (xy 447.815149 -319.637305) (xy 447.823092 -319.690009) (xy 447.82359 -319.716658)
			(xy 447.823092 -319.743307) (xy 450.555604 -319.743307) (xy 450.555604 -319.690009) (xy 450.563547 -319.637305)
			(xy 450.579257 -319.586375) (xy 450.602383 -319.538354) (xy 450.632407 -319.494317) (xy 450.668659 -319.455246)
			(xy 450.71033 -319.422015) (xy 450.756488 -319.395366) (xy 450.806102 -319.375894) (xy 450.858064 -319.364034)
			(xy 450.911214 -319.360051) (xy 450.964364 -319.364034) (xy 451.016326 -319.375894) (xy 451.06594 -319.395366)
			(xy 451.112098 -319.422015) (xy 451.153769 -319.455246) (xy 451.190021 -319.494317) (xy 451.220045 -319.538354)
			(xy 451.243171 -319.586375) (xy 451.258881 -319.637305) (xy 451.266824 -319.690009) (xy 451.267322 -319.716658)
			(xy 451.266824 -319.743307) (xy 451.258881 -319.796011) (xy 451.243171 -319.846941) (xy 451.221521 -319.891897)
			(xy 453.852016 -319.891897) (xy 453.852016 -319.838599) (xy 453.859959 -319.785895) (xy 453.875669 -319.734965)
			(xy 453.898795 -319.686944) (xy 453.928819 -319.642907) (xy 453.965071 -319.603836) (xy 454.006742 -319.570605)
			(xy 454.0529 -319.543956) (xy 454.102514 -319.524484) (xy 454.154476 -319.512624) (xy 454.207626 -319.508641)
			(xy 454.260776 -319.512624) (xy 454.312738 -319.524484) (xy 454.362352 -319.543956) (xy 454.40851 -319.570605)
			(xy 454.450181 -319.603836) (xy 454.486433 -319.642907) (xy 454.516457 -319.686944) (xy 454.539583 -319.734965)
			(xy 454.542156 -319.743307) (xy 458.099404 -319.743307) (xy 458.099404 -319.690009) (xy 458.107347 -319.637305)
			(xy 458.123057 -319.586375) (xy 458.146183 -319.538354) (xy 458.176207 -319.494317) (xy 458.212459 -319.455246)
			(xy 458.25413 -319.422015) (xy 458.300288 -319.395366) (xy 458.349902 -319.375894) (xy 458.401864 -319.364034)
			(xy 458.455014 -319.360051) (xy 458.508164 -319.364034) (xy 458.560126 -319.375894) (xy 458.60974 -319.395366)
			(xy 458.655898 -319.422015) (xy 458.697569 -319.455246) (xy 458.733821 -319.494317) (xy 458.763845 -319.538354)
			(xy 458.786971 -319.586375) (xy 458.802681 -319.637305) (xy 458.810624 -319.690009) (xy 458.811122 -319.716658)
			(xy 458.810624 -319.743307) (xy 458.802681 -319.796011) (xy 458.786971 -319.846941) (xy 458.763845 -319.894962)
			(xy 458.733821 -319.938999) (xy 458.697569 -319.97807) (xy 458.655898 -320.011301) (xy 458.60974 -320.03795)
			(xy 458.560126 -320.057422) (xy 458.508164 -320.069282) (xy 458.455014 -320.073266) (xy 458.401864 -320.069282)
			(xy 458.349902 -320.057422) (xy 458.300288 -320.03795) (xy 458.25413 -320.011301) (xy 458.212459 -319.97807)
			(xy 458.176207 -319.938999) (xy 458.146183 -319.894962) (xy 458.123057 -319.846941) (xy 458.107347 -319.796011)
			(xy 458.099404 -319.743307) (xy 454.542156 -319.743307) (xy 454.555293 -319.785895) (xy 454.563236 -319.838599)
			(xy 454.563734 -319.865248) (xy 454.563236 -319.891897) (xy 454.555293 -319.944601) (xy 454.539583 -319.995531)
			(xy 454.516457 -320.043552) (xy 454.486433 -320.087589) (xy 454.450181 -320.12666) (xy 454.40851 -320.159891)
			(xy 454.362352 -320.18654) (xy 454.312738 -320.206012) (xy 454.260776 -320.217872) (xy 454.207626 -320.221856)
			(xy 454.154476 -320.217872) (xy 454.102514 -320.206012) (xy 454.0529 -320.18654) (xy 454.006742 -320.159891)
			(xy 453.965071 -320.12666) (xy 453.928819 -320.087589) (xy 453.898795 -320.043552) (xy 453.875669 -319.995531)
			(xy 453.859959 -319.944601) (xy 453.852016 -319.891897) (xy 451.221521 -319.891897) (xy 451.220045 -319.894962)
			(xy 451.190021 -319.938999) (xy 451.153769 -319.97807) (xy 451.112098 -320.011301) (xy 451.06594 -320.03795)
			(xy 451.016326 -320.057422) (xy 450.964364 -320.069282) (xy 450.911214 -320.073266) (xy 450.858064 -320.069282)
			(xy 450.806102 -320.057422) (xy 450.756488 -320.03795) (xy 450.71033 -320.011301) (xy 450.668659 -319.97807)
			(xy 450.632407 -319.938999) (xy 450.602383 -319.894962) (xy 450.579257 -319.846941) (xy 450.563547 -319.796011)
			(xy 450.555604 -319.743307) (xy 447.823092 -319.743307) (xy 447.815149 -319.796011) (xy 447.799439 -319.846941)
			(xy 447.776313 -319.894962) (xy 447.746289 -319.938999) (xy 447.710037 -319.97807) (xy 447.668366 -320.011301)
			(xy 447.622208 -320.03795) (xy 447.572594 -320.057422) (xy 447.520632 -320.069282) (xy 447.467482 -320.073266)
			(xy 447.414332 -320.069282) (xy 447.36237 -320.057422) (xy 447.312756 -320.03795) (xy 447.266598 -320.011301)
			(xy 447.224927 -319.97807) (xy 447.188675 -319.938999) (xy 447.158651 -319.894962) (xy 447.135525 -319.846941)
			(xy 447.119815 -319.796011) (xy 447.111872 -319.743307) (xy 443.723024 -319.743307) (xy 443.715081 -319.796011)
			(xy 443.699371 -319.846941) (xy 443.676245 -319.894962) (xy 443.646221 -319.938999) (xy 443.609969 -319.97807)
			(xy 443.568298 -320.011301) (xy 443.52214 -320.03795) (xy 443.472526 -320.057422) (xy 443.420564 -320.069282)
			(xy 443.367414 -320.073266) (xy 443.314264 -320.069282) (xy 443.262302 -320.057422) (xy 443.212688 -320.03795)
			(xy 443.16653 -320.011301) (xy 443.124859 -319.97807) (xy 443.088607 -319.938999) (xy 443.058583 -319.894962)
			(xy 443.035457 -319.846941) (xy 443.019747 -319.796011) (xy 443.011804 -319.743307) (xy 440.279292 -319.743307)
			(xy 440.271349 -319.796011) (xy 440.255639 -319.846941) (xy 440.232513 -319.894962) (xy 440.202489 -319.938999)
			(xy 440.166237 -319.97807) (xy 440.124566 -320.011301) (xy 440.078408 -320.03795) (xy 440.028794 -320.057422)
			(xy 439.976832 -320.069282) (xy 439.923682 -320.073266) (xy 439.870532 -320.069282) (xy 439.81857 -320.057422)
			(xy 439.768956 -320.03795) (xy 439.722798 -320.011301) (xy 439.681127 -319.97807) (xy 439.644875 -319.938999)
			(xy 439.614851 -319.894962) (xy 439.591725 -319.846941) (xy 439.576015 -319.796011) (xy 439.568072 -319.743307)
			(xy 435.606559 -319.743307) (xy 435.591437 -319.792331) (xy 435.568311 -319.840352) (xy 435.538287 -319.884389)
			(xy 435.502035 -319.92346) (xy 435.460364 -319.956691) (xy 435.414206 -319.98334) (xy 435.364592 -320.002812)
			(xy 435.31263 -320.014672) (xy 435.25948 -320.018656) (xy 435.20633 -320.014672) (xy 435.154368 -320.002812)
			(xy 435.104754 -319.98334) (xy 435.058596 -319.956691) (xy 435.016925 -319.92346) (xy 434.980673 -319.884389)
			(xy 434.950649 -319.840352) (xy 434.927523 -319.792331) (xy 434.911813 -319.741401) (xy 434.90387 -319.688697)
			(xy 431.919616 -319.688697) (xy 431.924216 -319.719219) (xy 431.924714 -319.745868) (xy 431.924216 -319.772517)
			(xy 431.916273 -319.825221) (xy 431.900563 -319.876151) (xy 431.877437 -319.924172) (xy 431.847413 -319.968209)
			(xy 431.811161 -320.00728) (xy 431.76949 -320.040511) (xy 431.723332 -320.06716) (xy 431.673718 -320.086632)
			(xy 431.621756 -320.098492) (xy 431.568606 -320.102476) (xy 431.515456 -320.098492) (xy 431.463494 -320.086632)
			(xy 431.41388 -320.06716) (xy 431.367722 -320.040511) (xy 431.326051 -320.00728) (xy 431.289799 -319.968209)
			(xy 431.259775 -319.924172) (xy 431.236649 -319.876151) (xy 431.220939 -319.825221) (xy 431.212996 -319.772517)
			(xy 428.631022 -319.772517) (xy 428.627481 -319.796011) (xy 428.611771 -319.846941) (xy 428.588645 -319.894962)
			(xy 428.558621 -319.938999) (xy 428.522369 -319.97807) (xy 428.480698 -320.011301) (xy 428.43454 -320.03795)
			(xy 428.384926 -320.057422) (xy 428.332964 -320.069282) (xy 428.279814 -320.073266) (xy 428.226664 -320.069282)
			(xy 428.174702 -320.057422) (xy 428.125088 -320.03795) (xy 428.07893 -320.011301) (xy 428.037259 -319.97807)
			(xy 428.001007 -319.938999) (xy 427.970983 -319.894962) (xy 427.947857 -319.846941) (xy 427.932147 -319.796011)
			(xy 427.924204 -319.743307) (xy 425.191692 -319.743307) (xy 425.183749 -319.796011) (xy 425.168039 -319.846941)
			(xy 425.144913 -319.894962) (xy 425.114889 -319.938999) (xy 425.078637 -319.97807) (xy 425.036966 -320.011301)
			(xy 424.990808 -320.03795) (xy 424.941194 -320.057422) (xy 424.889232 -320.069282) (xy 424.836082 -320.073266)
			(xy 424.782932 -320.069282) (xy 424.73097 -320.057422) (xy 424.681356 -320.03795) (xy 424.635198 -320.011301)
			(xy 424.593527 -319.97807) (xy 424.557275 -319.938999) (xy 424.527251 -319.894962) (xy 424.504125 -319.846941)
			(xy 424.488415 -319.796011) (xy 424.480472 -319.743307) (xy 420.154082 -319.743307) (xy 420.140115 -319.75836)
			(xy 420.098444 -319.791591) (xy 420.052286 -319.81824) (xy 420.002672 -319.837712) (xy 419.95071 -319.849572)
			(xy 419.89756 -319.853556) (xy 419.84441 -319.849572) (xy 419.792448 -319.837712) (xy 419.742834 -319.81824)
			(xy 419.696676 -319.791591) (xy 419.655005 -319.75836) (xy 419.618753 -319.719289) (xy 419.588729 -319.675252)
			(xy 419.565603 -319.627231) (xy 419.549893 -319.576301) (xy 419.54195 -319.523597) (xy 417.591052 -319.523597)
			(xy 417.601113 -319.538354) (xy 417.624239 -319.586375) (xy 417.639949 -319.637305) (xy 417.647892 -319.690009)
			(xy 417.64839 -319.716658) (xy 417.647892 -319.743307) (xy 417.639949 -319.796011) (xy 417.624239 -319.846941)
			(xy 417.601113 -319.894962) (xy 417.571089 -319.938999) (xy 417.534837 -319.97807) (xy 417.493166 -320.011301)
			(xy 417.447008 -320.03795) (xy 417.397394 -320.057422) (xy 417.345432 -320.069282) (xy 417.292282 -320.073266)
			(xy 417.239132 -320.069282) (xy 417.18717 -320.057422) (xy 417.137556 -320.03795) (xy 417.091398 -320.011301)
			(xy 417.049727 -319.97807) (xy 417.013475 -319.938999) (xy 416.983451 -319.894962) (xy 416.960325 -319.846941)
			(xy 416.944615 -319.796011) (xy 416.936672 -319.743307) (xy 413.547824 -319.743307) (xy 413.539881 -319.796011)
			(xy 413.524171 -319.846941) (xy 413.501045 -319.894962) (xy 413.471021 -319.938999) (xy 413.434769 -319.97807)
			(xy 413.393098 -320.011301) (xy 413.34694 -320.03795) (xy 413.297326 -320.057422) (xy 413.245364 -320.069282)
			(xy 413.192214 -320.073266) (xy 413.139064 -320.069282) (xy 413.087102 -320.057422) (xy 413.037488 -320.03795)
			(xy 412.99133 -320.011301) (xy 412.949659 -319.97807) (xy 412.913407 -319.938999) (xy 412.883383 -319.894962)
			(xy 412.860257 -319.846941) (xy 412.844547 -319.796011) (xy 412.836604 -319.743307) (xy 412.339292 -319.743307)
			(xy 412.331349 -319.796011) (xy 412.315639 -319.846941) (xy 412.292513 -319.894962) (xy 412.262489 -319.938999)
			(xy 412.226237 -319.97807) (xy 412.184566 -320.011301) (xy 412.138408 -320.03795) (xy 412.088794 -320.057422)
			(xy 412.036832 -320.069282) (xy 411.983682 -320.073266) (xy 411.930532 -320.069282) (xy 411.87857 -320.057422)
			(xy 411.828956 -320.03795) (xy 411.782798 -320.011301) (xy 411.741127 -319.97807) (xy 411.704875 -319.938999)
			(xy 411.674851 -319.894962) (xy 411.651725 -319.846941) (xy 411.636015 -319.796011) (xy 411.628072 -319.743307)
			(xy 409.65584 -319.743307) (xy 409.662317 -319.764305) (xy 409.67026 -319.817009) (xy 409.670758 -319.843658)
			(xy 409.670652 -319.854673) (xy 409.669253 -319.87666) (xy 409.667964 -319.8876) (xy 409.666737 -319.900775)
			(xy 409.670334 -319.92698) (xy 409.680538 -319.951383) (xy 409.696666 -319.972349) (xy 409.717635 -319.988472)
			(xy 409.74204 -319.998671) (xy 409.755086 -320.000884) (xy 409.780342 -320.004837) (xy 409.829478 -320.018925)
			(xy 409.876095 -320.039897) (xy 409.919233 -320.067319) (xy 409.958006 -320.100629) (xy 409.991617 -320.139141)
			(xy 410.019375 -320.182064) (xy 410.040709 -320.228516) (xy 410.05518 -320.277541) (xy 410.062492 -320.328132)
			(xy 410.062934 -320.35369) (xy 410.062436 -320.380339) (xy 410.054493 -320.433043) (xy 410.038783 -320.483973)
			(xy 410.015657 -320.531994) (xy 409.985633 -320.576031) (xy 409.969475 -320.593445) (xy 412.29279 -320.593445)
			(xy 412.29279 -320.540147) (xy 412.300733 -320.487443) (xy 412.316443 -320.436513) (xy 412.339569 -320.388492)
			(xy 412.369593 -320.344455) (xy 412.405845 -320.305384) (xy 412.447516 -320.272153) (xy 412.493674 -320.245504)
			(xy 412.543288 -320.226032) (xy 412.59525 -320.214172) (xy 412.6484 -320.210189) (xy 412.70155 -320.214172)
			(xy 412.753512 -320.226032) (xy 412.803126 -320.245504) (xy 412.849284 -320.272153) (xy 412.890955 -320.305384)
			(xy 412.927207 -320.344455) (xy 412.957231 -320.388492) (xy 412.980357 -320.436513) (xy 412.996067 -320.487443)
			(xy 413.00401 -320.540147) (xy 413.004508 -320.566796) (xy 413.00401 -320.593445) (xy 412.996067 -320.646149)
			(xy 412.980357 -320.697079) (xy 412.957231 -320.7451) (xy 412.927207 -320.789137) (xy 412.890955 -320.828208)
			(xy 412.849284 -320.861439) (xy 412.803126 -320.888088) (xy 412.753512 -320.90756) (xy 412.70155 -320.91942)
			(xy 412.6484 -320.923404) (xy 412.59525 -320.91942) (xy 412.543288 -320.90756) (xy 412.493674 -320.888088)
			(xy 412.447516 -320.861439) (xy 412.405845 -320.828208) (xy 412.369593 -320.789137) (xy 412.339569 -320.7451)
			(xy 412.316443 -320.697079) (xy 412.300733 -320.646149) (xy 412.29279 -320.593445) (xy 409.969475 -320.593445)
			(xy 409.949381 -320.615102) (xy 409.90771 -320.648333) (xy 409.861552 -320.674982) (xy 409.811938 -320.694454)
			(xy 409.759976 -320.706314) (xy 409.706826 -320.710298) (xy 409.653676 -320.706314) (xy 409.601714 -320.694454)
			(xy 409.5521 -320.674982) (xy 409.505942 -320.648333) (xy 409.464271 -320.615102) (xy 409.428019 -320.576031)
			(xy 409.397995 -320.531994) (xy 409.374869 -320.483973) (xy 409.359159 -320.433043) (xy 409.351216 -320.380339)
			(xy 409.350718 -320.35369) (xy 409.350828 -320.342675) (xy 409.352224 -320.320688) (xy 409.353512 -320.309748)
			(xy 409.354712 -320.296571) (xy 409.351125 -320.270366) (xy 409.340929 -320.245962) (xy 409.324806 -320.224995)
			(xy 409.303839 -320.208872) (xy 409.279435 -320.198675) (xy 409.26639 -320.196464) (xy 409.241122 -320.19258)
			(xy 409.191982 -320.178485) (xy 409.145362 -320.157507) (xy 409.102222 -320.130078) (xy 409.063448 -320.09676)
			(xy 409.029838 -320.05824) (xy 409.002083 -320.015308) (xy 408.980752 -319.968849) (xy 408.966286 -319.919816)
			(xy 408.95898 -319.869219) (xy 408.958542 -319.843658) (xy 408.370171 -319.843658) (xy 408.355005 -319.87515)
			(xy 408.324981 -319.919187) (xy 408.288729 -319.958258) (xy 408.247058 -319.991489) (xy 408.2009 -320.018138)
			(xy 408.151286 -320.03761) (xy 408.099324 -320.04947) (xy 408.046174 -320.053454) (xy 407.993024 -320.04947)
			(xy 407.941062 -320.03761) (xy 407.891448 -320.018138) (xy 407.84529 -319.991489) (xy 407.803619 -319.958258)
			(xy 407.767367 -319.919187) (xy 407.737343 -319.87515) (xy 407.714217 -319.827129) (xy 407.698507 -319.776199)
			(xy 407.690564 -319.723495) (xy 407.4668 -319.723495) (xy 407.4668 -321.16903) (xy 408.04973 -321.16903)
			(xy 408.050214 -321.1417) (xy 408.058584 -321.087683) (xy 408.0751 -321.035577) (xy 408.099377 -320.986603)
			(xy 408.130845 -320.941909) (xy 408.168766 -320.902541) (xy 408.190192 -320.885566) (xy 408.201761 -320.87607)
			(xy 408.219258 -320.851805) (xy 408.228981 -320.823513) (xy 408.230095 -320.793618) (xy 408.222505 -320.764681)
			(xy 408.206862 -320.739181) (xy 408.196034 -320.728848) (xy 408.17747 -320.711903) (xy 408.144886 -320.67363)
			(xy 408.118008 -320.631156) (xy 408.09737 -320.585324) (xy 408.083381 -320.537046) (xy 408.07632 -320.48728)
			(xy 408.075892 -320.462148) (xy 408.07639 -320.435499) (xy 408.084333 -320.382795) (xy 408.100043 -320.331865)
			(xy 408.123169 -320.283844) (xy 408.153193 -320.239807) (xy 408.189445 -320.200736) (xy 408.231116 -320.167505)
			(xy 408.277274 -320.140856) (xy 408.326888 -320.121384) (xy 408.37885 -320.109524) (xy 408.432 -320.105541)
			(xy 408.48515 -320.109524) (xy 408.537112 -320.121384) (xy 408.586726 -320.140856) (xy 408.632884 -320.167505)
			(xy 408.674555 -320.200736) (xy 408.710807 -320.239807) (xy 408.740831 -320.283844) (xy 408.763957 -320.331865)
			(xy 408.779667 -320.382795) (xy 408.78761 -320.435499) (xy 408.788108 -320.462148) (xy 408.787593 -320.489477)
			(xy 408.779228 -320.543491) (xy 408.762716 -320.595596) (xy 408.738445 -320.64457) (xy 408.706984 -320.689265)
			(xy 408.669069 -320.728635) (xy 408.647646 -320.745612) (xy 408.636102 -320.755133) (xy 408.618614 -320.779394)
			(xy 408.608896 -320.807678) (xy 408.607778 -320.837564) (xy 408.615357 -320.866495) (xy 408.630985 -320.891994)
			(xy 408.641804 -320.90233) (xy 408.660345 -320.9193) (xy 408.692933 -320.957566) (xy 408.719816 -321.000034)
			(xy 408.740459 -321.045861) (xy 408.754451 -321.094136) (xy 408.761516 -321.143899) (xy 408.761946 -321.16903)
			(xy 408.761856 -321.173856) (xy 416.912044 -321.173856) (xy 416.91256 -321.146593) (xy 416.920871 -321.092705)
			(xy 416.937308 -321.040717) (xy 416.961486 -320.991845) (xy 416.992838 -320.947235) (xy 417.011358 -320.927222)
			(xy 417.021278 -320.916226) (xy 417.034853 -320.889921) (xy 417.040302 -320.860826) (xy 417.037165 -320.831391)
			(xy 417.025707 -320.804097) (xy 417.016692 -320.792348) (xy 417.00152 -320.773188) (xy 416.976037 -320.731486)
			(xy 416.956494 -320.686691) (xy 416.943257 -320.639646) (xy 416.936577 -320.591232) (xy 416.936174 -320.566796)
			(xy 416.936672 -320.540147) (xy 416.944615 -320.487443) (xy 416.960325 -320.436513) (xy 416.983451 -320.388492)
			(xy 417.013475 -320.344455) (xy 417.049727 -320.305384) (xy 417.091398 -320.272153) (xy 417.137556 -320.245504)
			(xy 417.18717 -320.226032) (xy 417.239132 -320.214172) (xy 417.292282 -320.210189) (xy 417.345432 -320.214172)
			(xy 417.397394 -320.226032) (xy 417.447008 -320.245504) (xy 417.493166 -320.272153) (xy 417.534837 -320.305384)
			(xy 417.571089 -320.344455) (xy 417.601113 -320.388492) (xy 417.624239 -320.436513) (xy 417.639949 -320.487443)
			(xy 417.647892 -320.540147) (xy 417.64839 -320.566796) (xy 417.647897 -320.594059) (xy 417.639579 -320.647948)
			(xy 417.623136 -320.699937) (xy 417.605059 -320.736468) (xy 419.912292 -320.736468) (xy 419.91281 -320.709788)
			(xy 419.92079 -320.657028) (xy 419.936551 -320.606049) (xy 419.95974 -320.557991) (xy 419.989839 -320.51393)
			(xy 420.026173 -320.474852) (xy 420.067931 -320.441632) (xy 420.114177 -320.415012) (xy 420.163877 -320.39559)
			(xy 420.215918 -320.383798) (xy 420.242492 -320.381376) (xy 420.255744 -320.379914) (xy 420.280903 -320.371137)
			(xy 420.302933 -320.356146) (xy 420.320331 -320.335962) (xy 420.33191 -320.311963) (xy 420.33688 -320.285784)
			(xy 420.334904 -320.25921) (xy 420.330884 -320.246502) (xy 420.321638 -320.218116) (xy 420.31168 -320.159256)
			(xy 420.311072 -320.129408) (xy 420.31157 -320.102759) (xy 420.319513 -320.050055) (xy 420.335223 -319.999125)
			(xy 420.358349 -319.951104) (xy 420.388373 -319.907067) (xy 420.424625 -319.867996) (xy 420.466296 -319.834765)
			(xy 420.512454 -319.808116) (xy 420.562068 -319.788644) (xy 420.61403 -319.776784) (xy 420.66718 -319.772801)
			(xy 420.72033 -319.776784) (xy 420.772292 -319.788644) (xy 420.821906 -319.808116) (xy 420.868064 -319.834765)
			(xy 420.909735 -319.867996) (xy 420.945987 -319.907067) (xy 420.976011 -319.951104) (xy 420.999137 -319.999125)
			(xy 421.014847 -320.050055) (xy 421.02279 -320.102759) (xy 421.023288 -320.129408) (xy 421.022766 -320.156088)
			(xy 421.014789 -320.208849) (xy 420.999031 -320.259829) (xy 420.975843 -320.307888) (xy 420.945745 -320.35195)
			(xy 420.90941 -320.391029) (xy 420.867652 -320.424249) (xy 420.821405 -320.450868) (xy 420.771704 -320.47029)
			(xy 420.719662 -320.482079) (xy 420.693088 -320.4845) (xy 420.67982 -320.485849) (xy 420.654646 -320.494639)
			(xy 420.632608 -320.509648) (xy 420.615208 -320.529852) (xy 420.603633 -320.553872) (xy 420.602897 -320.557758)
			(xy 426.695997 -320.557758) (xy 426.701477 -320.503878) (xy 426.715053 -320.45145) (xy 426.736411 -320.401682)
			(xy 426.765059 -320.355721) (xy 426.800337 -320.314629) (xy 426.84143 -320.279353) (xy 426.88739 -320.250706)
			(xy 426.937159 -320.229349) (xy 426.989588 -320.215775) (xy 427.043468 -320.210296) (xy 427.097556 -320.21304)
			(xy 427.150605 -320.223942) (xy 427.201392 -320.242751) (xy 427.248744 -320.269034) (xy 427.291571 -320.302184)
			(xy 427.328884 -320.341437) (xy 427.359822 -320.385887) (xy 427.383673 -320.43451) (xy 427.399887 -320.486184)
			(xy 427.408088 -320.539717) (xy 427.408594 -320.566796) (xy 427.408158 -320.591572) (xy 427.407895 -320.593445)
			(xy 432.024272 -320.593445) (xy 432.024272 -320.540147) (xy 432.032215 -320.487443) (xy 432.047925 -320.436513)
			(xy 432.071051 -320.388492) (xy 432.101075 -320.344455) (xy 432.137327 -320.305384) (xy 432.178998 -320.272153)
			(xy 432.225156 -320.245504) (xy 432.27477 -320.226032) (xy 432.326732 -320.214172) (xy 432.379882 -320.210189)
			(xy 432.433032 -320.214172) (xy 432.484994 -320.226032) (xy 432.534608 -320.245504) (xy 432.580766 -320.272153)
			(xy 432.622437 -320.305384) (xy 432.658689 -320.344455) (xy 432.688713 -320.388492) (xy 432.711839 -320.436513)
			(xy 432.727549 -320.487443) (xy 432.735492 -320.540147) (xy 432.73599 -320.566796) (xy 432.735492 -320.593445)
			(xy 434.98261 -320.593445) (xy 434.98261 -320.540147) (xy 434.990553 -320.487443) (xy 435.006263 -320.436513)
			(xy 435.029389 -320.388492) (xy 435.059413 -320.344455) (xy 435.095665 -320.305384) (xy 435.137336 -320.272153)
			(xy 435.183494 -320.245504) (xy 435.233108 -320.226032) (xy 435.28507 -320.214172) (xy 435.33822 -320.210189)
			(xy 435.39137 -320.214172) (xy 435.443332 -320.226032) (xy 435.492946 -320.245504) (xy 435.539104 -320.272153)
			(xy 435.580775 -320.305384) (xy 435.617027 -320.344455) (xy 435.647051 -320.388492) (xy 435.670177 -320.436513)
			(xy 435.685887 -320.487443) (xy 435.69383 -320.540147) (xy 435.694328 -320.566796) (xy 435.69383 -320.593445)
			(xy 439.568072 -320.593445) (xy 439.568072 -320.540147) (xy 439.576015 -320.487443) (xy 439.591725 -320.436513)
			(xy 439.614851 -320.388492) (xy 439.644875 -320.344455) (xy 439.681127 -320.305384) (xy 439.722798 -320.272153)
			(xy 439.768956 -320.245504) (xy 439.81857 -320.226032) (xy 439.870532 -320.214172) (xy 439.923682 -320.210189)
			(xy 439.976832 -320.214172) (xy 440.028794 -320.226032) (xy 440.078408 -320.245504) (xy 440.124566 -320.272153)
			(xy 440.166237 -320.305384) (xy 440.202489 -320.344455) (xy 440.232513 -320.388492) (xy 440.255639 -320.436513)
			(xy 440.271349 -320.487443) (xy 440.279292 -320.540147) (xy 440.27979 -320.566796) (xy 440.279292 -320.593445)
			(xy 442.54673 -320.593445) (xy 442.54673 -320.540147) (xy 442.554673 -320.487443) (xy 442.570383 -320.436513)
			(xy 442.593509 -320.388492) (xy 442.623533 -320.344455) (xy 442.659785 -320.305384) (xy 442.701456 -320.272153)
			(xy 442.747614 -320.245504) (xy 442.797228 -320.226032) (xy 442.84919 -320.214172) (xy 442.90234 -320.210189)
			(xy 442.95549 -320.214172) (xy 443.007452 -320.226032) (xy 443.057066 -320.245504) (xy 443.103224 -320.272153)
			(xy 443.144895 -320.305384) (xy 443.181147 -320.344455) (xy 443.211171 -320.388492) (xy 443.234297 -320.436513)
			(xy 443.250007 -320.487443) (xy 443.25795 -320.540147) (xy 443.258448 -320.566796) (xy 443.25795 -320.593445)
			(xy 447.111872 -320.593445) (xy 447.111872 -320.540147) (xy 447.119815 -320.487443) (xy 447.135525 -320.436513)
			(xy 447.158651 -320.388492) (xy 447.188675 -320.344455) (xy 447.224927 -320.305384) (xy 447.266598 -320.272153)
			(xy 447.312756 -320.245504) (xy 447.36237 -320.226032) (xy 447.414332 -320.214172) (xy 447.467482 -320.210189)
			(xy 447.520632 -320.214172) (xy 447.572594 -320.226032) (xy 447.622208 -320.245504) (xy 447.668366 -320.272153)
			(xy 447.710037 -320.305384) (xy 447.746289 -320.344455) (xy 447.776313 -320.388492) (xy 447.799439 -320.436513)
			(xy 447.815149 -320.487443) (xy 447.823092 -320.540147) (xy 447.82359 -320.566796) (xy 447.823092 -320.593445)
			(xy 450.08545 -320.593445) (xy 450.08545 -320.540147) (xy 450.093393 -320.487443) (xy 450.109103 -320.436513)
			(xy 450.132229 -320.388492) (xy 450.162253 -320.344455) (xy 450.198505 -320.305384) (xy 450.240176 -320.272153)
			(xy 450.286334 -320.245504) (xy 450.335948 -320.226032) (xy 450.38791 -320.214172) (xy 450.44106 -320.210189)
			(xy 450.49421 -320.214172) (xy 450.546172 -320.226032) (xy 450.595786 -320.245504) (xy 450.641944 -320.272153)
			(xy 450.683615 -320.305384) (xy 450.719867 -320.344455) (xy 450.749891 -320.388492) (xy 450.773017 -320.436513)
			(xy 450.788727 -320.487443) (xy 450.79667 -320.540147) (xy 450.797168 -320.566796) (xy 450.79667 -320.593445)
			(xy 454.655672 -320.593445) (xy 454.655672 -320.540147) (xy 454.663615 -320.487443) (xy 454.679325 -320.436513)
			(xy 454.702451 -320.388492) (xy 454.732475 -320.344455) (xy 454.768727 -320.305384) (xy 454.810398 -320.272153)
			(xy 454.856556 -320.245504) (xy 454.90617 -320.226032) (xy 454.958132 -320.214172) (xy 455.011282 -320.210189)
			(xy 455.064432 -320.214172) (xy 455.116394 -320.226032) (xy 455.166008 -320.245504) (xy 455.212166 -320.272153)
			(xy 455.253837 -320.305384) (xy 455.290089 -320.344455) (xy 455.320113 -320.388492) (xy 455.343239 -320.436513)
			(xy 455.358949 -320.487443) (xy 455.366892 -320.540147) (xy 455.36739 -320.566796) (xy 455.366892 -320.593445)
			(xy 457.63179 -320.593445) (xy 457.63179 -320.540147) (xy 457.639733 -320.487443) (xy 457.655443 -320.436513)
			(xy 457.678569 -320.388492) (xy 457.708593 -320.344455) (xy 457.744845 -320.305384) (xy 457.786516 -320.272153)
			(xy 457.832674 -320.245504) (xy 457.882288 -320.226032) (xy 457.93425 -320.214172) (xy 457.9874 -320.210189)
			(xy 458.04055 -320.214172) (xy 458.092512 -320.226032) (xy 458.142126 -320.245504) (xy 458.188284 -320.272153)
			(xy 458.229955 -320.305384) (xy 458.266207 -320.344455) (xy 458.296231 -320.388492) (xy 458.319357 -320.436513)
			(xy 458.335067 -320.487443) (xy 458.34301 -320.540147) (xy 458.343508 -320.566796) (xy 458.34301 -320.593445)
			(xy 462.199472 -320.593445) (xy 462.199472 -320.540147) (xy 462.207415 -320.487443) (xy 462.223125 -320.436513)
			(xy 462.246251 -320.388492) (xy 462.276275 -320.344455) (xy 462.312527 -320.305384) (xy 462.354198 -320.272153)
			(xy 462.400356 -320.245504) (xy 462.44997 -320.226032) (xy 462.501932 -320.214172) (xy 462.555082 -320.210189)
			(xy 462.608232 -320.214172) (xy 462.660194 -320.226032) (xy 462.709808 -320.245504) (xy 462.755966 -320.272153)
			(xy 462.797637 -320.305384) (xy 462.833889 -320.344455) (xy 462.863913 -320.388492) (xy 462.887039 -320.436513)
			(xy 462.902749 -320.487443) (xy 462.910692 -320.540147) (xy 462.91119 -320.566796) (xy 462.910692 -320.593445)
			(xy 462.902749 -320.646149) (xy 462.887039 -320.697079) (xy 462.863913 -320.7451) (xy 462.833889 -320.789137)
			(xy 462.797637 -320.828208) (xy 462.755966 -320.861439) (xy 462.709808 -320.888088) (xy 462.660194 -320.90756)
			(xy 462.608232 -320.91942) (xy 462.555082 -320.923404) (xy 462.501932 -320.91942) (xy 462.44997 -320.90756)
			(xy 462.400356 -320.888088) (xy 462.354198 -320.861439) (xy 462.312527 -320.828208) (xy 462.276275 -320.789137)
			(xy 462.246251 -320.7451) (xy 462.223125 -320.697079) (xy 462.207415 -320.646149) (xy 462.199472 -320.593445)
			(xy 458.34301 -320.593445) (xy 458.335067 -320.646149) (xy 458.319357 -320.697079) (xy 458.296231 -320.7451)
			(xy 458.266207 -320.789137) (xy 458.229955 -320.828208) (xy 458.188284 -320.861439) (xy 458.142126 -320.888088)
			(xy 458.092512 -320.90756) (xy 458.04055 -320.91942) (xy 457.9874 -320.923404) (xy 457.93425 -320.91942)
			(xy 457.882288 -320.90756) (xy 457.832674 -320.888088) (xy 457.786516 -320.861439) (xy 457.744845 -320.828208)
			(xy 457.708593 -320.789137) (xy 457.678569 -320.7451) (xy 457.655443 -320.697079) (xy 457.639733 -320.646149)
			(xy 457.63179 -320.593445) (xy 455.366892 -320.593445) (xy 455.358949 -320.646149) (xy 455.343239 -320.697079)
			(xy 455.320113 -320.7451) (xy 455.290089 -320.789137) (xy 455.253837 -320.828208) (xy 455.212166 -320.861439)
			(xy 455.166008 -320.888088) (xy 455.116394 -320.90756) (xy 455.064432 -320.91942) (xy 455.011282 -320.923404)
			(xy 454.958132 -320.91942) (xy 454.90617 -320.90756) (xy 454.856556 -320.888088) (xy 454.810398 -320.861439)
			(xy 454.768727 -320.828208) (xy 454.732475 -320.789137) (xy 454.702451 -320.7451) (xy 454.679325 -320.697079)
			(xy 454.663615 -320.646149) (xy 454.655672 -320.593445) (xy 450.79667 -320.593445) (xy 450.788727 -320.646149)
			(xy 450.773017 -320.697079) (xy 450.749891 -320.7451) (xy 450.719867 -320.789137) (xy 450.683615 -320.828208)
			(xy 450.641944 -320.861439) (xy 450.595786 -320.888088) (xy 450.546172 -320.90756) (xy 450.49421 -320.91942)
			(xy 450.44106 -320.923404) (xy 450.38791 -320.91942) (xy 450.335948 -320.90756) (xy 450.286334 -320.888088)
			(xy 450.240176 -320.861439) (xy 450.198505 -320.828208) (xy 450.162253 -320.789137) (xy 450.132229 -320.7451)
			(xy 450.109103 -320.697079) (xy 450.093393 -320.646149) (xy 450.08545 -320.593445) (xy 447.823092 -320.593445)
			(xy 447.815149 -320.646149) (xy 447.799439 -320.697079) (xy 447.776313 -320.7451) (xy 447.746289 -320.789137)
			(xy 447.710037 -320.828208) (xy 447.668366 -320.861439) (xy 447.622208 -320.888088) (xy 447.572594 -320.90756)
			(xy 447.520632 -320.91942) (xy 447.467482 -320.923404) (xy 447.414332 -320.91942) (xy 447.36237 -320.90756)
			(xy 447.312756 -320.888088) (xy 447.266598 -320.861439) (xy 447.224927 -320.828208) (xy 447.188675 -320.789137)
			(xy 447.158651 -320.7451) (xy 447.135525 -320.697079) (xy 447.119815 -320.646149) (xy 447.111872 -320.593445)
			(xy 443.25795 -320.593445) (xy 443.250007 -320.646149) (xy 443.234297 -320.697079) (xy 443.211171 -320.7451)
			(xy 443.181147 -320.789137) (xy 443.144895 -320.828208) (xy 443.103224 -320.861439) (xy 443.057066 -320.888088)
			(xy 443.007452 -320.90756) (xy 442.95549 -320.91942) (xy 442.90234 -320.923404) (xy 442.84919 -320.91942)
			(xy 442.797228 -320.90756) (xy 442.747614 -320.888088) (xy 442.701456 -320.861439) (xy 442.659785 -320.828208)
			(xy 442.623533 -320.789137) (xy 442.593509 -320.7451) (xy 442.570383 -320.697079) (xy 442.554673 -320.646149)
			(xy 442.54673 -320.593445) (xy 440.279292 -320.593445) (xy 440.271349 -320.646149) (xy 440.255639 -320.697079)
			(xy 440.232513 -320.7451) (xy 440.202489 -320.789137) (xy 440.166237 -320.828208) (xy 440.124566 -320.861439)
			(xy 440.078408 -320.888088) (xy 440.028794 -320.90756) (xy 439.976832 -320.91942) (xy 439.923682 -320.923404)
			(xy 439.870532 -320.91942) (xy 439.81857 -320.90756) (xy 439.768956 -320.888088) (xy 439.722798 -320.861439)
			(xy 439.681127 -320.828208) (xy 439.644875 -320.789137) (xy 439.614851 -320.7451) (xy 439.591725 -320.697079)
			(xy 439.576015 -320.646149) (xy 439.568072 -320.593445) (xy 435.69383 -320.593445) (xy 435.685887 -320.646149)
			(xy 435.670177 -320.697079) (xy 435.647051 -320.7451) (xy 435.617027 -320.789137) (xy 435.580775 -320.828208)
			(xy 435.539104 -320.861439) (xy 435.492946 -320.888088) (xy 435.443332 -320.90756) (xy 435.39137 -320.91942)
			(xy 435.33822 -320.923404) (xy 435.28507 -320.91942) (xy 435.233108 -320.90756) (xy 435.183494 -320.888088)
			(xy 435.137336 -320.861439) (xy 435.095665 -320.828208) (xy 435.059413 -320.789137) (xy 435.029389 -320.7451)
			(xy 435.006263 -320.697079) (xy 434.990553 -320.646149) (xy 434.98261 -320.593445) (xy 432.735492 -320.593445)
			(xy 432.727549 -320.646149) (xy 432.711839 -320.697079) (xy 432.688713 -320.7451) (xy 432.658689 -320.789137)
			(xy 432.622437 -320.828208) (xy 432.580766 -320.861439) (xy 432.534608 -320.888088) (xy 432.484994 -320.90756)
			(xy 432.433032 -320.91942) (xy 432.379882 -320.923404) (xy 432.326732 -320.91942) (xy 432.27477 -320.90756)
			(xy 432.225156 -320.888088) (xy 432.178998 -320.861439) (xy 432.137327 -320.828208) (xy 432.101075 -320.789137)
			(xy 432.071051 -320.7451) (xy 432.047925 -320.697079) (xy 432.032215 -320.646149) (xy 432.024272 -320.593445)
			(xy 427.407895 -320.593445) (xy 427.401272 -320.640645) (xy 427.394878 -320.664586) (xy 427.39156 -320.677582)
			(xy 427.391105 -320.704391) (xy 427.397655 -320.730391) (xy 427.410755 -320.753786) (xy 427.429501 -320.772956)
			(xy 427.452596 -320.786578) (xy 427.478444 -320.793708) (xy 427.505256 -320.793854) (xy 427.518322 -320.790824)
			(xy 427.540589 -320.78534) (xy 427.586071 -320.779479) (xy 427.609 -320.77914) (xy 427.637001 -320.779701)
			(xy 427.692312 -320.788461) (xy 427.745573 -320.805765) (xy 427.795471 -320.831188) (xy 427.840778 -320.864103)
			(xy 427.880379 -320.903701) (xy 427.913297 -320.949005) (xy 427.9265 -320.973704) (xy 427.933431 -320.986317)
			(xy 427.953124 -321.007293) (xy 427.977879 -321.021954) (xy 428.005739 -321.029141) (xy 428.034497 -321.028283)
			(xy 428.061879 -321.01945) (xy 428.074074 -321.011804) (xy 428.096329 -320.99725) (xy 428.144249 -320.974205)
			(xy 428.195062 -320.958537) (xy 428.24764 -320.950595) (xy 428.274226 -320.950082) (xy 428.300873 -320.950601)
			(xy 428.353572 -320.958548) (xy 428.404498 -320.97426) (xy 428.452514 -320.997386) (xy 428.496547 -321.02741)
			(xy 428.531988 -321.060297) (xy 431.19801 -321.060297) (xy 431.19801 -321.006999) (xy 431.205953 -320.954295)
			(xy 431.221663 -320.903365) (xy 431.244789 -320.855344) (xy 431.274813 -320.811307) (xy 431.311065 -320.772236)
			(xy 431.352736 -320.739005) (xy 431.398894 -320.712356) (xy 431.448508 -320.692884) (xy 431.50047 -320.681024)
			(xy 431.55362 -320.677041) (xy 431.60677 -320.681024) (xy 431.658732 -320.692884) (xy 431.708346 -320.712356)
			(xy 431.754504 -320.739005) (xy 431.796175 -320.772236) (xy 431.832427 -320.811307) (xy 431.862451 -320.855344)
			(xy 431.885577 -320.903365) (xy 431.901287 -320.954295) (xy 431.90923 -321.006999) (xy 431.909728 -321.033648)
			(xy 431.90923 -321.060297) (xy 431.901287 -321.113001) (xy 431.885577 -321.163931) (xy 431.862451 -321.211952)
			(xy 431.832427 -321.255989) (xy 431.796175 -321.29506) (xy 431.754504 -321.328291) (xy 431.708346 -321.35494)
			(xy 431.658732 -321.374412) (xy 431.60677 -321.386272) (xy 431.55362 -321.390256) (xy 431.50047 -321.386272)
			(xy 431.448508 -321.374412) (xy 431.398894 -321.35494) (xy 431.352736 -321.328291) (xy 431.311065 -321.29506)
			(xy 431.274813 -321.255989) (xy 431.244789 -321.211952) (xy 431.221663 -321.163931) (xy 431.205953 -321.113001)
			(xy 431.19801 -321.060297) (xy 428.531988 -321.060297) (xy 428.535613 -321.063661) (xy 428.56884 -321.10533)
			(xy 428.595486 -321.151485) (xy 428.614956 -321.201096) (xy 428.626815 -321.253054) (xy 428.630798 -321.3062)
			(xy 428.626815 -321.359346) (xy 428.614956 -321.411304) (xy 428.602388 -321.443329) (xy 432.015636 -321.443329)
			(xy 432.015636 -321.390031) (xy 432.023579 -321.337327) (xy 432.039289 -321.286397) (xy 432.062415 -321.238376)
			(xy 432.092439 -321.194339) (xy 432.128691 -321.155268) (xy 432.170362 -321.122037) (xy 432.21652 -321.095388)
			(xy 432.266134 -321.075916) (xy 432.318096 -321.064056) (xy 432.371246 -321.060073) (xy 432.424396 -321.064056)
			(xy 432.476358 -321.075916) (xy 432.525972 -321.095388) (xy 432.57213 -321.122037) (xy 432.613801 -321.155268)
			(xy 432.650053 -321.194339) (xy 432.680077 -321.238376) (xy 432.703203 -321.286397) (xy 432.718913 -321.337327)
			(xy 432.726856 -321.390031) (xy 432.727354 -321.41668) (xy 432.726856 -321.443329) (xy 435.467496 -321.443329)
			(xy 435.467496 -321.390031) (xy 435.475439 -321.337327) (xy 435.491149 -321.286397) (xy 435.514275 -321.238376)
			(xy 435.544299 -321.194339) (xy 435.580551 -321.155268) (xy 435.622222 -321.122037) (xy 435.66838 -321.095388)
			(xy 435.717994 -321.075916) (xy 435.769956 -321.064056) (xy 435.823106 -321.060073) (xy 435.876256 -321.064056)
			(xy 435.928218 -321.075916) (xy 435.977832 -321.095388) (xy 436.02399 -321.122037) (xy 436.065661 -321.155268)
			(xy 436.101913 -321.194339) (xy 436.131937 -321.238376) (xy 436.155063 -321.286397) (xy 436.170773 -321.337327)
			(xy 436.178716 -321.390031) (xy 436.179214 -321.41668) (xy 436.178716 -321.443329) (xy 439.556896 -321.443329)
			(xy 439.556896 -321.390031) (xy 439.564839 -321.337327) (xy 439.580549 -321.286397) (xy 439.603675 -321.238376)
			(xy 439.633699 -321.194339) (xy 439.669951 -321.155268) (xy 439.711622 -321.122037) (xy 439.75778 -321.095388)
			(xy 439.807394 -321.075916) (xy 439.859356 -321.064056) (xy 439.912506 -321.060073) (xy 439.965656 -321.064056)
			(xy 440.017618 -321.075916) (xy 440.067232 -321.095388) (xy 440.11339 -321.122037) (xy 440.155061 -321.155268)
			(xy 440.191313 -321.194339) (xy 440.221337 -321.238376) (xy 440.244463 -321.286397) (xy 440.260173 -321.337327)
			(xy 440.268116 -321.390031) (xy 440.268614 -321.41668) (xy 440.268116 -321.443329) (xy 443.011804 -321.443329)
			(xy 443.011804 -321.390031) (xy 443.019747 -321.337327) (xy 443.035457 -321.286397) (xy 443.058583 -321.238376)
			(xy 443.088607 -321.194339) (xy 443.124859 -321.155268) (xy 443.16653 -321.122037) (xy 443.212688 -321.095388)
			(xy 443.262302 -321.075916) (xy 443.314264 -321.064056) (xy 443.367414 -321.060073) (xy 443.420564 -321.064056)
			(xy 443.472526 -321.075916) (xy 443.52214 -321.095388) (xy 443.568298 -321.122037) (xy 443.609969 -321.155268)
			(xy 443.646221 -321.194339) (xy 443.676245 -321.238376) (xy 443.699371 -321.286397) (xy 443.715081 -321.337327)
			(xy 443.723024 -321.390031) (xy 443.723522 -321.41668) (xy 443.723024 -321.443329) (xy 447.111872 -321.443329)
			(xy 447.111872 -321.390031) (xy 447.119815 -321.337327) (xy 447.135525 -321.286397) (xy 447.158651 -321.238376)
			(xy 447.188675 -321.194339) (xy 447.224927 -321.155268) (xy 447.266598 -321.122037) (xy 447.312756 -321.095388)
			(xy 447.36237 -321.075916) (xy 447.414332 -321.064056) (xy 447.467482 -321.060073) (xy 447.520632 -321.064056)
			(xy 447.572594 -321.075916) (xy 447.622208 -321.095388) (xy 447.668366 -321.122037) (xy 447.710037 -321.155268)
			(xy 447.746289 -321.194339) (xy 447.776313 -321.238376) (xy 447.799439 -321.286397) (xy 447.815149 -321.337327)
			(xy 447.823092 -321.390031) (xy 447.82359 -321.41668) (xy 447.823092 -321.443329) (xy 450.555604 -321.443329)
			(xy 450.555604 -321.390031) (xy 450.563547 -321.337327) (xy 450.579257 -321.286397) (xy 450.602383 -321.238376)
			(xy 450.632407 -321.194339) (xy 450.668659 -321.155268) (xy 450.71033 -321.122037) (xy 450.756488 -321.095388)
			(xy 450.806102 -321.075916) (xy 450.858064 -321.064056) (xy 450.911214 -321.060073) (xy 450.964364 -321.064056)
			(xy 451.016326 -321.075916) (xy 451.06594 -321.095388) (xy 451.112098 -321.122037) (xy 451.153769 -321.155268)
			(xy 451.184696 -321.1886) (xy 453.886756 -321.1886) (xy 453.89074 -321.135441) (xy 453.902603 -321.08347)
			(xy 453.92208 -321.033848) (xy 453.948735 -320.987683) (xy 453.981974 -320.946006) (xy 454.021054 -320.90975)
			(xy 454.065101 -320.879724) (xy 454.113132 -320.856598) (xy 454.164073 -320.84089) (xy 454.216786 -320.83295)
			(xy 454.24344 -320.83248) (xy 454.270243 -320.833002) (xy 454.32324 -320.841056) (xy 454.374432 -320.856961)
			(xy 454.422663 -320.880357) (xy 454.466843 -320.910716) (xy 454.505975 -320.947353) (xy 454.539175 -320.98944)
			(xy 454.565694 -321.036027) (xy 454.584931 -321.086062) (xy 454.591166 -321.112134) (xy 454.594495 -321.125271)
			(xy 454.607115 -321.149246) (xy 454.625593 -321.16906) (xy 454.64863 -321.18332) (xy 454.674605 -321.191022)
			(xy 454.701692 -321.191624) (xy 454.727984 -321.185085) (xy 454.751633 -321.171864) (xy 454.7616 -321.16268)
			(xy 454.781722 -321.143666) (xy 454.826741 -321.111449) (xy 454.8762 -321.086581) (xy 454.92891 -321.069662)
			(xy 454.983603 -321.061097) (xy 455.011282 -321.060572) (xy 455.037933 -321.061084) (xy 455.090639 -321.069026)
			(xy 455.141572 -321.084734) (xy 455.189596 -321.107859) (xy 455.233636 -321.137883) (xy 455.272709 -321.174136)
			(xy 455.305943 -321.215808) (xy 455.332594 -321.261967) (xy 455.352068 -321.311583) (xy 455.363929 -321.363548)
			(xy 455.367912 -321.4167) (xy 455.365917 -321.443329) (xy 458.099404 -321.443329) (xy 458.099404 -321.390031)
			(xy 458.107347 -321.337327) (xy 458.123057 -321.286397) (xy 458.146183 -321.238376) (xy 458.176207 -321.194339)
			(xy 458.212459 -321.155268) (xy 458.25413 -321.122037) (xy 458.300288 -321.095388) (xy 458.349902 -321.075916)
			(xy 458.401864 -321.064056) (xy 458.455014 -321.060073) (xy 458.508164 -321.064056) (xy 458.560126 -321.075916)
			(xy 458.60974 -321.095388) (xy 458.655898 -321.122037) (xy 458.697569 -321.155268) (xy 458.733821 -321.194339)
			(xy 458.763845 -321.238376) (xy 458.786971 -321.286397) (xy 458.802681 -321.337327) (xy 458.810624 -321.390031)
			(xy 458.811122 -321.41668) (xy 458.810624 -321.443329) (xy 462.199472 -321.443329) (xy 462.199472 -321.390031)
			(xy 462.207415 -321.337327) (xy 462.223125 -321.286397) (xy 462.246251 -321.238376) (xy 462.276275 -321.194339)
			(xy 462.312527 -321.155268) (xy 462.354198 -321.122037) (xy 462.400356 -321.095388) (xy 462.44997 -321.075916)
			(xy 462.501932 -321.064056) (xy 462.555082 -321.060073) (xy 462.608232 -321.064056) (xy 462.660194 -321.075916)
			(xy 462.709808 -321.095388) (xy 462.755966 -321.122037) (xy 462.797637 -321.155268) (xy 462.833889 -321.194339)
			(xy 462.863913 -321.238376) (xy 462.887039 -321.286397) (xy 462.902749 -321.337327) (xy 462.910692 -321.390031)
			(xy 462.91119 -321.41668) (xy 462.910692 -321.443329) (xy 462.902749 -321.496033) (xy 462.887039 -321.546963)
			(xy 462.863913 -321.594984) (xy 462.833889 -321.639021) (xy 462.797637 -321.678092) (xy 462.755966 -321.711323)
			(xy 462.709808 -321.737972) (xy 462.660194 -321.757444) (xy 462.608232 -321.769304) (xy 462.555082 -321.773288)
			(xy 462.501932 -321.769304) (xy 462.44997 -321.757444) (xy 462.400356 -321.737972) (xy 462.354198 -321.711323)
			(xy 462.312527 -321.678092) (xy 462.276275 -321.639021) (xy 462.246251 -321.594984) (xy 462.223125 -321.546963)
			(xy 462.207415 -321.496033) (xy 462.199472 -321.443329) (xy 458.810624 -321.443329) (xy 458.802681 -321.496033)
			(xy 458.786971 -321.546963) (xy 458.763845 -321.594984) (xy 458.733821 -321.639021) (xy 458.697569 -321.678092)
			(xy 458.655898 -321.711323) (xy 458.60974 -321.737972) (xy 458.560126 -321.757444) (xy 458.508164 -321.769304)
			(xy 458.455014 -321.773288) (xy 458.401864 -321.769304) (xy 458.349902 -321.757444) (xy 458.300288 -321.737972)
			(xy 458.25413 -321.711323) (xy 458.212459 -321.678092) (xy 458.176207 -321.639021) (xy 458.146183 -321.594984)
			(xy 458.123057 -321.546963) (xy 458.107347 -321.496033) (xy 458.099404 -321.443329) (xy 455.365917 -321.443329)
			(xy 455.363929 -321.469852) (xy 455.352068 -321.521817) (xy 455.332594 -321.571433) (xy 455.305943 -321.617592)
			(xy 455.272709 -321.659264) (xy 455.233636 -321.695517) (xy 455.189596 -321.725541) (xy 455.141572 -321.748666)
			(xy 455.090639 -321.764374) (xy 455.037933 -321.772316) (xy 455.011282 -321.772788) (xy 454.984479 -321.772271)
			(xy 454.93148 -321.764219) (xy 454.880286 -321.748316) (xy 454.832054 -321.72492) (xy 454.787873 -321.694561)
			(xy 454.748741 -321.657922) (xy 454.715541 -321.615833) (xy 454.689024 -321.569244) (xy 454.669789 -321.519207)
			(xy 454.663556 -321.493134) (xy 454.660204 -321.480005) (xy 454.647583 -321.456038) (xy 454.629107 -321.43623)
			(xy 454.606075 -321.421974) (xy 454.580106 -321.414272) (xy 454.553025 -321.413666) (xy 454.526737 -321.420198)
			(xy 454.50309 -321.43341) (xy 454.493122 -321.442588) (xy 454.473028 -321.461634) (xy 454.428003 -321.493848)
			(xy 454.378536 -321.51871) (xy 454.32582 -321.535622) (xy 454.271122 -321.544176) (xy 454.24344 -321.544696)
			(xy 454.216786 -321.54425) (xy 454.164073 -321.53631) (xy 454.113132 -321.520602) (xy 454.065101 -321.497476)
			(xy 454.021054 -321.46745) (xy 453.981974 -321.431194) (xy 453.948735 -321.389517) (xy 453.92208 -321.343352)
			(xy 453.902603 -321.29373) (xy 453.89074 -321.241759) (xy 453.886756 -321.1886) (xy 451.184696 -321.1886)
			(xy 451.190021 -321.194339) (xy 451.220045 -321.238376) (xy 451.243171 -321.286397) (xy 451.258881 -321.337327)
			(xy 451.266824 -321.390031) (xy 451.267322 -321.41668) (xy 451.266824 -321.443329) (xy 451.258881 -321.496033)
			(xy 451.243171 -321.546963) (xy 451.220045 -321.594984) (xy 451.190021 -321.639021) (xy 451.153769 -321.678092)
			(xy 451.112098 -321.711323) (xy 451.06594 -321.737972) (xy 451.016326 -321.757444) (xy 450.964364 -321.769304)
			(xy 450.911214 -321.773288) (xy 450.858064 -321.769304) (xy 450.806102 -321.757444) (xy 450.756488 -321.737972)
			(xy 450.71033 -321.711323) (xy 450.668659 -321.678092) (xy 450.632407 -321.639021) (xy 450.602383 -321.594984)
			(xy 450.579257 -321.546963) (xy 450.563547 -321.496033) (xy 450.555604 -321.443329) (xy 447.823092 -321.443329)
			(xy 447.815149 -321.496033) (xy 447.799439 -321.546963) (xy 447.776313 -321.594984) (xy 447.746289 -321.639021)
			(xy 447.710037 -321.678092) (xy 447.668366 -321.711323) (xy 447.622208 -321.737972) (xy 447.572594 -321.757444)
			(xy 447.520632 -321.769304) (xy 447.467482 -321.773288) (xy 447.414332 -321.769304) (xy 447.36237 -321.757444)
			(xy 447.312756 -321.737972) (xy 447.266598 -321.711323) (xy 447.224927 -321.678092) (xy 447.188675 -321.639021)
			(xy 447.158651 -321.594984) (xy 447.135525 -321.546963) (xy 447.119815 -321.496033) (xy 447.111872 -321.443329)
			(xy 443.723024 -321.443329) (xy 443.715081 -321.496033) (xy 443.699371 -321.546963) (xy 443.676245 -321.594984)
			(xy 443.646221 -321.639021) (xy 443.609969 -321.678092) (xy 443.568298 -321.711323) (xy 443.52214 -321.737972)
			(xy 443.472526 -321.757444) (xy 443.420564 -321.769304) (xy 443.367414 -321.773288) (xy 443.314264 -321.769304)
			(xy 443.262302 -321.757444) (xy 443.212688 -321.737972) (xy 443.16653 -321.711323) (xy 443.124859 -321.678092)
			(xy 443.088607 -321.639021) (xy 443.058583 -321.594984) (xy 443.035457 -321.546963) (xy 443.019747 -321.496033)
			(xy 443.011804 -321.443329) (xy 440.268116 -321.443329) (xy 440.260173 -321.496033) (xy 440.244463 -321.546963)
			(xy 440.221337 -321.594984) (xy 440.191313 -321.639021) (xy 440.155061 -321.678092) (xy 440.11339 -321.711323)
			(xy 440.067232 -321.737972) (xy 440.017618 -321.757444) (xy 439.965656 -321.769304) (xy 439.912506 -321.773288)
			(xy 439.859356 -321.769304) (xy 439.807394 -321.757444) (xy 439.75778 -321.737972) (xy 439.711622 -321.711323)
			(xy 439.669951 -321.678092) (xy 439.633699 -321.639021) (xy 439.603675 -321.594984) (xy 439.580549 -321.546963)
			(xy 439.564839 -321.496033) (xy 439.556896 -321.443329) (xy 436.178716 -321.443329) (xy 436.170773 -321.496033)
			(xy 436.155063 -321.546963) (xy 436.131937 -321.594984) (xy 436.101913 -321.639021) (xy 436.065661 -321.678092)
			(xy 436.02399 -321.711323) (xy 435.977832 -321.737972) (xy 435.928218 -321.757444) (xy 435.876256 -321.769304)
			(xy 435.823106 -321.773288) (xy 435.769956 -321.769304) (xy 435.717994 -321.757444) (xy 435.66838 -321.737972)
			(xy 435.622222 -321.711323) (xy 435.580551 -321.678092) (xy 435.544299 -321.639021) (xy 435.514275 -321.594984)
			(xy 435.491149 -321.546963) (xy 435.475439 -321.496033) (xy 435.467496 -321.443329) (xy 432.726856 -321.443329)
			(xy 432.718913 -321.496033) (xy 432.703203 -321.546963) (xy 432.680077 -321.594984) (xy 432.650053 -321.639021)
			(xy 432.613801 -321.678092) (xy 432.57213 -321.711323) (xy 432.525972 -321.737972) (xy 432.476358 -321.757444)
			(xy 432.424396 -321.769304) (xy 432.371246 -321.773288) (xy 432.318096 -321.769304) (xy 432.266134 -321.757444)
			(xy 432.21652 -321.737972) (xy 432.170362 -321.711323) (xy 432.128691 -321.678092) (xy 432.092439 -321.639021)
			(xy 432.062415 -321.594984) (xy 432.039289 -321.546963) (xy 432.023579 -321.496033) (xy 432.015636 -321.443329)
			(xy 428.602388 -321.443329) (xy 428.595486 -321.460915) (xy 428.56884 -321.50707) (xy 428.535613 -321.548739)
			(xy 428.496547 -321.58499) (xy 428.452514 -321.615014) (xy 428.404498 -321.63814) (xy 428.353572 -321.653852)
			(xy 428.300873 -321.661799) (xy 428.274226 -321.662298) (xy 428.246224 -321.661777) (xy 428.190912 -321.653007)
			(xy 428.137651 -321.635693) (xy 428.087754 -321.610263) (xy 428.042448 -321.577343) (xy 428.002848 -321.537741)
			(xy 427.969929 -321.492434) (xy 427.956726 -321.467734) (xy 427.949755 -321.455144) (xy 427.930074 -321.434164)
			(xy 427.905328 -321.419498) (xy 427.877475 -321.412307) (xy 427.848722 -321.41316) (xy 427.821345 -321.42199)
			(xy 427.809152 -321.429634) (xy 427.786886 -321.44417) (xy 427.73897 -321.467221) (xy 427.68816 -321.482894)
			(xy 427.635586 -321.490841) (xy 427.609 -321.491356) (xy 427.581019 -321.490759) (xy 427.525747 -321.482006)
			(xy 427.472524 -321.464714) (xy 427.422661 -321.43931) (xy 427.377385 -321.406419) (xy 427.337812 -321.366851)
			(xy 427.304915 -321.32158) (xy 427.279504 -321.271721) (xy 427.262206 -321.2185) (xy 427.253445 -321.163229)
			(xy 427.252892 -321.135248) (xy 427.253334 -321.110472) (xy 427.260216 -321.061399) (xy 427.266608 -321.037458)
			(xy 427.269896 -321.024454) (xy 427.27036 -320.997647) (xy 427.263818 -320.971646) (xy 427.250723 -320.94825)
			(xy 427.23198 -320.929078) (xy 427.208886 -320.915457) (xy 427.18304 -320.908329) (xy 427.156229 -320.908188)
			(xy 427.143164 -320.91122) (xy 427.120898 -320.916708) (xy 427.075416 -320.922566) (xy 427.052486 -320.922904)
			(xy 427.025407 -320.922387) (xy 426.971874 -320.914184) (xy 426.920201 -320.89797) (xy 426.871579 -320.874117)
			(xy 426.827129 -320.843177) (xy 426.787877 -320.805863) (xy 426.754728 -320.763036) (xy 426.728447 -320.715682)
			(xy 426.709639 -320.664895) (xy 426.698738 -320.611846) (xy 426.695997 -320.557758) (xy 420.602897 -320.557758)
			(xy 420.598672 -320.580071) (xy 420.600665 -320.60666) (xy 420.604696 -320.619374) (xy 420.613936 -320.647762)
			(xy 420.623898 -320.70662) (xy 420.624508 -320.736468) (xy 420.624216 -320.757824) (xy 420.619118 -320.800231)
			(xy 420.614348 -320.82105) (xy 420.611405 -320.835322) (xy 420.612834 -320.864414) (xy 420.6224 -320.891926)
			(xy 420.639329 -320.915628) (xy 420.662249 -320.933602) (xy 420.689305 -320.944391) (xy 420.703756 -320.946272)
			(xy 420.729985 -320.949105) (xy 420.781257 -320.96153) (xy 420.830133 -320.981386) (xy 420.875543 -321.008238)
			(xy 420.893355 -321.022705) (xy 424.380142 -321.022705) (xy 424.380142 -320.969407) (xy 424.388085 -320.916703)
			(xy 424.403795 -320.865773) (xy 424.426921 -320.817752) (xy 424.456945 -320.773715) (xy 424.493197 -320.734644)
			(xy 424.534868 -320.701413) (xy 424.581026 -320.674764) (xy 424.63064 -320.655292) (xy 424.682602 -320.643432)
			(xy 424.735752 -320.639449) (xy 424.788902 -320.643432) (xy 424.840864 -320.655292) (xy 424.890478 -320.674764)
			(xy 424.936636 -320.701413) (xy 424.978307 -320.734644) (xy 425.014559 -320.773715) (xy 425.044583 -320.817752)
			(xy 425.067709 -320.865773) (xy 425.083419 -320.916703) (xy 425.091362 -320.969407) (xy 425.09186 -320.996056)
			(xy 425.091362 -321.022705) (xy 425.083419 -321.075409) (xy 425.067709 -321.126339) (xy 425.044583 -321.17436)
			(xy 425.014559 -321.218397) (xy 424.978307 -321.257468) (xy 424.936636 -321.290699) (xy 424.890478 -321.317348)
			(xy 424.840864 -321.33682) (xy 424.788902 -321.34868) (xy 424.735752 -321.352664) (xy 424.682602 -321.34868)
			(xy 424.63064 -321.33682) (xy 424.581026 -321.317348) (xy 424.534868 -321.290699) (xy 424.493197 -321.257468)
			(xy 424.456945 -321.218397) (xy 424.426921 -321.17436) (xy 424.403795 -321.126339) (xy 424.388085 -321.075409)
			(xy 424.380142 -321.022705) (xy 420.893355 -321.022705) (xy 420.916493 -321.041498) (xy 420.952085 -321.080438)
			(xy 420.981541 -321.124205) (xy 421.004214 -321.17184) (xy 421.019608 -321.222299) (xy 421.027386 -321.274478)
			(xy 421.02786 -321.300856) (xy 421.027362 -321.327505) (xy 421.019419 -321.380209) (xy 421.003709 -321.431139)
			(xy 420.980583 -321.47916) (xy 420.950559 -321.523197) (xy 420.914307 -321.562268) (xy 420.872636 -321.595499)
			(xy 420.826478 -321.622148) (xy 420.776864 -321.64162) (xy 420.724902 -321.65348) (xy 420.671752 -321.657464)
			(xy 420.618602 -321.65348) (xy 420.56664 -321.64162) (xy 420.517026 -321.622148) (xy 420.470868 -321.595499)
			(xy 420.429197 -321.562268) (xy 420.392945 -321.523197) (xy 420.362921 -321.47916) (xy 420.339795 -321.431139)
			(xy 420.324085 -321.380209) (xy 420.316142 -321.327505) (xy 420.315644 -321.300856) (xy 420.315939 -321.2795)
			(xy 420.321035 -321.237093) (xy 420.325804 -321.216274) (xy 420.328815 -321.202009) (xy 420.327392 -321.172896)
			(xy 420.317821 -321.145365) (xy 420.300879 -321.121647) (xy 420.27794 -321.103665) (xy 420.250862 -321.092877)
			(xy 420.236396 -321.091052) (xy 420.210175 -321.088152) (xy 420.158906 -321.075736) (xy 420.110032 -321.055888)
			(xy 420.064622 -321.029044) (xy 420.023672 -320.995791) (xy 419.988079 -320.956859) (xy 419.958622 -320.913099)
			(xy 419.935946 -320.865471) (xy 419.920549 -320.815017) (xy 419.912768 -320.762843) (xy 419.912292 -320.736468)
			(xy 417.605059 -320.736468) (xy 417.598953 -320.748808) (xy 417.567598 -320.793417) (xy 417.549076 -320.81343)
			(xy 417.5392 -320.824463) (xy 417.525616 -320.850754) (xy 417.520157 -320.87984) (xy 417.523283 -320.909267)
			(xy 417.534731 -320.936557) (xy 417.543742 -320.948304) (xy 417.558896 -320.967477) (xy 417.584382 -321.009176)
			(xy 417.603928 -321.053967) (xy 417.617168 -321.10101) (xy 417.623854 -321.149421) (xy 417.62426 -321.173856)
			(xy 417.623762 -321.200505) (xy 417.615819 -321.253209) (xy 417.600109 -321.304139) (xy 417.576983 -321.35216)
			(xy 417.546959 -321.396197) (xy 417.510707 -321.435268) (xy 417.469036 -321.468499) (xy 417.422878 -321.495148)
			(xy 417.373264 -321.51462) (xy 417.321302 -321.52648) (xy 417.268152 -321.530464) (xy 417.215002 -321.52648)
			(xy 417.16304 -321.51462) (xy 417.113426 -321.495148) (xy 417.067268 -321.468499) (xy 417.025597 -321.435268)
			(xy 416.989345 -321.396197) (xy 416.959321 -321.35216) (xy 416.936195 -321.304139) (xy 416.920485 -321.253209)
			(xy 416.912542 -321.200505) (xy 416.912044 -321.173856) (xy 408.761856 -321.173856) (xy 408.761448 -321.195679)
			(xy 408.753505 -321.248383) (xy 408.737795 -321.299313) (xy 408.714669 -321.347334) (xy 408.684645 -321.391371)
			(xy 408.648393 -321.430442) (xy 408.606722 -321.463673) (xy 408.560564 -321.490322) (xy 408.51095 -321.509794)
			(xy 408.458988 -321.521654) (xy 408.405838 -321.525638) (xy 408.352688 -321.521654) (xy 408.300726 -321.509794)
			(xy 408.251112 -321.490322) (xy 408.204954 -321.463673) (xy 408.163283 -321.430442) (xy 408.127031 -321.391371)
			(xy 408.097007 -321.347334) (xy 408.073881 -321.299313) (xy 408.058171 -321.248383) (xy 408.050228 -321.195679)
			(xy 408.04973 -321.16903) (xy 407.4668 -321.16903) (xy 407.4668 -322.369749) (xy 415.741388 -322.369749)
			(xy 415.741388 -322.315251) (xy 415.749143 -322.261309) (xy 415.764496 -322.209019) (xy 415.787133 -322.159446)
			(xy 415.816595 -322.113599) (xy 415.852281 -322.072411) (xy 415.893465 -322.03672) (xy 415.939309 -322.007254)
			(xy 415.988879 -321.984611) (xy 416.041168 -321.969252) (xy 416.095109 -321.961491) (xy 416.122358 -321.961002)
			(xy 416.149857 -321.961476) (xy 416.204285 -321.969388) (xy 416.257014 -321.985025) (xy 416.306955 -322.008064)
			(xy 416.353075 -322.038029) (xy 416.394419 -322.0743) (xy 416.430133 -322.116126) (xy 416.459478 -322.162642)
			(xy 416.4711 -322.18757) (xy 416.476995 -322.199647) (xy 416.493947 -322.220485) (xy 416.515741 -322.236189)
			(xy 416.540873 -322.245674) (xy 416.567608 -322.248287) (xy 416.594101 -322.243847) (xy 416.606482 -322.238624)
			(xy 416.63165 -322.227563) (xy 416.684358 -322.211948) (xy 416.738762 -322.204055) (xy 416.766248 -322.203572)
			(xy 416.793496 -322.204102) (xy 416.847435 -322.211863) (xy 416.899721 -322.227222) (xy 416.94929 -322.249864)
			(xy 416.995132 -322.27933) (xy 417.036314 -322.31502) (xy 417.071999 -322.356207) (xy 417.101459 -322.402052)
			(xy 417.124095 -322.451624) (xy 417.139447 -322.503912) (xy 417.147202 -322.557852) (xy 417.147202 -322.612348)
			(xy 417.139447 -322.666288) (xy 417.124095 -322.718576) (xy 417.101459 -322.768148) (xy 417.071999 -322.813993)
			(xy 417.036314 -322.85518) (xy 416.995132 -322.89087) (xy 416.94929 -322.920336) (xy 416.899721 -322.942978)
			(xy 416.847435 -322.958337) (xy 416.793496 -322.966098) (xy 416.766248 -322.966588) (xy 416.738748 -322.966115)
			(xy 416.684321 -322.958204) (xy 416.631591 -322.942567) (xy 416.58165 -322.919527) (xy 416.53553 -322.889562)
			(xy 416.494186 -322.853292) (xy 416.458472 -322.811465) (xy 416.429128 -322.764948) (xy 416.417506 -322.74002)
			(xy 416.411719 -322.727884) (xy 416.394745 -322.707041) (xy 416.372927 -322.691339) (xy 416.347772 -322.681863)
			(xy 416.321017 -322.679267) (xy 416.294509 -322.68373) (xy 416.282124 -322.688966) (xy 416.256955 -322.700024)
			(xy 416.204247 -322.715641) (xy 416.149844 -322.723535) (xy 416.122358 -322.724018) (xy 416.095109 -322.723509)
			(xy 416.041168 -322.715748) (xy 415.988879 -322.700389) (xy 415.939309 -322.677746) (xy 415.893465 -322.64828)
			(xy 415.852281 -322.612589) (xy 415.816595 -322.571401) (xy 415.787133 -322.525554) (xy 415.764496 -322.475981)
			(xy 415.749143 -322.423691) (xy 415.741388 -322.369749) (xy 407.4668 -322.369749) (xy 407.4668 -323.063108)
			(xy 407.497026 -323.07657) (xy 407.520024 -323.087344) (xy 407.562689 -323.11489) (xy 407.600642 -323.148634)
			(xy 407.632991 -323.187783) (xy 407.658976 -323.231417) (xy 407.677986 -323.27851) (xy 407.689574 -323.327955)
			(xy 407.693468 -323.37859) (xy 407.689577 -323.429226) (xy 407.677992 -323.478672) (xy 407.658985 -323.525765)
			(xy 407.633002 -323.569401) (xy 407.600656 -323.608551) (xy 407.562705 -323.642298) (xy 407.520041 -323.669847)
			(xy 407.497026 -323.680582) (xy 407.4668 -323.694044) (xy 407.4668 -326.985376) (xy 441.073538 -326.985376)
			(xy 441.077609 -326.929754) (xy 441.089735 -326.875317) (xy 441.109658 -326.823226) (xy 441.136954 -326.774591)
			(xy 441.17104 -326.730448) (xy 441.211189 -326.691739) (xy 441.256547 -326.659288) (xy 441.306147 -326.633787)
			(xy 441.358931 -326.61578) (xy 441.413774 -326.60565) (xy 441.469508 -326.603613) (xy 441.524945 -326.609713)
			(xy 441.578902 -326.623819) (xy 441.630231 -326.645631) (xy 441.677837 -326.674685) (xy 441.720705 -326.71036)
			(xy 441.757922 -326.751897) (xy 441.788695 -326.79841) (xy 441.812367 -326.848907) (xy 441.828435 -326.902314)
			(xy 441.836555 -326.95749) (xy 441.8366 -326.959976) (xy 442.267338 -326.959976) (xy 442.271409 -326.904354)
			(xy 442.283535 -326.849917) (xy 442.303458 -326.797826) (xy 442.330754 -326.749191) (xy 442.36484 -326.705048)
			(xy 442.404989 -326.666339) (xy 442.450347 -326.633888) (xy 442.499947 -326.608387) (xy 442.552731 -326.59038)
			(xy 442.607574 -326.58025) (xy 442.663308 -326.578213) (xy 442.718745 -326.584313) (xy 442.772702 -326.598419)
			(xy 442.824031 -326.620231) (xy 442.871637 -326.649285) (xy 442.914505 -326.68496) (xy 442.951722 -326.726497)
			(xy 442.982495 -326.77301) (xy 443.006167 -326.823507) (xy 443.022235 -326.876914) (xy 443.030355 -326.93209)
			(xy 443.030864 -326.959976) (xy 443.0304 -326.985376) (xy 443.562738 -326.985376) (xy 443.566809 -326.929754)
			(xy 443.578935 -326.875317) (xy 443.598858 -326.823226) (xy 443.626154 -326.774591) (xy 443.66024 -326.730448)
			(xy 443.700389 -326.691739) (xy 443.745747 -326.659288) (xy 443.795347 -326.633787) (xy 443.848131 -326.61578)
			(xy 443.902974 -326.60565) (xy 443.958708 -326.603613) (xy 444.014145 -326.609713) (xy 444.068102 -326.623819)
			(xy 444.119431 -326.645631) (xy 444.167037 -326.674685) (xy 444.209905 -326.71036) (xy 444.247122 -326.751897)
			(xy 444.277895 -326.79841) (xy 444.301567 -326.848907) (xy 444.317635 -326.902314) (xy 444.325755 -326.95749)
			(xy 444.326264 -326.985376) (xy 444.325755 -327.013262) (xy 444.317635 -327.068438) (xy 444.301567 -327.121845)
			(xy 444.277895 -327.172342) (xy 444.247122 -327.218855) (xy 444.209905 -327.260392) (xy 444.167037 -327.296067)
			(xy 444.119431 -327.325121) (xy 444.068102 -327.346933) (xy 444.014145 -327.361039) (xy 443.958708 -327.367139)
			(xy 443.902974 -327.365102) (xy 443.848131 -327.354972) (xy 443.795347 -327.336965) (xy 443.745747 -327.311464)
			(xy 443.700389 -327.279013) (xy 443.66024 -327.240304) (xy 443.626154 -327.196161) (xy 443.598858 -327.147526)
			(xy 443.578935 -327.095435) (xy 443.566809 -327.040998) (xy 443.562738 -326.985376) (xy 443.0304 -326.985376)
			(xy 443.030355 -326.987862) (xy 443.022235 -327.043038) (xy 443.006167 -327.096445) (xy 442.982495 -327.146942)
			(xy 442.951722 -327.193455) (xy 442.914505 -327.234992) (xy 442.871637 -327.270667) (xy 442.824031 -327.299721)
			(xy 442.772702 -327.321533) (xy 442.718745 -327.335639) (xy 442.663308 -327.341739) (xy 442.607574 -327.339702)
			(xy 442.552731 -327.329572) (xy 442.499947 -327.311565) (xy 442.450347 -327.286064) (xy 442.404989 -327.253613)
			(xy 442.36484 -327.214904) (xy 442.330754 -327.170761) (xy 442.303458 -327.122126) (xy 442.283535 -327.070035)
			(xy 442.271409 -327.015598) (xy 442.267338 -326.959976) (xy 441.8366 -326.959976) (xy 441.837064 -326.985376)
			(xy 441.836555 -327.013262) (xy 441.828435 -327.068438) (xy 441.812367 -327.121845) (xy 441.788695 -327.172342)
			(xy 441.757922 -327.218855) (xy 441.720705 -327.260392) (xy 441.677837 -327.296067) (xy 441.630231 -327.325121)
			(xy 441.578902 -327.346933) (xy 441.524945 -327.361039) (xy 441.469508 -327.367139) (xy 441.413774 -327.365102)
			(xy 441.358931 -327.354972) (xy 441.306147 -327.336965) (xy 441.256547 -327.311464) (xy 441.211189 -327.279013)
			(xy 441.17104 -327.240304) (xy 441.136954 -327.196161) (xy 441.109658 -327.147526) (xy 441.089735 -327.095435)
			(xy 441.077609 -327.040998) (xy 441.073538 -326.985376) (xy 407.4668 -326.985376) (xy 407.4668 -327.294748)
			(xy 408.0256 -327.853548) (xy 464.15706 -327.853548)
		)
		(stroke
			(width 0)
			(type solid)
		)
		(fill yes)
		(layer "In13.Cu")
		(net "GND")
	)
	(gr_poly
		(pts
			(xy 11.197844 -115.011962) (xy 11.212414 -115.011485) (xy 11.240364 -115.003244) (xy 11.26485 -114.987446)
			(xy 11.283877 -114.965376) (xy 11.295899 -114.938831) (xy 11.299935 -114.909972) (xy 11.295657 -114.881148)
			(xy 11.290046 -114.86769) (xy 11.278873 -114.842377) (xy 11.26313 -114.789334) (xy 11.25521 -114.734574)
			(xy 11.25474 -114.706908) (xy 11.255253 -114.677919) (xy 11.263986 -114.620602) (xy 11.281312 -114.565274)
			(xy 11.293602 -114.539014) (xy 11.299915 -114.524908) (xy 11.304606 -114.494378) (xy 11.299962 -114.46384)
			(xy 11.286406 -114.436084) (xy 11.265178 -114.413646) (xy 11.251946 -114.405664) (xy 11.227014 -114.391064)
			(xy 11.181468 -114.355519) (xy 11.141803 -114.313511) (xy 11.108927 -114.266002) (xy 11.083592 -114.214078)
			(xy 11.066377 -114.158927) (xy 11.057675 -114.101812) (xy 11.057128 -114.072924) (xy 11.057614 -114.045673)
			(xy 11.06537 -113.991725) (xy 11.080725 -113.93943) (xy 11.103367 -113.889853) (xy 11.132833 -113.844003)
			(xy 11.168524 -113.802812) (xy 11.209715 -113.767121) (xy 11.255565 -113.737655) (xy 11.305142 -113.715013)
			(xy 11.357437 -113.699658) (xy 11.411385 -113.691902) (xy 11.465887 -113.691902) (xy 11.519835 -113.699658)
			(xy 11.57213 -113.715013) (xy 11.621707 -113.737655) (xy 11.667557 -113.767121) (xy 11.708748 -113.802812)
			(xy 11.744439 -113.844003) (xy 11.773905 -113.889853) (xy 11.796547 -113.93943) (xy 11.811902 -113.991725)
			(xy 11.819658 -114.045673) (xy 11.820144 -114.072924) (xy 11.819564 -114.103228) (xy 11.81 -114.163078)
			(xy 11.801094 -114.19205) (xy 11.797231 -114.205232) (xy 11.795913 -114.232659) (xy 11.801954 -114.259444)
			(xy 11.814916 -114.28365) (xy 11.833861 -114.303525) (xy 11.857419 -114.317631) (xy 11.883885 -114.324947)
			(xy 11.897614 -114.3254) (xy 12.238482 -114.3254) (xy 12.252212 -114.324952) (xy 12.27868 -114.317637)
			(xy 12.30224 -114.303531) (xy 12.321188 -114.283654) (xy 12.334151 -114.259446) (xy 12.340192 -114.232659)
			(xy 12.338874 -114.20523) (xy 12.335002 -114.19205) (xy 12.32609 -114.163079) (xy 12.316513 -114.10323)
			(xy 12.315952 -114.072924) (xy 12.316438 -114.045673) (xy 12.324194 -113.991725) (xy 12.339549 -113.93943)
			(xy 12.362191 -113.889853) (xy 12.391657 -113.844003) (xy 12.427348 -113.802812) (xy 12.468539 -113.767121)
			(xy 12.514389 -113.737655) (xy 12.563966 -113.715013) (xy 12.616261 -113.699658) (xy 12.670209 -113.691902)
			(xy 12.724711 -113.691902) (xy 12.778659 -113.699658) (xy 12.830954 -113.715013) (xy 12.880531 -113.737655)
			(xy 12.926381 -113.767121) (xy 12.967572 -113.802812) (xy 13.003263 -113.844003) (xy 13.032729 -113.889853)
			(xy 13.055371 -113.93943) (xy 13.070726 -113.991725) (xy 13.078482 -114.045673) (xy 13.078968 -114.072924)
			(xy 13.078434 -114.101811) (xy 13.069721 -114.158923) (xy 13.052497 -114.214069) (xy 13.027157 -114.265989)
			(xy 12.994279 -114.313495) (xy 12.954615 -114.355501) (xy 12.909072 -114.391048) (xy 12.88415 -114.405664)
			(xy 12.870937 -114.41367) (xy 12.849715 -114.436102) (xy 12.836164 -114.463849) (xy 12.831521 -114.494378)
			(xy 12.836211 -114.524899) (xy 12.842494 -114.539014) (xy 12.854744 -114.565289) (xy 12.872055 -114.620616)
			(xy 12.880818 -114.677922) (xy 12.881356 -114.706908) (xy 12.880898 -114.734574) (xy 12.872973 -114.789334)
			(xy 12.857217 -114.842374) (xy 12.84605 -114.86769) (xy 12.840351 -114.881122) (xy 12.83607 -114.909972)
			(xy 12.840109 -114.938857) (xy 12.852141 -114.965426) (xy 12.871186 -114.987516) (xy 12.895694 -115.00333)
			(xy 12.923669 -115.011579) (xy 12.938252 -115.011962) (xy 40.971724 -115.011962) (xy 45.68952 -110.294166)
			(xy 46.814994 -110.294166) (xy 46.818804 -110.293658) (xy 46.832943 -110.291652) (xy 46.86142 -110.289492)
			(xy 46.8757 -110.28934) (xy 46.88998 -110.289481) (xy 46.918458 -110.291645) (xy 46.932596 -110.293658)
			(xy 46.936406 -110.294166) (xy 48.904906 -110.294166) (xy 48.920548 -110.293596) (xy 48.95037 -110.284139)
			(xy 48.975939 -110.266112) (xy 48.994864 -110.2412) (xy 49.005375 -110.211734) (xy 49.006506 -110.196122)
			(xy 49.007898 -110.169508) (xy 49.017147 -110.117024) (xy 49.03361 -110.066339) (xy 49.056967 -110.018437)
			(xy 49.086763 -109.974253) (xy 49.122419 -109.934645) (xy 49.16324 -109.900386) (xy 49.208432 -109.87214)
			(xy 49.257114 -109.850459) (xy 49.308341 -109.835765) (xy 49.361114 -109.828342) (xy 49.38776 -109.827822)
			(xy 49.416147 -109.828347) (xy 49.472293 -109.836768) (xy 49.526572 -109.853415) (xy 49.577785 -109.877921)
			(xy 49.624801 -109.909745) (xy 49.666584 -109.948183) (xy 49.702209 -109.992388) (xy 49.730892 -110.041384)
			(xy 49.751999 -110.094089) (xy 49.765063 -110.149339) (xy 49.767998 -110.17758) (xy 49.769522 -110.196122)
			(xy 49.818544 -110.245144) (xy 49.86909 -110.194598) (xy 49.887074 -110.177241) (xy 49.927486 -110.147835)
			(xy 49.972004 -110.12512) (xy 50.01953 -110.109657) (xy 50.068891 -110.101827) (xy 50.09388 -110.10138)
			(xy 54.899052 -110.10138) (xy 54.913871 -110.100867) (xy 54.94226 -110.092353) (xy 54.967015 -110.076054)
			(xy 54.986056 -110.053341) (xy 54.997782 -110.026121) (xy 55.00121 -109.996681) (xy 54.999128 -109.982)
			(xy 54.996308 -109.965315) (xy 54.99326 -109.93161) (xy 54.993032 -109.91469) (xy 54.993518 -109.887439)
			(xy 55.001274 -109.833491) (xy 55.016629 -109.781196) (xy 55.039271 -109.731619) (xy 55.068737 -109.685769)
			(xy 55.104428 -109.644578) (xy 55.145619 -109.608887) (xy 55.191469 -109.579421) (xy 55.241046 -109.556779)
			(xy 55.293341 -109.541424) (xy 55.347289 -109.533668) (xy 55.401791 -109.533668) (xy 55.455739 -109.541424)
			(xy 55.508034 -109.556779) (xy 55.557611 -109.579421) (xy 55.603461 -109.608887) (xy 55.644652 -109.644578)
			(xy 55.680343 -109.685769) (xy 55.709809 -109.731619) (xy 55.732451 -109.781196) (xy 55.747806 -109.833491)
			(xy 55.755562 -109.887439) (xy 55.756048 -109.91469) (xy 55.755844 -109.931612) (xy 55.752792 -109.965317)
			(xy 55.749952 -109.982) (xy 55.747854 -109.996686) (xy 55.75126 -110.026142) (xy 55.76298 -110.053381)
			(xy 55.782026 -110.076108) (xy 55.806795 -110.092411) (xy 55.835202 -110.100916) (xy 55.850028 -110.10138)
			(xy 57.45734 -110.10138) (xy 57.482323 -110.101894) (xy 57.531668 -110.109749) (xy 57.579182 -110.125213)
			(xy 57.623698 -110.147906) (xy 57.664125 -110.177272) (xy 57.68213 -110.194598) (xy 57.781698 -110.294166)
			(xy 64.889126 -110.294166) (xy 65.652904 -109.530388) (xy 65.65138 -109.507274) (xy 65.650618 -109.483906)
			(xy 65.651138 -109.455921) (xy 65.659893 -109.40064) (xy 65.677189 -109.34741) (xy 65.702599 -109.297541)
			(xy 65.735498 -109.252261) (xy 65.775076 -109.212685) (xy 65.820358 -109.179789) (xy 65.870228 -109.154381)
			(xy 65.92346 -109.137089) (xy 65.978741 -109.128337) (xy 66.006726 -109.127798) (xy 66.030094 -109.12856)
			(xy 66.053208 -109.130084) (xy 66.150744 -109.032548) (xy 74.488802 -109.032548) (xy 78.273656 -105.247694)
			(xy 110.345474 -105.247694) (xy 112.42421 -103.168958) (xy 112.442193 -103.1516) (xy 112.482603 -103.12219)
			(xy 112.527121 -103.099474) (xy 112.574648 -103.08401) (xy 112.62401 -103.076182) (xy 112.649 -103.07574)
			(xy 113.30432 -103.07574) (xy 116.27104 -100.109274) (xy 116.266468 -100.083112) (xy 116.26364 -100.066364)
			(xy 116.260592 -100.032532) (xy 116.260372 -100.015548) (xy 116.260858 -99.988297) (xy 116.268614 -99.934349)
			(xy 116.283969 -99.882054) (xy 116.306611 -99.832477) (xy 116.336077 -99.786627) (xy 116.371768 -99.745436)
			(xy 116.412959 -99.709745) (xy 116.458809 -99.680279) (xy 116.508386 -99.657637) (xy 116.560681 -99.642282)
			(xy 116.614629 -99.634526) (xy 116.669131 -99.634526) (xy 116.723079 -99.642282) (xy 116.775374 -99.657637)
			(xy 116.824951 -99.680279) (xy 116.870801 -99.709745) (xy 116.911992 -99.745436) (xy 116.947683 -99.786627)
			(xy 116.977149 -99.832477) (xy 116.999791 -99.882054) (xy 117.015146 -99.934349) (xy 117.022902 -99.988297)
			(xy 117.023388 -100.015548) (xy 117.022626 -100.038408) (xy 117.02226 -100.052259) (xy 117.028089 -100.079333)
			(xy 117.040977 -100.103847) (xy 117.059977 -100.123997) (xy 117.083692 -100.138301) (xy 117.110378 -100.145709)
			(xy 117.124226 -100.146104) (xy 157.705298 -100.146104) (xy 158.340552 -99.510596) (xy 158.340552 -99.294188)
			(xy 158.341064 -99.269205) (xy 158.348916 -99.219859) (xy 158.36438 -99.172344) (xy 158.387074 -99.127828)
			(xy 158.416443 -99.087403) (xy 158.43377 -99.069398) (xy 159.131508 -98.37166) (xy 159.131508 -80.28813)
			(xy 159.727646 -79.691992) (xy 159.731202 -79.684118) (xy 159.737128 -79.671903) (xy 159.750476 -79.648259)
			(xy 159.757872 -79.636874) (xy 159.757872 -79.3623) (xy 159.758383 -79.337316) (xy 159.766232 -79.287967)
			(xy 159.781691 -79.240449) (xy 159.80438 -79.195928) (xy 159.833743 -79.155496) (xy 159.85109 -79.13751)
			(xy 160.15335 -78.83525) (xy 160.171334 -78.817894) (xy 160.211746 -78.788491) (xy 160.256264 -78.765781)
			(xy 160.303791 -78.750324) (xy 160.353152 -78.742502) (xy 160.37814 -78.742032) (xy 161.036 -78.742032)
			(xy 161.060984 -78.742543) (xy 161.110331 -78.750393) (xy 161.157847 -78.765855) (xy 161.202366 -78.788547)
			(xy 161.242794 -78.817914) (xy 161.26079 -78.83525) (xy 161.34207 -78.91653) (xy 163.147756 -78.91653)
			(xy 163.158424 -78.8797) (xy 163.166987 -78.851659) (xy 163.191513 -78.798405) (xy 163.223893 -78.749528)
			(xy 163.263365 -78.706177) (xy 163.309002 -78.66937) (xy 163.359729 -78.639973) (xy 163.414355 -78.618678)
			(xy 163.471594 -78.605986) (xy 163.500816 -78.603602) (xy 163.515516 -78.602144) (xy 163.543201 -78.591877)
			(xy 163.566796 -78.574124) (xy 163.584329 -78.550365) (xy 163.594338 -78.522586) (xy 163.595986 -78.493104)
			(xy 163.593018 -78.478634) (xy 163.588138 -78.456863) (xy 163.582913 -78.412551) (xy 163.582604 -78.390242)
			(xy 163.583064 -78.362989) (xy 163.590815 -78.309039) (xy 163.606166 -78.25674) (xy 163.628803 -78.207158)
			(xy 163.658266 -78.161303) (xy 163.693955 -78.120107) (xy 163.735143 -78.08441) (xy 163.780993 -78.054938)
			(xy 163.83057 -78.032292) (xy 163.882866 -78.016931) (xy 163.936816 -78.00917) (xy 163.99132 -78.009165)
			(xy 164.045271 -78.016918) (xy 164.09757 -78.032269) (xy 164.147151 -78.054908) (xy 164.193005 -78.084372)
			(xy 164.2342 -78.120062) (xy 164.269896 -78.161251) (xy 164.299367 -78.207102) (xy 164.322012 -78.25668)
			(xy 164.337371 -78.308976) (xy 164.345131 -78.362926) (xy 164.345134 -78.41743) (xy 164.33738 -78.471381)
			(xy 164.322027 -78.523679) (xy 164.299388 -78.573259) (xy 164.269922 -78.619113) (xy 164.234231 -78.660307)
			(xy 164.193041 -78.696002) (xy 164.147189 -78.725471) (xy 164.097611 -78.748115) (xy 164.045314 -78.763473)
			(xy 163.991364 -78.771232) (xy 163.964112 -78.77175) (xy 163.929822 -78.770226) (xy 163.919372 -78.769801)
			(xy 163.899545 -78.776384) (xy 163.883982 -78.790323) (xy 163.87526 -78.809307) (xy 163.874824 -78.830195)
			(xy 163.87826 -78.840076) (xy 163.88216 -78.849813) (xy 163.889022 -78.869636) (xy 163.891976 -78.8797)
			(xy 163.902644 -78.91653) (xy 168.566846 -78.91653) (xy 169.225214 -78.258162) (xy 169.225214 -57.669684)
			(xy 169.201565 -57.654764) (xy 169.158503 -57.619094) (xy 169.12111 -57.57752) (xy 169.090186 -57.530934)
			(xy 169.066392 -57.480332) (xy 169.05024 -57.4268) (xy 169.042075 -57.371483) (xy 169.042071 -57.315567)
			(xy 169.050229 -57.260249) (xy 169.066375 -57.206714) (xy 169.090161 -57.15611) (xy 169.12108 -57.109519)
			(xy 169.158467 -57.067941) (xy 169.201524 -57.032265) (xy 169.225214 -57.017412) (xy 169.225214 -46.60646)
			(xy 167.1955 -44.576746) (xy 165.888924 -44.576746) (xy 165.874079 -44.577254) (xy 165.845643 -44.585786)
			(xy 165.820862 -44.602137) (xy 165.801831 -44.624924) (xy 165.790158 -44.652222) (xy 165.78683 -44.681724)
			(xy 165.792128 -44.710937) (xy 165.805604 -44.737391) (xy 165.815518 -44.74845) (xy 165.835187 -44.769879)
			(xy 165.868463 -44.817584) (xy 165.894116 -44.869785) (xy 165.911553 -44.925274) (xy 165.92037 -44.982766)
			(xy 165.920928 -45.011848) (xy 165.920442 -45.039099) (xy 165.912686 -45.093047) (xy 165.897331 -45.145342)
			(xy 165.874689 -45.194919) (xy 165.845223 -45.240769) (xy 165.809532 -45.28196) (xy 165.768341 -45.317651)
			(xy 165.722491 -45.347117) (xy 165.672914 -45.369759) (xy 165.620619 -45.385114) (xy 165.566671 -45.39287)
			(xy 165.512169 -45.39287) (xy 165.458221 -45.385114) (xy 165.405926 -45.369759) (xy 165.356349 -45.347117)
			(xy 165.310499 -45.317651) (xy 165.269308 -45.28196) (xy 165.233617 -45.240769) (xy 165.204151 -45.194919)
			(xy 165.181509 -45.145342) (xy 165.166154 -45.093047) (xy 165.158398 -45.039099) (xy 165.157912 -45.011848)
			(xy 165.158461 -44.982767) (xy 165.167291 -44.92528) (xy 165.184738 -44.869796) (xy 165.210399 -44.817601)
			(xy 165.243679 -44.769902) (xy 165.263322 -44.74845) (xy 165.273198 -44.737362) (xy 165.286652 -44.710908)
			(xy 165.291937 -44.681704) (xy 165.288607 -44.652212) (xy 165.276945 -44.624921) (xy 165.257932 -44.602132)
			(xy 165.233172 -44.585767) (xy 165.204755 -44.577207) (xy 165.189916 -44.576746) (xy 159.943292 -44.576746)
			(xy 159.943292 -44.682156) (xy 159.942795 -44.709556) (xy 159.934915 -44.763788) (xy 159.919368 -44.816338)
			(xy 159.896473 -44.866128) (xy 159.8667 -44.912136) (xy 159.849058 -44.933108) (xy 159.83982 -44.944407)
			(xy 159.827635 -44.970914) (xy 159.823457 -44.999787) (xy 159.827628 -45.028661) (xy 159.839806 -45.055172)
			(xy 159.849058 -45.066458) (xy 159.866698 -45.08739) (xy 159.896421 -45.133357) (xy 159.919259 -45.183104)
			(xy 159.934743 -45.235607) (xy 159.942554 -45.289786) (xy 159.943038 -45.317156) (xy 159.942552 -45.344407)
			(xy 159.934796 -45.398355) (xy 159.919441 -45.45065) (xy 159.896799 -45.500227) (xy 159.867333 -45.546077)
			(xy 159.831642 -45.587268) (xy 159.790451 -45.622959) (xy 159.744601 -45.652425) (xy 159.695024 -45.675067)
			(xy 159.642729 -45.690422) (xy 159.588781 -45.698178) (xy 159.534279 -45.698178) (xy 159.480331 -45.690422)
			(xy 159.428036 -45.675067) (xy 159.378459 -45.652425) (xy 159.332609 -45.622959) (xy 159.291418 -45.587268)
			(xy 159.255727 -45.546077) (xy 159.226261 -45.500227) (xy 159.203619 -45.45065) (xy 159.188264 -45.398355)
			(xy 159.180508 -45.344407) (xy 159.180022 -45.317156) (xy 159.180497 -45.289787) (xy 159.188327 -45.235612)
			(xy 159.203819 -45.183113) (xy 159.226657 -45.133367) (xy 159.256369 -45.087395) (xy 159.274002 -45.066458)
			(xy 159.283141 -45.05511) (xy 159.29523 -45.028615) (xy 159.299369 -44.999787) (xy 159.295223 -44.970961)
			(xy 159.283127 -44.944468) (xy 159.274002 -44.933108) (xy 159.256325 -44.912162) (xy 159.226536 -44.866157)
			(xy 159.203638 -44.816362) (xy 159.188102 -44.763802) (xy 159.18025 -44.70956) (xy 159.179768 -44.682156)
			(xy 159.179768 -44.576746) (xy 156.82595 -44.576746) (xy 156.810672 -44.577256) (xy 156.781481 -44.586284)
			(xy 156.75627 -44.603546) (xy 156.737296 -44.627496) (xy 156.726259 -44.655988) (xy 156.724149 -44.68647)
			(xy 156.727144 -44.70146) (xy 156.731885 -44.722993) (xy 156.736981 -44.76679) (xy 156.737304 -44.788836)
			(xy 156.737304 -45.652436) (xy 156.736807 -45.680016) (xy 156.728837 -45.734596) (xy 156.713084 -45.787458)
			(xy 156.689877 -45.837498) (xy 156.6597 -45.883671) (xy 156.6418 -45.904658) (xy 156.635964 -45.911822)
			(xy 156.629399 -45.929078) (xy 156.629402 -45.947541) (xy 156.635974 -45.964795) (xy 156.6418 -45.971968)
			(xy 156.659643 -45.992955) (xy 156.689732 -46.039096) (xy 156.71287 -46.089086) (xy 156.728576 -46.141885)
			(xy 156.736523 -46.196394) (xy 156.736846 -46.213268) (xy 164.684962 -46.213268) (xy 164.689033 -46.157646)
			(xy 164.701159 -46.103209) (xy 164.721082 -46.051118) (xy 164.748378 -46.002483) (xy 164.782464 -45.95834)
			(xy 164.822613 -45.919631) (xy 164.867971 -45.88718) (xy 164.917571 -45.861679) (xy 164.970355 -45.843672)
			(xy 165.025198 -45.833542) (xy 165.080932 -45.831505) (xy 165.136369 -45.837605) (xy 165.190326 -45.851711)
			(xy 165.241655 -45.873523) (xy 165.289261 -45.902577) (xy 165.332129 -45.938252) (xy 165.369346 -45.979789)
			(xy 165.400119 -46.026302) (xy 165.423791 -46.076799) (xy 165.439859 -46.130206) (xy 165.447979 -46.185382)
			(xy 165.448488 -46.213268) (xy 165.447979 -46.241154) (xy 165.439859 -46.29633) (xy 165.423791 -46.349737)
			(xy 165.400119 -46.400234) (xy 165.369346 -46.446747) (xy 165.332129 -46.488284) (xy 165.289261 -46.523959)
			(xy 165.241655 -46.553013) (xy 165.190326 -46.574825) (xy 165.136369 -46.588931) (xy 165.080932 -46.595031)
			(xy 165.025198 -46.592994) (xy 164.970355 -46.582864) (xy 164.917571 -46.564857) (xy 164.867971 -46.539356)
			(xy 164.822613 -46.506905) (xy 164.782464 -46.468196) (xy 164.748378 -46.424053) (xy 164.721082 -46.375418)
			(xy 164.701159 -46.323327) (xy 164.689033 -46.26889) (xy 164.684962 -46.213268) (xy 156.736846 -46.213268)
			(xy 156.73705 -46.223936) (xy 156.736564 -46.251187) (xy 156.728808 -46.305135) (xy 156.713453 -46.35743)
			(xy 156.690811 -46.407007) (xy 156.661345 -46.452857) (xy 156.625654 -46.494048) (xy 156.584463 -46.529739)
			(xy 156.538613 -46.559205) (xy 156.489036 -46.581847) (xy 156.436741 -46.597202) (xy 156.382793 -46.604958)
			(xy 156.328291 -46.604958) (xy 156.274343 -46.597202) (xy 156.222048 -46.581847) (xy 156.172471 -46.559205)
			(xy 156.126621 -46.529739) (xy 156.08543 -46.494048) (xy 156.049739 -46.452857) (xy 156.020273 -46.407007)
			(xy 155.997631 -46.35743) (xy 155.982276 -46.305135) (xy 155.97452 -46.251187) (xy 155.974034 -46.223936)
			(xy 155.974536 -46.196393) (xy 155.982494 -46.141883) (xy 155.998205 -46.089084) (xy 156.021344 -46.039092)
			(xy 156.051429 -45.992946) (xy 156.069284 -45.971968) (xy 156.075061 -45.964778) (xy 156.081544 -45.947525)
			(xy 156.081548 -45.929094) (xy 156.075071 -45.911839) (xy 156.069284 -45.904658) (xy 156.051411 -45.883652)
			(xy 156.021264 -45.837469) (xy 155.998069 -45.787431) (xy 155.982305 -45.73458) (xy 155.974302 -45.680011)
			(xy 155.97378 -45.652436) (xy 155.97378 -44.825412) (xy 155.97378 -44.816268) (xy 155.97378 -44.788836)
			(xy 155.97409 -44.766789) (xy 155.97918 -44.722989) (xy 155.98394 -44.70146) (xy 155.986905 -44.686479)
			(xy 155.984747 -44.656028) (xy 155.973694 -44.627573) (xy 155.954731 -44.60365) (xy 155.92955 -44.586394)
			(xy 155.900397 -44.577341) (xy 155.885134 -44.576746) (xy 151.342344 -44.576746) (xy 150.848568 -44.08297)
			(xy 146.130772 -44.08297) (xy 146.075908 -44.137834) (xy 145.911316 -44.137834) (xy 144.542002 -42.76852)
			(xy 144.508982 -42.785538) (xy 144.481808 -42.798893) (xy 144.424287 -42.817786) (xy 144.364503 -42.827356)
			(xy 144.33423 -42.827956) (xy 144.306976 -42.827472) (xy 144.253023 -42.81972) (xy 144.200721 -42.804367)
			(xy 144.151137 -42.781729) (xy 144.10528 -42.752264) (xy 144.064082 -42.716573) (xy 144.028383 -42.675383)
			(xy 143.998909 -42.629531) (xy 143.97626 -42.579952) (xy 143.960897 -42.527654) (xy 143.953133 -42.473702)
			(xy 143.952722 -42.446448) (xy 143.953301 -42.416174) (xy 143.962868 -42.356386) (xy 143.981768 -42.298863)
			(xy 143.99514 -42.271696) (xy 144.012158 -42.238676) (xy 141.626844 -39.853362) (xy 141.616391 -39.843642)
			(xy 141.591384 -39.829904) (xy 141.563552 -39.823621) (xy 141.535068 -39.825283) (xy 141.508156 -39.83476)
			(xy 141.484916 -39.851313) (xy 141.467163 -39.873649) (xy 141.461236 -39.886636) (xy 141.45005 -39.91248)
			(xy 141.421188 -39.960834) (xy 141.38553 -40.004419) (xy 141.343852 -40.042288) (xy 141.29706 -40.073619)
			(xy 141.24617 -40.097731) (xy 141.192289 -40.114098) (xy 141.136586 -40.122367) (xy 141.10843 -40.122856)
			(xy 141.081176 -40.122372) (xy 141.027223 -40.11462) (xy 140.974921 -40.099267) (xy 140.925337 -40.076629)
			(xy 140.87948 -40.047164) (xy 140.838282 -40.011473) (xy 140.802583 -39.970283) (xy 140.773109 -39.924431)
			(xy 140.75046 -39.874852) (xy 140.735097 -39.822554) (xy 140.727333 -39.768602) (xy 140.726922 -39.741348)
			(xy 140.727429 -39.713194) (xy 140.73571 -39.657497) (xy 140.752084 -39.603621) (xy 140.776196 -39.552736)
			(xy 140.807522 -39.505945) (xy 140.845383 -39.464265) (xy 140.888957 -39.4286) (xy 140.937299 -39.399724)
			(xy 140.963142 -39.388542) (xy 140.976173 -39.382681) (xy 140.99856 -39.364948) (xy 141.015149 -39.341701)
			(xy 141.024638 -39.314764) (xy 141.026281 -39.286251) (xy 141.01995 -39.258402) (xy 141.006142 -39.233403)
			(xy 140.996416 -39.222934) (xy 138.834876 -37.061394) (xy 138.42619 -37.061394) (xy 138.41274 -37.061808)
			(xy 138.386775 -37.068837) (xy 138.363548 -37.082404) (xy 138.344671 -37.101567) (xy 138.331454 -37.124996)
			(xy 138.324817 -37.151063) (xy 138.32459 -37.164518) (xy 138.32459 -37.169852) (xy 138.324104 -37.197103)
			(xy 138.316348 -37.251051) (xy 138.300993 -37.303346) (xy 138.278351 -37.352923) (xy 138.248885 -37.398773)
			(xy 138.213194 -37.439964) (xy 138.172003 -37.475655) (xy 138.126153 -37.505121) (xy 138.076576 -37.527763)
			(xy 138.024281 -37.543118) (xy 137.970333 -37.550874) (xy 137.915831 -37.550874) (xy 137.861883 -37.543118)
			(xy 137.809588 -37.527763) (xy 137.760011 -37.505121) (xy 137.714161 -37.475655) (xy 137.67297 -37.439964)
			(xy 137.637279 -37.398773) (xy 137.607813 -37.352923) (xy 137.585171 -37.303346) (xy 137.569816 -37.251051)
			(xy 137.56206 -37.197103) (xy 137.561574 -37.169852) (xy 137.561574 -37.164518) (xy 137.561362 -37.151063)
			(xy 137.554723 -37.124995) (xy 137.541504 -37.101568) (xy 137.522623 -37.082407) (xy 137.499392 -37.068845)
			(xy 137.473424 -37.061824) (xy 137.459974 -37.061394) (xy 131.100576 -37.061394) (xy 129.564384 -35.525202)
			(xy 129.564384 -29.820362) (xy 127.754126 -28.010104) (xy 103.617522 -28.010104) (xy 102.410768 -29.216858)
			(xy 102.410768 -29.450792) (xy 117.047262 -29.450792) (xy 117.051333 -29.39517) (xy 117.063459 -29.340733)
			(xy 117.083382 -29.288642) (xy 117.110678 -29.240007) (xy 117.144764 -29.195864) (xy 117.184913 -29.157155)
			(xy 117.230271 -29.124704) (xy 117.279871 -29.099203) (xy 117.332655 -29.081196) (xy 117.387498 -29.071066)
			(xy 117.443232 -29.069029) (xy 117.498669 -29.075129) (xy 117.552626 -29.089235) (xy 117.603955 -29.111047)
			(xy 117.651561 -29.140101) (xy 117.694429 -29.175776) (xy 117.731646 -29.217313) (xy 117.762419 -29.263826)
			(xy 117.786091 -29.314323) (xy 117.802159 -29.36773) (xy 117.810279 -29.422906) (xy 117.810788 -29.450792)
			(xy 117.810279 -29.478678) (xy 117.802159 -29.533854) (xy 117.786091 -29.587261) (xy 117.762419 -29.637758)
			(xy 117.731646 -29.684271) (xy 117.694429 -29.725808) (xy 117.651561 -29.761483) (xy 117.603955 -29.790537)
			(xy 117.552626 -29.812349) (xy 117.498669 -29.826455) (xy 117.443232 -29.832555) (xy 117.387498 -29.830518)
			(xy 117.332655 -29.820388) (xy 117.279871 -29.802381) (xy 117.230271 -29.77688) (xy 117.184913 -29.744429)
			(xy 117.144764 -29.70572) (xy 117.110678 -29.661577) (xy 117.083382 -29.612942) (xy 117.063459 -29.560851)
			(xy 117.051333 -29.506414) (xy 117.047262 -29.450792) (xy 102.410768 -29.450792) (xy 102.410768 -29.710888)
			(xy 102.542594 -29.842714) (xy 108.596682 -29.842714) (xy 108.600753 -29.787092) (xy 108.612879 -29.732655)
			(xy 108.632802 -29.680564) (xy 108.660098 -29.631929) (xy 108.694184 -29.587786) (xy 108.734333 -29.549077)
			(xy 108.779691 -29.516626) (xy 108.829291 -29.491125) (xy 108.882075 -29.473118) (xy 108.936918 -29.462988)
			(xy 108.992652 -29.460951) (xy 109.048089 -29.467051) (xy 109.102046 -29.481157) (xy 109.153375 -29.502969)
			(xy 109.200981 -29.532023) (xy 109.243849 -29.567698) (xy 109.281066 -29.609235) (xy 109.311839 -29.655748)
			(xy 109.335511 -29.706245) (xy 109.351579 -29.759652) (xy 109.359699 -29.814828) (xy 109.360208 -29.842714)
			(xy 109.359699 -29.8706) (xy 109.351579 -29.925776) (xy 109.335511 -29.979183) (xy 109.311839 -30.02968)
			(xy 109.281066 -30.076193) (xy 109.243849 -30.11773) (xy 109.200981 -30.153405) (xy 109.153375 -30.182459)
			(xy 109.102046 -30.204271) (xy 109.048089 -30.218377) (xy 108.992652 -30.224477) (xy 108.936918 -30.22244)
			(xy 108.882075 -30.21231) (xy 108.829291 -30.194303) (xy 108.779691 -30.168802) (xy 108.734333 -30.136351)
			(xy 108.694184 -30.097642) (xy 108.660098 -30.053499) (xy 108.632802 -30.004864) (xy 108.612879 -29.952773)
			(xy 108.600753 -29.898336) (xy 108.596682 -29.842714) (xy 102.542594 -29.842714) (xy 102.959154 -30.259274)
			(xy 104.220772 -30.259274) (xy 104.826308 -30.86481) (xy 108.555788 -30.86481) (xy 108.559859 -30.809188)
			(xy 108.571985 -30.754751) (xy 108.591908 -30.70266) (xy 108.619204 -30.654025) (xy 108.65329 -30.609882)
			(xy 108.693439 -30.571173) (xy 108.738797 -30.538722) (xy 108.788397 -30.513221) (xy 108.841181 -30.495214)
			(xy 108.896024 -30.485084) (xy 108.951758 -30.483047) (xy 109.007195 -30.489147) (xy 109.061152 -30.503253)
			(xy 109.112481 -30.525065) (xy 109.160087 -30.554119) (xy 109.202955 -30.589794) (xy 109.240172 -30.631331)
			(xy 109.270945 -30.677844) (xy 109.294617 -30.728341) (xy 109.310685 -30.781748) (xy 109.318805 -30.836924)
			(xy 109.319314 -30.86481) (xy 109.318805 -30.892696) (xy 109.310685 -30.947872) (xy 109.294617 -31.001279)
			(xy 109.270945 -31.051776) (xy 109.240172 -31.098289) (xy 109.202955 -31.139826) (xy 109.160087 -31.175501)
			(xy 109.112481 -31.204555) (xy 109.061152 -31.226367) (xy 109.007195 -31.240473) (xy 108.951758 -31.246573)
			(xy 108.896024 -31.244536) (xy 108.841181 -31.234406) (xy 108.788397 -31.216399) (xy 108.738797 -31.190898)
			(xy 108.693439 -31.158447) (xy 108.65329 -31.119738) (xy 108.619204 -31.075595) (xy 108.591908 -31.02696)
			(xy 108.571985 -30.974869) (xy 108.559859 -30.920432) (xy 108.555788 -30.86481) (xy 104.826308 -30.86481)
			(xy 106.250486 -32.288988) (xy 110.242858 -32.288988) (xy 110.257988 -32.28844) (xy 110.286922 -32.279579)
			(xy 110.311985 -32.262624) (xy 110.330976 -32.239066) (xy 110.342225 -32.210974) (xy 110.344742 -32.180819)
			(xy 110.338307 -32.151252) (xy 110.323485 -32.124871) (xy 110.312962 -32.113982) (xy 110.294644 -32.095908)
			(xy 110.262539 -32.055691) (xy 110.236128 -32.011525) (xy 110.215889 -31.964212) (xy 110.20219 -31.914608)
			(xy 110.195279 -31.863614) (xy 110.194852 -31.837884) (xy 110.195338 -31.810633) (xy 110.203094 -31.756685)
			(xy 110.218449 -31.70439) (xy 110.241091 -31.654813) (xy 110.270557 -31.608963) (xy 110.306248 -31.567772)
			(xy 110.347439 -31.532081) (xy 110.393289 -31.502615) (xy 110.442866 -31.479973) (xy 110.495161 -31.464618)
			(xy 110.549109 -31.456862) (xy 110.603611 -31.456862) (xy 110.657559 -31.464618) (xy 110.709854 -31.479973)
			(xy 110.759431 -31.502615) (xy 110.805281 -31.532081) (xy 110.846472 -31.567772) (xy 110.882163 -31.608963)
			(xy 110.911629 -31.654813) (xy 110.934271 -31.70439) (xy 110.949626 -31.756685) (xy 110.957382 -31.810633)
			(xy 110.957868 -31.837884) (xy 110.957448 -31.863615) (xy 110.950537 -31.91461) (xy 110.936838 -31.964215)
			(xy 110.9166 -32.01153) (xy 110.890189 -32.055697) (xy 110.858084 -32.095916) (xy 110.839758 -32.113982)
			(xy 110.829211 -32.124836) (xy 110.814434 -32.151229) (xy 110.808032 -32.180793) (xy 110.810565 -32.210935)
			(xy 110.821812 -32.239015) (xy 110.840787 -32.262571) (xy 110.865827 -32.279541) (xy 110.894739 -32.288436)
			(xy 110.909862 -32.288988) (xy 111.736124 -32.288988) (xy 111.790988 -32.234124) (xy 114.314478 -32.234124)
			(xy 117.765322 -35.684968) (xy 126.270002 -35.684968) (xy 126.274073 -35.629346) (xy 126.286199 -35.574909)
			(xy 126.306122 -35.522818) (xy 126.333418 -35.474183) (xy 126.367504 -35.43004) (xy 126.407653 -35.391331)
			(xy 126.453011 -35.35888) (xy 126.502611 -35.333379) (xy 126.555395 -35.315372) (xy 126.610238 -35.305242)
			(xy 126.665972 -35.303205) (xy 126.721409 -35.309305) (xy 126.775366 -35.323411) (xy 126.826695 -35.345223)
			(xy 126.874301 -35.374277) (xy 126.917169 -35.409952) (xy 126.954386 -35.451489) (xy 126.985159 -35.498002)
			(xy 127.008831 -35.548499) (xy 127.024899 -35.601906) (xy 127.033019 -35.657082) (xy 127.033528 -35.684968)
			(xy 127.453642 -35.684968) (xy 127.457713 -35.629346) (xy 127.469839 -35.574909) (xy 127.489762 -35.522818)
			(xy 127.517058 -35.474183) (xy 127.551144 -35.43004) (xy 127.591293 -35.391331) (xy 127.636651 -35.35888)
			(xy 127.686251 -35.333379) (xy 127.739035 -35.315372) (xy 127.793878 -35.305242) (xy 127.849612 -35.303205)
			(xy 127.905049 -35.309305) (xy 127.959006 -35.323411) (xy 128.010335 -35.345223) (xy 128.057941 -35.374277)
			(xy 128.100809 -35.409952) (xy 128.138026 -35.451489) (xy 128.168799 -35.498002) (xy 128.192471 -35.548499)
			(xy 128.208539 -35.601906) (xy 128.216659 -35.657082) (xy 128.217168 -35.684968) (xy 128.487422 -35.684968)
			(xy 128.491493 -35.629346) (xy 128.503619 -35.574909) (xy 128.523542 -35.522818) (xy 128.550838 -35.474183)
			(xy 128.584924 -35.43004) (xy 128.625073 -35.391331) (xy 128.670431 -35.35888) (xy 128.720031 -35.333379)
			(xy 128.772815 -35.315372) (xy 128.827658 -35.305242) (xy 128.883392 -35.303205) (xy 128.938829 -35.309305)
			(xy 128.992786 -35.323411) (xy 129.044115 -35.345223) (xy 129.091721 -35.374277) (xy 129.134589 -35.409952)
			(xy 129.171806 -35.451489) (xy 129.202579 -35.498002) (xy 129.226251 -35.548499) (xy 129.242319 -35.601906)
			(xy 129.250439 -35.657082) (xy 129.250948 -35.684968) (xy 129.250439 -35.712854) (xy 129.242319 -35.76803)
			(xy 129.226251 -35.821437) (xy 129.202579 -35.871934) (xy 129.171806 -35.918447) (xy 129.134589 -35.959984)
			(xy 129.091721 -35.995659) (xy 129.044115 -36.024713) (xy 128.992786 -36.046525) (xy 128.938829 -36.060631)
			(xy 128.883392 -36.066731) (xy 128.827658 -36.064694) (xy 128.772815 -36.054564) (xy 128.720031 -36.036557)
			(xy 128.670431 -36.011056) (xy 128.625073 -35.978605) (xy 128.584924 -35.939896) (xy 128.550838 -35.895753)
			(xy 128.523542 -35.847118) (xy 128.503619 -35.795027) (xy 128.491493 -35.74059) (xy 128.487422 -35.684968)
			(xy 128.217168 -35.684968) (xy 128.216659 -35.712854) (xy 128.208539 -35.76803) (xy 128.192471 -35.821437)
			(xy 128.168799 -35.871934) (xy 128.138026 -35.918447) (xy 128.100809 -35.959984) (xy 128.057941 -35.995659)
			(xy 128.010335 -36.024713) (xy 127.959006 -36.046525) (xy 127.905049 -36.060631) (xy 127.849612 -36.066731)
			(xy 127.793878 -36.064694) (xy 127.739035 -36.054564) (xy 127.686251 -36.036557) (xy 127.636651 -36.011056)
			(xy 127.591293 -35.978605) (xy 127.551144 -35.939896) (xy 127.517058 -35.895753) (xy 127.489762 -35.847118)
			(xy 127.469839 -35.795027) (xy 127.457713 -35.74059) (xy 127.453642 -35.684968) (xy 127.033528 -35.684968)
			(xy 127.033019 -35.712854) (xy 127.024899 -35.76803) (xy 127.008831 -35.821437) (xy 126.985159 -35.871934)
			(xy 126.954386 -35.918447) (xy 126.917169 -35.959984) (xy 126.874301 -35.995659) (xy 126.826695 -36.024713)
			(xy 126.775366 -36.046525) (xy 126.721409 -36.060631) (xy 126.665972 -36.066731) (xy 126.610238 -36.064694)
			(xy 126.555395 -36.054564) (xy 126.502611 -36.036557) (xy 126.453011 -36.011056) (xy 126.407653 -35.978605)
			(xy 126.367504 -35.939896) (xy 126.333418 -35.895753) (xy 126.306122 -35.847118) (xy 126.286199 -35.795027)
			(xy 126.274073 -35.74059) (xy 126.270002 -35.684968) (xy 117.765322 -35.684968) (xy 118.803928 -36.723574)
			(xy 118.825498 -36.736245) (xy 118.86543 -36.766377) (xy 118.901086 -36.801467) (xy 118.931854 -36.840911)
			(xy 118.944898 -36.862258) (xy 118.9482 -36.867846) (xy 119.43588 -37.355526) (xy 122.015502 -37.355526)
			(xy 122.019573 -37.299904) (xy 122.031699 -37.245467) (xy 122.051622 -37.193376) (xy 122.078918 -37.144741)
			(xy 122.113004 -37.100598) (xy 122.153153 -37.061889) (xy 122.198511 -37.029438) (xy 122.248111 -37.003937)
			(xy 122.300895 -36.98593) (xy 122.355738 -36.9758) (xy 122.411472 -36.973763) (xy 122.466909 -36.979863)
			(xy 122.520866 -36.993969) (xy 122.572195 -37.015781) (xy 122.619801 -37.044835) (xy 122.662669 -37.08051)
			(xy 122.699886 -37.122047) (xy 122.730659 -37.16856) (xy 122.754331 -37.219057) (xy 122.770399 -37.272464)
			(xy 122.778519 -37.32764) (xy 122.779028 -37.355526) (xy 122.778519 -37.383412) (xy 122.770399 -37.438588)
			(xy 122.754331 -37.491995) (xy 122.730659 -37.542492) (xy 122.704753 -37.581649) (xy 130.604286 -37.581649)
			(xy 130.604286 -37.527151) (xy 130.612041 -37.473208) (xy 130.627394 -37.420918) (xy 130.650031 -37.371344)
			(xy 130.679493 -37.325497) (xy 130.71518 -37.284308) (xy 130.756364 -37.248617) (xy 130.802209 -37.219151)
			(xy 130.85178 -37.196508) (xy 130.904069 -37.181149) (xy 130.958011 -37.173388) (xy 130.98526 -37.1729)
			(xy 131.014681 -37.173474) (xy 131.072824 -37.182516) (xy 131.12889 -37.200377) (xy 131.181549 -37.226633)
			(xy 131.229554 -37.260661) (xy 131.271766 -37.301656) (xy 131.307184 -37.348645) (xy 131.321556 -37.374322)
			(xy 131.328264 -37.386031) (xy 131.34681 -37.405625) (xy 131.369837 -37.419682) (xy 131.395741 -37.427223)
			(xy 131.422715 -37.427722) (xy 131.44888 -37.421144) (xy 131.472411 -37.407947) (xy 131.491668 -37.389052)
			(xy 131.498848 -37.377624) (xy 131.513629 -37.353314) (xy 131.549255 -37.308956) (xy 131.591071 -37.270379)
			(xy 131.63815 -37.238436) (xy 131.68945 -37.213836) (xy 131.743833 -37.197124) (xy 131.800094 -37.18867)
			(xy 131.82854 -37.18814) (xy 131.855793 -37.188533) (xy 131.909743 -37.196295) (xy 131.96204 -37.211655)
			(xy 132.011618 -37.234302) (xy 132.057469 -37.263773) (xy 132.09866 -37.299469) (xy 132.134351 -37.340663)
			(xy 132.163818 -37.386517) (xy 132.186459 -37.436098) (xy 132.201814 -37.488396) (xy 132.20957 -37.542347)
			(xy 132.20957 -37.596853) (xy 132.201814 -37.650804) (xy 132.186459 -37.703102) (xy 132.163818 -37.752683)
			(xy 132.134351 -37.798537) (xy 132.09866 -37.839731) (xy 132.057469 -37.875427) (xy 132.011618 -37.904898)
			(xy 131.96204 -37.927545) (xy 131.909743 -37.942905) (xy 131.855793 -37.950667) (xy 131.82854 -37.951156)
			(xy 131.799118 -37.950605) (xy 131.740973 -37.941562) (xy 131.684905 -37.923699) (xy 131.632245 -37.89744)
			(xy 131.58424 -37.863407) (xy 131.54203 -37.822408) (xy 131.506614 -37.775414) (xy 131.492244 -37.749734)
			(xy 131.485534 -37.738028) (xy 131.466985 -37.718442) (xy 131.443958 -37.704391) (xy 131.418057 -37.696854)
			(xy 131.391087 -37.696356) (xy 131.364925 -37.702931) (xy 131.341395 -37.716121) (xy 131.322135 -37.735008)
			(xy 131.314952 -37.746432) (xy 131.300155 -37.770732) (xy 131.264533 -37.815092) (xy 131.222721 -37.853671)
			(xy 131.175644 -37.885616) (xy 131.124347 -37.910218) (xy 131.069966 -37.926931) (xy 131.013706 -37.935386)
			(xy 130.98526 -37.935916) (xy 130.958011 -37.935412) (xy 130.904069 -37.927651) (xy 130.85178 -37.912292)
			(xy 130.802209 -37.889649) (xy 130.756364 -37.860183) (xy 130.71518 -37.824492) (xy 130.679493 -37.783303)
			(xy 130.650031 -37.737456) (xy 130.627394 -37.687882) (xy 130.612041 -37.635592) (xy 130.604286 -37.581649)
			(xy 122.704753 -37.581649) (xy 122.699886 -37.589005) (xy 122.662669 -37.630542) (xy 122.619801 -37.666217)
			(xy 122.572195 -37.695271) (xy 122.520866 -37.717083) (xy 122.466909 -37.731189) (xy 122.411472 -37.737289)
			(xy 122.355738 -37.735252) (xy 122.300895 -37.725122) (xy 122.248111 -37.707115) (xy 122.198511 -37.681614)
			(xy 122.153153 -37.649163) (xy 122.113004 -37.610454) (xy 122.078918 -37.566311) (xy 122.051622 -37.517676)
			(xy 122.031699 -37.465585) (xy 122.019573 -37.411148) (xy 122.015502 -37.355526) (xy 119.43588 -37.355526)
			(xy 120.130062 -38.049708) (xy 133.685024 -38.049708) (xy 133.689095 -37.994086) (xy 133.701221 -37.939649)
			(xy 133.721144 -37.887558) (xy 133.74844 -37.838923) (xy 133.782526 -37.79478) (xy 133.822675 -37.756071)
			(xy 133.868033 -37.72362) (xy 133.917633 -37.698119) (xy 133.970417 -37.680112) (xy 134.02526 -37.669982)
			(xy 134.080994 -37.667945) (xy 134.136431 -37.674045) (xy 134.190388 -37.688151) (xy 134.241717 -37.709963)
			(xy 134.289323 -37.739017) (xy 134.332191 -37.774692) (xy 134.369408 -37.816229) (xy 134.400181 -37.862742)
			(xy 134.423853 -37.913239) (xy 134.439921 -37.966646) (xy 134.448041 -38.021822) (xy 134.44855 -38.049708)
			(xy 134.448041 -38.077594) (xy 134.439921 -38.13277) (xy 134.423853 -38.186177) (xy 134.400181 -38.236674)
			(xy 134.369408 -38.283187) (xy 134.332191 -38.324724) (xy 134.289323 -38.360399) (xy 134.241717 -38.389453)
			(xy 134.190388 -38.411265) (xy 134.136431 -38.425371) (xy 134.080994 -38.431471) (xy 134.02526 -38.429434)
			(xy 133.970417 -38.419304) (xy 133.917633 -38.401297) (xy 133.868033 -38.375796) (xy 133.822675 -38.343345)
			(xy 133.782526 -38.304636) (xy 133.74844 -38.260493) (xy 133.721144 -38.211858) (xy 133.701221 -38.159767)
			(xy 133.689095 -38.10533) (xy 133.685024 -38.049708) (xy 120.130062 -38.049708) (xy 121.500646 -39.420292)
			(xy 121.500646 -40.986456) (xy 122.654566 -40.986456) (xy 122.658637 -40.930834) (xy 122.670763 -40.876397)
			(xy 122.690686 -40.824306) (xy 122.717982 -40.775671) (xy 122.752068 -40.731528) (xy 122.792217 -40.692819)
			(xy 122.837575 -40.660368) (xy 122.887175 -40.634867) (xy 122.939959 -40.61686) (xy 122.994802 -40.60673)
			(xy 123.050536 -40.604693) (xy 123.105973 -40.610793) (xy 123.15993 -40.624899) (xy 123.211259 -40.646711)
			(xy 123.258865 -40.675765) (xy 123.301733 -40.71144) (xy 123.33895 -40.752977) (xy 123.369723 -40.79949)
			(xy 123.393395 -40.849987) (xy 123.409463 -40.903394) (xy 123.417583 -40.95857) (xy 123.418083 -40.985948)
			(xy 133.456172 -40.985948) (xy 133.456658 -40.958697) (xy 133.464414 -40.904749) (xy 133.479769 -40.852454)
			(xy 133.502411 -40.802877) (xy 133.531877 -40.757027) (xy 133.567568 -40.715836) (xy 133.608759 -40.680145)
			(xy 133.654609 -40.650679) (xy 133.704186 -40.628037) (xy 133.756481 -40.612682) (xy 133.810429 -40.604926)
			(xy 133.864931 -40.604926) (xy 133.918879 -40.612682) (xy 133.971174 -40.628037) (xy 134.020751 -40.650679)
			(xy 134.066601 -40.680145) (xy 134.107792 -40.715836) (xy 134.143483 -40.757027) (xy 134.172949 -40.802877)
			(xy 134.195591 -40.852454) (xy 134.210946 -40.904749) (xy 134.211847 -40.911018) (xy 135.448292 -40.911018)
			(xy 135.452363 -40.855396) (xy 135.464489 -40.800959) (xy 135.484412 -40.748868) (xy 135.511708 -40.700233)
			(xy 135.545794 -40.65609) (xy 135.585943 -40.617381) (xy 135.631301 -40.58493) (xy 135.680901 -40.559429)
			(xy 135.733685 -40.541422) (xy 135.788528 -40.531292) (xy 135.844262 -40.529255) (xy 135.899699 -40.535355)
			(xy 135.953656 -40.549461) (xy 136.004985 -40.571273) (xy 136.052591 -40.600327) (xy 136.095459 -40.636002)
			(xy 136.132676 -40.677539) (xy 136.163449 -40.724052) (xy 136.187121 -40.774549) (xy 136.203189 -40.827956)
			(xy 136.211309 -40.883132) (xy 136.211818 -40.911018) (xy 136.211309 -40.938904) (xy 136.203189 -40.99408)
			(xy 136.187121 -41.047487) (xy 136.163449 -41.097984) (xy 136.132676 -41.144497) (xy 136.095459 -41.186034)
			(xy 136.052591 -41.221709) (xy 136.004985 -41.250763) (xy 135.953656 -41.272575) (xy 135.899699 -41.286681)
			(xy 135.844262 -41.292781) (xy 135.788528 -41.290744) (xy 135.733685 -41.280614) (xy 135.680901 -41.262607)
			(xy 135.631301 -41.237106) (xy 135.585943 -41.204655) (xy 135.545794 -41.165946) (xy 135.511708 -41.121803)
			(xy 135.484412 -41.073168) (xy 135.464489 -41.021077) (xy 135.452363 -40.96664) (xy 135.448292 -40.911018)
			(xy 134.211847 -40.911018) (xy 134.218702 -40.958697) (xy 134.219188 -40.985948) (xy 134.2187 -41.012945)
			(xy 134.211106 -41.0664) (xy 134.196048 -41.118251) (xy 134.173828 -41.167459) (xy 134.144888 -41.213041)
			(xy 134.109809 -41.254086) (xy 134.069292 -41.289773) (xy 134.046976 -41.304972) (xy 134.035596 -41.31302)
			(xy 134.017345 -41.334074) (xy 134.005466 -41.359277) (xy 134.000843 -41.386753) (xy 134.003819 -41.414456)
			(xy 134.014174 -41.440323) (xy 134.031135 -41.462428) (xy 134.053441 -41.479124) (xy 134.06628 -41.48455)
			(xy 134.09284 -41.495356) (xy 134.142612 -41.523827) (xy 134.187565 -41.559423) (xy 134.226687 -41.601345)
			(xy 134.259096 -41.648647) (xy 134.284063 -41.700266) (xy 134.301027 -41.755039) (xy 134.309605 -41.811734)
			(xy 134.31012 -41.840404) (xy 134.309634 -41.867655) (xy 134.301878 -41.921603) (xy 134.286523 -41.973898)
			(xy 134.263881 -42.023475) (xy 134.234415 -42.069325) (xy 134.198724 -42.110516) (xy 134.157533 -42.146207)
			(xy 134.111683 -42.175673) (xy 134.062106 -42.198315) (xy 134.009811 -42.21367) (xy 133.955863 -42.221426)
			(xy 133.901361 -42.221426) (xy 133.847413 -42.21367) (xy 133.795118 -42.198315) (xy 133.745541 -42.175673)
			(xy 133.699691 -42.146207) (xy 133.6585 -42.110516) (xy 133.622809 -42.069325) (xy 133.593343 -42.023475)
			(xy 133.570701 -41.973898) (xy 133.555346 -41.921603) (xy 133.54759 -41.867655) (xy 133.547104 -41.840404)
			(xy 133.547559 -41.813406) (xy 133.555159 -41.759949) (xy 133.570223 -41.708098) (xy 133.592449 -41.65889)
			(xy 133.621393 -41.613308) (xy 133.656477 -41.572264) (xy 133.696998 -41.536579) (xy 133.719316 -41.52138)
			(xy 133.730747 -41.513398) (xy 133.749001 -41.492332) (xy 133.76088 -41.467115) (xy 133.7655 -41.439626)
			(xy 133.762516 -41.411911) (xy 133.752151 -41.386036) (xy 133.735177 -41.363925) (xy 133.712857 -41.347227)
			(xy 133.700012 -41.341802) (xy 133.673469 -41.330957) (xy 133.623699 -41.30249) (xy 133.578747 -41.266899)
			(xy 133.539625 -41.224983) (xy 133.507214 -41.177686) (xy 133.482244 -41.126074) (xy 133.465275 -41.071306)
			(xy 133.456691 -41.014616) (xy 133.456172 -40.985948) (xy 123.418083 -40.985948) (xy 123.418092 -40.986456)
			(xy 123.417583 -41.014342) (xy 123.409463 -41.069518) (xy 123.393395 -41.122925) (xy 123.369723 -41.173422)
			(xy 123.33895 -41.219935) (xy 123.301733 -41.261472) (xy 123.258865 -41.297147) (xy 123.211259 -41.326201)
			(xy 123.15993 -41.348013) (xy 123.105973 -41.362119) (xy 123.050536 -41.368219) (xy 122.994802 -41.366182)
			(xy 122.939959 -41.356052) (xy 122.887175 -41.338045) (xy 122.837575 -41.312544) (xy 122.792217 -41.280093)
			(xy 122.752068 -41.241384) (xy 122.717982 -41.197241) (xy 122.690686 -41.148606) (xy 122.670763 -41.096515)
			(xy 122.658637 -41.042078) (xy 122.654566 -40.986456) (xy 121.500646 -40.986456) (xy 121.500646 -41.504616)
			(xy 120.73255 -42.272712) (xy 120.074182 -42.272712) (xy 111.539782 -33.738312) (xy 109.850682 -33.738312)
			(xy 109.842046 -33.778444) (xy 109.835876 -33.805071) (xy 109.816941 -33.856344) (xy 109.790883 -33.904391)
			(xy 109.758237 -33.948227) (xy 109.719669 -33.986957) (xy 109.675969 -34.019787) (xy 109.628033 -34.046045)
			(xy 109.576839 -34.065195) (xy 109.523438 -34.076844) (xy 109.46892 -34.080753) (xy 109.414402 -34.076844)
			(xy 109.361001 -34.065195) (xy 109.309807 -34.046045) (xy 109.261871 -34.019787) (xy 109.218171 -33.986957)
			(xy 109.179603 -33.948227) (xy 109.146957 -33.904391) (xy 109.120899 -33.856344) (xy 109.101964 -33.805071)
			(xy 109.095794 -33.778444) (xy 109.087158 -33.738312) (xy 105.652316 -33.738312) (xy 105.073704 -33.1597)
			(xy 105.050336 -33.161732) (xy 105.018586 -33.163002) (xy 104.991336 -33.162515) (xy 104.93739 -33.154757)
			(xy 104.885097 -33.139401) (xy 104.835522 -33.116759) (xy 104.789674 -33.087292) (xy 104.748486 -33.0516)
			(xy 104.712796 -33.01041) (xy 104.683332 -32.964561) (xy 104.660692 -32.914984) (xy 104.645339 -32.862691)
			(xy 104.637583 -32.808744) (xy 104.637078 -32.781494) (xy 104.638348 -32.749744) (xy 104.64038 -32.726376)
			(xy 104.359456 -32.445452) (xy 97.771966 -32.445452) (xy 97.757067 -32.445976) (xy 97.72854 -32.454588)
			(xy 97.703714 -32.471067) (xy 97.684701 -32.494012) (xy 97.673122 -32.521468) (xy 97.669961 -32.551098)
			(xy 97.672144 -32.565848) (xy 97.675241 -32.583401) (xy 97.678552 -32.618891) (xy 97.678748 -32.636714)
			(xy 97.678262 -32.663965) (xy 97.670506 -32.717913) (xy 97.655151 -32.770208) (xy 97.632509 -32.819785)
			(xy 97.603043 -32.865635) (xy 97.567352 -32.906826) (xy 97.526161 -32.942517) (xy 97.480311 -32.971983)
			(xy 97.430734 -32.994625) (xy 97.378439 -33.00998) (xy 97.324491 -33.017736) (xy 97.269989 -33.017736)
			(xy 97.216041 -33.00998) (xy 97.163746 -32.994625) (xy 97.114169 -32.971983) (xy 97.068319 -32.942517)
			(xy 97.027128 -32.906826) (xy 96.991437 -32.865635) (xy 96.961971 -32.819785) (xy 96.939329 -32.770208)
			(xy 96.923974 -32.717913) (xy 96.916218 -32.663965) (xy 96.915732 -32.636714) (xy 96.915926 -32.618891)
			(xy 96.919233 -32.5834) (xy 96.922336 -32.565848) (xy 96.924576 -32.55111) (xy 96.921391 -32.521486)
			(xy 96.909794 -32.49404) (xy 96.89077 -32.471108) (xy 96.865939 -32.454641) (xy 96.837412 -32.44604)
			(xy 96.822514 -32.445452) (xy 94.649036 -32.445452) (xy 94.287086 -32.083756) (xy 93.579696 -32.083756)
			(xy 93.564485 -32.084321) (xy 93.535412 -32.093275) (xy 93.510261 -32.110389) (xy 93.49126 -32.134147)
			(xy 93.480093 -32.162445) (xy 93.477748 -32.192775) (xy 93.484434 -32.222453) (xy 93.491558 -32.235902)
			(xy 93.503617 -32.257695) (xy 93.522609 -32.303739) (xy 93.535455 -32.351861) (xy 93.541936 -32.401245)
			(xy 93.542358 -32.426148) (xy 93.541872 -32.453399) (xy 93.534116 -32.507347) (xy 93.518761 -32.559642)
			(xy 93.496119 -32.609219) (xy 93.466653 -32.655069) (xy 93.430962 -32.69626) (xy 93.389771 -32.731951)
			(xy 93.343921 -32.761417) (xy 93.294344 -32.784059) (xy 93.242049 -32.799414) (xy 93.188101 -32.80717)
			(xy 93.133599 -32.80717) (xy 93.079651 -32.799414) (xy 93.027356 -32.784059) (xy 92.977779 -32.761417)
			(xy 92.931929 -32.731951) (xy 92.890738 -32.69626) (xy 92.855047 -32.655069) (xy 92.825581 -32.609219)
			(xy 92.802939 -32.559642) (xy 92.787584 -32.507347) (xy 92.779828 -32.453399) (xy 92.779342 -32.426148)
			(xy 92.779742 -32.401243) (xy 92.786218 -32.351855) (xy 92.799065 -32.30373) (xy 92.818065 -32.257686)
			(xy 92.830142 -32.235902) (xy 92.83721 -32.222432) (xy 92.843892 -32.192771) (xy 92.841549 -32.162458)
			(xy 92.830388 -32.134177) (xy 92.811399 -32.110433) (xy 92.786263 -32.093329) (xy 92.757206 -32.08438)
			(xy 92.742004 -32.083756) (xy 90.82786 -32.083756) (xy 90.799493 -32.083108) (xy 90.743661 -32.073013)
			(xy 90.716862 -32.06369) (xy 90.708226 -32.060388) (xy 89.219278 -32.060388) (xy 87.895684 -33.383982)
			(xy 94.863156 -33.383982) (xy 94.867227 -33.32836) (xy 94.879353 -33.273923) (xy 94.899276 -33.221832)
			(xy 94.926572 -33.173197) (xy 94.960658 -33.129054) (xy 95.000807 -33.090345) (xy 95.046165 -33.057894)
			(xy 95.095765 -33.032393) (xy 95.148549 -33.014386) (xy 95.203392 -33.004256) (xy 95.259126 -33.002219)
			(xy 95.314563 -33.008319) (xy 95.36852 -33.022425) (xy 95.419849 -33.044237) (xy 95.467455 -33.073291)
			(xy 95.510323 -33.108966) (xy 95.54754 -33.150503) (xy 95.578313 -33.197016) (xy 95.601985 -33.247513)
			(xy 95.610107 -33.274508) (xy 95.958912 -33.274508) (xy 95.962983 -33.218886) (xy 95.975109 -33.164449)
			(xy 95.995032 -33.112358) (xy 96.022328 -33.063723) (xy 96.056414 -33.01958) (xy 96.096563 -32.980871)
			(xy 96.141921 -32.94842) (xy 96.191521 -32.922919) (xy 96.244305 -32.904912) (xy 96.299148 -32.894782)
			(xy 96.354882 -32.892745) (xy 96.410319 -32.898845) (xy 96.464276 -32.912951) (xy 96.515605 -32.934763)
			(xy 96.563211 -32.963817) (xy 96.606079 -32.999492) (xy 96.643296 -33.041029) (xy 96.674069 -33.087542)
			(xy 96.697741 -33.138039) (xy 96.713809 -33.191446) (xy 96.721929 -33.246622) (xy 96.722438 -33.274508)
			(xy 96.721929 -33.302394) (xy 96.713809 -33.35757) (xy 96.697741 -33.410977) (xy 96.674069 -33.461474)
			(xy 96.643296 -33.507987) (xy 96.606079 -33.549524) (xy 96.563211 -33.585199) (xy 96.515605 -33.614253)
			(xy 96.464276 -33.636065) (xy 96.410319 -33.650171) (xy 96.354882 -33.656271) (xy 96.299148 -33.654234)
			(xy 96.244305 -33.644104) (xy 96.191521 -33.626097) (xy 96.141921 -33.600596) (xy 96.096563 -33.568145)
			(xy 96.056414 -33.529436) (xy 96.022328 -33.485293) (xy 95.995032 -33.436658) (xy 95.975109 -33.384567)
			(xy 95.962983 -33.33013) (xy 95.958912 -33.274508) (xy 95.610107 -33.274508) (xy 95.618053 -33.30092)
			(xy 95.626173 -33.356096) (xy 95.626682 -33.383982) (xy 95.626173 -33.411868) (xy 95.618053 -33.467044)
			(xy 95.601985 -33.520451) (xy 95.578313 -33.570948) (xy 95.54754 -33.617461) (xy 95.510323 -33.658998)
			(xy 95.467455 -33.694673) (xy 95.419849 -33.723727) (xy 95.36852 -33.745539) (xy 95.314563 -33.759645)
			(xy 95.259126 -33.765745) (xy 95.203392 -33.763708) (xy 95.148549 -33.753578) (xy 95.095765 -33.735571)
			(xy 95.046165 -33.71007) (xy 95.000807 -33.677619) (xy 94.960658 -33.63891) (xy 94.926572 -33.594767)
			(xy 94.899276 -33.546132) (xy 94.879353 -33.494041) (xy 94.867227 -33.439604) (xy 94.863156 -33.383982)
			(xy 87.895684 -33.383982) (xy 87.266018 -34.013648) (xy 92.597222 -34.013648) (xy 92.601293 -33.958026)
			(xy 92.613419 -33.903589) (xy 92.633342 -33.851498) (xy 92.660638 -33.802863) (xy 92.694724 -33.75872)
			(xy 92.734873 -33.720011) (xy 92.780231 -33.68756) (xy 92.829831 -33.662059) (xy 92.882615 -33.644052)
			(xy 92.937458 -33.633922) (xy 92.993192 -33.631885) (xy 93.048629 -33.637985) (xy 93.102586 -33.652091)
			(xy 93.153915 -33.673903) (xy 93.201521 -33.702957) (xy 93.244389 -33.738632) (xy 93.281606 -33.780169)
			(xy 93.312379 -33.826682) (xy 93.336051 -33.877179) (xy 93.352119 -33.930586) (xy 93.360239 -33.985762)
			(xy 93.360748 -34.013648) (xy 93.360239 -34.041534) (xy 93.352119 -34.09671) (xy 93.336051 -34.150117)
			(xy 93.312379 -34.200614) (xy 93.281606 -34.247127) (xy 93.244389 -34.288664) (xy 93.201521 -34.324339)
			(xy 93.153915 -34.353393) (xy 93.102586 -34.375205) (xy 93.048629 -34.389311) (xy 92.993192 -34.395411)
			(xy 92.937458 -34.393374) (xy 92.882615 -34.383244) (xy 92.829831 -34.365237) (xy 92.780231 -34.339736)
			(xy 92.734873 -34.307285) (xy 92.694724 -34.268576) (xy 92.660638 -34.224433) (xy 92.633342 -34.175798)
			(xy 92.613419 -34.123707) (xy 92.601293 -34.06927) (xy 92.597222 -34.013648) (xy 87.266018 -34.013648)
			(xy 85.580474 -35.699192) (xy 84.849208 -35.699192) (xy 84.849208 -36.643818) (xy 89.835988 -36.643818)
			(xy 89.840059 -36.588196) (xy 89.852185 -36.533759) (xy 89.872108 -36.481668) (xy 89.899404 -36.433033)
			(xy 89.93349 -36.38889) (xy 89.973639 -36.350181) (xy 90.018997 -36.31773) (xy 90.068597 -36.292229)
			(xy 90.121381 -36.274222) (xy 90.176224 -36.264092) (xy 90.231958 -36.262055) (xy 90.287395 -36.268155)
			(xy 90.341352 -36.282261) (xy 90.392681 -36.304073) (xy 90.440287 -36.333127) (xy 90.483155 -36.368802)
			(xy 90.520372 -36.410339) (xy 90.551145 -36.456852) (xy 90.574817 -36.507349) (xy 90.590885 -36.560756)
			(xy 90.599005 -36.615932) (xy 90.599514 -36.643818) (xy 90.599005 -36.671704) (xy 90.590885 -36.72688)
			(xy 90.574817 -36.780287) (xy 90.551145 -36.830784) (xy 90.520372 -36.877297) (xy 90.483155 -36.918834)
			(xy 90.440287 -36.954509) (xy 90.392681 -36.983563) (xy 90.341352 -37.005375) (xy 90.32236 -37.01034)
			(xy 112.312194 -37.01034) (xy 112.316265 -36.954718) (xy 112.328391 -36.900281) (xy 112.348314 -36.84819)
			(xy 112.37561 -36.799555) (xy 112.409696 -36.755412) (xy 112.449845 -36.716703) (xy 112.495203 -36.684252)
			(xy 112.544803 -36.658751) (xy 112.597587 -36.640744) (xy 112.65243 -36.630614) (xy 112.708164 -36.628577)
			(xy 112.763601 -36.634677) (xy 112.817558 -36.648783) (xy 112.868887 -36.670595) (xy 112.916493 -36.699649)
			(xy 112.959361 -36.735324) (xy 112.996578 -36.776861) (xy 113.027351 -36.823374) (xy 113.051023 -36.873871)
			(xy 113.067091 -36.927278) (xy 113.075211 -36.982454) (xy 113.07572 -37.01034) (xy 113.075211 -37.038226)
			(xy 113.067091 -37.093402) (xy 113.051023 -37.146809) (xy 113.027351 -37.197306) (xy 112.996578 -37.243819)
			(xy 112.959361 -37.285356) (xy 112.916493 -37.321031) (xy 112.868887 -37.350085) (xy 112.817558 -37.371897)
			(xy 112.763601 -37.386003) (xy 112.708164 -37.392103) (xy 112.65243 -37.390066) (xy 112.597587 -37.379936)
			(xy 112.544803 -37.361929) (xy 112.495203 -37.336428) (xy 112.449845 -37.303977) (xy 112.409696 -37.265268)
			(xy 112.37561 -37.221125) (xy 112.348314 -37.17249) (xy 112.328391 -37.120399) (xy 112.316265 -37.065962)
			(xy 112.312194 -37.01034) (xy 90.32236 -37.01034) (xy 90.287395 -37.019481) (xy 90.231958 -37.025581)
			(xy 90.176224 -37.023544) (xy 90.121381 -37.013414) (xy 90.068597 -36.995407) (xy 90.018997 -36.969906)
			(xy 89.973639 -36.937455) (xy 89.93349 -36.898746) (xy 89.899404 -36.854603) (xy 89.872108 -36.805968)
			(xy 89.852185 -36.753877) (xy 89.840059 -36.69944) (xy 89.835988 -36.643818) (xy 84.849208 -36.643818)
			(xy 84.849208 -37.709348) (xy 87.191086 -37.709348) (xy 87.195157 -37.653726) (xy 87.207283 -37.599289)
			(xy 87.227206 -37.547198) (xy 87.254502 -37.498563) (xy 87.288588 -37.45442) (xy 87.328737 -37.415711)
			(xy 87.374095 -37.38326) (xy 87.423695 -37.357759) (xy 87.476479 -37.339752) (xy 87.531322 -37.329622)
			(xy 87.587056 -37.327585) (xy 87.642493 -37.333685) (xy 87.69645 -37.347791) (xy 87.747779 -37.369603)
			(xy 87.795385 -37.398657) (xy 87.838253 -37.434332) (xy 87.87547 -37.475869) (xy 87.906243 -37.522382)
			(xy 87.929915 -37.572879) (xy 87.945983 -37.626286) (xy 87.951105 -37.661088) (xy 100.196902 -37.661088)
			(xy 100.200973 -37.605466) (xy 100.213099 -37.551029) (xy 100.233022 -37.498938) (xy 100.260318 -37.450303)
			(xy 100.294404 -37.40616) (xy 100.334553 -37.367451) (xy 100.379911 -37.335) (xy 100.429511 -37.309499)
			(xy 100.482295 -37.291492) (xy 100.537138 -37.281362) (xy 100.592872 -37.279325) (xy 100.648309 -37.285425)
			(xy 100.702266 -37.299531) (xy 100.753595 -37.321343) (xy 100.801201 -37.350397) (xy 100.844069 -37.386072)
			(xy 100.881286 -37.427609) (xy 100.912059 -37.474122) (xy 100.935731 -37.524619) (xy 100.951799 -37.578026)
			(xy 100.959919 -37.633202) (xy 100.960428 -37.661088) (xy 100.959919 -37.688974) (xy 100.951799 -37.74415)
			(xy 100.935731 -37.797557) (xy 100.912059 -37.848054) (xy 100.881286 -37.894567) (xy 100.844069 -37.936104)
			(xy 100.838496 -37.940742) (xy 108.782102 -37.940742) (xy 108.786173 -37.88512) (xy 108.798299 -37.830683)
			(xy 108.818222 -37.778592) (xy 108.845518 -37.729957) (xy 108.879604 -37.685814) (xy 108.919753 -37.647105)
			(xy 108.965111 -37.614654) (xy 109.014711 -37.589153) (xy 109.067495 -37.571146) (xy 109.122338 -37.561016)
			(xy 109.178072 -37.558979) (xy 109.233509 -37.565079) (xy 109.287466 -37.579185) (xy 109.338795 -37.600997)
			(xy 109.386401 -37.630051) (xy 109.429269 -37.665726) (xy 109.466486 -37.707263) (xy 109.497259 -37.753776)
			(xy 109.520931 -37.804273) (xy 109.536999 -37.85768) (xy 109.545119 -37.912856) (xy 109.545628 -37.940742)
			(xy 109.545119 -37.968628) (xy 109.536999 -38.023804) (xy 109.520931 -38.077211) (xy 109.497259 -38.127708)
			(xy 109.466486 -38.174221) (xy 109.429269 -38.215758) (xy 109.386401 -38.251433) (xy 109.338795 -38.280487)
			(xy 109.287466 -38.302299) (xy 109.233509 -38.316405) (xy 109.178072 -38.322505) (xy 109.122338 -38.320468)
			(xy 109.067495 -38.310338) (xy 109.014711 -38.292331) (xy 108.965111 -38.26683) (xy 108.919753 -38.234379)
			(xy 108.879604 -38.19567) (xy 108.845518 -38.151527) (xy 108.818222 -38.102892) (xy 108.798299 -38.050801)
			(xy 108.786173 -37.996364) (xy 108.782102 -37.940742) (xy 100.838496 -37.940742) (xy 100.801201 -37.971779)
			(xy 100.753595 -38.000833) (xy 100.702266 -38.022645) (xy 100.648309 -38.036751) (xy 100.592872 -38.042851)
			(xy 100.537138 -38.040814) (xy 100.482295 -38.030684) (xy 100.429511 -38.012677) (xy 100.379911 -37.987176)
			(xy 100.334553 -37.954725) (xy 100.294404 -37.916016) (xy 100.260318 -37.871873) (xy 100.233022 -37.823238)
			(xy 100.213099 -37.771147) (xy 100.200973 -37.71671) (xy 100.196902 -37.661088) (xy 87.951105 -37.661088)
			(xy 87.954103 -37.681462) (xy 87.954612 -37.709348) (xy 87.954103 -37.737234) (xy 87.945983 -37.79241)
			(xy 87.929915 -37.845817) (xy 87.906243 -37.896314) (xy 87.87547 -37.942827) (xy 87.838253 -37.984364)
			(xy 87.795385 -38.020039) (xy 87.747779 -38.049093) (xy 87.69645 -38.070905) (xy 87.642493 -38.085011)
			(xy 87.587056 -38.091111) (xy 87.531322 -38.089074) (xy 87.476479 -38.078944) (xy 87.423695 -38.060937)
			(xy 87.374095 -38.035436) (xy 87.328737 -38.002985) (xy 87.288588 -37.964276) (xy 87.254502 -37.920133)
			(xy 87.227206 -37.871498) (xy 87.207283 -37.819407) (xy 87.195157 -37.76497) (xy 87.191086 -37.709348)
			(xy 84.849208 -37.709348) (xy 84.849208 -38.211252) (xy 84.848771 -38.233923) (xy 84.842272 -38.278798)
			(xy 84.83989 -38.287452) (xy 85.022942 -38.287452) (xy 85.027013 -38.23183) (xy 85.039139 -38.177393)
			(xy 85.059062 -38.125302) (xy 85.086358 -38.076667) (xy 85.120444 -38.032524) (xy 85.160593 -37.993815)
			(xy 85.205951 -37.961364) (xy 85.255551 -37.935863) (xy 85.308335 -37.917856) (xy 85.363178 -37.907726)
			(xy 85.418912 -37.905689) (xy 85.474349 -37.911789) (xy 85.528306 -37.925895) (xy 85.579635 -37.947707)
			(xy 85.627241 -37.976761) (xy 85.670109 -38.012436) (xy 85.707326 -38.053973) (xy 85.738099 -38.100486)
			(xy 85.761771 -38.150983) (xy 85.777839 -38.20439) (xy 85.777877 -38.204648) (xy 88.797382 -38.204648)
			(xy 88.801453 -38.149026) (xy 88.813579 -38.094589) (xy 88.833502 -38.042498) (xy 88.860798 -37.993863)
			(xy 88.894884 -37.94972) (xy 88.935033 -37.911011) (xy 88.980391 -37.87856) (xy 89.029991 -37.853059)
			(xy 89.082775 -37.835052) (xy 89.137618 -37.824922) (xy 89.193352 -37.822885) (xy 89.248789 -37.828985)
			(xy 89.302746 -37.843091) (xy 89.354075 -37.864903) (xy 89.401681 -37.893957) (xy 89.444549 -37.929632)
			(xy 89.481766 -37.971169) (xy 89.512539 -38.017682) (xy 89.536211 -38.068179) (xy 89.552279 -38.121586)
			(xy 89.560399 -38.176762) (xy 89.560908 -38.204648) (xy 89.560399 -38.232534) (xy 89.552279 -38.28771)
			(xy 89.536211 -38.341117) (xy 89.512539 -38.391614) (xy 89.481766 -38.438127) (xy 89.444549 -38.479664)
			(xy 89.401681 -38.515339) (xy 89.354075 -38.544393) (xy 89.302746 -38.566205) (xy 89.248789 -38.580311)
			(xy 89.193352 -38.586411) (xy 89.137618 -38.584374) (xy 89.082775 -38.574244) (xy 89.029991 -38.556237)
			(xy 88.980391 -38.530736) (xy 88.935033 -38.498285) (xy 88.894884 -38.459576) (xy 88.860798 -38.415433)
			(xy 88.833502 -38.366798) (xy 88.813579 -38.314707) (xy 88.801453 -38.26027) (xy 88.797382 -38.204648)
			(xy 85.777877 -38.204648) (xy 85.785959 -38.259566) (xy 85.786468 -38.287452) (xy 85.785959 -38.315338)
			(xy 85.777839 -38.370514) (xy 85.761771 -38.423921) (xy 85.738099 -38.474418) (xy 85.707326 -38.520931)
			(xy 85.670109 -38.562468) (xy 85.627241 -38.598143) (xy 85.579635 -38.627197) (xy 85.528306 -38.649009)
			(xy 85.474349 -38.663115) (xy 85.418912 -38.669215) (xy 85.363178 -38.667178) (xy 85.308335 -38.657048)
			(xy 85.255551 -38.639041) (xy 85.205951 -38.61354) (xy 85.160593 -38.581089) (xy 85.120444 -38.54238)
			(xy 85.086358 -38.498237) (xy 85.059062 -38.449602) (xy 85.039139 -38.397511) (xy 85.027013 -38.343074)
			(xy 85.022942 -38.287452) (xy 84.83989 -38.287452) (xy 84.836254 -38.30066) (xy 84.834884 -38.327276)
			(xy 84.825637 -38.379762) (xy 84.809173 -38.430451) (xy 84.785815 -38.478354) (xy 84.756017 -38.52254)
			(xy 84.720359 -38.562149) (xy 84.679535 -38.596409) (xy 84.63434 -38.624653) (xy 84.585653 -38.646332)
			(xy 84.534424 -38.661023) (xy 84.481647 -38.668441) (xy 84.455 -38.66896) (xy 84.427748 -38.668497)
			(xy 84.3738 -38.660739) (xy 84.321505 -38.645383) (xy 84.271928 -38.62274) (xy 84.226078 -38.593271)
			(xy 84.184889 -38.557577) (xy 84.1492 -38.516383) (xy 84.119737 -38.47053) (xy 84.0971 -38.42095)
			(xy 84.08175 -38.368653) (xy 84.074 -38.314704) (xy 84.073492 -38.287452) (xy 84.073997 -38.25932)
			(xy 84.082263 -38.203667) (xy 84.09861 -38.14983) (xy 84.122682 -38.098976) (xy 84.153958 -38.052207)
			(xy 84.191761 -38.010535) (xy 84.213192 -37.992304) (xy 84.213192 -35.699192) (xy 77.364844 -35.699192)
			(xy 77.350005 -35.699708) (xy 77.321581 -35.708244) (xy 77.296805 -35.72458) (xy 77.277761 -35.747342)
			(xy 77.266053 -35.774613) (xy 77.262667 -35.804097) (xy 77.267889 -35.833312) (xy 77.274166 -35.846766)
			(xy 77.287252 -35.873751) (xy 77.30579 -35.930783) (xy 77.315199 -35.99001) (xy 77.315822 -36.019994)
			(xy 77.315381 -36.046049) (xy 77.308242 -36.097667) (xy 77.301598 -36.122864) (xy 77.298117 -36.137033)
			(xy 77.298496 -36.166197) (xy 77.307093 -36.194067) (xy 77.323209 -36.218376) (xy 77.345533 -36.237146)
			(xy 77.372248 -36.248849) (xy 77.40118 -36.252534) (xy 77.415644 -36.250626) (xy 77.430718 -36.24836)
			(xy 77.461107 -36.245945) (xy 77.47635 -36.2458) (xy 77.502952 -36.246264) (xy 77.555639 -36.25366)
			(xy 77.606789 -36.268301) (xy 77.655409 -36.289904) (xy 77.700558 -36.31805) (xy 77.741361 -36.352194)
			(xy 77.777027 -36.391673) (xy 77.792326 -36.41344) (xy 77.80066 -36.42492) (xy 77.822404 -36.443124)
			(xy 77.848317 -36.454642) (xy 77.8764 -36.458582) (xy 77.904483 -36.454642) (xy 77.930396 -36.443124)
			(xy 77.95214 -36.42492) (xy 77.960474 -36.41344) (xy 77.975768 -36.391668) (xy 78.011425 -36.35218)
			(xy 78.052225 -36.318031) (xy 78.097376 -36.289886) (xy 78.146001 -36.268289) (xy 78.197156 -36.253662)
			(xy 78.249847 -36.246287) (xy 78.27645 -36.2458) (xy 78.303705 -36.24626) (xy 78.35766 -36.254011)
			(xy 78.409963 -36.269362) (xy 78.459548 -36.292001) (xy 78.505406 -36.321468) (xy 78.546604 -36.35716)
			(xy 78.582302 -36.398354) (xy 78.611775 -36.444208) (xy 78.63442 -36.493791) (xy 78.649778 -36.546091)
			(xy 78.657537 -36.600045) (xy 78.657537 -36.654555) (xy 78.649778 -36.708509) (xy 78.63442 -36.760809)
			(xy 78.611775 -36.810392) (xy 78.582302 -36.856246) (xy 78.546604 -36.89744) (xy 78.505406 -36.933132)
			(xy 78.459548 -36.962599) (xy 78.409963 -36.985238) (xy 78.35766 -37.000589) (xy 78.303705 -37.00834)
			(xy 78.27645 -37.008816) (xy 78.249848 -37.008352) (xy 78.19716 -37.000956) (xy 78.14601 -36.986315)
			(xy 78.097389 -36.964713) (xy 78.052239 -36.936568) (xy 78.011435 -36.902425) (xy 77.975768 -36.862947)
			(xy 77.960474 -36.841176) (xy 77.95214 -36.829696) (xy 77.930396 -36.811492) (xy 77.904483 -36.799974)
			(xy 77.8764 -36.796034) (xy 77.848317 -36.799974) (xy 77.822404 -36.811492) (xy 77.80066 -36.829696)
			(xy 77.792326 -36.841176) (xy 77.777032 -36.862947) (xy 77.741373 -36.902434) (xy 77.700573 -36.936581)
			(xy 77.655422 -36.964725) (xy 77.606798 -36.986321) (xy 77.555643 -37.000948) (xy 77.502952 -37.008322)
			(xy 77.47635 -37.008816) (xy 77.449095 -37.008356) (xy 77.395138 -37.000605) (xy 77.342834 -36.985253)
			(xy 77.293247 -36.962614) (xy 77.247387 -36.933147) (xy 77.206187 -36.897454) (xy 77.170488 -36.85626)
			(xy 77.141014 -36.810404) (xy 77.118367 -36.760821) (xy 77.103007 -36.708519) (xy 77.095248 -36.654563)
			(xy 77.094842 -36.627308) (xy 77.095283 -36.601253) (xy 77.102423 -36.549635) (xy 77.109066 -36.524438)
			(xy 77.112548 -36.510271) (xy 77.112171 -36.48111) (xy 77.103574 -36.453243) (xy 77.087457 -36.428938)
			(xy 77.065133 -36.410173) (xy 77.038418 -36.398477) (xy 77.009488 -36.394801) (xy 76.99502 -36.396676)
			(xy 76.979946 -36.398945) (xy 76.949557 -36.401365) (xy 76.934314 -36.401502) (xy 76.907061 -36.40104)
			(xy 76.853109 -36.393284) (xy 76.800809 -36.377929) (xy 76.751228 -36.355288) (xy 76.705373 -36.32582)
			(xy 76.66418 -36.290126) (xy 76.628485 -36.248933) (xy 76.599016 -36.203079) (xy 76.576373 -36.153498)
			(xy 76.561017 -36.101199) (xy 76.553261 -36.047247) (xy 76.552806 -36.019994) (xy 76.553361 -35.990004)
			(xy 76.562754 -35.930764) (xy 76.581323 -35.873731) (xy 76.594462 -35.846766) (xy 76.600724 -35.833301)
			(xy 76.60598 -35.804087) (xy 76.602614 -35.774596) (xy 76.590911 -35.747318) (xy 76.571858 -35.724558)
			(xy 76.547065 -35.708237) (xy 76.518626 -35.699734) (xy 76.503784 -35.699192) (xy 75.71232 -35.699192)
			(xy 75.697338 -35.722629) (xy 75.661656 -35.765301) (xy 75.620156 -35.802338) (xy 75.573717 -35.832957)
			(xy 75.523325 -35.856508) (xy 75.470047 -35.872492) (xy 75.415012 -35.880569) (xy 75.359388 -35.880569)
			(xy 75.304353 -35.872492) (xy 75.251075 -35.856508) (xy 75.200683 -35.832957) (xy 75.154244 -35.802338)
			(xy 75.112744 -35.765301) (xy 75.077062 -35.722629) (xy 75.06208 -35.699192) (xy 73.237344 -35.699192)
			(xy 73.22417 -35.723788) (xy 73.191726 -35.76918) (xy 73.153015 -35.809362) (xy 73.108864 -35.843476)
			(xy 73.060215 -35.870795) (xy 73.008105 -35.890736) (xy 72.953646 -35.902874) (xy 72.898 -35.906948)
			(xy 72.842354 -35.902874) (xy 72.787895 -35.890736) (xy 72.735785 -35.870795) (xy 72.687136 -35.843476)
			(xy 72.642985 -35.809362) (xy 72.604274 -35.76918) (xy 72.57183 -35.723788) (xy 72.558656 -35.699192)
			(xy 72.214994 -35.699192) (xy 72.199829 -35.721628) (xy 72.164168 -35.762381) (xy 72.123098 -35.797676)
			(xy 72.077446 -35.826804) (xy 72.028131 -35.849177) (xy 71.976147 -35.864346) (xy 71.922538 -35.872005)
			(xy 71.895462 -35.87242) (xy 71.863273 -35.87173) (xy 71.799815 -35.860873) (xy 71.769224 -35.85083)
			(xy 71.754741 -35.846307) (xy 71.724441 -35.845049) (xy 71.695107 -35.852742) (xy 71.669325 -35.86871)
			(xy 71.649368 -35.891543) (xy 71.642732 -35.905186) (xy 71.631095 -35.93004) (xy 71.601745 -35.976409)
			(xy 71.566055 -36.018096) (xy 71.524761 -36.054241) (xy 71.478716 -36.084097) (xy 71.428868 -36.107049)
			(xy 71.376247 -36.122623) (xy 71.321937 -36.130498) (xy 71.294498 -36.130992) (xy 71.26727 -36.130507)
			(xy 71.213368 -36.122763) (xy 71.161115 -36.107434) (xy 71.111573 -36.084829) (xy 71.065749 -36.05541)
			(xy 71.024574 -36.019773) (xy 70.988884 -35.978644) (xy 70.959406 -35.932857) (xy 70.936738 -35.883344)
			(xy 70.921341 -35.831111) (xy 70.913528 -35.777219) (xy 70.91299 -35.749992) (xy 70.91299 -35.699192)
			(xy 70.696836 -35.699192) (xy 70.689724 -35.741356) (xy 70.6845 -35.769048) (xy 70.66698 -35.822606)
			(xy 70.641773 -35.873006) (xy 70.609429 -35.91915) (xy 70.570649 -35.960036) (xy 70.526279 -35.994774)
			(xy 70.477282 -36.022608) (xy 70.424724 -36.042934) (xy 70.369748 -36.055309) (xy 70.31355 -36.059464)
			(xy 70.257352 -36.055309) (xy 70.202376 -36.042934) (xy 70.149818 -36.022608) (xy 70.100821 -35.994774)
			(xy 70.056451 -35.960036) (xy 70.017671 -35.91915) (xy 69.985327 -35.873006) (xy 69.96012 -35.822606)
			(xy 69.9426 -35.769048) (xy 69.937376 -35.741356) (xy 69.930264 -35.699192) (xy 69.661532 -35.699192)
			(xy 69.64934 -35.732466) (xy 69.639473 -35.758004) (xy 69.613471 -35.806182) (xy 69.580849 -35.850149)
			(xy 69.542276 -35.889) (xy 69.498546 -35.921937) (xy 69.450555 -35.948285) (xy 69.399291 -35.967501)
			(xy 69.345806 -35.979191) (xy 69.2912 -35.983114) (xy 69.236594 -35.979191) (xy 69.183109 -35.967501)
			(xy 69.131845 -35.948285) (xy 69.083854 -35.921937) (xy 69.040124 -35.889) (xy 69.001551 -35.850149)
			(xy 68.968929 -35.806182) (xy 68.942927 -35.758004) (xy 68.93306 -35.732466) (xy 68.920868 -35.699192)
			(xy 68.151248 -35.699192) (xy 68.13804 -35.729672) (xy 68.126551 -35.754703) (xy 68.097009 -35.801182)
			(xy 68.060664 -35.842559) (xy 68.018382 -35.877848) (xy 67.971172 -35.906208) (xy 67.920159 -35.926962)
			(xy 67.866559 -35.939616) (xy 67.81165 -35.943867) (xy 67.756741 -35.939616) (xy 67.703141 -35.926962)
			(xy 67.652128 -35.906208) (xy 67.604918 -35.877848) (xy 67.562636 -35.842559) (xy 67.526291 -35.801182)
			(xy 67.496749 -35.754703) (xy 67.48526 -35.729672) (xy 67.472052 -35.699192) (xy 66.504058 -35.699192)
			(xy 66.489946 -35.699643) (xy 66.462799 -35.707359) (xy 66.438804 -35.722217) (xy 66.419797 -35.743081)
			(xy 66.407233 -35.768353) (xy 66.402074 -35.7961) (xy 66.402966 -35.81019) (xy 66.40449 -35.844988)
			(xy 66.404004 -35.872239) (xy 66.396248 -35.926187) (xy 66.380893 -35.978482) (xy 66.358251 -36.028059)
			(xy 66.328785 -36.073909) (xy 66.293094 -36.1151) (xy 66.251903 -36.150791) (xy 66.206053 -36.180257)
			(xy 66.156476 -36.202899) (xy 66.104181 -36.218254) (xy 66.050233 -36.22601) (xy 65.995731 -36.22601)
			(xy 65.941783 -36.218254) (xy 65.889488 -36.202899) (xy 65.839911 -36.180257) (xy 65.794061 -36.150791)
			(xy 65.75287 -36.1151) (xy 65.717179 -36.073909) (xy 65.687713 -36.028059) (xy 65.665071 -35.978482)
			(xy 65.649716 -35.926187) (xy 65.64196 -35.872239) (xy 65.641474 -35.844988) (xy 65.642998 -35.81019)
			(xy 65.643847 -35.796103) (xy 65.638671 -35.76837) (xy 65.626107 -35.743111) (xy 65.607113 -35.722252)
			(xy 65.583139 -35.707383) (xy 65.556011 -35.699638) (xy 65.541906 -35.699192) (xy 62.431676 -35.699192)
			(xy 62.418528 -35.699607) (xy 62.393105 -35.706333) (xy 62.370246 -35.719333) (xy 62.351468 -35.737742)
			(xy 62.338017 -35.760339) (xy 62.330788 -35.785623) (xy 62.330076 -35.79876) (xy 62.329042 -35.826962)
			(xy 62.319691 -35.882616) (xy 62.302245 -35.936285) (xy 62.277085 -35.9868) (xy 62.244759 -36.033058)
			(xy 62.205972 -36.07405) (xy 62.161571 -36.108882) (xy 62.112523 -36.136795) (xy 62.0599 -36.157179)
			(xy 62.004848 -36.16959) (xy 61.948568 -36.173757) (xy 61.892288 -36.16959) (xy 61.837236 -36.157179)
			(xy 61.784613 -36.136795) (xy 61.735565 -36.108882) (xy 61.691164 -36.07405) (xy 61.652377 -36.033058)
			(xy 61.620051 -35.9868) (xy 61.594891 -35.936285) (xy 61.577445 -35.882616) (xy 61.568094 -35.826962)
			(xy 61.56706 -35.79876) (xy 61.566383 -35.785621) (xy 61.559151 -35.760335) (xy 61.545694 -35.737738)
			(xy 61.526907 -35.719332) (xy 61.504039 -35.706341) (xy 61.47861 -35.699627) (xy 61.46546 -35.699192)
			(xy 58.534808 -35.699192) (xy 54.685692 -31.850076) (xy 54.685692 -22.195536) (xy 18.261076 -22.195536)
			(xy 15.847568 -24.609044) (xy 15.847568 -27.757628) (xy 16.877792 -28.721304) (xy 16.924128 -28.765343)
			(xy 17.011875 -28.858325) (xy 17.093683 -28.956572) (xy 17.169237 -29.059707) (xy 17.238245 -29.167331)
			(xy 17.300441 -29.27903) (xy 17.355586 -29.394374) (xy 17.403467 -29.512917) (xy 17.4439 -29.634203)
			(xy 17.476728 -29.757764) (xy 17.501825 -29.883124) (xy 17.519095 -30.009801) (xy 17.528471 -30.137304)
			(xy 17.529916 -30.265144) (xy 17.523425 -30.392827) (xy 17.509023 -30.519861) (xy 17.486766 -30.645757)
			(xy 17.45674 -30.770029) (xy 17.419059 -30.892198) (xy 17.37387 -31.011793) (xy 17.321347 -31.128354)
			(xy 17.261692 -31.24143) (xy 17.195134 -31.350587) (xy 17.121931 -31.455403) (xy 17.042365 -31.555475)
			(xy 16.956742 -31.650416) (xy 16.865393 -31.739861) (xy 16.768669 -31.823465) (xy 16.666944 -31.900905)
			(xy 16.560609 -31.971884) (xy 16.450074 -32.036127) (xy 16.335766 -32.093387) (xy 16.218125 -32.143443)
			(xy 16.097604 -32.186103) (xy 15.974669 -32.221201) (xy 15.912338 -32.235394) (xy 15.89786 -32.238696)
			(xy 14.092174 -34.044382) (xy 10.08761 -34.044382) (xy 6.357366 -30.314138) (xy 2.517394 -30.314138)
			(xy 0.98171 -31.849822) (xy 0.98171 -36.65728) (xy 63.675512 -36.65728) (xy 63.679583 -36.601658)
			(xy 63.691709 -36.547221) (xy 63.711632 -36.49513) (xy 63.738928 -36.446495) (xy 63.773014 -36.402352)
			(xy 63.813163 -36.363643) (xy 63.858521 -36.331192) (xy 63.908121 -36.305691) (xy 63.960905 -36.287684)
			(xy 64.015748 -36.277554) (xy 64.071482 -36.275517) (xy 64.126919 -36.281617) (xy 64.180876 -36.295723)
			(xy 64.232205 -36.317535) (xy 64.279811 -36.346589) (xy 64.322679 -36.382264) (xy 64.359896 -36.423801)
			(xy 64.390669 -36.470314) (xy 64.414341 -36.520811) (xy 64.430409 -36.574218) (xy 64.438529 -36.629394)
			(xy 64.439038 -36.65728) (xy 64.438529 -36.685166) (xy 64.430409 -36.740342) (xy 64.414341 -36.793749)
			(xy 64.390669 -36.844246) (xy 64.359896 -36.890759) (xy 64.322679 -36.932296) (xy 64.279811 -36.967971)
			(xy 64.232205 -36.997025) (xy 64.180876 -37.018837) (xy 64.126919 -37.032943) (xy 64.071482 -37.039043)
			(xy 64.015748 -37.037006) (xy 63.960905 -37.026876) (xy 63.908121 -37.008869) (xy 63.858521 -36.983368)
			(xy 63.813163 -36.950917) (xy 63.773014 -36.912208) (xy 63.738928 -36.868065) (xy 63.711632 -36.81943)
			(xy 63.691709 -36.767339) (xy 63.679583 -36.712902) (xy 63.675512 -36.65728) (xy 0.98171 -36.65728)
			(xy 0.98171 -37.897562) (xy 75.723494 -37.897562) (xy 75.727565 -37.84194) (xy 75.739691 -37.787503)
			(xy 75.759614 -37.735412) (xy 75.78691 -37.686777) (xy 75.820996 -37.642634) (xy 75.861145 -37.603925)
			(xy 75.906503 -37.571474) (xy 75.956103 -37.545973) (xy 76.008887 -37.527966) (xy 76.06373 -37.517836)
			(xy 76.119464 -37.515799) (xy 76.174901 -37.521899) (xy 76.228858 -37.536005) (xy 76.280187 -37.557817)
			(xy 76.327793 -37.586871) (xy 76.370661 -37.622546) (xy 76.407878 -37.664083) (xy 76.438651 -37.710596)
			(xy 76.45426 -37.743892) (xy 82.100164 -37.743892) (xy 82.104235 -37.68827) (xy 82.116361 -37.633833)
			(xy 82.136284 -37.581742) (xy 82.16358 -37.533107) (xy 82.197666 -37.488964) (xy 82.237815 -37.450255)
			(xy 82.283173 -37.417804) (xy 82.332773 -37.392303) (xy 82.385557 -37.374296) (xy 82.4404 -37.364166)
			(xy 82.496134 -37.362129) (xy 82.551571 -37.368229) (xy 82.605528 -37.382335) (xy 82.656857 -37.404147)
			(xy 82.704463 -37.433201) (xy 82.747331 -37.468876) (xy 82.784548 -37.510413) (xy 82.815321 -37.556926)
			(xy 82.838993 -37.607423) (xy 82.855061 -37.66083) (xy 82.863181 -37.716006) (xy 82.86369 -37.743892)
			(xy 82.863181 -37.771778) (xy 82.855061 -37.826954) (xy 82.838993 -37.880361) (xy 82.815321 -37.930858)
			(xy 82.784548 -37.977371) (xy 82.747331 -38.018908) (xy 82.704463 -38.054583) (xy 82.656857 -38.083637)
			(xy 82.605528 -38.105449) (xy 82.551571 -38.119555) (xy 82.496134 -38.125655) (xy 82.4404 -38.123618)
			(xy 82.385557 -38.113488) (xy 82.332773 -38.095481) (xy 82.283173 -38.06998) (xy 82.237815 -38.037529)
			(xy 82.197666 -37.99882) (xy 82.16358 -37.954677) (xy 82.136284 -37.906042) (xy 82.116361 -37.853951)
			(xy 82.104235 -37.799514) (xy 82.100164 -37.743892) (xy 76.45426 -37.743892) (xy 76.462323 -37.761093)
			(xy 76.478391 -37.8145) (xy 76.486511 -37.869676) (xy 76.48702 -37.897562) (xy 76.486511 -37.925448)
			(xy 76.478391 -37.980624) (xy 76.462323 -38.034031) (xy 76.438651 -38.084528) (xy 76.407878 -38.131041)
			(xy 76.370661 -38.172578) (xy 76.327793 -38.208253) (xy 76.280187 -38.237307) (xy 76.228858 -38.259119)
			(xy 76.174901 -38.273225) (xy 76.119464 -38.279325) (xy 76.06373 -38.277288) (xy 76.008887 -38.267158)
			(xy 75.956103 -38.249151) (xy 75.906503 -38.22365) (xy 75.861145 -38.191199) (xy 75.820996 -38.15249)
			(xy 75.78691 -38.108347) (xy 75.759614 -38.059712) (xy 75.739691 -38.007621) (xy 75.727565 -37.953184)
			(xy 75.723494 -37.897562) (xy 0.98171 -37.897562) (xy 0.98171 -38.554152) (xy 61.140592 -38.554152)
			(xy 61.144663 -38.49853) (xy 61.156789 -38.444093) (xy 61.176712 -38.392002) (xy 61.204008 -38.343367)
			(xy 61.238094 -38.299224) (xy 61.278243 -38.260515) (xy 61.323601 -38.228064) (xy 61.373201 -38.202563)
			(xy 61.425985 -38.184556) (xy 61.480828 -38.174426) (xy 61.536562 -38.172389) (xy 61.591999 -38.178489)
			(xy 61.645956 -38.192595) (xy 61.697285 -38.214407) (xy 61.744891 -38.243461) (xy 61.787759 -38.279136)
			(xy 61.824976 -38.320673) (xy 61.855749 -38.367186) (xy 61.85695 -38.369748) (xy 65.810382 -38.369748)
			(xy 65.814453 -38.314126) (xy 65.826579 -38.259689) (xy 65.846502 -38.207598) (xy 65.873798 -38.158963)
			(xy 65.907884 -38.11482) (xy 65.948033 -38.076111) (xy 65.993391 -38.04366) (xy 66.042991 -38.018159)
			(xy 66.095775 -38.000152) (xy 66.150618 -37.990022) (xy 66.206352 -37.987985) (xy 66.261789 -37.994085)
			(xy 66.315746 -38.008191) (xy 66.367075 -38.030003) (xy 66.414681 -38.059057) (xy 66.457549 -38.094732)
			(xy 66.494766 -38.136269) (xy 66.525539 -38.182782) (xy 66.549211 -38.233279) (xy 66.565279 -38.286686)
			(xy 66.573399 -38.341862) (xy 66.573908 -38.369748) (xy 66.573399 -38.397634) (xy 66.572232 -38.405562)
			(xy 66.820794 -38.405562) (xy 66.824865 -38.34994) (xy 66.836991 -38.295503) (xy 66.856914 -38.243412)
			(xy 66.88421 -38.194777) (xy 66.918296 -38.150634) (xy 66.958445 -38.111925) (xy 67.003803 -38.079474)
			(xy 67.053403 -38.053973) (xy 67.106187 -38.035966) (xy 67.16103 -38.025836) (xy 67.216764 -38.023799)
			(xy 67.272201 -38.029899) (xy 67.326158 -38.044005) (xy 67.377487 -38.065817) (xy 67.425093 -38.094871)
			(xy 67.467961 -38.130546) (xy 67.505178 -38.172083) (xy 67.535951 -38.218596) (xy 67.559623 -38.269093)
			(xy 67.575691 -38.3225) (xy 67.583811 -38.377676) (xy 67.58432 -38.405562) (xy 67.583811 -38.433448)
			(xy 67.575691 -38.488624) (xy 67.559623 -38.542031) (xy 67.535951 -38.592528) (xy 67.505178 -38.639041)
			(xy 67.467961 -38.680578) (xy 67.425093 -38.716253) (xy 67.393127 -38.735762) (xy 71.742044 -38.735762)
			(xy 71.746115 -38.68014) (xy 71.758241 -38.625703) (xy 71.778164 -38.573612) (xy 71.80546 -38.524977)
			(xy 71.839546 -38.480834) (xy 71.879695 -38.442125) (xy 71.925053 -38.409674) (xy 71.974653 -38.384173)
			(xy 72.027437 -38.366166) (xy 72.08228 -38.356036) (xy 72.138014 -38.353999) (xy 72.193451 -38.360099)
			(xy 72.247408 -38.374205) (xy 72.298737 -38.396017) (xy 72.346343 -38.425071) (xy 72.389211 -38.460746)
			(xy 72.426428 -38.502283) (xy 72.457201 -38.548796) (xy 72.480873 -38.599293) (xy 72.496941 -38.6527)
			(xy 72.505061 -38.707876) (xy 72.50557 -38.735762) (xy 72.505061 -38.763648) (xy 72.496941 -38.818824)
			(xy 72.480873 -38.872231) (xy 72.457201 -38.922728) (xy 72.426428 -38.969241) (xy 72.389211 -39.010778)
			(xy 72.346343 -39.046453) (xy 72.307718 -39.070026) (xy 74.434444 -39.070026) (xy 74.438515 -39.014404)
			(xy 74.450641 -38.959967) (xy 74.470564 -38.907876) (xy 74.49786 -38.859241) (xy 74.531946 -38.815098)
			(xy 74.572095 -38.776389) (xy 74.617453 -38.743938) (xy 74.667053 -38.718437) (xy 74.719837 -38.70043)
			(xy 74.77468 -38.6903) (xy 74.830414 -38.688263) (xy 74.885851 -38.694363) (xy 74.939808 -38.708469)
			(xy 74.991137 -38.730281) (xy 75.038743 -38.759335) (xy 75.081611 -38.79501) (xy 75.118828 -38.836547)
			(xy 75.149601 -38.88306) (xy 75.173273 -38.933557) (xy 75.188196 -38.983158) (xy 108.782102 -38.983158)
			(xy 108.786173 -38.927536) (xy 108.798299 -38.873099) (xy 108.818222 -38.821008) (xy 108.845518 -38.772373)
			(xy 108.879604 -38.72823) (xy 108.919753 -38.689521) (xy 108.965111 -38.65707) (xy 109.014711 -38.631569)
			(xy 109.067495 -38.613562) (xy 109.122338 -38.603432) (xy 109.178072 -38.601395) (xy 109.233509 -38.607495)
			(xy 109.287466 -38.621601) (xy 109.338795 -38.643413) (xy 109.386401 -38.672467) (xy 109.429269 -38.708142)
			(xy 109.466486 -38.749679) (xy 109.483998 -38.776148) (xy 113.091466 -38.776148) (xy 113.095537 -38.720526)
			(xy 113.107663 -38.666089) (xy 113.127586 -38.613998) (xy 113.154882 -38.565363) (xy 113.188968 -38.52122)
			(xy 113.229117 -38.482511) (xy 113.274475 -38.45006) (xy 113.324075 -38.424559) (xy 113.376859 -38.406552)
			(xy 113.431702 -38.396422) (xy 113.487436 -38.394385) (xy 113.542873 -38.400485) (xy 113.59683 -38.414591)
			(xy 113.648159 -38.436403) (xy 113.695765 -38.465457) (xy 113.738633 -38.501132) (xy 113.77585 -38.542669)
			(xy 113.806623 -38.589182) (xy 113.830295 -38.639679) (xy 113.846363 -38.693086) (xy 113.854483 -38.748262)
			(xy 113.854992 -38.776148) (xy 113.854483 -38.804034) (xy 113.846363 -38.85921) (xy 113.830295 -38.912617)
			(xy 113.806623 -38.963114) (xy 113.77585 -39.009627) (xy 113.738633 -39.051164) (xy 113.695765 -39.086839)
			(xy 113.648159 -39.115893) (xy 113.59683 -39.137705) (xy 113.542873 -39.151811) (xy 113.487436 -39.157911)
			(xy 113.431702 -39.155874) (xy 113.376859 -39.145744) (xy 113.324075 -39.127737) (xy 113.274475 -39.102236)
			(xy 113.229117 -39.069785) (xy 113.188968 -39.031076) (xy 113.154882 -38.986933) (xy 113.127586 -38.938298)
			(xy 113.107663 -38.886207) (xy 113.095537 -38.83177) (xy 113.091466 -38.776148) (xy 109.483998 -38.776148)
			(xy 109.497259 -38.796192) (xy 109.520931 -38.846689) (xy 109.536999 -38.900096) (xy 109.545119 -38.955272)
			(xy 109.545628 -38.983158) (xy 109.545119 -39.011044) (xy 109.536999 -39.06622) (xy 109.520931 -39.119627)
			(xy 109.497259 -39.170124) (xy 109.466486 -39.216637) (xy 109.429269 -39.258174) (xy 109.386401 -39.293849)
			(xy 109.338795 -39.322903) (xy 109.309255 -39.335456) (xy 114.687094 -39.335456) (xy 114.691165 -39.279834)
			(xy 114.703291 -39.225397) (xy 114.723214 -39.173306) (xy 114.75051 -39.124671) (xy 114.784596 -39.080528)
			(xy 114.824745 -39.041819) (xy 114.870103 -39.009368) (xy 114.919703 -38.983867) (xy 114.972487 -38.96586)
			(xy 115.02733 -38.95573) (xy 115.083064 -38.953693) (xy 115.138501 -38.959793) (xy 115.192458 -38.973899)
			(xy 115.243787 -38.995711) (xy 115.291393 -39.024765) (xy 115.334261 -39.06044) (xy 115.371478 -39.101977)
			(xy 115.402251 -39.14849) (xy 115.425923 -39.198987) (xy 115.441991 -39.252394) (xy 115.450111 -39.30757)
			(xy 115.45062 -39.335456) (xy 115.450111 -39.363342) (xy 115.441991 -39.418518) (xy 115.425923 -39.471925)
			(xy 115.402251 -39.522422) (xy 115.371478 -39.568935) (xy 115.334261 -39.610472) (xy 115.291393 -39.646147)
			(xy 115.243787 -39.675201) (xy 115.192458 -39.697013) (xy 115.138501 -39.711119) (xy 115.083064 -39.717219)
			(xy 115.02733 -39.715182) (xy 114.972487 -39.705052) (xy 114.919703 -39.687045) (xy 114.870103 -39.661544)
			(xy 114.824745 -39.629093) (xy 114.784596 -39.590384) (xy 114.75051 -39.546241) (xy 114.723214 -39.497606)
			(xy 114.703291 -39.445515) (xy 114.691165 -39.391078) (xy 114.687094 -39.335456) (xy 109.309255 -39.335456)
			(xy 109.287466 -39.344715) (xy 109.233509 -39.358821) (xy 109.178072 -39.364921) (xy 109.122338 -39.362884)
			(xy 109.067495 -39.352754) (xy 109.014711 -39.334747) (xy 108.965111 -39.309246) (xy 108.919753 -39.276795)
			(xy 108.879604 -39.238086) (xy 108.845518 -39.193943) (xy 108.818222 -39.145308) (xy 108.798299 -39.093217)
			(xy 108.786173 -39.03878) (xy 108.782102 -38.983158) (xy 75.188196 -38.983158) (xy 75.189341 -38.986964)
			(xy 75.197461 -39.04214) (xy 75.19797 -39.070026) (xy 75.197461 -39.097912) (xy 75.189341 -39.153088)
			(xy 75.173273 -39.206495) (xy 75.149601 -39.256992) (xy 75.118828 -39.303505) (xy 75.081611 -39.345042)
			(xy 75.038743 -39.380717) (xy 74.991137 -39.409771) (xy 74.939808 -39.431583) (xy 74.885851 -39.445689)
			(xy 74.830414 -39.451789) (xy 74.77468 -39.449752) (xy 74.719837 -39.439622) (xy 74.667053 -39.421615)
			(xy 74.617453 -39.396114) (xy 74.572095 -39.363663) (xy 74.531946 -39.324954) (xy 74.49786 -39.280811)
			(xy 74.470564 -39.232176) (xy 74.450641 -39.180085) (xy 74.438515 -39.125648) (xy 74.434444 -39.070026)
			(xy 72.307718 -39.070026) (xy 72.298737 -39.075507) (xy 72.247408 -39.097319) (xy 72.193451 -39.111425)
			(xy 72.138014 -39.117525) (xy 72.08228 -39.115488) (xy 72.027437 -39.105358) (xy 71.974653 -39.087351)
			(xy 71.925053 -39.06185) (xy 71.879695 -39.029399) (xy 71.839546 -38.99069) (xy 71.80546 -38.946547)
			(xy 71.778164 -38.897912) (xy 71.758241 -38.845821) (xy 71.746115 -38.791384) (xy 71.742044 -38.735762)
			(xy 67.393127 -38.735762) (xy 67.377487 -38.745307) (xy 67.326158 -38.767119) (xy 67.272201 -38.781225)
			(xy 67.216764 -38.787325) (xy 67.16103 -38.785288) (xy 67.106187 -38.775158) (xy 67.053403 -38.757151)
			(xy 67.003803 -38.73165) (xy 66.958445 -38.699199) (xy 66.918296 -38.66049) (xy 66.88421 -38.616347)
			(xy 66.856914 -38.567712) (xy 66.836991 -38.515621) (xy 66.824865 -38.461184) (xy 66.820794 -38.405562)
			(xy 66.572232 -38.405562) (xy 66.565279 -38.45281) (xy 66.549211 -38.506217) (xy 66.525539 -38.556714)
			(xy 66.494766 -38.603227) (xy 66.457549 -38.644764) (xy 66.414681 -38.680439) (xy 66.367075 -38.709493)
			(xy 66.315746 -38.731305) (xy 66.261789 -38.745411) (xy 66.206352 -38.751511) (xy 66.150618 -38.749474)
			(xy 66.095775 -38.739344) (xy 66.042991 -38.721337) (xy 65.993391 -38.695836) (xy 65.948033 -38.663385)
			(xy 65.907884 -38.624676) (xy 65.873798 -38.580533) (xy 65.846502 -38.531898) (xy 65.826579 -38.479807)
			(xy 65.814453 -38.42537) (xy 65.810382 -38.369748) (xy 61.85695 -38.369748) (xy 61.879421 -38.417683)
			(xy 61.895489 -38.47109) (xy 61.903609 -38.526266) (xy 61.904118 -38.554152) (xy 61.903609 -38.582038)
			(xy 61.895489 -38.637214) (xy 61.879421 -38.690621) (xy 61.855749 -38.741118) (xy 61.827196 -38.784276)
			(xy 63.050672 -38.784276) (xy 63.054743 -38.728654) (xy 63.066869 -38.674217) (xy 63.086792 -38.622126)
			(xy 63.114088 -38.573491) (xy 63.148174 -38.529348) (xy 63.188323 -38.490639) (xy 63.233681 -38.458188)
			(xy 63.283281 -38.432687) (xy 63.336065 -38.41468) (xy 63.390908 -38.40455) (xy 63.446642 -38.402513)
			(xy 63.502079 -38.408613) (xy 63.556036 -38.422719) (xy 63.607365 -38.444531) (xy 63.654971 -38.473585)
			(xy 63.697839 -38.50926) (xy 63.735056 -38.550797) (xy 63.765829 -38.59731) (xy 63.789501 -38.647807)
			(xy 63.805569 -38.701214) (xy 63.813689 -38.75639) (xy 63.814198 -38.784276) (xy 63.813689 -38.812162)
			(xy 63.805569 -38.867338) (xy 63.789501 -38.920745) (xy 63.765829 -38.971242) (xy 63.735056 -39.017755)
			(xy 63.697839 -39.059292) (xy 63.654971 -39.094967) (xy 63.607365 -39.124021) (xy 63.556036 -39.145833)
			(xy 63.502079 -39.159939) (xy 63.446642 -39.166039) (xy 63.390908 -39.164002) (xy 63.336065 -39.153872)
			(xy 63.283281 -39.135865) (xy 63.233681 -39.110364) (xy 63.188323 -39.077913) (xy 63.148174 -39.039204)
			(xy 63.114088 -38.995061) (xy 63.086792 -38.946426) (xy 63.066869 -38.894335) (xy 63.054743 -38.839898)
			(xy 63.050672 -38.784276) (xy 61.827196 -38.784276) (xy 61.824976 -38.787631) (xy 61.787759 -38.829168)
			(xy 61.744891 -38.864843) (xy 61.697285 -38.893897) (xy 61.645956 -38.915709) (xy 61.591999 -38.929815)
			(xy 61.536562 -38.935915) (xy 61.480828 -38.933878) (xy 61.425985 -38.923748) (xy 61.373201 -38.905741)
			(xy 61.323601 -38.88024) (xy 61.278243 -38.847789) (xy 61.238094 -38.80908) (xy 61.204008 -38.764937)
			(xy 61.176712 -38.716302) (xy 61.156789 -38.664211) (xy 61.144663 -38.609774) (xy 61.140592 -38.554152)
			(xy 0.98171 -38.554152) (xy 0.98171 -39.421562) (xy 66.820794 -39.421562) (xy 66.824865 -39.36594)
			(xy 66.836991 -39.311503) (xy 66.856914 -39.259412) (xy 66.88421 -39.210777) (xy 66.918296 -39.166634)
			(xy 66.958445 -39.127925) (xy 67.003803 -39.095474) (xy 67.053403 -39.069973) (xy 67.106187 -39.051966)
			(xy 67.16103 -39.041836) (xy 67.216764 -39.039799) (xy 67.272201 -39.045899) (xy 67.326158 -39.060005)
			(xy 67.377487 -39.081817) (xy 67.425093 -39.110871) (xy 67.467961 -39.146546) (xy 67.505178 -39.188083)
			(xy 67.535951 -39.234596) (xy 67.559623 -39.285093) (xy 67.575691 -39.3385) (xy 67.583811 -39.393676)
			(xy 67.58432 -39.421562) (xy 67.583811 -39.449448) (xy 67.575691 -39.504624) (xy 67.559623 -39.558031)
			(xy 67.535951 -39.608528) (xy 67.505178 -39.655041) (xy 67.467961 -39.696578) (xy 67.425093 -39.732253)
			(xy 67.377487 -39.761307) (xy 67.326158 -39.783119) (xy 67.272201 -39.797225) (xy 67.216764 -39.803325)
			(xy 67.16103 -39.801288) (xy 67.106187 -39.791158) (xy 67.053403 -39.773151) (xy 67.003803 -39.74765)
			(xy 66.958445 -39.715199) (xy 66.918296 -39.67649) (xy 66.88421 -39.632347) (xy 66.856914 -39.583712)
			(xy 66.836991 -39.531621) (xy 66.824865 -39.477184) (xy 66.820794 -39.421562) (xy 0.98171 -39.421562)
			(xy 0.98171 -39.808658) (xy 64.961006 -39.808658) (xy 64.965077 -39.753036) (xy 64.977203 -39.698599)
			(xy 64.997126 -39.646508) (xy 65.024422 -39.597873) (xy 65.058508 -39.55373) (xy 65.098657 -39.515021)
			(xy 65.144015 -39.48257) (xy 65.193615 -39.457069) (xy 65.246399 -39.439062) (xy 65.301242 -39.428932)
			(xy 65.356976 -39.426895) (xy 65.412413 -39.432995) (xy 65.46637 -39.447101) (xy 65.517699 -39.468913)
			(xy 65.565305 -39.497967) (xy 65.608173 -39.533642) (xy 65.64539 -39.575179) (xy 65.676163 -39.621692)
			(xy 65.699835 -39.672189) (xy 65.715903 -39.725596) (xy 65.724023 -39.780772) (xy 65.724532 -39.808658)
			(xy 65.724023 -39.836544) (xy 65.715903 -39.89172) (xy 65.715293 -39.893748) (xy 72.902062 -39.893748)
			(xy 72.906133 -39.838126) (xy 72.918259 -39.783689) (xy 72.938182 -39.731598) (xy 72.965478 -39.682963)
			(xy 72.999564 -39.63882) (xy 73.039713 -39.600111) (xy 73.085071 -39.56766) (xy 73.134671 -39.542159)
			(xy 73.187455 -39.524152) (xy 73.242298 -39.514022) (xy 73.298032 -39.511985) (xy 73.353469 -39.518085)
			(xy 73.407426 -39.532191) (xy 73.458755 -39.554003) (xy 73.503944 -39.581582) (xy 98.888802 -39.581582)
			(xy 98.892873 -39.52596) (xy 98.904999 -39.471523) (xy 98.924922 -39.419432) (xy 98.952218 -39.370797)
			(xy 98.986304 -39.326654) (xy 99.026453 -39.287945) (xy 99.071811 -39.255494) (xy 99.121411 -39.229993)
			(xy 99.174195 -39.211986) (xy 99.229038 -39.201856) (xy 99.284772 -39.199819) (xy 99.340209 -39.205919)
			(xy 99.394166 -39.220025) (xy 99.445495 -39.241837) (xy 99.493101 -39.270891) (xy 99.535969 -39.306566)
			(xy 99.573186 -39.348103) (xy 99.603959 -39.394616) (xy 99.627631 -39.445113) (xy 99.643699 -39.49852)
			(xy 99.651819 -39.553696) (xy 99.652328 -39.581582) (xy 99.651819 -39.609468) (xy 99.643699 -39.664644)
			(xy 99.627631 -39.718051) (xy 99.603959 -39.768548) (xy 99.573186 -39.815061) (xy 99.535969 -39.856598)
			(xy 99.493101 -39.892273) (xy 99.445495 -39.921327) (xy 99.394166 -39.943139) (xy 99.340209 -39.957245)
			(xy 99.284772 -39.963345) (xy 99.229038 -39.961308) (xy 99.174195 -39.951178) (xy 99.121411 -39.933171)
			(xy 99.071811 -39.90767) (xy 99.026453 -39.875219) (xy 98.986304 -39.83651) (xy 98.952218 -39.792367)
			(xy 98.924922 -39.743732) (xy 98.904999 -39.691641) (xy 98.892873 -39.637204) (xy 98.888802 -39.581582)
			(xy 73.503944 -39.581582) (xy 73.506361 -39.583057) (xy 73.549229 -39.618732) (xy 73.586446 -39.660269)
			(xy 73.617219 -39.706782) (xy 73.640891 -39.757279) (xy 73.656959 -39.810686) (xy 73.665079 -39.865862)
			(xy 73.665588 -39.893748) (xy 73.665079 -39.921634) (xy 73.656959 -39.97681) (xy 73.640891 -40.030217)
			(xy 73.617219 -40.080714) (xy 73.586446 -40.127227) (xy 73.549229 -40.168764) (xy 73.506361 -40.204439)
			(xy 73.458755 -40.233493) (xy 73.407426 -40.255305) (xy 73.353469 -40.269411) (xy 73.298032 -40.275511)
			(xy 73.242298 -40.273474) (xy 73.187455 -40.263344) (xy 73.134671 -40.245337) (xy 73.085071 -40.219836)
			(xy 73.039713 -40.187385) (xy 72.999564 -40.148676) (xy 72.965478 -40.104533) (xy 72.938182 -40.055898)
			(xy 72.918259 -40.003807) (xy 72.906133 -39.94937) (xy 72.902062 -39.893748) (xy 65.715293 -39.893748)
			(xy 65.699835 -39.945127) (xy 65.676163 -39.995624) (xy 65.64539 -40.042137) (xy 65.608173 -40.083674)
			(xy 65.565305 -40.119349) (xy 65.517699 -40.148403) (xy 65.46637 -40.170215) (xy 65.412413 -40.184321)
			(xy 65.356976 -40.190421) (xy 65.301242 -40.188384) (xy 65.246399 -40.178254) (xy 65.193615 -40.160247)
			(xy 65.144015 -40.134746) (xy 65.098657 -40.102295) (xy 65.058508 -40.063586) (xy 65.024422 -40.019443)
			(xy 64.997126 -39.970808) (xy 64.977203 -39.918717) (xy 64.965077 -39.86428) (xy 64.961006 -39.808658)
			(xy 0.98171 -39.808658) (xy 0.98171 -40.564308) (xy 61.972442 -40.564308) (xy 61.976513 -40.508686)
			(xy 61.988639 -40.454249) (xy 62.008562 -40.402158) (xy 62.035858 -40.353523) (xy 62.069944 -40.30938)
			(xy 62.110093 -40.270671) (xy 62.155451 -40.23822) (xy 62.205051 -40.212719) (xy 62.257835 -40.194712)
			(xy 62.312678 -40.184582) (xy 62.368412 -40.182545) (xy 62.423849 -40.188645) (xy 62.477806 -40.202751)
			(xy 62.529135 -40.224563) (xy 62.576741 -40.253617) (xy 62.619609 -40.289292) (xy 62.656826 -40.330829)
			(xy 62.687599 -40.377342) (xy 62.711271 -40.427839) (xy 62.727339 -40.481246) (xy 62.73433 -40.528748)
			(xy 65.683382 -40.528748) (xy 65.687453 -40.473126) (xy 65.699579 -40.418689) (xy 65.719502 -40.366598)
			(xy 65.746798 -40.317963) (xy 65.780884 -40.27382) (xy 65.821033 -40.235111) (xy 65.866391 -40.20266)
			(xy 65.915991 -40.177159) (xy 65.968775 -40.159152) (xy 66.023618 -40.149022) (xy 66.079352 -40.146985)
			(xy 66.134789 -40.153085) (xy 66.188746 -40.167191) (xy 66.240075 -40.189003) (xy 66.287681 -40.218057)
			(xy 66.330549 -40.253732) (xy 66.367766 -40.295269) (xy 66.398539 -40.341782) (xy 66.422211 -40.392279)
			(xy 66.435835 -40.437562) (xy 66.820794 -40.437562) (xy 66.824865 -40.38194) (xy 66.836991 -40.327503)
			(xy 66.856914 -40.275412) (xy 66.88421 -40.226777) (xy 66.918296 -40.182634) (xy 66.958445 -40.143925)
			(xy 67.003803 -40.111474) (xy 67.053403 -40.085973) (xy 67.106187 -40.067966) (xy 67.16103 -40.057836)
			(xy 67.216764 -40.055799) (xy 67.272201 -40.061899) (xy 67.326158 -40.076005) (xy 67.377487 -40.097817)
			(xy 67.425093 -40.126871) (xy 67.467961 -40.162546) (xy 67.505178 -40.204083) (xy 67.535951 -40.250596)
			(xy 67.559623 -40.301093) (xy 67.570683 -40.337856) (xy 74.924317 -40.337856) (xy 74.924317 -40.283344)
			(xy 74.932075 -40.229386) (xy 74.947433 -40.177082) (xy 74.970079 -40.127496) (xy 74.999551 -40.081638)
			(xy 75.03525 -40.040441) (xy 75.076448 -40.004744) (xy 75.122307 -39.975273) (xy 75.171894 -39.952629)
			(xy 75.224198 -39.937272) (xy 75.278156 -39.929516) (xy 75.305412 -39.929054) (xy 75.332017 -39.92947)
			(xy 75.384713 -39.936855) (xy 75.43587 -39.951493) (xy 75.484496 -39.9731) (xy 75.529646 -40.001257)
			(xy 75.570444 -40.035417) (xy 75.606097 -40.074917) (xy 75.621388 -40.096694) (xy 75.629722 -40.108174)
			(xy 75.651466 -40.126378) (xy 75.677379 -40.137896) (xy 75.705462 -40.141836) (xy 75.733545 -40.137896)
			(xy 75.759458 -40.126378) (xy 75.781202 -40.108174) (xy 75.789536 -40.096694) (xy 75.804876 -40.074957)
			(xy 75.840533 -40.035474) (xy 75.881328 -40.001327) (xy 75.92647 -39.973177) (xy 75.975085 -39.951569)
			(xy 76.026229 -39.936922) (xy 76.078912 -39.929521) (xy 76.105512 -39.929054) (xy 76.13276 -39.929617)
			(xy 76.186701 -39.937374) (xy 76.238989 -39.952729) (xy 76.28856 -39.975368) (xy 76.334404 -40.004832)
			(xy 76.375589 -40.04052) (xy 76.411275 -40.081706) (xy 76.440737 -40.127551) (xy 76.463375 -40.177122)
			(xy 76.478728 -40.229411) (xy 76.486484 -40.283352) (xy 76.486484 -40.337848) (xy 76.478728 -40.391789)
			(xy 76.475804 -40.401748) (xy 81.107532 -40.401748) (xy 81.111603 -40.346126) (xy 81.123729 -40.291689)
			(xy 81.143652 -40.239598) (xy 81.170948 -40.190963) (xy 81.205034 -40.14682) (xy 81.245183 -40.108111)
			(xy 81.290541 -40.07566) (xy 81.340141 -40.050159) (xy 81.392925 -40.032152) (xy 81.447768 -40.022022)
			(xy 81.503502 -40.019985) (xy 81.558939 -40.026085) (xy 81.612896 -40.040191) (xy 81.664225 -40.062003)
			(xy 81.711831 -40.091057) (xy 81.754699 -40.126732) (xy 81.791916 -40.168269) (xy 81.822689 -40.214782)
			(xy 81.846361 -40.265279) (xy 81.859908 -40.310308) (xy 92.753432 -40.310308) (xy 92.757503 -40.254686)
			(xy 92.769629 -40.200249) (xy 92.789552 -40.148158) (xy 92.816848 -40.099523) (xy 92.850934 -40.05538)
			(xy 92.891083 -40.016671) (xy 92.936441 -39.98422) (xy 92.986041 -39.958719) (xy 93.038825 -39.940712)
			(xy 93.093668 -39.930582) (xy 93.149402 -39.928545) (xy 93.204839 -39.934645) (xy 93.258796 -39.948751)
			(xy 93.310125 -39.970563) (xy 93.352401 -39.996364) (xy 108.782102 -39.996364) (xy 108.786173 -39.940742)
			(xy 108.798299 -39.886305) (xy 108.818222 -39.834214) (xy 108.845518 -39.785579) (xy 108.879604 -39.741436)
			(xy 108.919753 -39.702727) (xy 108.965111 -39.670276) (xy 109.014711 -39.644775) (xy 109.067495 -39.626768)
			(xy 109.122338 -39.616638) (xy 109.178072 -39.614601) (xy 109.233509 -39.620701) (xy 109.287466 -39.634807)
			(xy 109.338795 -39.656619) (xy 109.386401 -39.685673) (xy 109.429269 -39.721348) (xy 109.466486 -39.762885)
			(xy 109.497259 -39.809398) (xy 109.520931 -39.859895) (xy 109.536999 -39.913302) (xy 109.545119 -39.968478)
			(xy 109.545628 -39.996364) (xy 109.545119 -40.02425) (xy 109.536999 -40.079426) (xy 109.520931 -40.132833)
			(xy 109.497259 -40.18333) (xy 109.466486 -40.229843) (xy 109.429269 -40.27138) (xy 109.386401 -40.307055)
			(xy 109.338795 -40.336109) (xy 109.287466 -40.357921) (xy 109.233509 -40.372027) (xy 109.178072 -40.378127)
			(xy 109.122338 -40.37609) (xy 109.067495 -40.36596) (xy 109.014711 -40.347953) (xy 108.965111 -40.322452)
			(xy 108.919753 -40.290001) (xy 108.879604 -40.251292) (xy 108.845518 -40.207149) (xy 108.818222 -40.158514)
			(xy 108.798299 -40.106423) (xy 108.786173 -40.051986) (xy 108.782102 -39.996364) (xy 93.352401 -39.996364)
			(xy 93.357731 -39.999617) (xy 93.400599 -40.035292) (xy 93.437816 -40.076829) (xy 93.468589 -40.123342)
			(xy 93.492261 -40.173839) (xy 93.508329 -40.227246) (xy 93.516449 -40.282422) (xy 93.516958 -40.310308)
			(xy 93.516449 -40.338194) (xy 93.508329 -40.39337) (xy 93.492261 -40.446777) (xy 93.468589 -40.497274)
			(xy 93.437816 -40.543787) (xy 93.400599 -40.585324) (xy 93.357731 -40.620999) (xy 93.310125 -40.650053)
			(xy 93.258796 -40.671865) (xy 93.204839 -40.685971) (xy 93.149402 -40.692071) (xy 93.093668 -40.690034)
			(xy 93.038825 -40.679904) (xy 92.986041 -40.661897) (xy 92.936441 -40.636396) (xy 92.891083 -40.603945)
			(xy 92.850934 -40.565236) (xy 92.816848 -40.521093) (xy 92.789552 -40.472458) (xy 92.769629 -40.420367)
			(xy 92.757503 -40.36593) (xy 92.753432 -40.310308) (xy 81.859908 -40.310308) (xy 81.862429 -40.318686)
			(xy 81.870549 -40.373862) (xy 81.871058 -40.401748) (xy 81.870549 -40.429634) (xy 81.862429 -40.48481)
			(xy 81.846361 -40.538217) (xy 81.822689 -40.588714) (xy 81.791916 -40.635227) (xy 81.754699 -40.676764)
			(xy 81.711831 -40.712439) (xy 81.664225 -40.741493) (xy 81.612896 -40.763305) (xy 81.558939 -40.777411)
			(xy 81.503502 -40.783511) (xy 81.447768 -40.781474) (xy 81.392925 -40.771344) (xy 81.340141 -40.753337)
			(xy 81.290541 -40.727836) (xy 81.245183 -40.695385) (xy 81.205034 -40.656676) (xy 81.170948 -40.612533)
			(xy 81.143652 -40.563898) (xy 81.123729 -40.511807) (xy 81.111603 -40.45737) (xy 81.107532 -40.401748)
			(xy 76.475804 -40.401748) (xy 76.463375 -40.444078) (xy 76.440737 -40.493649) (xy 76.411275 -40.539494)
			(xy 76.375589 -40.58068) (xy 76.334404 -40.616368) (xy 76.28856 -40.645832) (xy 76.238989 -40.668471)
			(xy 76.186701 -40.683826) (xy 76.13276 -40.691583) (xy 76.105512 -40.69207) (xy 76.078908 -40.691625)
			(xy 76.026214 -40.684244) (xy 75.975058 -40.66961) (xy 75.926432 -40.648008) (xy 75.881282 -40.619855)
			(xy 75.840483 -40.5857) (xy 75.804828 -40.546205) (xy 75.789536 -40.52443) (xy 75.781202 -40.51295)
			(xy 75.759458 -40.494746) (xy 75.733545 -40.483228) (xy 75.705462 -40.479288) (xy 75.677379 -40.483228)
			(xy 75.651466 -40.494746) (xy 75.629722 -40.51295) (xy 75.621388 -40.52443) (xy 75.606103 -40.546208)
			(xy 75.570436 -40.585688) (xy 75.529632 -40.619832) (xy 75.48448 -40.647977) (xy 75.435857 -40.669578)
			(xy 75.384704 -40.684216) (xy 75.332015 -40.691608) (xy 75.305412 -40.69207) (xy 75.278156 -40.691684)
			(xy 75.224198 -40.683928) (xy 75.171894 -40.668571) (xy 75.122307 -40.645927) (xy 75.076448 -40.616456)
			(xy 75.03525 -40.580759) (xy 74.999551 -40.539562) (xy 74.970079 -40.493704) (xy 74.947433 -40.444118)
			(xy 74.932075 -40.391814) (xy 74.924317 -40.337856) (xy 67.570683 -40.337856) (xy 67.575691 -40.3545)
			(xy 67.583811 -40.409676) (xy 67.58432 -40.437562) (xy 67.583811 -40.465448) (xy 67.575691 -40.520624)
			(xy 67.559623 -40.574031) (xy 67.535951 -40.624528) (xy 67.505178 -40.671041) (xy 67.467961 -40.712578)
			(xy 67.425093 -40.748253) (xy 67.377487 -40.777307) (xy 67.326158 -40.799119) (xy 67.272201 -40.813225)
			(xy 67.216764 -40.819325) (xy 67.16103 -40.817288) (xy 67.106187 -40.807158) (xy 67.053403 -40.789151)
			(xy 67.003803 -40.76365) (xy 66.958445 -40.731199) (xy 66.918296 -40.69249) (xy 66.88421 -40.648347)
			(xy 66.856914 -40.599712) (xy 66.836991 -40.547621) (xy 66.824865 -40.493184) (xy 66.820794 -40.437562)
			(xy 66.435835 -40.437562) (xy 66.438279 -40.445686) (xy 66.446399 -40.500862) (xy 66.446908 -40.528748)
			(xy 66.446399 -40.556634) (xy 66.438279 -40.61181) (xy 66.422211 -40.665217) (xy 66.398539 -40.715714)
			(xy 66.367766 -40.762227) (xy 66.330549 -40.803764) (xy 66.287681 -40.839439) (xy 66.240075 -40.868493)
			(xy 66.188746 -40.890305) (xy 66.134789 -40.904411) (xy 66.079352 -40.910511) (xy 66.023618 -40.908474)
			(xy 65.968775 -40.898344) (xy 65.915991 -40.880337) (xy 65.866391 -40.854836) (xy 65.821033 -40.822385)
			(xy 65.780884 -40.783676) (xy 65.746798 -40.739533) (xy 65.719502 -40.690898) (xy 65.699579 -40.638807)
			(xy 65.687453 -40.58437) (xy 65.683382 -40.528748) (xy 62.73433 -40.528748) (xy 62.735459 -40.536422)
			(xy 62.735968 -40.564308) (xy 62.735459 -40.592194) (xy 62.727339 -40.64737) (xy 62.711271 -40.700777)
			(xy 62.687599 -40.751274) (xy 62.656826 -40.797787) (xy 62.619609 -40.839324) (xy 62.576741 -40.874999)
			(xy 62.529135 -40.904053) (xy 62.477806 -40.925865) (xy 62.423849 -40.939971) (xy 62.368412 -40.946071)
			(xy 62.312678 -40.944034) (xy 62.257835 -40.933904) (xy 62.205051 -40.915897) (xy 62.155451 -40.890396)
			(xy 62.110093 -40.857945) (xy 62.069944 -40.819236) (xy 62.035858 -40.775093) (xy 62.008562 -40.726458)
			(xy 61.988639 -40.674367) (xy 61.976513 -40.61993) (xy 61.972442 -40.564308) (xy 0.98171 -40.564308)
			(xy 0.98171 -41.166542) (xy 1.004718 -41.1831) (xy 1.046037 -41.221906) (xy 1.081159 -41.266398)
			(xy 1.109312 -41.315597) (xy 1.112493 -41.323768) (xy 59.003182 -41.323768) (xy 59.007253 -41.268146)
			(xy 59.019379 -41.213709) (xy 59.039302 -41.161618) (xy 59.066598 -41.112983) (xy 59.100684 -41.06884)
			(xy 59.140833 -41.030131) (xy 59.186191 -40.99768) (xy 59.235791 -40.972179) (xy 59.288575 -40.954172)
			(xy 59.343418 -40.944042) (xy 59.399152 -40.942005) (xy 59.454589 -40.948105) (xy 59.508546 -40.962211)
			(xy 59.559875 -40.984023) (xy 59.607481 -41.013077) (xy 59.650349 -41.048752) (xy 59.687566 -41.090289)
			(xy 59.718339 -41.136802) (xy 59.742011 -41.187299) (xy 59.758079 -41.240706) (xy 59.763574 -41.278048)
			(xy 61.150752 -41.278048) (xy 61.154823 -41.222426) (xy 61.166949 -41.167989) (xy 61.186872 -41.115898)
			(xy 61.214168 -41.067263) (xy 61.248254 -41.02312) (xy 61.288403 -40.984411) (xy 61.333761 -40.95196)
			(xy 61.383361 -40.926459) (xy 61.436145 -40.908452) (xy 61.490988 -40.898322) (xy 61.546722 -40.896285)
			(xy 61.602159 -40.902385) (xy 61.656116 -40.916491) (xy 61.707445 -40.938303) (xy 61.755051 -40.967357)
			(xy 61.797919 -41.003032) (xy 61.80628 -41.012364) (xy 108.782102 -41.012364) (xy 108.786173 -40.956742)
			(xy 108.798299 -40.902305) (xy 108.818222 -40.850214) (xy 108.845518 -40.801579) (xy 108.879604 -40.757436)
			(xy 108.919753 -40.718727) (xy 108.965111 -40.686276) (xy 109.014711 -40.660775) (xy 109.067495 -40.642768)
			(xy 109.122338 -40.632638) (xy 109.178072 -40.630601) (xy 109.233509 -40.636701) (xy 109.287466 -40.650807)
			(xy 109.338795 -40.672619) (xy 109.386401 -40.701673) (xy 109.429269 -40.737348) (xy 109.466486 -40.778885)
			(xy 109.497259 -40.825398) (xy 109.520931 -40.875895) (xy 109.536999 -40.929302) (xy 109.545119 -40.984478)
			(xy 109.545628 -41.012364) (xy 109.545119 -41.04025) (xy 109.536999 -41.095426) (xy 109.520931 -41.148833)
			(xy 109.497259 -41.19933) (xy 109.466486 -41.245843) (xy 109.429269 -41.28738) (xy 109.386401 -41.323055)
			(xy 109.338795 -41.352109) (xy 109.287466 -41.373921) (xy 109.233509 -41.388027) (xy 109.178072 -41.394127)
			(xy 109.122338 -41.39209) (xy 109.067495 -41.38196) (xy 109.014711 -41.363953) (xy 108.965111 -41.338452)
			(xy 108.919753 -41.306001) (xy 108.879604 -41.267292) (xy 108.845518 -41.223149) (xy 108.818222 -41.174514)
			(xy 108.798299 -41.122423) (xy 108.786173 -41.067986) (xy 108.782102 -41.012364) (xy 61.80628 -41.012364)
			(xy 61.835136 -41.044569) (xy 61.865909 -41.091082) (xy 61.889581 -41.141579) (xy 61.905649 -41.194986)
			(xy 61.913769 -41.250162) (xy 61.914278 -41.278048) (xy 61.913769 -41.305934) (xy 61.905649 -41.36111)
			(xy 61.889581 -41.414517) (xy 61.865909 -41.465014) (xy 61.835136 -41.511527) (xy 61.797919 -41.553064)
			(xy 61.77739 -41.570148) (xy 104.122218 -41.570148) (xy 104.126289 -41.514526) (xy 104.138415 -41.460089)
			(xy 104.158338 -41.407998) (xy 104.185634 -41.359363) (xy 104.21972 -41.31522) (xy 104.259869 -41.276511)
			(xy 104.305227 -41.24406) (xy 104.354827 -41.218559) (xy 104.407611 -41.200552) (xy 104.462454 -41.190422)
			(xy 104.518188 -41.188385) (xy 104.573625 -41.194485) (xy 104.627582 -41.208591) (xy 104.678911 -41.230403)
			(xy 104.726517 -41.259457) (xy 104.769385 -41.295132) (xy 104.806602 -41.336669) (xy 104.837375 -41.383182)
			(xy 104.861047 -41.433679) (xy 104.877115 -41.487086) (xy 104.885235 -41.542262) (xy 104.885744 -41.570148)
			(xy 104.885235 -41.598034) (xy 104.877115 -41.65321) (xy 104.861047 -41.706617) (xy 104.837375 -41.757114)
			(xy 104.806602 -41.803627) (xy 104.769385 -41.845164) (xy 104.726517 -41.880839) (xy 104.678911 -41.909893)
			(xy 104.627582 -41.931705) (xy 104.573625 -41.945811) (xy 104.518188 -41.951911) (xy 104.462454 -41.949874)
			(xy 104.407611 -41.939744) (xy 104.354827 -41.921737) (xy 104.305227 -41.896236) (xy 104.259869 -41.863785)
			(xy 104.21972 -41.825076) (xy 104.185634 -41.780933) (xy 104.158338 -41.732298) (xy 104.138415 -41.680207)
			(xy 104.126289 -41.62577) (xy 104.122218 -41.570148) (xy 61.77739 -41.570148) (xy 61.755051 -41.588739)
			(xy 61.707445 -41.617793) (xy 61.656116 -41.639605) (xy 61.602159 -41.653711) (xy 61.546722 -41.659811)
			(xy 61.490988 -41.657774) (xy 61.436145 -41.647644) (xy 61.383361 -41.629637) (xy 61.333761 -41.604136)
			(xy 61.288403 -41.571685) (xy 61.248254 -41.532976) (xy 61.214168 -41.488833) (xy 61.186872 -41.440198)
			(xy 61.166949 -41.388107) (xy 61.154823 -41.33367) (xy 61.150752 -41.278048) (xy 59.763574 -41.278048)
			(xy 59.766199 -41.295882) (xy 59.766708 -41.323768) (xy 59.766199 -41.351654) (xy 59.758079 -41.40683)
			(xy 59.742011 -41.460237) (xy 59.718339 -41.510734) (xy 59.687566 -41.557247) (xy 59.650349 -41.598784)
			(xy 59.607481 -41.634459) (xy 59.559875 -41.663513) (xy 59.508546 -41.685325) (xy 59.454589 -41.699431)
			(xy 59.399152 -41.705531) (xy 59.343418 -41.703494) (xy 59.288575 -41.693364) (xy 59.235791 -41.675357)
			(xy 59.186191 -41.649856) (xy 59.140833 -41.617405) (xy 59.100684 -41.578696) (xy 59.066598 -41.534553)
			(xy 59.039302 -41.485918) (xy 59.019379 -41.433827) (xy 59.007253 -41.37939) (xy 59.003182 -41.323768)
			(xy 1.112493 -41.323768) (xy 1.129877 -41.36842) (xy 1.142399 -41.423704) (xy 1.146604 -41.480232)
			(xy 1.142399 -41.53676) (xy 1.129877 -41.592044) (xy 1.109312 -41.644867) (xy 1.081159 -41.694066)
			(xy 1.046037 -41.738558) (xy 1.004718 -41.777364) (xy 0.98171 -41.793922) (xy 0.98171 -42.023538)
			(xy 73.451972 -42.023538) (xy 73.456043 -41.967916) (xy 73.468169 -41.913479) (xy 73.488092 -41.861388)
			(xy 73.515388 -41.812753) (xy 73.549474 -41.76861) (xy 73.589623 -41.729901) (xy 73.634981 -41.69745)
			(xy 73.684581 -41.671949) (xy 73.737365 -41.653942) (xy 73.792208 -41.643812) (xy 73.847942 -41.641775)
			(xy 73.903379 -41.647875) (xy 73.957336 -41.661981) (xy 74.008665 -41.683793) (xy 74.056271 -41.712847)
			(xy 74.099139 -41.748522) (xy 74.136356 -41.790059) (xy 74.167129 -41.836572) (xy 74.190801 -41.887069)
			(xy 74.206869 -41.940476) (xy 74.214989 -41.995652) (xy 74.215498 -42.023538) (xy 74.721972 -42.023538)
			(xy 74.726043 -41.967916) (xy 74.738169 -41.913479) (xy 74.758092 -41.861388) (xy 74.785388 -41.812753)
			(xy 74.819474 -41.76861) (xy 74.859623 -41.729901) (xy 74.904981 -41.69745) (xy 74.954581 -41.671949)
			(xy 75.007365 -41.653942) (xy 75.062208 -41.643812) (xy 75.117942 -41.641775) (xy 75.173379 -41.647875)
			(xy 75.227336 -41.661981) (xy 75.278665 -41.683793) (xy 75.326271 -41.712847) (xy 75.369139 -41.748522)
			(xy 75.406356 -41.790059) (xy 75.437129 -41.836572) (xy 75.460801 -41.887069) (xy 75.476869 -41.940476)
			(xy 75.484989 -41.995652) (xy 75.485498 -42.023538) (xy 75.484989 -42.051424) (xy 75.477053 -42.105348)
			(xy 77.343026 -42.105348) (xy 77.343026 -42.050852) (xy 77.350782 -41.996911) (xy 77.366135 -41.944623)
			(xy 77.388773 -41.895052) (xy 77.418236 -41.849208) (xy 77.453923 -41.808023) (xy 77.495108 -41.772336)
			(xy 77.540952 -41.742873) (xy 77.590523 -41.720235) (xy 77.642811 -41.704882) (xy 77.696752 -41.697126)
			(xy 77.724 -41.69664) (xy 77.751371 -41.697096) (xy 77.805551 -41.704915) (xy 77.858054 -41.720406)
			(xy 77.907801 -41.74325) (xy 77.953767 -41.772977) (xy 77.974698 -41.79062) (xy 77.986026 -41.799856)
			(xy 78.012583 -41.812032) (xy 78.0415 -41.816205) (xy 78.070417 -41.812032) (xy 78.096974 -41.799856)
			(xy 78.108302 -41.79062) (xy 78.129225 -41.77297) (xy 78.1752 -41.743259) (xy 78.22495 -41.720425)
			(xy 78.277453 -41.704936) (xy 78.33163 -41.697112) (xy 78.359 -41.69664) (xy 78.387738 -41.69718)
			(xy 78.444564 -41.705801) (xy 78.499454 -41.722848) (xy 78.551166 -41.747936) (xy 78.59853 -41.780496)
			(xy 78.619858 -41.799764) (xy 78.629887 -41.808661) (xy 78.653558 -41.821238) (xy 78.679684 -41.827232)
			(xy 78.70647 -41.826234) (xy 78.732077 -41.818311) (xy 78.754746 -41.804007) (xy 78.76413 -41.79443)
			(xy 78.78225 -41.775367) (xy 78.822838 -41.741918) (xy 78.867637 -41.714363) (xy 78.915798 -41.693227)
			(xy 78.966407 -41.678909) (xy 79.018503 -41.671681) (xy 79.0448 -41.67124) (xy 79.072055 -41.67163)
			(xy 79.126009 -41.679387) (xy 79.178311 -41.694744) (xy 79.227894 -41.717388) (xy 79.27375 -41.746858)
			(xy 79.314946 -41.782554) (xy 79.350642 -41.82375) (xy 79.380112 -41.869606) (xy 79.402756 -41.919189)
			(xy 79.418113 -41.971491) (xy 79.42587 -42.025445) (xy 79.42587 -42.079955) (xy 79.418113 -42.133909)
			(xy 79.402756 -42.186211) (xy 79.380112 -42.235794) (xy 79.350642 -42.28165) (xy 79.314946 -42.322846)
			(xy 79.27375 -42.358542) (xy 79.227894 -42.388012) (xy 79.178311 -42.410656) (xy 79.126009 -42.426013)
			(xy 79.072055 -42.43377) (xy 79.0448 -42.434256) (xy 79.016062 -42.433717) (xy 78.959236 -42.425096)
			(xy 78.904346 -42.408049) (xy 78.852634 -42.382961) (xy 78.80527 -42.3504) (xy 78.783942 -42.331132)
			(xy 78.773913 -42.322235) (xy 78.750242 -42.309659) (xy 78.724116 -42.303665) (xy 78.69733 -42.304663)
			(xy 78.671723 -42.312586) (xy 78.649054 -42.326889) (xy 78.63967 -42.336466) (xy 78.621549 -42.355528)
			(xy 78.580962 -42.388978) (xy 78.536162 -42.416532) (xy 78.488002 -42.437669) (xy 78.437393 -42.451987)
			(xy 78.385297 -42.459215) (xy 78.359 -42.459656) (xy 78.331629 -42.459201) (xy 78.277449 -42.451382)
			(xy 78.224946 -42.435891) (xy 78.175199 -42.413047) (xy 78.129233 -42.383319) (xy 78.108302 -42.365676)
			(xy 78.096974 -42.35644) (xy 78.070417 -42.344264) (xy 78.0415 -42.340091) (xy 78.012583 -42.344264)
			(xy 77.986026 -42.35644) (xy 77.974698 -42.365676) (xy 77.953774 -42.383326) (xy 77.9078 -42.413037)
			(xy 77.85805 -42.435871) (xy 77.805547 -42.45136) (xy 77.75137 -42.459184) (xy 77.724 -42.459656)
			(xy 77.696752 -42.459074) (xy 77.642811 -42.451318) (xy 77.590523 -42.435965) (xy 77.540952 -42.413327)
			(xy 77.495108 -42.383864) (xy 77.453923 -42.348177) (xy 77.418236 -42.306992) (xy 77.388773 -42.261148)
			(xy 77.366135 -42.211577) (xy 77.350782 -42.159289) (xy 77.343026 -42.105348) (xy 75.477053 -42.105348)
			(xy 75.476869 -42.1066) (xy 75.460801 -42.160007) (xy 75.437129 -42.210504) (xy 75.406356 -42.257017)
			(xy 75.369139 -42.298554) (xy 75.326271 -42.334229) (xy 75.278665 -42.363283) (xy 75.227336 -42.385095)
			(xy 75.173379 -42.399201) (xy 75.117942 -42.405301) (xy 75.062208 -42.403264) (xy 75.007365 -42.393134)
			(xy 74.954581 -42.375127) (xy 74.904981 -42.349626) (xy 74.859623 -42.317175) (xy 74.819474 -42.278466)
			(xy 74.785388 -42.234323) (xy 74.758092 -42.185688) (xy 74.738169 -42.133597) (xy 74.726043 -42.07916)
			(xy 74.721972 -42.023538) (xy 74.215498 -42.023538) (xy 74.214989 -42.051424) (xy 74.206869 -42.1066)
			(xy 74.190801 -42.160007) (xy 74.167129 -42.210504) (xy 74.136356 -42.257017) (xy 74.099139 -42.298554)
			(xy 74.056271 -42.334229) (xy 74.008665 -42.363283) (xy 73.957336 -42.385095) (xy 73.903379 -42.399201)
			(xy 73.847942 -42.405301) (xy 73.792208 -42.403264) (xy 73.737365 -42.393134) (xy 73.684581 -42.375127)
			(xy 73.634981 -42.349626) (xy 73.589623 -42.317175) (xy 73.549474 -42.278466) (xy 73.515388 -42.234323)
			(xy 73.488092 -42.185688) (xy 73.468169 -42.133597) (xy 73.456043 -42.07916) (xy 73.451972 -42.023538)
			(xy 0.98171 -42.023538) (xy 0.98171 -42.784522) (xy 130.389882 -42.784522) (xy 130.393953 -42.7289)
			(xy 130.406079 -42.674463) (xy 130.426002 -42.622372) (xy 130.453298 -42.573737) (xy 130.487384 -42.529594)
			(xy 130.527533 -42.490885) (xy 130.572891 -42.458434) (xy 130.622491 -42.432933) (xy 130.675275 -42.414926)
			(xy 130.730118 -42.404796) (xy 130.785852 -42.402759) (xy 130.841289 -42.408859) (xy 130.895246 -42.422965)
			(xy 130.946575 -42.444777) (xy 130.994181 -42.473831) (xy 131.037049 -42.509506) (xy 131.074266 -42.551043)
			(xy 131.105039 -42.597556) (xy 131.128711 -42.648053) (xy 131.131101 -42.655998) (xy 140.643862 -42.655998)
			(xy 140.647933 -42.600376) (xy 140.660059 -42.545939) (xy 140.679982 -42.493848) (xy 140.707278 -42.445213)
			(xy 140.741364 -42.40107) (xy 140.781513 -42.362361) (xy 140.826871 -42.32991) (xy 140.876471 -42.304409)
			(xy 140.929255 -42.286402) (xy 140.984098 -42.276272) (xy 141.039832 -42.274235) (xy 141.095269 -42.280335)
			(xy 141.149226 -42.294441) (xy 141.200555 -42.316253) (xy 141.248161 -42.345307) (xy 141.291029 -42.380982)
			(xy 141.328246 -42.422519) (xy 141.359019 -42.469032) (xy 141.382691 -42.519529) (xy 141.398759 -42.572936)
			(xy 141.406879 -42.628112) (xy 141.407388 -42.655998) (xy 141.406879 -42.683884) (xy 141.398759 -42.73906)
			(xy 141.382691 -42.792467) (xy 141.359019 -42.842964) (xy 141.328246 -42.889477) (xy 141.291029 -42.931014)
			(xy 141.248161 -42.966689) (xy 141.200555 -42.995743) (xy 141.149226 -43.017555) (xy 141.095269 -43.031661)
			(xy 141.039832 -43.037761) (xy 140.984098 -43.035724) (xy 140.929255 -43.025594) (xy 140.876471 -43.007587)
			(xy 140.826871 -42.982086) (xy 140.781513 -42.949635) (xy 140.741364 -42.910926) (xy 140.707278 -42.866783)
			(xy 140.679982 -42.818148) (xy 140.660059 -42.766057) (xy 140.647933 -42.71162) (xy 140.643862 -42.655998)
			(xy 131.131101 -42.655998) (xy 131.144779 -42.70146) (xy 131.152899 -42.756636) (xy 131.153408 -42.784522)
			(xy 131.152899 -42.812408) (xy 131.144779 -42.867584) (xy 131.128711 -42.920991) (xy 131.105039 -42.971488)
			(xy 131.074266 -43.018001) (xy 131.037049 -43.059538) (xy 130.994181 -43.095213) (xy 130.946575 -43.124267)
			(xy 130.895246 -43.146079) (xy 130.841289 -43.160185) (xy 130.785852 -43.166285) (xy 130.730118 -43.164248)
			(xy 130.675275 -43.154118) (xy 130.622491 -43.136111) (xy 130.572891 -43.11061) (xy 130.527533 -43.078159)
			(xy 130.487384 -43.03945) (xy 130.453298 -42.995307) (xy 130.426002 -42.946672) (xy 130.406079 -42.894581)
			(xy 130.393953 -42.840144) (xy 130.389882 -42.784522) (xy 0.98171 -42.784522) (xy 0.98171 -43.999912)
			(xy 16.984223 -43.999912) (xy 16.988246 -43.914168) (xy 17.000281 -43.829177) (xy 17.020222 -43.745687)
			(xy 17.047893 -43.66443) (xy 17.083052 -43.586122) (xy 17.125389 -43.511451) (xy 17.174532 -43.441072)
			(xy 17.23005 -43.375604) (xy 17.291454 -43.315623) (xy 17.358206 -43.261655) (xy 17.429717 -43.214175)
			(xy 17.505361 -43.1736) (xy 17.584472 -43.140287) (xy 17.666354 -43.114528) (xy 17.750289 -43.09655)
			(xy 17.835539 -43.08651) (xy 17.921354 -43.084498) (xy 18.00698 -43.090531) (xy 18.091665 -43.104555)
			(xy 18.174665 -43.126447) (xy 18.25525 -43.156016) (xy 18.332713 -43.193) (xy 18.406371 -43.237076)
			(xy 18.453898 -43.271948) (xy 132.515862 -43.271948) (xy 132.519933 -43.216326) (xy 132.532059 -43.161889)
			(xy 132.551982 -43.109798) (xy 132.579278 -43.061163) (xy 132.613364 -43.01702) (xy 132.653513 -42.978311)
			(xy 132.698871 -42.94586) (xy 132.748471 -42.920359) (xy 132.801255 -42.902352) (xy 132.856098 -42.892222)
			(xy 132.911832 -42.890185) (xy 132.967269 -42.896285) (xy 133.021226 -42.910391) (xy 133.072555 -42.932203)
			(xy 133.120161 -42.961257) (xy 133.163029 -42.996932) (xy 133.200246 -43.038469) (xy 133.231019 -43.084982)
			(xy 133.254691 -43.135479) (xy 133.270759 -43.188886) (xy 133.278879 -43.244062) (xy 133.279388 -43.271948)
			(xy 133.278879 -43.299834) (xy 133.270759 -43.35501) (xy 133.254691 -43.408417) (xy 133.231019 -43.458914)
			(xy 133.200246 -43.505427) (xy 133.163029 -43.546964) (xy 133.120161 -43.582639) (xy 133.072555 -43.611693)
			(xy 133.071108 -43.612308) (xy 144.263362 -43.612308) (xy 144.267433 -43.556686) (xy 144.279559 -43.502249)
			(xy 144.299482 -43.450158) (xy 144.326778 -43.401523) (xy 144.360864 -43.35738) (xy 144.401013 -43.318671)
			(xy 144.446371 -43.28622) (xy 144.495971 -43.260719) (xy 144.548755 -43.242712) (xy 144.603598 -43.232582)
			(xy 144.659332 -43.230545) (xy 144.714769 -43.236645) (xy 144.768726 -43.250751) (xy 144.820055 -43.272563)
			(xy 144.867661 -43.301617) (xy 144.910529 -43.337292) (xy 144.947746 -43.378829) (xy 144.978519 -43.425342)
			(xy 145.002191 -43.475839) (xy 145.018259 -43.529246) (xy 145.026379 -43.584422) (xy 145.026888 -43.612308)
			(xy 145.026379 -43.640194) (xy 145.018259 -43.69537) (xy 145.002191 -43.748777) (xy 144.978519 -43.799274)
			(xy 144.947746 -43.845787) (xy 144.910529 -43.887324) (xy 144.867661 -43.922999) (xy 144.820055 -43.952053)
			(xy 144.768726 -43.973865) (xy 144.714769 -43.987971) (xy 144.659332 -43.994071) (xy 144.603598 -43.992034)
			(xy 144.548755 -43.981904) (xy 144.495971 -43.963897) (xy 144.446371 -43.938396) (xy 144.401013 -43.905945)
			(xy 144.360864 -43.867236) (xy 144.326778 -43.823093) (xy 144.299482 -43.774458) (xy 144.279559 -43.722367)
			(xy 144.267433 -43.66793) (xy 144.263362 -43.612308) (xy 133.071108 -43.612308) (xy 133.021226 -43.633505)
			(xy 132.967269 -43.647611) (xy 132.911832 -43.653711) (xy 132.856098 -43.651674) (xy 132.801255 -43.641544)
			(xy 132.748471 -43.623537) (xy 132.698871 -43.598036) (xy 132.653513 -43.565585) (xy 132.613364 -43.526876)
			(xy 132.579278 -43.482733) (xy 132.551982 -43.434098) (xy 132.532059 -43.382007) (xy 132.519933 -43.32757)
			(xy 132.515862 -43.271948) (xy 18.453898 -43.271948) (xy 18.475579 -43.287856) (xy 18.539727 -43.344893)
			(xy 18.598253 -43.407687) (xy 18.650641 -43.475685) (xy 18.696431 -43.54829) (xy 18.735222 -43.624864)
			(xy 18.766671 -43.704734) (xy 18.790504 -43.787198) (xy 18.806509 -43.871531) (xy 18.814547 -43.956993)
			(xy 18.81505 -43.999912) (xy 18.814547 -44.042831) (xy 18.806509 -44.128293) (xy 18.790504 -44.212626)
			(xy 18.783994 -44.235151) (xy 59.284093 -44.235151) (xy 59.284093 -44.180649) (xy 59.29185 -44.126703)
			(xy 59.307205 -44.07441) (xy 59.329845 -44.024834) (xy 59.359311 -43.978985) (xy 59.395002 -43.937797)
			(xy 59.436192 -43.902106) (xy 59.482041 -43.872642) (xy 59.531617 -43.850002) (xy 59.583911 -43.834648)
			(xy 59.637857 -43.826893) (xy 59.665108 -43.82643) (xy 59.692219 -43.826915) (xy 59.745896 -43.834576)
			(xy 59.797948 -43.849757) (xy 59.847329 -43.872152) (xy 59.893042 -43.901311) (xy 59.934168 -43.936645)
			(xy 59.952382 -43.956732) (xy 59.963139 -43.968109) (xy 59.989912 -43.984306) (xy 60.020331 -43.991643)
			(xy 60.051544 -43.989431) (xy 60.080625 -43.977879) (xy 60.093098 -43.968416) (xy 60.113649 -43.952162)
			(xy 60.158348 -43.924823) (xy 60.206367 -43.903856) (xy 60.256803 -43.889656) (xy 60.308708 -43.882489)
			(xy 60.334906 -43.882056) (xy 60.362154 -43.882615) (xy 60.416096 -43.890371) (xy 60.468385 -43.905725)
			(xy 60.517957 -43.928365) (xy 60.563802 -43.957828) (xy 60.604988 -43.993516) (xy 60.640675 -44.034702)
			(xy 60.670138 -44.080548) (xy 60.692777 -44.13012) (xy 60.70813 -44.18241) (xy 60.715886 -44.236352)
			(xy 60.715886 -44.290848) (xy 60.70813 -44.34479) (xy 60.692777 -44.39708) (xy 60.670138 -44.446652)
			(xy 60.640675 -44.492498) (xy 60.604988 -44.533684) (xy 60.563802 -44.569372) (xy 60.517957 -44.598835)
			(xy 60.468385 -44.621475) (xy 60.416096 -44.636829) (xy 60.362154 -44.644585) (xy 60.334906 -44.645072)
			(xy 60.307796 -44.644576) (xy 60.254119 -44.636917) (xy 60.202067 -44.621739) (xy 60.152686 -44.599345)
			(xy 60.106973 -44.570189) (xy 60.065846 -44.534856) (xy 60.047632 -44.51477) (xy 60.036863 -44.503406)
			(xy 60.010094 -44.487207) (xy 59.979678 -44.479868) (xy 59.948468 -44.482077) (xy 59.919389 -44.493625)
			(xy 59.906916 -44.503086) (xy 59.88636 -44.519334) (xy 59.841662 -44.546674) (xy 59.793644 -44.567642)
			(xy 59.74321 -44.581843) (xy 59.691306 -44.589012) (xy 59.665108 -44.589446) (xy 59.637857 -44.588907)
			(xy 59.583911 -44.581152) (xy 59.531617 -44.565798) (xy 59.482041 -44.543158) (xy 59.436192 -44.513694)
			(xy 59.395002 -44.478003) (xy 59.359311 -44.436815) (xy 59.329845 -44.390966) (xy 59.307205 -44.34139)
			(xy 59.29185 -44.289097) (xy 59.284093 -44.235151) (xy 18.783994 -44.235151) (xy 18.766671 -44.29509)
			(xy 18.735222 -44.37496) (xy 18.696431 -44.451534) (xy 18.650641 -44.524139) (xy 18.598253 -44.592137)
			(xy 18.539727 -44.654931) (xy 18.475579 -44.711968) (xy 18.406371 -44.762748) (xy 18.332713 -44.806824)
			(xy 18.25525 -44.843808) (xy 18.174665 -44.873377) (xy 18.091665 -44.895269) (xy 18.00698 -44.909293)
			(xy 17.921354 -44.915326) (xy 17.835539 -44.913314) (xy 17.750289 -44.903274) (xy 17.666354 -44.885296)
			(xy 17.584472 -44.859537) (xy 17.505361 -44.826224) (xy 17.429717 -44.785649) (xy 17.358206 -44.738169)
			(xy 17.291454 -44.684201) (xy 17.23005 -44.62422) (xy 17.174532 -44.558752) (xy 17.125389 -44.488373)
			(xy 17.083052 -44.413702) (xy 17.047893 -44.335394) (xy 17.020222 -44.254137) (xy 17.000281 -44.170647)
			(xy 16.988246 -44.085656) (xy 16.984223 -43.999912) (xy 0.98171 -43.999912) (xy 0.98171 -44.99991)
			(xy 13.567662 -44.99991) (xy 13.571733 -44.944288) (xy 13.583859 -44.889851) (xy 13.603782 -44.83776)
			(xy 13.631078 -44.789125) (xy 13.665164 -44.744982) (xy 13.705313 -44.706273) (xy 13.750671 -44.673822)
			(xy 13.800271 -44.648321) (xy 13.853055 -44.630314) (xy 13.907898 -44.620184) (xy 13.963632 -44.618147)
			(xy 14.019069 -44.624247) (xy 14.073026 -44.638353) (xy 14.124355 -44.660165) (xy 14.171961 -44.689219)
			(xy 14.214829 -44.724894) (xy 14.252046 -44.766431) (xy 14.282819 -44.812944) (xy 14.306491 -44.863441)
			(xy 14.322559 -44.916848) (xy 14.330679 -44.972024) (xy 14.331188 -44.99991) (xy 14.330679 -45.027796)
			(xy 14.322559 -45.082972) (xy 14.306491 -45.136379) (xy 14.282819 -45.186876) (xy 14.252046 -45.233389)
			(xy 14.214829 -45.274926) (xy 14.171961 -45.310601) (xy 14.124355 -45.339655) (xy 14.073026 -45.361467)
			(xy 14.019069 -45.375573) (xy 13.963632 -45.381673) (xy 13.907898 -45.379636) (xy 13.853055 -45.369506)
			(xy 13.800271 -45.351499) (xy 13.750671 -45.325998) (xy 13.705313 -45.293547) (xy 13.665164 -45.254838)
			(xy 13.631078 -45.210695) (xy 13.603782 -45.16206) (xy 13.583859 -45.109969) (xy 13.571733 -45.055532)
			(xy 13.567662 -44.99991) (xy 0.98171 -44.99991) (xy 0.98171 -45.105828) (xy 1.182878 -45.306742)
			(xy 1.199559 -45.32401) (xy 1.227825 -45.362819) (xy 1.249664 -45.405574) (xy 1.264539 -45.451223)
			(xy 1.270729 -45.49013) (xy 34.238436 -45.49013) (xy 34.242507 -45.434508) (xy 34.254633 -45.380071)
			(xy 34.274556 -45.32798) (xy 34.301852 -45.279345) (xy 34.335938 -45.235202) (xy 34.376087 -45.196493)
			(xy 34.421445 -45.164042) (xy 34.471045 -45.138541) (xy 34.523829 -45.120534) (xy 34.578672 -45.110404)
			(xy 34.634406 -45.108367) (xy 34.689843 -45.114467) (xy 34.7438 -45.128573) (xy 34.795129 -45.150385)
			(xy 34.842735 -45.179439) (xy 34.885603 -45.215114) (xy 34.92282 -45.256651) (xy 34.953593 -45.303164)
			(xy 34.977265 -45.353661) (xy 34.993333 -45.407068) (xy 35.001453 -45.462244) (xy 35.001962 -45.49013)
			(xy 35.001651 -45.507148) (xy 35.107372 -45.507148) (xy 35.107858 -45.479897) (xy 35.115614 -45.425949)
			(xy 35.130969 -45.373654) (xy 35.153611 -45.324077) (xy 35.183077 -45.278227) (xy 35.218768 -45.237036)
			(xy 35.259959 -45.201345) (xy 35.305809 -45.171879) (xy 35.355386 -45.149237) (xy 35.407681 -45.133882)
			(xy 35.461629 -45.126126) (xy 35.516131 -45.126126) (xy 35.570079 -45.133882) (xy 35.622374 -45.149237)
			(xy 35.671951 -45.171879) (xy 35.717801 -45.201345) (xy 35.758992 -45.237036) (xy 35.794683 -45.278227)
			(xy 35.824149 -45.324077) (xy 35.846791 -45.373654) (xy 35.862146 -45.425949) (xy 35.869902 -45.479897)
			(xy 35.870388 -45.507148) (xy 35.870146 -45.527302) (xy 35.865949 -45.567392) (xy 35.862006 -45.587158)
			(xy 35.859407 -45.601789) (xy 35.861756 -45.631395) (xy 35.872524 -45.659073) (xy 35.890801 -45.682482)
			(xy 35.915041 -45.699642) (xy 35.943193 -45.709102) (xy 35.958018 -45.710094) (xy 35.984699 -45.711371)
			(xy 36.037337 -45.72046) (xy 36.088191 -45.736805) (xy 36.136267 -45.760086) (xy 36.180624 -45.789847)
			(xy 36.220395 -45.825507) (xy 36.2548 -45.866368) (xy 36.283167 -45.91163) (xy 36.304942 -45.960407)
			(xy 36.319696 -46.011745) (xy 36.327143 -46.06464) (xy 36.327588 -46.091348) (xy 36.326881 -46.124891)
			(xy 36.315129 -46.190939) (xy 36.30422 -46.222666) (xy 36.299641 -46.236575) (xy 36.297663 -46.265773)
			(xy 36.304054 -46.294332) (xy 36.318289 -46.319902) (xy 36.339196 -46.340379) (xy 36.365057 -46.35408)
			(xy 36.393742 -46.359876) (xy 36.40836 -46.359064) (xy 36.44138 -46.35754) (xy 36.468635 -46.357974)
			(xy 36.522589 -46.36573) (xy 36.57489 -46.381085) (xy 36.624474 -46.403729) (xy 36.670329 -46.4332)
			(xy 36.711523 -46.468897) (xy 36.747217 -46.510093) (xy 36.776684 -46.555951) (xy 36.799324 -46.605536)
			(xy 36.814676 -46.657838) (xy 36.822428 -46.711793) (xy 36.822888 -46.739048) (xy 36.822324 -46.769757)
			(xy 36.812492 -46.830382) (xy 36.80333 -46.859698) (xy 36.799512 -46.872676) (xy 36.798064 -46.899677)
			(xy 36.803751 -46.926113) (xy 36.816174 -46.950131) (xy 36.834464 -46.970047) (xy 36.857339 -46.984468)
			(xy 36.883195 -46.992381) (xy 36.910223 -46.993233) (xy 36.923472 -46.990508) (xy 36.945489 -46.985535)
			(xy 36.990311 -46.980188) (xy 37.01288 -46.97984) (xy 37.040135 -46.980274) (xy 37.094089 -46.98803)
			(xy 37.14639 -47.003385) (xy 37.195974 -47.026029) (xy 37.23298 -47.049813) (xy 59.781451 -47.049813)
			(xy 59.785436 -46.895317) (xy 59.79737 -46.74123) (xy 59.817219 -46.587962) (xy 59.844933 -46.43592)
			(xy 59.880436 -46.285505) (xy 59.923635 -46.137118) (xy 59.974415 -45.991151) (xy 60.032642 -45.847991)
			(xy 60.098162 -45.708019) (xy 60.1708 -45.571605) (xy 60.250363 -45.439111) (xy 60.336642 -45.310889)
			(xy 60.429407 -45.187278) (xy 60.528412 -45.068606) (xy 60.633395 -44.955188) (xy 60.744077 -44.847324)
			(xy 60.860165 -44.745302) (xy 60.981351 -44.64939) (xy 61.107313 -44.559844) (xy 61.237718 -44.476901)
			(xy 61.37222 -44.400781) (xy 61.510462 -44.331685) (xy 61.652077 -44.269798) (xy 61.796691 -44.215282)
			(xy 61.943919 -44.168283) (xy 62.093371 -44.128926) (xy 62.244652 -44.097314) (xy 62.397358 -44.073531)
			(xy 62.551087 -44.057641) (xy 62.70543 -44.049685) (xy 62.782704 -44.049188) (xy 64.383158 -44.049188)
			(xy 64.461004 -44.049716) (xy 64.616485 -44.057793) (xy 64.771339 -44.073923) (xy 64.925148 -44.098061)
			(xy 65.077498 -44.130145) (xy 65.227979 -44.170085) (xy 65.376186 -44.217777) (xy 65.52172 -44.27309)
			(xy 65.66419 -44.335876) (xy 65.803212 -44.405966) (xy 65.938412 -44.483172) (xy 66.069427 -44.567285)
			(xy 66.195902 -44.65808) (xy 66.317499 -44.755312) (xy 66.43389 -44.858719) (xy 66.544761 -44.968023)
			(xy 66.649815 -45.08293) (xy 66.748768 -45.20313) (xy 66.841354 -45.3283) (xy 66.927324 -45.458104)
			(xy 67.006447 -45.592191) (xy 67.07851 -45.730201) (xy 67.111372 -45.800772) (xy 67.117919 -45.814089)
			(xy 67.137463 -45.836407) (xy 67.162592 -45.852176) (xy 67.191189 -45.860067) (xy 67.220848 -45.859416)
			(xy 67.249072 -45.850279) (xy 67.273485 -45.833424) (xy 67.292032 -45.81027) (xy 67.298062 -45.796708)
			(xy 67.329489 -45.72075) (xy 67.398808 -45.571676) (xy 67.475398 -45.426204) (xy 67.559074 -45.284688)
			(xy 67.64963 -45.147475) (xy 67.746848 -45.014897) (xy 67.850489 -44.887277) (xy 67.960301 -44.764928)
			(xy 68.076018 -44.648146) (xy 68.197355 -44.537217) (xy 68.324019 -44.432411) (xy 68.455701 -44.333982)
			(xy 68.592079 -44.242172) (xy 68.732821 -44.157203) (xy 68.877585 -44.079283) (xy 69.026018 -44.008601)
			(xy 69.177757 -43.945329) (xy 69.332434 -43.889623) (xy 69.489672 -43.841617) (xy 69.649086 -43.801429)
			(xy 69.81029 -43.769156) (xy 69.97289 -43.744877) (xy 70.13649 -43.728652) (xy 70.300691 -43.720519)
			(xy 70.382892 -43.720004) (xy 70.464625 -43.720498) (xy 70.627895 -43.728519) (xy 70.790574 -43.744541)
			(xy 70.952271 -43.768527) (xy 71.112596 -43.800418) (xy 71.271164 -43.840137) (xy 71.427591 -43.887589)
			(xy 71.581502 -43.942659) (xy 71.732525 -44.005215) (xy 71.880297 -44.075106) (xy 72.024462 -44.152163)
			(xy 72.07617 -44.183156) (xy 77.528323 -44.183156) (xy 77.528323 -44.128644) (xy 77.536081 -44.074687)
			(xy 77.551439 -44.022383) (xy 77.574085 -43.972797) (xy 77.603558 -43.926939) (xy 77.639257 -43.885742)
			(xy 77.680455 -43.850046) (xy 77.726315 -43.820576) (xy 77.775902 -43.797932) (xy 77.828206 -43.782577)
			(xy 77.882164 -43.774822) (xy 77.90942 -43.77436) (xy 77.936791 -43.7748) (xy 77.990972 -43.782622)
			(xy 78.043476 -43.798116) (xy 78.093223 -43.820964) (xy 78.139188 -43.850695) (xy 78.160118 -43.86834)
			(xy 78.171446 -43.877576) (xy 78.198003 -43.889752) (xy 78.22692 -43.893925) (xy 78.255837 -43.889752)
			(xy 78.282394 -43.877576) (xy 78.293722 -43.86834) (xy 78.314678 -43.85073) (xy 78.360643 -43.821013)
			(xy 78.410385 -43.79817) (xy 78.462881 -43.782673) (xy 78.517052 -43.774837) (xy 78.54442 -43.77436)
			(xy 78.571668 -43.774912) (xy 78.625609 -43.78267) (xy 78.677897 -43.798025) (xy 78.727467 -43.820666)
			(xy 78.773311 -43.85013) (xy 78.814496 -43.885818) (xy 78.850182 -43.927005) (xy 78.879644 -43.97285)
			(xy 78.902282 -44.022422) (xy 78.917635 -44.074711) (xy 78.92539 -44.128652) (xy 78.92539 -44.183148)
			(xy 78.917635 -44.237089) (xy 78.902282 -44.289378) (xy 78.879644 -44.33895) (xy 78.850182 -44.384795)
			(xy 78.814496 -44.425982) (xy 78.773311 -44.46167) (xy 78.727467 -44.491134) (xy 78.677897 -44.513775)
			(xy 78.625609 -44.52913) (xy 78.571668 -44.536888) (xy 78.54442 -44.537376) (xy 78.51705 -44.536904)
			(xy 78.462871 -44.529089) (xy 78.410368 -44.513601) (xy 78.360621 -44.490761) (xy 78.314654 -44.461037)
			(xy 78.293722 -44.443396) (xy 78.282394 -44.43416) (xy 78.255837 -44.421984) (xy 78.22692 -44.417811)
			(xy 78.198003 -44.421984) (xy 78.171446 -44.43416) (xy 78.160118 -44.443396) (xy 78.139189 -44.461039)
			(xy 78.093216 -44.490751) (xy 78.043467 -44.513586) (xy 77.990966 -44.529076) (xy 77.936789 -44.536903)
			(xy 77.90942 -44.537376) (xy 77.882164 -44.536978) (xy 77.828206 -44.529223) (xy 77.775902 -44.513868)
			(xy 77.726315 -44.491224) (xy 77.680455 -44.461754) (xy 77.639257 -44.426058) (xy 77.603558 -44.384861)
			(xy 77.574085 -44.339003) (xy 77.551439 -44.289417) (xy 77.536081 -44.237113) (xy 77.528323 -44.183156)
			(xy 72.07617 -44.183156) (xy 72.164671 -44.236202) (xy 72.300589 -44.327019) (xy 72.431886 -44.424396)
			(xy 72.558247 -44.528098) (xy 72.679368 -44.637875) (xy 72.794956 -44.753463) (xy 72.904733 -44.874584)
			(xy 73.008435 -45.000945) (xy 73.061167 -45.072046) (xy 78.296006 -45.072046) (xy 78.300077 -45.016424)
			(xy 78.312203 -44.961987) (xy 78.332126 -44.909896) (xy 78.359422 -44.861261) (xy 78.393508 -44.817118)
			(xy 78.433657 -44.778409) (xy 78.479015 -44.745958) (xy 78.528615 -44.720457) (xy 78.581399 -44.70245)
			(xy 78.636242 -44.69232) (xy 78.691976 -44.690283) (xy 78.747413 -44.696383) (xy 78.80137 -44.710489)
			(xy 78.852699 -44.732301) (xy 78.900305 -44.761355) (xy 78.943173 -44.79703) (xy 78.98039 -44.838567)
			(xy 79.011163 -44.88508) (xy 79.034835 -44.935577) (xy 79.050903 -44.988984) (xy 79.059023 -45.04416)
			(xy 79.059532 -45.072046) (xy 79.059023 -45.099932) (xy 79.050903 -45.155108) (xy 79.034835 -45.208515)
			(xy 79.011163 -45.259012) (xy 78.98039 -45.305525) (xy 78.943173 -45.347062) (xy 78.900305 -45.382737)
			(xy 78.852699 -45.411791) (xy 78.80137 -45.433603) (xy 78.747413 -45.447709) (xy 78.691976 -45.453809)
			(xy 78.636242 -45.451772) (xy 78.581399 -45.441642) (xy 78.528615 -45.423635) (xy 78.479015 -45.398134)
			(xy 78.433657 -45.365683) (xy 78.393508 -45.326974) (xy 78.359422 -45.282831) (xy 78.332126 -45.234196)
			(xy 78.312203 -45.182105) (xy 78.300077 -45.127668) (xy 78.296006 -45.072046) (xy 73.061167 -45.072046)
			(xy 73.105812 -45.132243) (xy 73.196629 -45.26816) (xy 73.280668 -45.40837) (xy 73.357725 -45.552535)
			(xy 73.427616 -45.700306) (xy 73.490172 -45.85133) (xy 73.545242 -46.00524) (xy 73.570361 -46.088046)
			(xy 78.296006 -46.088046) (xy 78.300077 -46.032424) (xy 78.312203 -45.977987) (xy 78.332126 -45.925896)
			(xy 78.359422 -45.877261) (xy 78.393508 -45.833118) (xy 78.433657 -45.794409) (xy 78.479015 -45.761958)
			(xy 78.528615 -45.736457) (xy 78.581399 -45.71845) (xy 78.636242 -45.70832) (xy 78.691976 -45.706283)
			(xy 78.747413 -45.712383) (xy 78.80137 -45.726489) (xy 78.852699 -45.748301) (xy 78.900305 -45.777355)
			(xy 78.943173 -45.81303) (xy 78.98039 -45.854567) (xy 79.011163 -45.90108) (xy 79.034835 -45.951577)
			(xy 79.050903 -46.004984) (xy 79.059023 -46.06016) (xy 79.059532 -46.088046) (xy 79.059023 -46.115932)
			(xy 79.050903 -46.171108) (xy 79.034835 -46.224515) (xy 79.011163 -46.275012) (xy 78.98039 -46.321525)
			(xy 78.943173 -46.363062) (xy 78.900305 -46.398737) (xy 78.852699 -46.427791) (xy 78.80137 -46.449603)
			(xy 78.747413 -46.463709) (xy 78.691976 -46.469809) (xy 78.636242 -46.467772) (xy 78.581399 -46.457642)
			(xy 78.528615 -46.439635) (xy 78.479015 -46.414134) (xy 78.433657 -46.381683) (xy 78.393508 -46.342974)
			(xy 78.359422 -46.298831) (xy 78.332126 -46.250196) (xy 78.312203 -46.198105) (xy 78.300077 -46.143668)
			(xy 78.296006 -46.088046) (xy 73.570361 -46.088046) (xy 73.592694 -46.161668) (xy 73.632413 -46.320236)
			(xy 73.664304 -46.480561) (xy 73.688289 -46.642258) (xy 73.704312 -46.804937) (xy 73.712332 -46.968207)
			(xy 73.712332 -47.031148) (xy 88.035382 -47.031148) (xy 88.039453 -46.975526) (xy 88.051579 -46.921089)
			(xy 88.071502 -46.868998) (xy 88.098798 -46.820363) (xy 88.132884 -46.77622) (xy 88.173033 -46.737511)
			(xy 88.218391 -46.70506) (xy 88.267991 -46.679559) (xy 88.320775 -46.661552) (xy 88.375618 -46.651422)
			(xy 88.431352 -46.649385) (xy 88.486789 -46.655485) (xy 88.540746 -46.669591) (xy 88.592075 -46.691403)
			(xy 88.639681 -46.720457) (xy 88.682549 -46.756132) (xy 88.719766 -46.797669) (xy 88.750539 -46.844182)
			(xy 88.774211 -46.894679) (xy 88.790279 -46.948086) (xy 88.798399 -47.003262) (xy 88.798908 -47.031148)
			(xy 88.798565 -47.04994) (xy 89.78165 -47.04994) (xy 89.78563 -46.895439) (xy 89.797557 -46.741349)
			(xy 89.817402 -46.588076) (xy 89.84511 -46.436028) (xy 89.880608 -46.285609) (xy 89.923803 -46.137216)
			(xy 89.97458 -45.991243) (xy 90.032804 -45.848078) (xy 90.098321 -45.708101) (xy 90.170957 -45.571681)
			(xy 90.250519 -45.439181) (xy 90.336796 -45.310953) (xy 90.42956 -45.187337) (xy 90.528565 -45.068659)
			(xy 90.633548 -44.955236) (xy 90.74423 -44.847368) (xy 90.860319 -44.74534) (xy 90.981506 -44.649424)
			(xy 91.10747 -44.559873) (xy 91.237877 -44.476926) (xy 91.372381 -44.400801) (xy 91.510626 -44.331702)
			(xy 91.652244 -44.269811) (xy 91.796861 -44.215293) (xy 91.944092 -44.168291) (xy 92.093548 -44.128931)
			(xy 92.244832 -44.097317) (xy 92.397543 -44.073533) (xy 92.551275 -44.057642) (xy 92.705622 -44.049686)
			(xy 92.782898 -44.049188) (xy 94.383098 -44.049188) (xy 94.460945 -44.049695) (xy 94.61643 -44.057764)
			(xy 94.771287 -44.073884) (xy 94.9251 -44.098013) (xy 95.077454 -44.130086) (xy 95.227941 -44.170016)
			(xy 95.376154 -44.217696) (xy 95.521696 -44.272997) (xy 95.664174 -44.335772) (xy 95.803205 -44.40585)
			(xy 95.938415 -44.483043) (xy 96.06944 -44.567145) (xy 96.195928 -44.657927) (xy 96.317538 -44.755147)
			(xy 96.433943 -44.858542) (xy 96.544829 -44.967834) (xy 96.649899 -45.082729) (xy 96.74887 -45.202918)
			(xy 96.841474 -45.328078) (xy 96.927464 -45.457871) (xy 97.006608 -45.591949) (xy 97.078692 -45.729951)
			(xy 97.111566 -45.800518) (xy 97.118214 -45.813727) (xy 97.137759 -45.835901) (xy 97.162829 -45.851559)
			(xy 97.19133 -45.859393) (xy 97.220881 -45.858749) (xy 97.249013 -45.84968) (xy 97.273377 -45.832945)
			(xy 97.291937 -45.809941) (xy 97.298002 -45.796454) (xy 97.329371 -45.720474) (xy 97.398691 -45.571403)
			(xy 97.475283 -45.425935) (xy 97.55896 -45.284424) (xy 97.64952 -45.147215) (xy 97.74674 -45.014643)
			(xy 97.850385 -44.88703) (xy 97.960201 -44.764687) (xy 98.075921 -44.647913) (xy 98.197263 -44.536993)
			(xy 98.323931 -44.432196) (xy 98.455617 -44.333778) (xy 98.592 -44.241978) (xy 98.732746 -44.157021)
			(xy 98.877514 -44.079114) (xy 99.02595 -44.008446) (xy 99.177693 -43.945189) (xy 99.332373 -43.889499)
			(xy 99.489612 -43.84151) (xy 99.649029 -43.801339) (xy 99.810234 -43.769085) (xy 99.972834 -43.744825)
			(xy 100.136433 -43.72862) (xy 100.300632 -43.720508) (xy 100.382832 -43.720004) (xy 100.464565 -43.720498)
			(xy 100.627835 -43.728519) (xy 100.790514 -43.744541) (xy 100.952211 -43.768527) (xy 101.112536 -43.800418)
			(xy 101.271104 -43.840137) (xy 101.427531 -43.887589) (xy 101.581442 -43.942659) (xy 101.732465 -44.005215)
			(xy 101.880237 -44.075106) (xy 102.024402 -44.152163) (xy 102.164611 -44.236202) (xy 102.300529 -44.327019)
			(xy 102.431826 -44.424396) (xy 102.558187 -44.528098) (xy 102.679308 -44.637875) (xy 102.794896 -44.753463)
			(xy 102.904673 -44.874584) (xy 103.008375 -45.000945) (xy 103.105752 -45.132243) (xy 103.196569 -45.26816)
			(xy 103.280608 -45.40837) (xy 103.357665 -45.552535) (xy 103.427556 -45.700306) (xy 103.490112 -45.85133)
			(xy 103.506558 -45.897292) (xy 149.549866 -45.897292) (xy 149.550295 -45.8709) (xy 149.557589 -45.818623)
			(xy 149.572023 -45.767851) (xy 149.593321 -45.719555) (xy 149.621076 -45.674658) (xy 149.654758 -45.634017)
			(xy 149.693722 -45.59841) (xy 149.71522 -45.583094) (xy 149.726311 -45.574847) (xy 149.744031 -45.553656)
			(xy 149.755428 -45.528494) (xy 149.75967 -45.501198) (xy 149.756445 -45.473763) (xy 149.74599 -45.448195)
			(xy 149.729069 -45.426361) (xy 149.718268 -45.41774) (xy 149.694763 -45.399646) (xy 149.653166 -45.357359)
			(xy 149.618619 -45.30914) (xy 149.591956 -45.256154) (xy 149.57382 -45.199678) (xy 149.564647 -45.141075)
			(xy 149.56409 -45.111416) (xy 149.564576 -45.084165) (xy 149.572332 -45.030217) (xy 149.587687 -44.977922)
			(xy 149.610329 -44.928345) (xy 149.639795 -44.882495) (xy 149.675486 -44.841304) (xy 149.716677 -44.805613)
			(xy 149.762527 -44.776147) (xy 149.812104 -44.753505) (xy 149.864399 -44.73815) (xy 149.918347 -44.730394)
			(xy 149.972849 -44.730394) (xy 150.026797 -44.73815) (xy 150.079092 -44.753505) (xy 150.128669 -44.776147)
			(xy 150.174519 -44.805613) (xy 150.21571 -44.841304) (xy 150.251401 -44.882495) (xy 150.280867 -44.928345)
			(xy 150.303509 -44.977922) (xy 150.318864 -45.030217) (xy 150.32662 -45.084165) (xy 150.327106 -45.111416)
			(xy 150.326695 -45.137808) (xy 150.319399 -45.190087) (xy 150.304963 -45.24086) (xy 150.283662 -45.289156)
			(xy 150.255904 -45.334054) (xy 150.222219 -45.374693) (xy 150.183252 -45.410299) (xy 150.161752 -45.425614)
			(xy 150.150656 -45.433852) (xy 150.13294 -45.455046) (xy 150.121546 -45.480211) (xy 150.117307 -45.507507)
			(xy 150.120532 -45.534941) (xy 150.12215 -45.538898) (xy 151.203912 -45.538898) (xy 151.207983 -45.483276)
			(xy 151.220109 -45.428839) (xy 151.240032 -45.376748) (xy 151.267328 -45.328113) (xy 151.301414 -45.28397)
			(xy 151.341563 -45.245261) (xy 151.386921 -45.21281) (xy 151.436521 -45.187309) (xy 151.489305 -45.169302)
			(xy 151.544148 -45.159172) (xy 151.599882 -45.157135) (xy 151.655319 -45.163235) (xy 151.709276 -45.177341)
			(xy 151.760605 -45.199153) (xy 151.808211 -45.228207) (xy 151.851079 -45.263882) (xy 151.888296 -45.305419)
			(xy 151.919069 -45.351932) (xy 151.942741 -45.402429) (xy 151.958809 -45.455836) (xy 151.966929 -45.511012)
			(xy 151.967438 -45.538898) (xy 151.966929 -45.566784) (xy 151.958809 -45.62196) (xy 151.942741 -45.675367)
			(xy 151.919069 -45.725864) (xy 151.888296 -45.772377) (xy 151.851079 -45.813914) (xy 151.808211 -45.849589)
			(xy 151.760605 -45.878643) (xy 151.709276 -45.900455) (xy 151.655319 -45.914561) (xy 151.599882 -45.920661)
			(xy 151.544148 -45.918624) (xy 151.489305 -45.908494) (xy 151.436521 -45.890487) (xy 151.386921 -45.864986)
			(xy 151.341563 -45.832535) (xy 151.301414 -45.793826) (xy 151.267328 -45.749683) (xy 151.240032 -45.701048)
			(xy 151.220109 -45.648957) (xy 151.207983 -45.59452) (xy 151.203912 -45.538898) (xy 150.12215 -45.538898)
			(xy 150.130986 -45.56051) (xy 150.147905 -45.582346) (xy 150.158704 -45.590968) (xy 150.182207 -45.609065)
			(xy 150.223805 -45.651351) (xy 150.258353 -45.699568) (xy 150.285017 -45.752554) (xy 150.303153 -45.80903)
			(xy 150.312325 -45.867634) (xy 150.312882 -45.897292) (xy 150.312396 -45.924543) (xy 150.30464 -45.978491)
			(xy 150.289285 -46.030786) (xy 150.266643 -46.080363) (xy 150.237177 -46.126213) (xy 150.201486 -46.167404)
			(xy 150.160295 -46.203095) (xy 150.114445 -46.232561) (xy 150.064868 -46.255203) (xy 150.012573 -46.270558)
			(xy 149.958625 -46.278314) (xy 149.904123 -46.278314) (xy 149.850175 -46.270558) (xy 149.79788 -46.255203)
			(xy 149.748303 -46.232561) (xy 149.702453 -46.203095) (xy 149.661262 -46.167404) (xy 149.625571 -46.126213)
			(xy 149.596105 -46.080363) (xy 149.573463 -46.030786) (xy 149.558108 -45.978491) (xy 149.550352 -45.924543)
			(xy 149.549866 -45.897292) (xy 103.506558 -45.897292) (xy 103.545182 -46.00524) (xy 103.592634 -46.161668)
			(xy 103.632353 -46.320236) (xy 103.664244 -46.480561) (xy 103.688229 -46.642258) (xy 103.695486 -46.715934)
			(xy 134.105902 -46.715934) (xy 134.109973 -46.660312) (xy 134.122099 -46.605875) (xy 134.142022 -46.553784)
			(xy 134.169318 -46.505149) (xy 134.203404 -46.461006) (xy 134.243553 -46.422297) (xy 134.288911 -46.389846)
			(xy 134.338511 -46.364345) (xy 134.391295 -46.346338) (xy 134.446138 -46.336208) (xy 134.501872 -46.334171)
			(xy 134.557309 -46.340271) (xy 134.611266 -46.354377) (xy 134.662595 -46.376189) (xy 134.710201 -46.405243)
			(xy 134.753069 -46.440918) (xy 134.790286 -46.482455) (xy 134.821059 -46.528968) (xy 134.844731 -46.579465)
			(xy 134.860799 -46.632872) (xy 134.868919 -46.688048) (xy 134.869428 -46.715934) (xy 134.868919 -46.74382)
			(xy 134.860799 -46.798996) (xy 134.844731 -46.852403) (xy 134.821059 -46.9029) (xy 134.790286 -46.949413)
			(xy 134.755219 -46.98855) (xy 150.296876 -46.98855) (xy 150.296876 -46.93405) (xy 150.304632 -46.880103)
			(xy 150.319986 -46.82781) (xy 150.342626 -46.778234) (xy 150.37209 -46.732384) (xy 150.40778 -46.691194)
			(xy 150.448968 -46.655502) (xy 150.494816 -46.626035) (xy 150.544391 -46.603393) (xy 150.596684 -46.588036)
			(xy 150.65063 -46.580277) (xy 150.67788 -46.57979) (xy 150.70711 -46.58037) (xy 150.764884 -46.589312)
			(xy 150.820618 -46.606958) (xy 150.87301 -46.632898) (xy 150.920833 -46.666523) (xy 150.96297 -46.707047)
			(xy 150.998435 -46.753523) (xy 151.012906 -46.778926) (xy 151.019939 -46.790804) (xy 151.039095 -46.810657)
			(xy 151.062873 -46.824646) (xy 151.089531 -46.831748) (xy 151.117117 -46.831441) (xy 151.143611 -46.823748)
			(xy 151.167071 -46.809233) (xy 151.18578 -46.788958) (xy 151.192484 -46.776894) (xy 151.204804 -46.753859)
			(xy 151.234839 -46.711116) (xy 151.270427 -46.672873) (xy 151.310902 -46.639845) (xy 151.355506 -46.612651)
			(xy 151.403405 -46.5918) (xy 151.453701 -46.577682) (xy 151.505454 -46.570562) (xy 151.531574 -46.570138)
			(xy 151.558375 -46.570591) (xy 151.611451 -46.578079) (xy 151.662955 -46.592926) (xy 151.711873 -46.614839)
			(xy 151.757241 -46.643386) (xy 151.798164 -46.678004) (xy 151.833836 -46.718012) (xy 151.849074 -46.740064)
			(xy 151.857302 -46.751532) (xy 151.878792 -46.769811) (xy 151.904463 -46.781515) (xy 151.932357 -46.78575)
			(xy 151.960345 -46.782195) (xy 151.986293 -46.77112) (xy 152.008222 -46.753369) (xy 152.016714 -46.742096)
			(xy 152.03207 -46.720948) (xy 152.067655 -46.682668) (xy 152.108133 -46.649606) (xy 152.152746 -46.622381)
			(xy 152.200659 -46.601501) (xy 152.250973 -46.58736) (xy 152.302748 -46.580221) (xy 152.32888 -46.57979)
			(xy 152.356134 -46.580256) (xy 152.410086 -46.588011) (xy 152.462386 -46.603365) (xy 152.511969 -46.626006)
			(xy 152.557824 -46.655473) (xy 152.599019 -46.691167) (xy 152.634715 -46.73236) (xy 152.664184 -46.778214)
			(xy 152.686828 -46.827795) (xy 152.702185 -46.880094) (xy 152.709943 -46.934046) (xy 152.709943 -46.954948)
			(xy 162.807902 -46.954948) (xy 162.811973 -46.899326) (xy 162.824099 -46.844889) (xy 162.844022 -46.792798)
			(xy 162.871318 -46.744163) (xy 162.905404 -46.70002) (xy 162.945553 -46.661311) (xy 162.990911 -46.62886)
			(xy 163.040511 -46.603359) (xy 163.093295 -46.585352) (xy 163.148138 -46.575222) (xy 163.203872 -46.573185)
			(xy 163.259309 -46.579285) (xy 163.313266 -46.593391) (xy 163.364595 -46.615203) (xy 163.412201 -46.644257)
			(xy 163.455069 -46.679932) (xy 163.492286 -46.721469) (xy 163.523059 -46.767982) (xy 163.546731 -46.818479)
			(xy 163.562799 -46.871886) (xy 163.570919 -46.927062) (xy 163.571428 -46.954948) (xy 163.570919 -46.982834)
			(xy 163.562799 -47.03801) (xy 163.546731 -47.091417) (xy 163.523059 -47.141914) (xy 163.492286 -47.188427)
			(xy 163.455069 -47.229964) (xy 163.412201 -47.265639) (xy 163.364595 -47.294693) (xy 163.313266 -47.316505)
			(xy 163.259309 -47.330611) (xy 163.203872 -47.336711) (xy 163.148138 -47.334674) (xy 163.093295 -47.324544)
			(xy 163.040511 -47.306537) (xy 162.990911 -47.281036) (xy 162.945553 -47.248585) (xy 162.905404 -47.209876)
			(xy 162.871318 -47.165733) (xy 162.844022 -47.117098) (xy 162.824099 -47.065007) (xy 162.811973 -47.01057)
			(xy 162.807902 -46.954948) (xy 152.709943 -46.954948) (xy 152.709943 -46.988554) (xy 152.702185 -47.042506)
			(xy 152.686828 -47.094805) (xy 152.664184 -47.144386) (xy 152.634715 -47.19024) (xy 152.599019 -47.231433)
			(xy 152.557824 -47.267127) (xy 152.511969 -47.296594) (xy 152.462386 -47.319235) (xy 152.410086 -47.334589)
			(xy 152.356134 -47.342344) (xy 152.32888 -47.342806) (xy 152.302079 -47.342368) (xy 152.249003 -47.334875)
			(xy 152.197499 -47.320024) (xy 152.148582 -47.298108) (xy 152.103215 -47.269559) (xy 152.062291 -47.23494)
			(xy 152.026618 -47.194932) (xy 152.01138 -47.17288) (xy 152.003207 -47.161372) (xy 151.981701 -47.143101)
			(xy 151.956019 -47.131407) (xy 151.928118 -47.127179) (xy 151.900124 -47.130741) (xy 151.874171 -47.14182)
			(xy 151.852235 -47.159573) (xy 151.84374 -47.170848) (xy 151.828363 -47.191981) (xy 151.792781 -47.230258)
			(xy 151.752306 -47.26332) (xy 151.707696 -47.290547) (xy 151.659787 -47.311429) (xy 151.609476 -47.325575)
			(xy 151.557705 -47.332719) (xy 151.531574 -47.333154) (xy 151.502344 -47.33256) (xy 151.44457 -47.323625)
			(xy 151.388834 -47.305983) (xy 151.336441 -47.280046) (xy 151.288617 -47.246423) (xy 151.246481 -47.205898)
			(xy 151.211018 -47.159422) (xy 151.196548 -47.134018) (xy 151.189576 -47.122104) (xy 151.170405 -47.102258)
			(xy 151.146616 -47.088276) (xy 151.11995 -47.081182) (xy 151.092358 -47.081495) (xy 151.06586 -47.089192)
			(xy 151.042394 -47.103709) (xy 151.023678 -47.123985) (xy 151.01697 -47.13605) (xy 151.004628 -47.159073)
			(xy 150.974594 -47.201813) (xy 150.939008 -47.240055) (xy 150.898536 -47.273082) (xy 150.853935 -47.300277)
			(xy 150.806041 -47.32113) (xy 150.755748 -47.335252) (xy 150.703999 -47.342379) (xy 150.67788 -47.342806)
			(xy 150.65063 -47.342323) (xy 150.596684 -47.334564) (xy 150.544391 -47.319207) (xy 150.494816 -47.296565)
			(xy 150.448968 -47.267098) (xy 150.40778 -47.231406) (xy 150.37209 -47.190216) (xy 150.342626 -47.144366)
			(xy 150.319986 -47.09479) (xy 150.304632 -47.042497) (xy 150.296876 -46.98855) (xy 134.755219 -46.98855)
			(xy 134.753069 -46.99095) (xy 134.710201 -47.026625) (xy 134.662595 -47.055679) (xy 134.611266 -47.077491)
			(xy 134.557309 -47.091597) (xy 134.501872 -47.097697) (xy 134.446138 -47.09566) (xy 134.391295 -47.08553)
			(xy 134.338511 -47.067523) (xy 134.288911 -47.042022) (xy 134.243553 -47.009571) (xy 134.203404 -46.970862)
			(xy 134.169318 -46.926719) (xy 134.142022 -46.878084) (xy 134.122099 -46.825993) (xy 134.109973 -46.771556)
			(xy 134.105902 -46.715934) (xy 103.695486 -46.715934) (xy 103.704252 -46.804937) (xy 103.712272 -46.968207)
			(xy 103.712272 -47.131673) (xy 103.704252 -47.294943) (xy 103.688229 -47.457622) (xy 103.664244 -47.619319)
			(xy 103.632353 -47.779644) (xy 103.60878 -47.873755) (xy 154.820543 -47.873755) (xy 154.820543 -47.819245)
			(xy 154.828301 -47.765291) (xy 154.843658 -47.71299) (xy 154.866303 -47.663407) (xy 154.895774 -47.617551)
			(xy 154.931471 -47.576357) (xy 154.972667 -47.540662) (xy 155.018524 -47.511193) (xy 155.068109 -47.488551)
			(xy 155.12041 -47.473196) (xy 155.174365 -47.465442) (xy 155.20162 -47.46498) (xy 155.22947 -47.465478)
			(xy 155.284575 -47.473592) (xy 155.337915 -47.489631) (xy 155.388357 -47.513253) (xy 155.43483 -47.543957)
			(xy 155.476346 -47.58109) (xy 155.512023 -47.623863) (xy 155.526994 -47.647352) (xy 155.53543 -47.659949)
			(xy 155.558111 -47.680031) (xy 155.585687 -47.692574) (xy 155.615729 -47.696472) (xy 155.645593 -47.691383)
			(xy 155.672648 -47.677754) (xy 155.683966 -47.667672) (xy 155.705441 -47.647858) (xy 155.753291 -47.614329)
			(xy 155.80569 -47.58848) (xy 155.861415 -47.570914) (xy 155.919166 -47.562042) (xy 155.94838 -47.5615)
			(xy 156.81198 -47.5615) (xy 156.841986 -47.562037) (xy 156.90126 -47.571409) (xy 156.958338 -47.58994)
			(xy 157.011813 -47.617174) (xy 157.060368 -47.65244) (xy 157.081982 -47.67326) (xy 157.091603 -47.68218)
			(xy 157.114286 -47.695339) (xy 157.139571 -47.702293) (xy 157.165793 -47.702582) (xy 157.191225 -47.696188)
			(xy 157.214193 -47.683532) (xy 157.223968 -47.674784) (xy 157.245395 -47.655059) (xy 157.293135 -47.621706)
			(xy 157.345387 -47.59599) (xy 157.400939 -47.578509) (xy 157.458501 -47.569667) (xy 157.48762 -47.56912)
			(xy 157.514872 -47.569551) (xy 157.568822 -47.577311) (xy 157.621118 -47.592669) (xy 157.670696 -47.615313)
			(xy 157.716548 -47.644782) (xy 157.757738 -47.680476) (xy 157.79343 -47.721668) (xy 157.822897 -47.767521)
			(xy 157.845538 -47.817101) (xy 157.860894 -47.869398) (xy 157.86865 -47.923348) (xy 157.86865 -47.977852)
			(xy 157.860894 -48.031802) (xy 157.845538 -48.084099) (xy 157.822897 -48.133679) (xy 157.79343 -48.179532)
			(xy 157.757738 -48.220724) (xy 157.716548 -48.256418) (xy 157.670696 -48.285887) (xy 157.621118 -48.308531)
			(xy 157.568822 -48.323889) (xy 157.514872 -48.331649) (xy 157.48762 -48.332136) (xy 157.457643 -48.331535)
			(xy 157.398428 -48.322147) (xy 157.34141 -48.303615) (xy 157.287991 -48.276395) (xy 157.239486 -48.241156)
			(xy 157.217872 -48.220376) (xy 157.208291 -48.211408) (xy 157.185598 -48.198248) (xy 157.160301 -48.191298)
			(xy 157.134069 -48.191017) (xy 157.10863 -48.197423) (xy 157.08566 -48.210095) (xy 157.075886 -48.218852)
			(xy 157.054411 -48.23856) (xy 157.006628 -48.271931) (xy 156.95433 -48.297657) (xy 156.898731 -48.315141)
			(xy 156.841122 -48.323976) (xy 156.81198 -48.324516) (xy 155.94838 -48.324516) (xy 155.920519 -48.323951)
			(xy 155.865389 -48.315841) (xy 155.812022 -48.299811) (xy 155.761548 -48.2762) (xy 155.715039 -48.24551)
			(xy 155.67348 -48.20839) (xy 155.637752 -48.165629) (xy 155.622752 -48.142144) (xy 155.614363 -48.129505)
			(xy 155.591683 -48.10939) (xy 155.564093 -48.096829) (xy 155.534029 -48.092933) (xy 155.504148 -48.098046)
			(xy 155.47709 -48.111717) (xy 155.46578 -48.121824) (xy 155.444316 -48.141613) (xy 155.396518 -48.175128)
			(xy 155.344174 -48.200974) (xy 155.288505 -48.218548) (xy 155.230809 -48.22744) (xy 155.20162 -48.227996)
			(xy 155.174365 -48.227558) (xy 155.12041 -48.219804) (xy 155.068109 -48.204449) (xy 155.018524 -48.181807)
			(xy 154.972667 -48.152338) (xy 154.931471 -48.116643) (xy 154.895774 -48.075449) (xy 154.866303 -48.029593)
			(xy 154.843658 -47.98001) (xy 154.828301 -47.927709) (xy 154.820543 -47.873755) (xy 103.60878 -47.873755)
			(xy 103.592634 -47.938212) (xy 103.545182 -48.09464) (xy 103.490112 -48.24855) (xy 103.427556 -48.399574)
			(xy 103.357665 -48.547345) (xy 103.341819 -48.576992) (xy 158.58744 -48.576992) (xy 158.587994 -48.548105)
			(xy 158.596694 -48.490989) (xy 158.613907 -48.435838) (xy 158.639241 -48.383914) (xy 158.672116 -48.336405)
			(xy 158.71178 -48.294397) (xy 158.757326 -48.258852) (xy 158.782258 -48.244252) (xy 158.795481 -48.236257)
			(xy 158.816707 -48.213821) (xy 158.830263 -48.186069) (xy 158.83491 -48.155535) (xy 158.830224 -48.125007)
			(xy 158.823914 -48.110902) (xy 158.81163 -48.08464) (xy 158.794302 -48.029312) (xy 158.785566 -47.971997)
			(xy 158.785052 -47.943008) (xy 158.785585 -47.915759) (xy 158.793339 -47.861815) (xy 158.808692 -47.809523)
			(xy 158.831329 -47.759949) (xy 158.860791 -47.7141) (xy 158.896477 -47.672911) (xy 158.937662 -47.637219)
			(xy 158.983507 -47.607752) (xy 159.033078 -47.585108) (xy 159.085368 -47.56975) (xy 159.139311 -47.561989)
			(xy 159.16656 -47.5615) (xy 160.03016 -47.5615) (xy 160.057412 -47.561993) (xy 160.111363 -47.569744)
			(xy 160.16366 -47.585096) (xy 160.213241 -47.607734) (xy 160.259095 -47.637199) (xy 160.300288 -47.672889)
			(xy 160.335982 -47.71408) (xy 160.365451 -47.759931) (xy 160.388093 -47.80951) (xy 160.403449 -47.861806)
			(xy 160.411205 -47.915756) (xy 160.411668 -47.943008) (xy 160.411135 -47.971994) (xy 160.40237 -48.0293)
			(xy 160.385057 -48.084627) (xy 160.372806 -48.110902) (xy 160.3665 -48.125008) (xy 160.361813 -48.155534)
			(xy 160.366461 -48.186067) (xy 160.380017 -48.213816) (xy 160.401246 -48.236248) (xy 160.414462 -48.244252)
			(xy 160.439394 -48.258852) (xy 160.484936 -48.294402) (xy 160.524599 -48.336411) (xy 160.557476 -48.38392)
			(xy 160.582815 -48.435842) (xy 160.600036 -48.49099) (xy 160.608747 -48.548105) (xy 160.60928 -48.576992)
			(xy 160.608794 -48.604243) (xy 160.601038 -48.658191) (xy 160.585683 -48.710486) (xy 160.563041 -48.760063)
			(xy 160.533575 -48.805913) (xy 160.497884 -48.847104) (xy 160.456693 -48.882795) (xy 160.410843 -48.912261)
			(xy 160.361266 -48.934903) (xy 160.308971 -48.950258) (xy 160.255023 -48.958014) (xy 160.200521 -48.958014)
			(xy 160.146573 -48.950258) (xy 160.094278 -48.934903) (xy 160.044701 -48.912261) (xy 159.998851 -48.882795)
			(xy 159.95766 -48.847104) (xy 159.921969 -48.805913) (xy 159.892503 -48.760063) (xy 159.869861 -48.710486)
			(xy 159.854506 -48.658191) (xy 159.84675 -48.604243) (xy 159.846264 -48.576992) (xy 159.846828 -48.546687)
			(xy 159.856403 -48.486837) (xy 159.865314 -48.457866) (xy 159.869156 -48.444678) (xy 159.870477 -48.417254)
			(xy 159.86444 -48.39047) (xy 159.851482 -48.366265) (xy 159.83254 -48.346389) (xy 159.808985 -48.332283)
			(xy 159.782522 -48.324965) (xy 159.768794 -48.324516) (xy 159.427926 -48.324516) (xy 159.414195 -48.324959)
			(xy 159.387727 -48.332273) (xy 159.364166 -48.346379) (xy 159.345219 -48.366257) (xy 159.332257 -48.390466)
			(xy 159.326218 -48.417254) (xy 159.32754 -48.444683) (xy 159.331406 -48.457866) (xy 159.340293 -48.486843)
			(xy 159.349869 -48.546689) (xy 159.350456 -48.576992) (xy 159.34997 -48.604243) (xy 159.342214 -48.658191)
			(xy 159.326859 -48.710486) (xy 159.304217 -48.760063) (xy 159.274751 -48.805913) (xy 159.23906 -48.847104)
			(xy 159.197869 -48.882795) (xy 159.152019 -48.912261) (xy 159.102442 -48.934903) (xy 159.050147 -48.950258)
			(xy 158.996199 -48.958014) (xy 158.941697 -48.958014) (xy 158.887749 -48.950258) (xy 158.835454 -48.934903)
			(xy 158.785877 -48.912261) (xy 158.740027 -48.882795) (xy 158.698836 -48.847104) (xy 158.663145 -48.805913)
			(xy 158.633679 -48.760063) (xy 158.611037 -48.710486) (xy 158.595682 -48.658191) (xy 158.587926 -48.604243)
			(xy 158.58744 -48.576992) (xy 103.341819 -48.576992) (xy 103.280608 -48.69151) (xy 103.196569 -48.83172)
			(xy 103.105752 -48.967637) (xy 103.008375 -49.098935) (xy 102.904673 -49.225296) (xy 102.890487 -49.240948)
			(xy 140.24737 -49.240948) (xy 140.247856 -49.213697) (xy 140.255612 -49.159749) (xy 140.270967 -49.107454)
			(xy 140.293609 -49.057877) (xy 140.323075 -49.012027) (xy 140.358766 -48.970836) (xy 140.399957 -48.935145)
			(xy 140.445807 -48.905679) (xy 140.495384 -48.883037) (xy 140.547679 -48.867682) (xy 140.601627 -48.859926)
			(xy 140.656129 -48.859926) (xy 140.710077 -48.867682) (xy 140.762372 -48.883037) (xy 140.811949 -48.905679)
			(xy 140.857799 -48.935145) (xy 140.89899 -48.970836) (xy 140.934681 -49.012027) (xy 140.964147 -49.057877)
			(xy 140.986789 -49.107454) (xy 141.002144 -49.159749) (xy 141.0099 -49.213697) (xy 141.010386 -49.240948)
			(xy 141.009708 -49.273234) (xy 140.998852 -49.336886) (xy 140.986516 -49.372012) (xy 146.806156 -49.372012)
			(xy 146.810227 -49.31639) (xy 146.822353 -49.261953) (xy 146.842276 -49.209862) (xy 146.869572 -49.161227)
			(xy 146.903658 -49.117084) (xy 146.943807 -49.078375) (xy 146.989165 -49.045924) (xy 147.038765 -49.020423)
			(xy 147.091549 -49.002416) (xy 147.146392 -48.992286) (xy 147.202126 -48.990249) (xy 147.257563 -48.996349)
			(xy 147.31152 -49.010455) (xy 147.362849 -49.032267) (xy 147.410455 -49.061321) (xy 147.453323 -49.096996)
			(xy 147.49054 -49.138533) (xy 147.521313 -49.185046) (xy 147.544985 -49.235543) (xy 147.561053 -49.28895)
			(xy 147.569173 -49.344126) (xy 147.569682 -49.372012) (xy 147.569173 -49.399898) (xy 147.561053 -49.455074)
			(xy 147.544985 -49.508481) (xy 147.521313 -49.558978) (xy 147.49054 -49.605491) (xy 147.453323 -49.647028)
			(xy 147.410455 -49.682703) (xy 147.362849 -49.711757) (xy 147.31152 -49.733569) (xy 147.257563 -49.747675)
			(xy 147.202126 -49.753775) (xy 147.146392 -49.751738) (xy 147.091549 -49.741608) (xy 147.038765 -49.723601)
			(xy 146.989165 -49.6981) (xy 146.943807 -49.665649) (xy 146.903658 -49.62694) (xy 146.869572 -49.582797)
			(xy 146.842276 -49.534162) (xy 146.822353 -49.482071) (xy 146.810227 -49.427634) (xy 146.806156 -49.372012)
			(xy 140.986516 -49.372012) (xy 140.977456 -49.39781) (xy 140.96238 -49.426368) (xy 140.956193 -49.438246)
			(xy 140.949649 -49.464208) (xy 140.950098 -49.490977) (xy 140.957509 -49.516705) (xy 140.97137 -49.539611)
			(xy 140.990722 -49.558112) (xy 141.014228 -49.57093) (xy 141.02715 -49.57445) (xy 141.054525 -49.581561)
			(xy 141.106932 -49.602834) (xy 141.155625 -49.631609) (xy 141.199537 -49.667257) (xy 141.237707 -49.708995)
			(xy 141.269297 -49.755911) (xy 141.293617 -49.806975) (xy 141.310132 -49.86107) (xy 141.318482 -49.91701)
			(xy 141.318996 -49.94529) (xy 141.318687 -49.967925) (xy 141.313336 -50.012876) (xy 141.308328 -50.034952)
			(xy 141.305376 -50.049854) (xy 141.307269 -50.080154) (xy 141.317979 -50.108561) (xy 141.336561 -50.132569)
			(xy 141.361375 -50.150059) (xy 141.390232 -50.15949) (xy 141.420587 -50.160027) (xy 141.435328 -50.156364)
			(xy 141.461183 -50.149372) (xy 141.514212 -50.14185) (xy 141.540992 -50.141378) (xy 141.568242 -50.141885)
			(xy 141.622189 -50.14964) (xy 141.674482 -50.164994) (xy 141.724058 -50.187633) (xy 141.769908 -50.217097)
			(xy 141.811098 -50.252786) (xy 141.84679 -50.293974) (xy 141.876257 -50.339822) (xy 141.898899 -50.389397)
			(xy 141.914255 -50.44169) (xy 141.922013 -50.495636) (xy 141.9225 -50.522886) (xy 141.92228 -50.54168)
			(xy 141.918591 -50.579087) (xy 141.915134 -50.597562) (xy 141.912757 -50.611318) (xy 141.91489 -50.639148)
			(xy 141.924478 -50.66536) (xy 141.940804 -50.687998) (xy 141.962649 -50.705371) (xy 141.988381 -50.716181)
			(xy 142.016079 -50.719621) (xy 142.029942 -50.717958) (xy 142.044269 -50.715916) (xy 142.073129 -50.713754)
			(xy 142.0876 -50.71364) (xy 142.114851 -50.714078) (xy 142.168797 -50.721834) (xy 142.22109 -50.737188)
			(xy 142.270666 -50.759828) (xy 142.316516 -50.789293) (xy 142.357706 -50.824983) (xy 142.393397 -50.866171)
			(xy 142.412576 -50.896012) (xy 155.708856 -50.896012) (xy 155.712927 -50.84039) (xy 155.725053 -50.785953)
			(xy 155.744976 -50.733862) (xy 155.772272 -50.685227) (xy 155.806358 -50.641084) (xy 155.846507 -50.602375)
			(xy 155.891865 -50.569924) (xy 155.941465 -50.544423) (xy 155.994249 -50.526416) (xy 156.049092 -50.516286)
			(xy 156.104826 -50.514249) (xy 156.160263 -50.520349) (xy 156.21422 -50.534455) (xy 156.265549 -50.556267)
			(xy 156.313155 -50.585321) (xy 156.356023 -50.620996) (xy 156.39324 -50.662533) (xy 156.424013 -50.709046)
			(xy 156.447685 -50.759543) (xy 156.463753 -50.81295) (xy 156.471873 -50.868126) (xy 156.472382 -50.896012)
			(xy 156.471873 -50.923898) (xy 156.463753 -50.979074) (xy 156.447685 -51.032481) (xy 156.424013 -51.082978)
			(xy 156.39324 -51.129491) (xy 156.356023 -51.171028) (xy 156.313155 -51.206703) (xy 156.265549 -51.235757)
			(xy 156.21422 -51.257569) (xy 156.160263 -51.271675) (xy 156.104826 -51.277775) (xy 156.049092 -51.275738)
			(xy 155.994249 -51.265608) (xy 155.941465 -51.247601) (xy 155.891865 -51.2221) (xy 155.846507 -51.189649)
			(xy 155.806358 -51.15094) (xy 155.772272 -51.106797) (xy 155.744976 -51.058162) (xy 155.725053 -51.006071)
			(xy 155.712927 -50.951634) (xy 155.708856 -50.896012) (xy 142.412576 -50.896012) (xy 142.422864 -50.912019)
			(xy 142.445506 -50.961595) (xy 142.460863 -51.013887) (xy 142.468621 -51.067833) (xy 142.468623 -51.122335)
			(xy 142.46087 -51.176281) (xy 142.445517 -51.228575) (xy 142.42288 -51.278152) (xy 142.393417 -51.324003)
			(xy 142.357729 -51.365195) (xy 142.316542 -51.400888) (xy 142.270695 -51.430357) (xy 142.22112 -51.453001)
			(xy 142.168828 -51.468359) (xy 142.114882 -51.47612) (xy 142.060381 -51.476125) (xy 142.006434 -51.468373)
			(xy 141.95414 -51.453023) (xy 141.904562 -51.430387) (xy 141.85871 -51.400926) (xy 141.817517 -51.36524)
			(xy 141.781822 -51.324055) (xy 141.752351 -51.278209) (xy 141.729705 -51.228635) (xy 141.714344 -51.176344)
			(xy 141.706581 -51.122398) (xy 141.706092 -51.095148) (xy 141.706318 -51.076354) (xy 141.710002 -51.038947)
			(xy 141.713458 -51.020472) (xy 141.715809 -51.006711) (xy 141.713683 -50.978883) (xy 141.704102 -50.952671)
			(xy 141.68778 -50.930032) (xy 141.665938 -50.912659) (xy 141.640208 -50.90185) (xy 141.612512 -50.898412)
			(xy 141.59865 -50.900076) (xy 141.584324 -50.902119) (xy 141.555463 -50.90428) (xy 141.540992 -50.904394)
			(xy 141.513738 -50.903952) (xy 141.459786 -50.896194) (xy 141.407487 -50.880836) (xy 141.357906 -50.858191)
			(xy 141.312052 -50.828721) (xy 141.270859 -50.793025) (xy 141.235166 -50.75183) (xy 141.205698 -50.705975)
			(xy 141.183056 -50.656393) (xy 141.167702 -50.604093) (xy 141.159946 -50.55014) (xy 141.159484 -50.522886)
			(xy 141.159789 -50.500251) (xy 141.165143 -50.4553) (xy 141.170152 -50.433224) (xy 141.173154 -50.41833)
			(xy 141.171255 -50.388023) (xy 141.160538 -50.359611) (xy 141.141947 -50.3356) (xy 141.117124 -50.318108)
			(xy 141.088259 -50.30868) (xy 141.057897 -50.308146) (xy 141.043152 -50.311812) (xy 141.017298 -50.318808)
			(xy 140.964268 -50.326327) (xy 140.937488 -50.326798) (xy 140.910236 -50.326333) (xy 140.856287 -50.318575)
			(xy 140.803991 -50.303218) (xy 140.754413 -50.280575) (xy 140.708562 -50.251106) (xy 140.667372 -50.215412)
			(xy 140.631681 -50.17422) (xy 140.602215 -50.128367) (xy 140.579575 -50.078788) (xy 140.56422 -50.026491)
			(xy 140.556465 -49.972542) (xy 140.55598 -49.94529) (xy 140.556365 -49.921082) (xy 140.562481 -49.873054)
			(xy 140.574613 -49.826183) (xy 140.592568 -49.781219) (xy 140.603986 -49.75987) (xy 140.610085 -49.747951)
			(xy 140.616628 -49.722006) (xy 140.616185 -49.695252) (xy 140.608786 -49.669538) (xy 140.594943 -49.64664)
			(xy 140.575612 -49.628139) (xy 140.552128 -49.615315) (xy 140.539216 -49.611788) (xy 140.511863 -49.604598)
			(xy 140.459457 -49.583337) (xy 140.410765 -49.554573) (xy 140.366851 -49.518936) (xy 140.328679 -49.477208)
			(xy 140.297086 -49.430302) (xy 140.272762 -49.379245) (xy 140.256242 -49.325158) (xy 140.247886 -49.269225)
			(xy 140.24737 -49.240948) (xy 102.890487 -49.240948) (xy 102.794896 -49.346417) (xy 102.679308 -49.462005)
			(xy 102.558187 -49.571782) (xy 102.431826 -49.675484) (xy 102.300529 -49.772861) (xy 102.164611 -49.863678)
			(xy 102.024402 -49.947717) (xy 101.880237 -50.024774) (xy 101.732465 -50.094665) (xy 101.581442 -50.157221)
			(xy 101.427531 -50.212291) (xy 101.271104 -50.259743) (xy 101.112536 -50.299462) (xy 100.952211 -50.331353)
			(xy 100.790514 -50.355339) (xy 100.627835 -50.371361) (xy 100.464565 -50.379382) (xy 100.382832 -50.379884)
			(xy 100.300633 -50.379346) (xy 100.136435 -50.371235) (xy 99.972838 -50.35503) (xy 99.81024 -50.33077)
			(xy 99.649037 -50.298516) (xy 99.489622 -50.258346) (xy 99.332384 -50.210357) (xy 99.177706 -50.154667)
			(xy 99.025965 -50.091411) (xy 98.87753 -50.020744) (xy 98.732764 -49.942837) (xy 98.592019 -49.857881)
			(xy 98.455639 -49.766082) (xy 98.323954 -49.667665) (xy 98.197288 -49.562869) (xy 98.075947 -49.451949)
			(xy 97.960229 -49.335176) (xy 97.850414 -49.212835) (xy 97.746771 -49.085223) (xy 97.649552 -48.952651)
			(xy 97.558994 -48.815444) (xy 97.475318 -48.673934) (xy 97.398727 -48.528468) (xy 97.329409 -48.379398)
			(xy 97.298002 -48.303434) (xy 97.291959 -48.289914) (xy 97.273434 -48.266828) (xy 97.249065 -48.250026)
			(xy 97.220901 -48.240919) (xy 97.191308 -48.240273) (xy 97.162774 -48.248142) (xy 97.137695 -48.263865)
			(xy 97.118181 -48.286121) (xy 97.111566 -48.29937) (xy 97.078712 -48.369946) (xy 97.006622 -48.507944)
			(xy 96.927474 -48.642019) (xy 96.84148 -48.77181) (xy 96.748872 -48.896966) (xy 96.649898 -49.017153)
			(xy 96.544826 -49.132045) (xy 96.433938 -49.241335) (xy 96.317532 -49.344728) (xy 96.195921 -49.441946)
			(xy 96.069433 -49.532727) (xy 95.938408 -49.616828) (xy 95.803198 -49.694021) (xy 95.664167 -49.764099)
			(xy 95.52169 -49.826874) (xy 95.376149 -49.882177) (xy 95.227937 -49.929859) (xy 95.077451 -49.969791)
			(xy 94.925097 -50.001867) (xy 94.771285 -50.025999) (xy 94.616429 -50.042123) (xy 94.460945 -50.050196)
			(xy 94.383098 -50.0507) (xy 92.782898 -50.0507) (xy 92.705622 -50.050194) (xy 92.551275 -50.042238)
			(xy 92.397543 -50.026347) (xy 92.244832 -50.002563) (xy 92.093548 -49.970949) (xy 91.944092 -49.931589)
			(xy 91.796861 -49.884587) (xy 91.652244 -49.830069) (xy 91.510626 -49.768178) (xy 91.372381 -49.699079)
			(xy 91.237877 -49.622954) (xy 91.10747 -49.540007) (xy 90.981506 -49.450456) (xy 90.860319 -49.35454)
			(xy 90.74423 -49.252512) (xy 90.633548 -49.144644) (xy 90.528565 -49.031221) (xy 90.42956 -48.912543)
			(xy 90.336796 -48.788927) (xy 90.250519 -48.660699) (xy 90.170957 -48.528199) (xy 90.098321 -48.391779)
			(xy 90.032804 -48.251802) (xy 89.97458 -48.108637) (xy 89.923803 -47.962664) (xy 89.880608 -47.814271)
			(xy 89.84511 -47.663852) (xy 89.817402 -47.511804) (xy 89.797557 -47.358531) (xy 89.78563 -47.204441)
			(xy 89.78165 -47.04994) (xy 88.798565 -47.04994) (xy 88.798399 -47.059034) (xy 88.790279 -47.11421)
			(xy 88.774211 -47.167617) (xy 88.750539 -47.218114) (xy 88.719766 -47.264627) (xy 88.682549 -47.306164)
			(xy 88.639681 -47.341839) (xy 88.592075 -47.370893) (xy 88.540746 -47.392705) (xy 88.486789 -47.406811)
			(xy 88.431352 -47.412911) (xy 88.375618 -47.410874) (xy 88.320775 -47.400744) (xy 88.267991 -47.382737)
			(xy 88.218391 -47.357236) (xy 88.173033 -47.324785) (xy 88.132884 -47.286076) (xy 88.098798 -47.241933)
			(xy 88.071502 -47.193298) (xy 88.051579 -47.141207) (xy 88.039453 -47.08677) (xy 88.035382 -47.031148)
			(xy 73.712332 -47.031148) (xy 73.712332 -47.131673) (xy 73.704312 -47.294943) (xy 73.688289 -47.457622)
			(xy 73.664304 -47.619319) (xy 73.632413 -47.779644) (xy 73.62903 -47.793148) (xy 87.400382 -47.793148)
			(xy 87.404453 -47.737526) (xy 87.416579 -47.683089) (xy 87.436502 -47.630998) (xy 87.463798 -47.582363)
			(xy 87.497884 -47.53822) (xy 87.538033 -47.499511) (xy 87.583391 -47.46706) (xy 87.632991 -47.441559)
			(xy 87.685775 -47.423552) (xy 87.740618 -47.413422) (xy 87.796352 -47.411385) (xy 87.851789 -47.417485)
			(xy 87.905746 -47.431591) (xy 87.957075 -47.453403) (xy 88.004681 -47.482457) (xy 88.047549 -47.518132)
			(xy 88.084766 -47.559669) (xy 88.115539 -47.606182) (xy 88.139211 -47.656679) (xy 88.155279 -47.710086)
			(xy 88.163399 -47.765262) (xy 88.163908 -47.793148) (xy 88.163399 -47.821034) (xy 88.155279 -47.87621)
			(xy 88.139211 -47.929617) (xy 88.115539 -47.980114) (xy 88.084766 -48.026627) (xy 88.047549 -48.068164)
			(xy 88.004681 -48.103839) (xy 87.957075 -48.132893) (xy 87.905746 -48.154705) (xy 87.851789 -48.168811)
			(xy 87.796352 -48.174911) (xy 87.740618 -48.172874) (xy 87.685775 -48.162744) (xy 87.632991 -48.144737)
			(xy 87.583391 -48.119236) (xy 87.538033 -48.086785) (xy 87.497884 -48.048076) (xy 87.463798 -48.003933)
			(xy 87.436502 -47.955298) (xy 87.416579 -47.903207) (xy 87.404453 -47.84877) (xy 87.400382 -47.793148)
			(xy 73.62903 -47.793148) (xy 73.592694 -47.938212) (xy 73.545242 -48.09464) (xy 73.490172 -48.24855)
			(xy 73.427616 -48.399574) (xy 73.357725 -48.547345) (xy 73.280668 -48.69151) (xy 73.196629 -48.83172)
			(xy 73.117688 -48.949864) (xy 87.468708 -48.949864) (xy 87.472779 -48.894242) (xy 87.484905 -48.839805)
			(xy 87.504828 -48.787714) (xy 87.532124 -48.739079) (xy 87.56621 -48.694936) (xy 87.606359 -48.656227)
			(xy 87.651717 -48.623776) (xy 87.701317 -48.598275) (xy 87.754101 -48.580268) (xy 87.808944 -48.570138)
			(xy 87.864678 -48.568101) (xy 87.920115 -48.574201) (xy 87.974072 -48.588307) (xy 88.025401 -48.610119)
			(xy 88.073007 -48.639173) (xy 88.115875 -48.674848) (xy 88.153092 -48.716385) (xy 88.183865 -48.762898)
			(xy 88.207537 -48.813395) (xy 88.223605 -48.866802) (xy 88.231725 -48.921978) (xy 88.232234 -48.949864)
			(xy 88.231725 -48.97775) (xy 88.223605 -49.032926) (xy 88.207537 -49.086333) (xy 88.183865 -49.13683)
			(xy 88.153092 -49.183343) (xy 88.115875 -49.22488) (xy 88.073007 -49.260555) (xy 88.025401 -49.289609)
			(xy 87.974072 -49.311421) (xy 87.920115 -49.325527) (xy 87.864678 -49.331627) (xy 87.808944 -49.32959)
			(xy 87.754101 -49.31946) (xy 87.701317 -49.301453) (xy 87.651717 -49.275952) (xy 87.606359 -49.243501)
			(xy 87.56621 -49.204792) (xy 87.532124 -49.160649) (xy 87.504828 -49.112014) (xy 87.484905 -49.059923)
			(xy 87.472779 -49.005486) (xy 87.468708 -48.949864) (xy 73.117688 -48.949864) (xy 73.105812 -48.967637)
			(xy 73.008435 -49.098935) (xy 72.904733 -49.225296) (xy 72.794956 -49.346417) (xy 72.679368 -49.462005)
			(xy 72.558247 -49.571782) (xy 72.431886 -49.675484) (xy 72.300589 -49.772861) (xy 72.164671 -49.863678)
			(xy 72.024462 -49.947717) (xy 71.880297 -50.024774) (xy 71.732525 -50.094665) (xy 71.581502 -50.157221)
			(xy 71.549199 -50.168779) (xy 78.051664 -50.168779) (xy 78.059416 -50.11483) (xy 78.074767 -50.062533)
			(xy 78.097404 -50.012953) (xy 78.126867 -49.967099) (xy 78.162555 -49.925905) (xy 78.203742 -49.890209)
			(xy 78.249591 -49.860738) (xy 78.299167 -49.838091) (xy 78.351461 -49.822731) (xy 78.405408 -49.814969)
			(xy 78.43266 -49.81448) (xy 78.448675 -49.814644) (xy 78.480594 -49.817315) (xy 78.496414 -49.819814)
			(xy 78.510403 -49.821744) (xy 78.538465 -49.81866) (xy 78.564606 -49.808002) (xy 78.586823 -49.790586)
			(xy 78.603415 -49.767746) (xy 78.613111 -49.741233) (xy 78.615166 -49.713078) (xy 78.612746 -49.699164)
			(xy 78.609074 -49.680071) (xy 78.605126 -49.641389) (xy 78.604872 -49.621948) (xy 78.605304 -49.594691)
			(xy 78.613055 -49.54073) (xy 78.628408 -49.488422) (xy 78.651049 -49.438831) (xy 78.680517 -49.392967)
			(xy 78.716212 -49.351764) (xy 78.757408 -49.316061) (xy 78.803266 -49.286584) (xy 78.852853 -49.263934)
			(xy 78.905158 -49.248571) (xy 78.959117 -49.240809) (xy 79.013632 -49.240805) (xy 79.067592 -49.24856)
			(xy 79.1199 -49.263916) (xy 79.169489 -49.28656) (xy 79.215351 -49.31603) (xy 79.256552 -49.351728)
			(xy 79.292253 -49.392927) (xy 79.321727 -49.438786) (xy 79.344374 -49.488374) (xy 79.359734 -49.54068)
			(xy 79.367493 -49.59464) (xy 79.367493 -49.649155) (xy 79.359735 -49.703114) (xy 79.344376 -49.755421)
			(xy 79.32173 -49.805009) (xy 79.292256 -49.850869) (xy 79.256556 -49.892068) (xy 79.215355 -49.927766)
			(xy 79.169494 -49.957238) (xy 79.119905 -49.979882) (xy 79.067598 -49.995239) (xy 79.013637 -50.002994)
			(xy 78.98638 -50.003456) (xy 78.970365 -50.003287) (xy 78.938446 -50.000619) (xy 78.922626 -49.998122)
			(xy 78.908635 -49.996189) (xy 78.880569 -49.999264) (xy 78.854422 -50.009919) (xy 78.8322 -50.027336)
			(xy 78.815607 -50.050179) (xy 78.805915 -50.076698) (xy 78.803868 -50.104857) (xy 78.806294 -50.118772)
			(xy 78.809979 -50.137863) (xy 78.813924 -50.176546) (xy 78.814168 -50.195988) (xy 78.813735 -50.22324)
			(xy 78.80598 -50.277189) (xy 78.790627 -50.329485) (xy 78.767987 -50.379064) (xy 78.738522 -50.424916)
			(xy 78.702832 -50.466108) (xy 78.661643 -50.501802) (xy 78.615793 -50.531271) (xy 78.566216 -50.553915)
			(xy 78.513921 -50.569273) (xy 78.459973 -50.577033) (xy 78.40547 -50.577036) (xy 78.351521 -50.569282)
			(xy 78.299224 -50.55393) (xy 78.249645 -50.531292) (xy 78.203792 -50.501828) (xy 78.162598 -50.466139)
			(xy 78.126903 -50.42495) (xy 78.097433 -50.379101) (xy 78.074788 -50.329525) (xy 78.059429 -50.27723)
			(xy 78.051668 -50.223282) (xy 78.051664 -50.168779) (xy 71.549199 -50.168779) (xy 71.427591 -50.212291)
			(xy 71.271164 -50.259743) (xy 71.112596 -50.299462) (xy 70.952271 -50.331353) (xy 70.790574 -50.355339)
			(xy 70.627895 -50.371361) (xy 70.464625 -50.379382) (xy 70.382892 -50.379884) (xy 70.300688 -50.379384)
			(xy 70.13648 -50.371273) (xy 69.972873 -50.355068) (xy 69.810265 -50.330807) (xy 69.649053 -50.298549)
			(xy 69.489629 -50.258374) (xy 69.332383 -50.210379) (xy 69.177697 -50.15468) (xy 69.025949 -50.091415)
			(xy 68.877509 -50.020737) (xy 68.732738 -49.942818) (xy 68.591989 -49.857849) (xy 68.455606 -49.766036)
			(xy 68.323921 -49.667603) (xy 68.197255 -49.56279) (xy 68.075917 -49.451854) (xy 67.960202 -49.335063)
			(xy 67.850393 -49.212703) (xy 67.746757 -49.085073) (xy 67.649547 -48.952483) (xy 67.559 -48.815256)
			(xy 67.475337 -48.673727) (xy 67.398761 -48.528241) (xy 67.329459 -48.379153) (xy 67.298062 -48.30318)
			(xy 67.291963 -48.28966) (xy 67.273429 -48.266526) (xy 67.249036 -48.249686) (xy 67.220834 -48.240557)
			(xy 67.1912 -48.239907) (xy 67.162625 -48.24779) (xy 67.137517 -48.263545) (xy 67.117987 -48.285843)
			(xy 67.111372 -48.299116) (xy 67.078481 -48.369679) (xy 67.006404 -48.507691) (xy 66.927268 -48.641781)
			(xy 66.841285 -48.771586) (xy 66.748686 -48.896758) (xy 66.64972 -49.01696) (xy 66.544655 -49.131868)
			(xy 66.433772 -49.241173) (xy 66.31737 -49.34458) (xy 66.195763 -49.441813) (xy 66.069277 -49.532608)
			(xy 65.938253 -49.616723) (xy 65.803043 -49.693929) (xy 65.664011 -49.764021) (xy 65.521532 -49.826808)
			(xy 65.375989 -49.882122) (xy 65.227772 -49.929815) (xy 65.077283 -49.969757) (xy 64.924924 -50.001842)
			(xy 64.771107 -50.025982) (xy 64.616245 -50.042114) (xy 64.460754 -50.050194) (xy 64.382904 -50.0507)
			(xy 62.78245 -50.0507) (xy 62.705176 -50.050188) (xy 62.550834 -50.04222) (xy 62.397107 -50.026316)
			(xy 62.244402 -50.002521) (xy 62.093124 -49.970896) (xy 61.943675 -49.931526) (xy 61.796451 -49.884514)
			(xy 61.651842 -49.829987) (xy 61.510232 -49.768087) (xy 61.371996 -49.69898) (xy 61.2375 -49.622848)
			(xy 61.107102 -49.539894) (xy 60.981148 -49.450337) (xy 60.85997 -49.354416) (xy 60.743891 -49.252383)
			(xy 60.633218 -49.14451) (xy 60.528245 -49.031083) (xy 60.429249 -48.912403) (xy 60.336495 -48.788784)
			(xy 60.250227 -48.660555) (xy 60.170674 -48.528054) (xy 60.098048 -48.391634) (xy 60.032541 -48.251656)
			(xy 59.974326 -48.108492) (xy 59.923558 -47.96252) (xy 59.880371 -47.814129) (xy 59.844881 -47.663712)
			(xy 59.81718 -47.511667) (xy 59.797344 -47.358397) (xy 59.785423 -47.20431) (xy 59.781451 -47.049813)
			(xy 37.23298 -47.049813) (xy 37.241829 -47.0555) (xy 37.283023 -47.091197) (xy 37.318717 -47.132393)
			(xy 37.348184 -47.178251) (xy 37.370824 -47.227836) (xy 37.386176 -47.280138) (xy 37.393928 -47.334093)
			(xy 37.394388 -47.361348) (xy 37.393963 -47.387793) (xy 37.386696 -47.440179) (xy 37.37991 -47.465742)
			(xy 37.376282 -47.480099) (xy 37.376604 -47.509699) (xy 37.385409 -47.53796) (xy 37.401954 -47.562505)
			(xy 37.424848 -47.581269) (xy 37.452165 -47.592672) (xy 37.481605 -47.595755) (xy 37.496242 -47.593504)
			(xy 37.513731 -47.590411) (xy 37.549095 -47.587103) (xy 37.566854 -47.5869) (xy 37.594111 -47.587306)
			(xy 37.64807 -47.595057) (xy 37.700377 -47.61041) (xy 37.749967 -47.63305) (xy 37.79583 -47.662517)
			(xy 37.837032 -47.698212) (xy 37.872735 -47.739406) (xy 37.902212 -47.785263) (xy 37.924863 -47.834848)
			(xy 37.940226 -47.887152) (xy 37.947989 -47.94111) (xy 37.947993 -47.995623) (xy 37.94024 -48.049583)
			(xy 37.924886 -48.101889) (xy 37.902244 -48.151478) (xy 37.872775 -48.19734) (xy 37.83708 -48.238541)
			(xy 37.795883 -48.274243) (xy 37.750026 -48.303718) (xy 37.70044 -48.326367) (xy 37.648136 -48.341728)
			(xy 37.594177 -48.34949) (xy 37.539664 -48.349492) (xy 37.485705 -48.341737) (xy 37.433399 -48.326381)
			(xy 37.383811 -48.303738) (xy 37.33795 -48.274268) (xy 37.29675 -48.238571) (xy 37.26105 -48.197373)
			(xy 37.231576 -48.151515) (xy 37.208929 -48.101928) (xy 37.193569 -48.049623) (xy 37.18581 -47.995665)
			(xy 37.185346 -47.968408) (xy 37.185785 -47.941964) (xy 37.193043 -47.889577) (xy 37.199824 -47.864014)
			(xy 37.203351 -47.849635) (xy 37.203041 -47.820051) (xy 37.194252 -47.7918) (xy 37.177723 -47.767261)
			(xy 37.154846 -47.7485) (xy 37.127547 -47.737095) (xy 37.098122 -47.734006) (xy 37.083492 -47.736252)
			(xy 37.066002 -47.73934) (xy 37.030639 -47.742651) (xy 37.01288 -47.742856) (xy 36.98563 -47.742341)
			(xy 36.931686 -47.734583) (xy 36.879395 -47.719228) (xy 36.829821 -47.696588) (xy 36.783973 -47.667124)
			(xy 36.742784 -47.631436) (xy 36.707093 -47.59025) (xy 36.677626 -47.544404) (xy 36.654982 -47.494831)
			(xy 36.639623 -47.442541) (xy 36.631861 -47.388598) (xy 36.631372 -47.361348) (xy 36.631932 -47.330639)
			(xy 36.641767 -47.270014) (xy 36.65093 -47.240698) (xy 36.6548 -47.227733) (xy 36.656249 -47.200722)
			(xy 36.65056 -47.174277) (xy 36.63813 -47.150252) (xy 36.619831 -47.130331) (xy 36.596945 -47.115911)
			(xy 36.571078 -47.108001) (xy 36.544041 -47.107157) (xy 36.530788 -47.109888) (xy 36.508769 -47.114853)
			(xy 36.463949 -47.120205) (xy 36.44138 -47.120556) (xy 36.41413 -47.120041) (xy 36.360186 -47.112283)
			(xy 36.307895 -47.096928) (xy 36.258321 -47.074288) (xy 36.212473 -47.044824) (xy 36.171284 -47.009136)
			(xy 36.135593 -46.96795) (xy 36.106126 -46.922104) (xy 36.083482 -46.872531) (xy 36.068123 -46.820241)
			(xy 36.060361 -46.766298) (xy 36.059872 -46.739048) (xy 36.06058 -46.705505) (xy 36.072332 -46.639457)
			(xy 36.08324 -46.60773) (xy 36.087865 -46.593833) (xy 36.089844 -46.564626) (xy 36.08345 -46.536058)
			(xy 36.069208 -46.510482) (xy 36.04829 -46.490002) (xy 36.022419 -46.476303) (xy 35.993722 -46.470514)
			(xy 35.9791 -46.471332) (xy 35.94608 -46.472856) (xy 35.91883 -46.472341) (xy 35.864886 -46.464583)
			(xy 35.812595 -46.449228) (xy 35.763021 -46.426588) (xy 35.717173 -46.397124) (xy 35.675984 -46.361436)
			(xy 35.640293 -46.32025) (xy 35.610826 -46.274404) (xy 35.588182 -46.224831) (xy 35.572823 -46.172541)
			(xy 35.565061 -46.118598) (xy 35.564572 -46.091348) (xy 35.564814 -46.071194) (xy 35.569012 -46.031104)
			(xy 35.572954 -46.011338) (xy 35.575596 -45.996712) (xy 35.573245 -45.967098) (xy 35.562471 -45.939414)
			(xy 35.544185 -45.916001) (xy 35.519935 -45.898842) (xy 35.491772 -45.889388) (xy 35.476942 -45.888402)
			(xy 35.450258 -45.887165) (xy 35.397619 -45.878071) (xy 35.346764 -45.861721) (xy 35.298688 -45.838435)
			(xy 35.254331 -45.808669) (xy 35.214561 -45.773005) (xy 35.180156 -45.73214) (xy 35.15179 -45.686876)
			(xy 35.130017 -45.638096) (xy 35.115263 -45.586755) (xy 35.107816 -45.533857) (xy 35.107372 -45.507148)
			(xy 35.001651 -45.507148) (xy 35.001453 -45.518016) (xy 34.993333 -45.573192) (xy 34.977265 -45.626599)
			(xy 34.953593 -45.677096) (xy 34.92282 -45.723609) (xy 34.885603 -45.765146) (xy 34.842735 -45.800821)
			(xy 34.795129 -45.829875) (xy 34.7438 -45.851687) (xy 34.689843 -45.865793) (xy 34.634406 -45.871893)
			(xy 34.578672 -45.869856) (xy 34.523829 -45.859726) (xy 34.471045 -45.841719) (xy 34.421445 -45.816218)
			(xy 34.376087 -45.783767) (xy 34.335938 -45.745058) (xy 34.301852 -45.700915) (xy 34.274556 -45.65228)
			(xy 34.254633 -45.600189) (xy 34.242507 -45.545752) (xy 34.238436 -45.49013) (xy 1.270729 -45.49013)
			(xy 1.272082 -45.498637) (xy 1.27254 -45.522642) (xy 1.27254 -45.882052) (xy 2.390335 -46.999906)
			(xy 13.567662 -46.999906) (xy 13.571733 -46.944284) (xy 13.583859 -46.889847) (xy 13.603782 -46.837756)
			(xy 13.631078 -46.789121) (xy 13.665164 -46.744978) (xy 13.705313 -46.706269) (xy 13.750671 -46.673818)
			(xy 13.800271 -46.648317) (xy 13.853055 -46.63031) (xy 13.907898 -46.62018) (xy 13.963632 -46.618143)
			(xy 14.019069 -46.624243) (xy 14.073026 -46.638349) (xy 14.124355 -46.660161) (xy 14.171961 -46.689215)
			(xy 14.214829 -46.72489) (xy 14.252046 -46.766427) (xy 14.282819 -46.81294) (xy 14.306491 -46.863437)
			(xy 14.322559 -46.916844) (xy 14.330679 -46.97202) (xy 14.331188 -46.999906) (xy 14.330679 -47.027792)
			(xy 14.322559 -47.082968) (xy 14.306491 -47.136375) (xy 14.282819 -47.186872) (xy 14.252046 -47.233385)
			(xy 14.214829 -47.274922) (xy 14.171961 -47.310597) (xy 14.130422 -47.335948) (xy 29.043882 -47.335948)
			(xy 29.047953 -47.280326) (xy 29.060079 -47.225889) (xy 29.080002 -47.173798) (xy 29.107298 -47.125163)
			(xy 29.141384 -47.08102) (xy 29.181533 -47.042311) (xy 29.226891 -47.00986) (xy 29.276491 -46.984359)
			(xy 29.329275 -46.966352) (xy 29.384118 -46.956222) (xy 29.439852 -46.954185) (xy 29.495289 -46.960285)
			(xy 29.549246 -46.974391) (xy 29.600575 -46.996203) (xy 29.648181 -47.025257) (xy 29.691049 -47.060932)
			(xy 29.728266 -47.102469) (xy 29.759039 -47.148982) (xy 29.782711 -47.199479) (xy 29.798779 -47.252886)
			(xy 29.806899 -47.308062) (xy 29.807408 -47.335948) (xy 29.806899 -47.363834) (xy 29.798779 -47.41901)
			(xy 29.782711 -47.472417) (xy 29.759039 -47.522914) (xy 29.728266 -47.569427) (xy 29.691049 -47.610964)
			(xy 29.648181 -47.646639) (xy 29.600575 -47.675693) (xy 29.549246 -47.697505) (xy 29.495289 -47.711611)
			(xy 29.439852 -47.717711) (xy 29.384118 -47.715674) (xy 29.329275 -47.705544) (xy 29.276491 -47.687537)
			(xy 29.226891 -47.662036) (xy 29.181533 -47.629585) (xy 29.141384 -47.590876) (xy 29.107298 -47.546733)
			(xy 29.080002 -47.498098) (xy 29.060079 -47.446007) (xy 29.047953 -47.39157) (xy 29.043882 -47.335948)
			(xy 14.130422 -47.335948) (xy 14.124355 -47.339651) (xy 14.073026 -47.361463) (xy 14.019069 -47.375569)
			(xy 13.963632 -47.381669) (xy 13.907898 -47.379632) (xy 13.853055 -47.369502) (xy 13.800271 -47.351495)
			(xy 13.750671 -47.325994) (xy 13.705313 -47.293543) (xy 13.665164 -47.254834) (xy 13.631078 -47.210691)
			(xy 13.603782 -47.162056) (xy 13.583859 -47.109965) (xy 13.571733 -47.055528) (xy 13.567662 -46.999906)
			(xy 2.390335 -46.999906) (xy 4.377271 -48.986948) (xy 8.170162 -48.986948) (xy 8.174233 -48.931326)
			(xy 8.186359 -48.876889) (xy 8.206282 -48.824798) (xy 8.233578 -48.776163) (xy 8.267664 -48.73202)
			(xy 8.307813 -48.693311) (xy 8.353171 -48.66086) (xy 8.402771 -48.635359) (xy 8.455555 -48.617352)
			(xy 8.510398 -48.607222) (xy 8.566132 -48.605185) (xy 8.621569 -48.611285) (xy 8.675526 -48.625391)
			(xy 8.726855 -48.647203) (xy 8.774461 -48.676257) (xy 8.817329 -48.711932) (xy 8.854546 -48.753469)
			(xy 8.885319 -48.799982) (xy 8.908991 -48.850479) (xy 8.925059 -48.903886) (xy 8.933179 -48.959062)
			(xy 8.933688 -48.986948) (xy 8.933179 -49.014834) (xy 8.925059 -49.07001) (xy 8.908991 -49.123417)
			(xy 8.885319 -49.173914) (xy 8.854546 -49.220427) (xy 8.817329 -49.261964) (xy 8.774461 -49.297639)
			(xy 8.726855 -49.326693) (xy 8.675526 -49.348505) (xy 8.621569 -49.362611) (xy 8.566132 -49.368711)
			(xy 8.510398 -49.366674) (xy 8.455555 -49.356544) (xy 8.402771 -49.338537) (xy 8.353171 -49.313036)
			(xy 8.307813 -49.280585) (xy 8.267664 -49.241876) (xy 8.233578 -49.197733) (xy 8.206282 -49.149098)
			(xy 8.186359 -49.097007) (xy 8.174233 -49.04257) (xy 8.170162 -48.986948) (xy 4.377271 -48.986948)
			(xy 4.957884 -49.567592) (xy 6.235698 -49.567592) (xy 6.239769 -49.51197) (xy 6.251895 -49.457533)
			(xy 6.271818 -49.405442) (xy 6.299114 -49.356807) (xy 6.3332 -49.312664) (xy 6.373349 -49.273955)
			(xy 6.418707 -49.241504) (xy 6.468307 -49.216003) (xy 6.521091 -49.197996) (xy 6.575934 -49.187866)
			(xy 6.631668 -49.185829) (xy 6.687105 -49.191929) (xy 6.741062 -49.206035) (xy 6.792391 -49.227847)
			(xy 6.839997 -49.256901) (xy 6.882865 -49.292576) (xy 6.920082 -49.334113) (xy 6.950855 -49.380626)
			(xy 6.974527 -49.431123) (xy 6.990595 -49.48453) (xy 6.998715 -49.539706) (xy 6.999224 -49.567592)
			(xy 6.998715 -49.595478) (xy 6.990595 -49.650654) (xy 6.974527 -49.704061) (xy 6.950855 -49.754558)
			(xy 6.920082 -49.801071) (xy 6.882865 -49.842608) (xy 6.839997 -49.878283) (xy 6.792391 -49.907337)
			(xy 6.741062 -49.929149) (xy 6.687105 -49.943255) (xy 6.631668 -49.949355) (xy 6.575934 -49.947318)
			(xy 6.521091 -49.937188) (xy 6.468307 -49.919181) (xy 6.418707 -49.89368) (xy 6.373349 -49.861229)
			(xy 6.3332 -49.82252) (xy 6.299114 -49.778377) (xy 6.271818 -49.729742) (xy 6.251895 -49.677651)
			(xy 6.239769 -49.623214) (xy 6.235698 -49.567592) (xy 4.957884 -49.567592) (xy 6.055868 -50.665634)
			(xy 6.055868 -51.018948) (xy 8.126982 -51.018948) (xy 8.131053 -50.963326) (xy 8.143179 -50.908889)
			(xy 8.163102 -50.856798) (xy 8.190398 -50.808163) (xy 8.224484 -50.76402) (xy 8.264633 -50.725311)
			(xy 8.309991 -50.69286) (xy 8.359591 -50.667359) (xy 8.412375 -50.649352) (xy 8.467218 -50.639222)
			(xy 8.522952 -50.637185) (xy 8.578389 -50.643285) (xy 8.632346 -50.657391) (xy 8.683675 -50.679203)
			(xy 8.731281 -50.708257) (xy 8.774149 -50.743932) (xy 8.811366 -50.785469) (xy 8.842139 -50.831982)
			(xy 8.865811 -50.882479) (xy 8.881879 -50.935886) (xy 8.889999 -50.991062) (xy 8.89016 -50.999898)
			(xy 21.586442 -50.999898) (xy 21.590513 -50.944276) (xy 21.602639 -50.889839) (xy 21.622562 -50.837748)
			(xy 21.649858 -50.789113) (xy 21.683944 -50.74497) (xy 21.724093 -50.706261) (xy 21.769451 -50.67381)
			(xy 21.819051 -50.648309) (xy 21.871835 -50.630302) (xy 21.926678 -50.620172) (xy 21.982412 -50.618135)
			(xy 22.037849 -50.624235) (xy 22.091806 -50.638341) (xy 22.143135 -50.660153) (xy 22.190741 -50.689207)
			(xy 22.233609 -50.724882) (xy 22.270826 -50.766419) (xy 22.301599 -50.812932) (xy 22.325271 -50.863429)
			(xy 22.341339 -50.916836) (xy 22.341414 -50.917348) (xy 80.966562 -50.917348) (xy 80.970633 -50.861726)
			(xy 80.982759 -50.807289) (xy 81.002682 -50.755198) (xy 81.029978 -50.706563) (xy 81.064064 -50.66242)
			(xy 81.104213 -50.623711) (xy 81.149571 -50.59126) (xy 81.199171 -50.565759) (xy 81.251955 -50.547752)
			(xy 81.306798 -50.537622) (xy 81.362532 -50.535585) (xy 81.417969 -50.541685) (xy 81.471926 -50.555791)
			(xy 81.523255 -50.577603) (xy 81.570861 -50.606657) (xy 81.613729 -50.642332) (xy 81.650946 -50.683869)
			(xy 81.681719 -50.730382) (xy 81.705391 -50.780879) (xy 81.721459 -50.834286) (xy 81.727065 -50.872381)
			(xy 136.895712 -50.872381) (xy 136.903465 -50.818424) (xy 136.918818 -50.766119) (xy 136.941458 -50.716531)
			(xy 136.970925 -50.67067) (xy 137.006618 -50.629469) (xy 137.047812 -50.593768) (xy 137.093668 -50.564292)
			(xy 137.143251 -50.541643) (xy 137.195553 -50.52628) (xy 137.24951 -50.518517) (xy 137.304021 -50.518512)
			(xy 137.357979 -50.526265) (xy 137.410284 -50.541618) (xy 137.459871 -50.564259) (xy 137.505732 -50.593726)
			(xy 137.546933 -50.62942) (xy 137.582634 -50.670614) (xy 137.612109 -50.71647) (xy 137.634758 -50.766054)
			(xy 137.65012 -50.818356) (xy 137.657883 -50.872312) (xy 137.658348 -50.899568) (xy 137.658062 -50.920505)
			(xy 137.653481 -50.962128) (xy 137.649204 -50.982626) (xy 137.646412 -50.99727) (xy 137.648545 -51.026992)
			(xy 137.659172 -51.054832) (xy 137.677387 -51.078416) (xy 137.701636 -51.095735) (xy 137.729854 -51.105312)
			(xy 137.759635 -51.106332) (xy 137.774172 -51.103022) (xy 137.797882 -51.09723) (xy 137.846288 -51.090984)
			(xy 137.870692 -51.090576) (xy 137.897946 -51.091047) (xy 137.951899 -51.098803) (xy 138.004199 -51.114159)
			(xy 138.053781 -51.136801) (xy 138.099636 -51.16627) (xy 138.14083 -51.201964) (xy 138.176526 -51.243158)
			(xy 138.205995 -51.289012) (xy 138.228639 -51.338594) (xy 138.243995 -51.390893) (xy 138.251753 -51.444846)
			(xy 138.251753 -51.476148) (xy 143.026382 -51.476148) (xy 143.030453 -51.420526) (xy 143.042579 -51.366089)
			(xy 143.062502 -51.313998) (xy 143.089798 -51.265363) (xy 143.123884 -51.22122) (xy 143.164033 -51.182511)
			(xy 143.209391 -51.15006) (xy 143.258991 -51.124559) (xy 143.311775 -51.106552) (xy 143.366618 -51.096422)
			(xy 143.422352 -51.094385) (xy 143.477789 -51.100485) (xy 143.531746 -51.114591) (xy 143.583075 -51.136403)
			(xy 143.630681 -51.165457) (xy 143.673549 -51.201132) (xy 143.710766 -51.242669) (xy 143.741539 -51.289182)
			(xy 143.765211 -51.339679) (xy 143.781279 -51.393086) (xy 143.782887 -51.404012) (xy 146.806156 -51.404012)
			(xy 146.810227 -51.34839) (xy 146.822353 -51.293953) (xy 146.842276 -51.241862) (xy 146.869572 -51.193227)
			(xy 146.903658 -51.149084) (xy 146.943807 -51.110375) (xy 146.989165 -51.077924) (xy 147.038765 -51.052423)
			(xy 147.091549 -51.034416) (xy 147.146392 -51.024286) (xy 147.202126 -51.022249) (xy 147.257563 -51.028349)
			(xy 147.31152 -51.042455) (xy 147.362849 -51.064267) (xy 147.410455 -51.093321) (xy 147.453323 -51.128996)
			(xy 147.49054 -51.170533) (xy 147.521313 -51.217046) (xy 147.544985 -51.267543) (xy 147.561053 -51.32095)
			(xy 147.569173 -51.376126) (xy 147.569682 -51.404012) (xy 147.569173 -51.431898) (xy 147.561053 -51.487074)
			(xy 147.544985 -51.540481) (xy 147.521313 -51.590978) (xy 147.49054 -51.637491) (xy 147.453323 -51.679028)
			(xy 147.410455 -51.714703) (xy 147.364338 -51.742848) (xy 151.703022 -51.742848) (xy 151.707093 -51.687226)
			(xy 151.719219 -51.632789) (xy 151.739142 -51.580698) (xy 151.766438 -51.532063) (xy 151.800524 -51.48792)
			(xy 151.840673 -51.449211) (xy 151.886031 -51.41676) (xy 151.935631 -51.391259) (xy 151.988415 -51.373252)
			(xy 152.043258 -51.363122) (xy 152.098992 -51.361085) (xy 152.154429 -51.367185) (xy 152.208386 -51.381291)
			(xy 152.259715 -51.403103) (xy 152.307321 -51.432157) (xy 152.350189 -51.467832) (xy 152.387406 -51.509369)
			(xy 152.418179 -51.555882) (xy 152.441851 -51.606379) (xy 152.457919 -51.659786) (xy 152.466039 -51.714962)
			(xy 152.466548 -51.742848) (xy 152.466039 -51.770734) (xy 152.457919 -51.82591) (xy 152.441851 -51.879317)
			(xy 152.418179 -51.929814) (xy 152.387406 -51.976327) (xy 152.350189 -52.017864) (xy 152.307321 -52.053539)
			(xy 152.282846 -52.068476) (xy 154.419806 -52.068476) (xy 154.423877 -52.012854) (xy 154.436003 -51.958417)
			(xy 154.455926 -51.906326) (xy 154.483222 -51.857691) (xy 154.517308 -51.813548) (xy 154.557457 -51.774839)
			(xy 154.602815 -51.742388) (xy 154.652415 -51.716887) (xy 154.705199 -51.69888) (xy 154.760042 -51.68875)
			(xy 154.815776 -51.686713) (xy 154.871213 -51.692813) (xy 154.92517 -51.706919) (xy 154.976499 -51.728731)
			(xy 155.024105 -51.757785) (xy 155.066973 -51.79346) (xy 155.10419 -51.834997) (xy 155.134963 -51.88151)
			(xy 155.158635 -51.932007) (xy 155.174703 -51.985414) (xy 155.182823 -52.04059) (xy 155.183332 -52.068476)
			(xy 155.182823 -52.096362) (xy 155.174703 -52.151538) (xy 155.158635 -52.204945) (xy 155.134963 -52.255442)
			(xy 155.10419 -52.301955) (xy 155.066973 -52.343492) (xy 155.024105 -52.379167) (xy 154.976499 -52.408221)
			(xy 154.92517 -52.430033) (xy 154.871213 -52.444139) (xy 154.815776 -52.450239) (xy 154.760042 -52.448202)
			(xy 154.705199 -52.438072) (xy 154.652415 -52.420065) (xy 154.602815 -52.394564) (xy 154.557457 -52.362113)
			(xy 154.517308 -52.323404) (xy 154.483222 -52.279261) (xy 154.455926 -52.230626) (xy 154.436003 -52.178535)
			(xy 154.423877 -52.124098) (xy 154.419806 -52.068476) (xy 152.282846 -52.068476) (xy 152.259715 -52.082593)
			(xy 152.208386 -52.104405) (xy 152.154429 -52.118511) (xy 152.098992 -52.124611) (xy 152.043258 -52.122574)
			(xy 151.988415 -52.112444) (xy 151.935631 -52.094437) (xy 151.886031 -52.068936) (xy 151.840673 -52.036485)
			(xy 151.800524 -51.997776) (xy 151.766438 -51.953633) (xy 151.739142 -51.904998) (xy 151.719219 -51.852907)
			(xy 151.707093 -51.79847) (xy 151.703022 -51.742848) (xy 147.364338 -51.742848) (xy 147.362849 -51.743757)
			(xy 147.31152 -51.765569) (xy 147.257563 -51.779675) (xy 147.202126 -51.785775) (xy 147.146392 -51.783738)
			(xy 147.091549 -51.773608) (xy 147.038765 -51.755601) (xy 146.989165 -51.7301) (xy 146.943807 -51.697649)
			(xy 146.903658 -51.65894) (xy 146.869572 -51.614797) (xy 146.842276 -51.566162) (xy 146.822353 -51.514071)
			(xy 146.810227 -51.459634) (xy 146.806156 -51.404012) (xy 143.782887 -51.404012) (xy 143.789399 -51.448262)
			(xy 143.789908 -51.476148) (xy 143.789399 -51.504034) (xy 143.781279 -51.55921) (xy 143.765211 -51.612617)
			(xy 143.741539 -51.663114) (xy 143.710766 -51.709627) (xy 143.673549 -51.751164) (xy 143.630681 -51.786839)
			(xy 143.583075 -51.815893) (xy 143.531746 -51.837705) (xy 143.477789 -51.851811) (xy 143.422352 -51.857911)
			(xy 143.366618 -51.855874) (xy 143.311775 -51.845744) (xy 143.258991 -51.827737) (xy 143.209391 -51.802236)
			(xy 143.164033 -51.769785) (xy 143.123884 -51.731076) (xy 143.089798 -51.686933) (xy 143.062502 -51.638298)
			(xy 143.042579 -51.586207) (xy 143.030453 -51.53177) (xy 143.026382 -51.476148) (xy 138.251753 -51.476148)
			(xy 138.251753 -51.499354) (xy 138.243995 -51.553307) (xy 138.228639 -51.605606) (xy 138.205995 -51.655188)
			(xy 138.176526 -51.701042) (xy 138.14083 -51.742236) (xy 138.099636 -51.77793) (xy 138.053781 -51.807399)
			(xy 138.004199 -51.830041) (xy 137.951899 -51.845397) (xy 137.897946 -51.853153) (xy 137.843438 -51.853152)
			(xy 137.789486 -51.845394) (xy 137.737186 -51.830036) (xy 137.687605 -51.807391) (xy 137.641751 -51.777921)
			(xy 137.600558 -51.742225) (xy 137.564865 -51.701029) (xy 137.535397 -51.655174) (xy 137.512756 -51.605591)
			(xy 137.497401 -51.553291) (xy 137.489646 -51.499338) (xy 137.489184 -51.472084) (xy 137.489461 -51.451146)
			(xy 137.494048 -51.409523) (xy 137.498328 -51.389026) (xy 137.501027 -51.374368) (xy 137.498906 -51.344658)
			(xy 137.488294 -51.316827) (xy 137.470095 -51.293248) (xy 137.445861 -51.27593) (xy 137.417658 -51.26635)
			(xy 137.387891 -51.265324) (xy 137.37336 -51.26863) (xy 137.349653 -51.274434) (xy 137.301244 -51.280672)
			(xy 137.27684 -51.281076) (xy 137.249584 -51.280688) (xy 137.195626 -51.272936) (xy 137.143321 -51.257583)
			(xy 137.093733 -51.234944) (xy 137.047872 -51.205477) (xy 137.006671 -51.169784) (xy 136.970969 -51.12859)
			(xy 136.941494 -51.082735) (xy 136.918844 -51.033151) (xy 136.903481 -50.980849) (xy 136.895718 -50.926893)
			(xy 136.895712 -50.872381) (xy 81.727065 -50.872381) (xy 81.729579 -50.889462) (xy 81.730088 -50.917348)
			(xy 81.729579 -50.945234) (xy 81.721459 -51.00041) (xy 81.705391 -51.053817) (xy 81.681719 -51.104314)
			(xy 81.650946 -51.150827) (xy 81.613729 -51.192364) (xy 81.570861 -51.228039) (xy 81.523255 -51.257093)
			(xy 81.471926 -51.278905) (xy 81.417969 -51.293011) (xy 81.362532 -51.299111) (xy 81.306798 -51.297074)
			(xy 81.251955 -51.286944) (xy 81.199171 -51.268937) (xy 81.149571 -51.243436) (xy 81.104213 -51.210985)
			(xy 81.064064 -51.172276) (xy 81.029978 -51.128133) (xy 81.002682 -51.079498) (xy 80.982759 -51.027407)
			(xy 80.970633 -50.97297) (xy 80.966562 -50.917348) (xy 22.341414 -50.917348) (xy 22.349459 -50.972012)
			(xy 22.349968 -50.999898) (xy 22.349459 -51.027784) (xy 22.341339 -51.08296) (xy 22.325271 -51.136367)
			(xy 22.301599 -51.186864) (xy 22.270826 -51.233377) (xy 22.233609 -51.274914) (xy 22.190741 -51.310589)
			(xy 22.143135 -51.339643) (xy 22.091806 -51.361455) (xy 22.037849 -51.375561) (xy 21.982412 -51.381661)
			(xy 21.926678 -51.379624) (xy 21.871835 -51.369494) (xy 21.819051 -51.351487) (xy 21.769451 -51.325986)
			(xy 21.724093 -51.293535) (xy 21.683944 -51.254826) (xy 21.649858 -51.210683) (xy 21.622562 -51.162048)
			(xy 21.602639 -51.109957) (xy 21.590513 -51.05552) (xy 21.586442 -50.999898) (xy 8.89016 -50.999898)
			(xy 8.890508 -51.018948) (xy 8.889999 -51.046834) (xy 8.881879 -51.10201) (xy 8.865811 -51.155417)
			(xy 8.842139 -51.205914) (xy 8.811366 -51.252427) (xy 8.774149 -51.293964) (xy 8.731281 -51.329639)
			(xy 8.683675 -51.358693) (xy 8.632346 -51.380505) (xy 8.578389 -51.394611) (xy 8.522952 -51.400711)
			(xy 8.467218 -51.398674) (xy 8.412375 -51.388544) (xy 8.359591 -51.370537) (xy 8.309991 -51.345036)
			(xy 8.264633 -51.312585) (xy 8.224484 -51.273876) (xy 8.190398 -51.229733) (xy 8.163102 -51.181098)
			(xy 8.143179 -51.129007) (xy 8.131053 -51.07457) (xy 8.126982 -51.018948) (xy 6.055868 -51.018948)
			(xy 6.055868 -51.631596) (xy 6.15899 -51.631596) (xy 6.163061 -51.575974) (xy 6.175187 -51.521537)
			(xy 6.19511 -51.469446) (xy 6.222406 -51.420811) (xy 6.256492 -51.376668) (xy 6.296641 -51.337959)
			(xy 6.341999 -51.305508) (xy 6.391599 -51.280007) (xy 6.444383 -51.262) (xy 6.499226 -51.25187) (xy 6.55496 -51.249833)
			(xy 6.610397 -51.255933) (xy 6.664354 -51.270039) (xy 6.715683 -51.291851) (xy 6.763289 -51.320905)
			(xy 6.806157 -51.35658) (xy 6.843374 -51.398117) (xy 6.874147 -51.44463) (xy 6.897819 -51.495127)
			(xy 6.913887 -51.548534) (xy 6.922007 -51.60371) (xy 6.922516 -51.631596) (xy 6.922007 -51.659482)
			(xy 6.913887 -51.714658) (xy 6.897819 -51.768065) (xy 6.874147 -51.818562) (xy 6.843374 -51.865075)
			(xy 6.806157 -51.906612) (xy 6.763289 -51.942287) (xy 6.715683 -51.971341) (xy 6.664354 -51.993153)
			(xy 6.633382 -52.00125) (xy 36.027366 -52.00125) (xy 36.027366 -51.94675) (xy 36.035121 -51.892804)
			(xy 36.050475 -51.840511) (xy 36.073114 -51.790934) (xy 36.102577 -51.745085) (xy 36.138266 -51.703894)
			(xy 36.179452 -51.668201) (xy 36.225299 -51.638733) (xy 36.274873 -51.616089) (xy 36.327165 -51.60073)
			(xy 36.38111 -51.592969) (xy 36.40836 -51.59248) (xy 36.4327 -51.592896) (xy 36.48098 -51.59914)
			(xy 36.504626 -51.604926) (xy 36.519414 -51.608207) (xy 36.549662 -51.606905) (xy 36.578198 -51.596789)
			(xy 36.602512 -51.578748) (xy 36.620464 -51.554369) (xy 36.630476 -51.525796) (xy 36.631626 -51.510692)
			(xy 36.633187 -51.48422) (xy 36.64278 -51.432066) (xy 36.6595 -51.381742) (xy 36.683026 -51.334217)
			(xy 36.712905 -51.290407) (xy 36.748561 -51.251155) (xy 36.789308 -51.217218) (xy 36.834361 -51.189248)
			(xy 36.882852 -51.167784) (xy 36.933848 -51.15324) (xy 36.986366 -51.145896) (xy 37.01288 -51.14544)
			(xy 37.040137 -51.145806) (xy 37.094097 -51.153561) (xy 37.146404 -51.168917) (xy 37.195993 -51.191562)
			(xy 37.241854 -51.221033) (xy 37.283055 -51.256731) (xy 37.318755 -51.29793) (xy 37.348229 -51.343789)
			(xy 37.370876 -51.393377) (xy 37.383936 -51.437854) (xy 131.504871 -51.437854) (xy 131.504871 -51.383346)
			(xy 131.512629 -51.329394) (xy 131.527987 -51.277095) (xy 131.550632 -51.227514) (xy 131.580102 -51.18166)
			(xy 131.615799 -51.140468) (xy 131.656996 -51.104776) (xy 131.702852 -51.07531) (xy 131.752436 -51.052671)
			(xy 131.804737 -51.03732) (xy 131.85869 -51.029568) (xy 131.885944 -51.029108) (xy 131.91192 -51.029535)
			(xy 131.963391 -51.036583) (xy 132.013428 -51.050555) (xy 132.061104 -51.071194) (xy 132.105535 -51.098117)
			(xy 132.145898 -51.130824) (xy 132.181445 -51.168709) (xy 132.19684 -51.189636) (xy 132.20527 -51.200652)
			(xy 132.226843 -51.218072) (xy 132.252299 -51.229063) (xy 132.279771 -51.232819) (xy 132.307243 -51.229063)
			(xy 132.332699 -51.218072) (xy 132.354272 -51.200652) (xy 132.362702 -51.189636) (xy 132.37808 -51.168698)
			(xy 132.413637 -51.130823) (xy 132.454007 -51.098124) (xy 132.498441 -51.071208) (xy 132.546117 -51.050572)
			(xy 132.596153 -51.036599) (xy 132.647623 -51.029547) (xy 132.673598 -51.029108) (xy 132.700852 -51.029539)
			(xy 132.754806 -51.037296) (xy 132.807106 -51.052652) (xy 132.856688 -51.075296) (xy 132.902544 -51.104765)
			(xy 132.943738 -51.14046) (xy 132.979434 -51.181655) (xy 133.008903 -51.22751) (xy 133.031547 -51.277092)
			(xy 133.046904 -51.329392) (xy 133.054661 -51.383346) (xy 133.054661 -51.421792) (xy 134.11276 -51.421792)
			(xy 134.116831 -51.36617) (xy 134.128957 -51.311733) (xy 134.14888 -51.259642) (xy 134.176176 -51.211007)
			(xy 134.210262 -51.166864) (xy 134.250411 -51.128155) (xy 134.295769 -51.095704) (xy 134.345369 -51.070203)
			(xy 134.398153 -51.052196) (xy 134.452996 -51.042066) (xy 134.50873 -51.040029) (xy 134.564167 -51.046129)
			(xy 134.618124 -51.060235) (xy 134.669453 -51.082047) (xy 134.717059 -51.111101) (xy 134.759927 -51.146776)
			(xy 134.797144 -51.188313) (xy 134.827917 -51.234826) (xy 134.851589 -51.285323) (xy 134.867657 -51.33873)
			(xy 134.875777 -51.393906) (xy 134.876286 -51.421792) (xy 134.875777 -51.449678) (xy 134.867657 -51.504854)
			(xy 134.851589 -51.558261) (xy 134.827917 -51.608758) (xy 134.797144 -51.655271) (xy 134.759927 -51.696808)
			(xy 134.717059 -51.732483) (xy 134.669453 -51.761537) (xy 134.618124 -51.783349) (xy 134.564167 -51.797455)
			(xy 134.50873 -51.803555) (xy 134.452996 -51.801518) (xy 134.398153 -51.791388) (xy 134.345369 -51.773381)
			(xy 134.295769 -51.74788) (xy 134.250411 -51.715429) (xy 134.210262 -51.67672) (xy 134.176176 -51.632577)
			(xy 134.14888 -51.583942) (xy 134.128957 -51.531851) (xy 134.116831 -51.477414) (xy 134.11276 -51.421792)
			(xy 133.054661 -51.421792) (xy 133.054661 -51.437854) (xy 133.046904 -51.491808) (xy 133.031547 -51.544108)
			(xy 133.008903 -51.59369) (xy 132.979434 -51.639545) (xy 132.943738 -51.68074) (xy 132.902544 -51.716435)
			(xy 132.856688 -51.745904) (xy 132.807106 -51.768548) (xy 132.754806 -51.783904) (xy 132.700852 -51.791661)
			(xy 132.673598 -51.792124) (xy 132.647622 -51.791694) (xy 132.59615 -51.784651) (xy 132.546112 -51.77068)
			(xy 132.498435 -51.750043) (xy 132.454004 -51.72312) (xy 132.413641 -51.690412) (xy 132.378095 -51.652524)
			(xy 132.362702 -51.631596) (xy 132.354299 -51.620536) (xy 132.332748 -51.603032) (xy 132.307277 -51.591984)
			(xy 132.279771 -51.588208) (xy 132.252265 -51.591984) (xy 132.226794 -51.603032) (xy 132.205243 -51.620536)
			(xy 132.19684 -51.631596) (xy 132.181445 -51.652521) (xy 132.14589 -51.690396) (xy 132.105523 -51.723094)
			(xy 132.061092 -51.750011) (xy 132.013419 -51.770649) (xy 131.963385 -51.784626) (xy 131.911918 -51.791682)
			(xy 131.885944 -51.792124) (xy 131.85869 -51.791632) (xy 131.804737 -51.78388) (xy 131.752436 -51.768529)
			(xy 131.702852 -51.74589) (xy 131.656996 -51.716424) (xy 131.615799 -51.680732) (xy 131.580102 -51.63954)
			(xy 131.550632 -51.593686) (xy 131.527987 -51.544105) (xy 131.512629 -51.491806) (xy 131.504871 -51.437854)
			(xy 37.383936 -51.437854) (xy 37.386235 -51.445683) (xy 37.393993 -51.499643) (xy 37.393993 -51.554157)
			(xy 37.386235 -51.608117) (xy 37.370876 -51.660423) (xy 37.348229 -51.710011) (xy 37.318755 -51.75587)
			(xy 37.283055 -51.797069) (xy 37.241854 -51.832767) (xy 37.195993 -51.862238) (xy 37.146404 -51.884883)
			(xy 37.094097 -51.900239) (xy 37.040137 -51.907994) (xy 37.01288 -51.908456) (xy 36.986323 -51.908009)
			(xy 36.933723 -51.900638) (xy 36.882655 -51.886041) (xy 36.858194 -51.87569) (xy 36.848138 -51.871757)
			(xy 36.826565 -51.871821) (xy 36.806915 -51.880722) (xy 36.79264 -51.896897) (xy 36.786251 -51.917502)
			(xy 36.787074 -51.928268) (xy 36.78936 -51.953922) (xy 36.790665 -51.968915) (xy 36.800904 -51.9972)
			(xy 36.818943 -52.021271) (xy 36.843217 -52.039038) (xy 36.871615 -52.048956) (xy 36.901671 -52.050165)
			(xy 36.91636 -52.046886) (xy 36.940071 -52.041097) (xy 36.988477 -52.034849) (xy 37.01288 -52.03444)
			(xy 37.040137 -52.034806) (xy 37.094097 -52.042561) (xy 37.146404 -52.057917) (xy 37.195993 -52.080562)
			(xy 37.241854 -52.110033) (xy 37.283055 -52.145731) (xy 37.318755 -52.18693) (xy 37.348229 -52.232789)
			(xy 37.370876 -52.282377) (xy 37.380264 -52.314348) (xy 70.671942 -52.314348) (xy 70.676013 -52.258726)
			(xy 70.688139 -52.204289) (xy 70.708062 -52.152198) (xy 70.735358 -52.103563) (xy 70.769444 -52.05942)
			(xy 70.809593 -52.020711) (xy 70.854951 -51.98826) (xy 70.904551 -51.962759) (xy 70.957335 -51.944752)
			(xy 71.012178 -51.934622) (xy 71.067912 -51.932585) (xy 71.123349 -51.938685) (xy 71.177306 -51.952791)
			(xy 71.228635 -51.974603) (xy 71.276241 -52.003657) (xy 71.319109 -52.039332) (xy 71.356326 -52.080869)
			(xy 71.387099 -52.127382) (xy 71.410771 -52.177879) (xy 71.426839 -52.231286) (xy 71.434959 -52.286462)
			(xy 71.435468 -52.314348) (xy 71.434959 -52.342234) (xy 71.426839 -52.39741) (xy 71.421262 -52.415948)
			(xy 99.876862 -52.415948) (xy 99.880933 -52.360326) (xy 99.893059 -52.305889) (xy 99.912982 -52.253798)
			(xy 99.940278 -52.205163) (xy 99.974364 -52.16102) (xy 100.014513 -52.122311) (xy 100.059871 -52.08986)
			(xy 100.109471 -52.064359) (xy 100.162255 -52.046352) (xy 100.217098 -52.036222) (xy 100.272832 -52.034185)
			(xy 100.328269 -52.040285) (xy 100.382226 -52.054391) (xy 100.433555 -52.076203) (xy 100.481161 -52.105257)
			(xy 100.524029 -52.140932) (xy 100.561246 -52.182469) (xy 100.592019 -52.228982) (xy 100.615691 -52.279479)
			(xy 100.631759 -52.332886) (xy 100.639879 -52.388062) (xy 100.640388 -52.415948) (xy 100.639879 -52.443834)
			(xy 100.631759 -52.49901) (xy 100.615691 -52.552417) (xy 100.592019 -52.602914) (xy 100.561246 -52.649427)
			(xy 100.524029 -52.690964) (xy 100.481161 -52.726639) (xy 100.433555 -52.755693) (xy 100.382226 -52.777505)
			(xy 100.328269 -52.791611) (xy 100.272832 -52.797711) (xy 100.217098 -52.795674) (xy 100.162255 -52.785544)
			(xy 100.109471 -52.767537) (xy 100.059871 -52.742036) (xy 100.014513 -52.709585) (xy 99.974364 -52.670876)
			(xy 99.940278 -52.626733) (xy 99.912982 -52.578098) (xy 99.893059 -52.526007) (xy 99.880933 -52.47157)
			(xy 99.876862 -52.415948) (xy 71.421262 -52.415948) (xy 71.410771 -52.450817) (xy 71.387099 -52.501314)
			(xy 71.356326 -52.547827) (xy 71.319109 -52.589364) (xy 71.276241 -52.625039) (xy 71.228635 -52.654093)
			(xy 71.177306 -52.675905) (xy 71.123349 -52.690011) (xy 71.067912 -52.696111) (xy 71.012178 -52.694074)
			(xy 70.957335 -52.683944) (xy 70.904551 -52.665937) (xy 70.854951 -52.640436) (xy 70.809593 -52.607985)
			(xy 70.769444 -52.569276) (xy 70.735358 -52.525133) (xy 70.708062 -52.476498) (xy 70.688139 -52.424407)
			(xy 70.676013 -52.36997) (xy 70.671942 -52.314348) (xy 37.380264 -52.314348) (xy 37.386235 -52.334683)
			(xy 37.393993 -52.388643) (xy 37.393993 -52.443157) (xy 37.386235 -52.497117) (xy 37.370876 -52.549423)
			(xy 37.348229 -52.599011) (xy 37.318755 -52.64487) (xy 37.283055 -52.686069) (xy 37.24303 -52.720748)
			(xy 68.387212 -52.720748) (xy 68.391283 -52.665126) (xy 68.403409 -52.610689) (xy 68.423332 -52.558598)
			(xy 68.450628 -52.509963) (xy 68.484714 -52.46582) (xy 68.524863 -52.427111) (xy 68.570221 -52.39466)
			(xy 68.619821 -52.369159) (xy 68.672605 -52.351152) (xy 68.727448 -52.341022) (xy 68.783182 -52.338985)
			(xy 68.838619 -52.345085) (xy 68.892576 -52.359191) (xy 68.943905 -52.381003) (xy 68.991511 -52.410057)
			(xy 69.034379 -52.445732) (xy 69.071596 -52.487269) (xy 69.102369 -52.533782) (xy 69.126041 -52.584279)
			(xy 69.142109 -52.637686) (xy 69.150229 -52.692862) (xy 69.150738 -52.720748) (xy 69.150229 -52.748634)
			(xy 69.142109 -52.80381) (xy 69.126041 -52.857217) (xy 69.117739 -52.874926) (xy 90.603068 -52.874926)
			(xy 90.607139 -52.819304) (xy 90.619265 -52.764867) (xy 90.639188 -52.712776) (xy 90.666484 -52.664141)
			(xy 90.70057 -52.619998) (xy 90.740719 -52.581289) (xy 90.786077 -52.548838) (xy 90.835677 -52.523337)
			(xy 90.888461 -52.50533) (xy 90.943304 -52.4952) (xy 90.999038 -52.493163) (xy 91.054475 -52.499263)
			(xy 91.108432 -52.513369) (xy 91.159761 -52.535181) (xy 91.207367 -52.564235) (xy 91.250235 -52.59991)
			(xy 91.287452 -52.641447) (xy 91.318225 -52.68796) (xy 91.341897 -52.738457) (xy 91.357965 -52.791864)
			(xy 91.366085 -52.84704) (xy 91.366469 -52.868068) (xy 152.866342 -52.868068) (xy 152.870413 -52.812446)
			(xy 152.882539 -52.758009) (xy 152.902462 -52.705918) (xy 152.929758 -52.657283) (xy 152.963844 -52.61314)
			(xy 153.003993 -52.574431) (xy 153.049351 -52.54198) (xy 153.098951 -52.516479) (xy 153.151735 -52.498472)
			(xy 153.206578 -52.488342) (xy 153.262312 -52.486305) (xy 153.317749 -52.492405) (xy 153.371706 -52.506511)
			(xy 153.423035 -52.528323) (xy 153.470641 -52.557377) (xy 153.513509 -52.593052) (xy 153.550726 -52.634589)
			(xy 153.581499 -52.681102) (xy 153.605171 -52.731599) (xy 153.621239 -52.785006) (xy 153.629359 -52.840182)
			(xy 153.629868 -52.868068) (xy 153.629359 -52.895954) (xy 153.621239 -52.95113) (xy 153.605171 -53.004537)
			(xy 153.581499 -53.055034) (xy 153.550726 -53.101547) (xy 153.513509 -53.143084) (xy 153.470641 -53.178759)
			(xy 153.423035 -53.207813) (xy 153.371706 -53.229625) (xy 153.317749 -53.243731) (xy 153.262312 -53.249831)
			(xy 153.206578 -53.247794) (xy 153.151735 -53.237664) (xy 153.098951 -53.219657) (xy 153.049351 -53.194156)
			(xy 153.003993 -53.161705) (xy 152.963844 -53.122996) (xy 152.929758 -53.078853) (xy 152.902462 -53.030218)
			(xy 152.882539 -52.978127) (xy 152.870413 -52.92369) (xy 152.866342 -52.868068) (xy 91.366469 -52.868068)
			(xy 91.366594 -52.874926) (xy 91.366085 -52.902812) (xy 91.357965 -52.957988) (xy 91.341897 -53.011395)
			(xy 91.318225 -53.061892) (xy 91.287452 -53.108405) (xy 91.250235 -53.149942) (xy 91.207367 -53.185617)
			(xy 91.159761 -53.214671) (xy 91.108432 -53.236483) (xy 91.054475 -53.250589) (xy 90.999038 -53.256689)
			(xy 90.943304 -53.254652) (xy 90.888461 -53.244522) (xy 90.835677 -53.226515) (xy 90.786077 -53.201014)
			(xy 90.740719 -53.168563) (xy 90.70057 -53.129854) (xy 90.666484 -53.085711) (xy 90.639188 -53.037076)
			(xy 90.619265 -52.984985) (xy 90.607139 -52.930548) (xy 90.603068 -52.874926) (xy 69.117739 -52.874926)
			(xy 69.102369 -52.907714) (xy 69.071596 -52.954227) (xy 69.034379 -52.995764) (xy 68.991511 -53.031439)
			(xy 68.943905 -53.060493) (xy 68.892576 -53.082305) (xy 68.838619 -53.096411) (xy 68.783182 -53.102511)
			(xy 68.727448 -53.100474) (xy 68.672605 -53.090344) (xy 68.619821 -53.072337) (xy 68.570221 -53.046836)
			(xy 68.524863 -53.014385) (xy 68.484714 -52.975676) (xy 68.450628 -52.931533) (xy 68.423332 -52.882898)
			(xy 68.403409 -52.830807) (xy 68.391283 -52.77637) (xy 68.387212 -52.720748) (xy 37.24303 -52.720748)
			(xy 37.241854 -52.721767) (xy 37.195993 -52.751238) (xy 37.146404 -52.773883) (xy 37.094097 -52.789239)
			(xy 37.040137 -52.796994) (xy 37.01288 -52.797456) (xy 36.983904 -52.796912) (xy 36.926616 -52.788158)
			(xy 36.871312 -52.770839) (xy 36.819264 -52.745353) (xy 36.771671 -52.712287) (xy 36.729627 -52.672402)
			(xy 36.6941 -52.626617) (xy 36.665907 -52.575984) (xy 36.645699 -52.521669) (xy 36.633939 -52.464922)
			(xy 36.63188 -52.436014) (xy 36.63062 -52.421013) (xy 36.620383 -52.392717) (xy 36.602337 -52.368637)
			(xy 36.578051 -52.350868) (xy 36.54964 -52.340955) (xy 36.519572 -52.339761) (xy 36.50488 -52.34305)
			(xy 36.481172 -52.348851) (xy 36.432764 -52.355091) (xy 36.40836 -52.355496) (xy 36.38111 -52.355031)
			(xy 36.327165 -52.34727) (xy 36.274873 -52.331911) (xy 36.225299 -52.309267) (xy 36.179452 -52.279799)
			(xy 36.138266 -52.244106) (xy 36.102577 -52.202915) (xy 36.073114 -52.157066) (xy 36.050475 -52.107489)
			(xy 36.035121 -52.055196) (xy 36.027366 -52.00125) (xy 6.633382 -52.00125) (xy 6.610397 -52.007259)
			(xy 6.55496 -52.013359) (xy 6.499226 -52.011322) (xy 6.444383 -52.001192) (xy 6.391599 -51.983185)
			(xy 6.341999 -51.957684) (xy 6.296641 -51.925233) (xy 6.256492 -51.886524) (xy 6.222406 -51.842381)
			(xy 6.19511 -51.793746) (xy 6.175187 -51.741655) (xy 6.163061 -51.687218) (xy 6.15899 -51.631596)
			(xy 6.055868 -51.631596) (xy 6.055868 -52.923948) (xy 8.170162 -52.923948) (xy 8.174233 -52.868326)
			(xy 8.186359 -52.813889) (xy 8.206282 -52.761798) (xy 8.233578 -52.713163) (xy 8.267664 -52.66902)
			(xy 8.307813 -52.630311) (xy 8.353171 -52.59786) (xy 8.402771 -52.572359) (xy 8.455555 -52.554352)
			(xy 8.510398 -52.544222) (xy 8.566132 -52.542185) (xy 8.621569 -52.548285) (xy 8.675526 -52.562391)
			(xy 8.726855 -52.584203) (xy 8.774461 -52.613257) (xy 8.817329 -52.648932) (xy 8.854546 -52.690469)
			(xy 8.885319 -52.736982) (xy 8.908991 -52.787479) (xy 8.925059 -52.840886) (xy 8.933179 -52.896062)
			(xy 8.933688 -52.923948) (xy 8.933179 -52.951834) (xy 8.926106 -52.999894) (xy 21.586442 -52.999894)
			(xy 21.590513 -52.944272) (xy 21.602639 -52.889835) (xy 21.622562 -52.837744) (xy 21.649858 -52.789109)
			(xy 21.683944 -52.744966) (xy 21.724093 -52.706257) (xy 21.769451 -52.673806) (xy 21.819051 -52.648305)
			(xy 21.871835 -52.630298) (xy 21.926678 -52.620168) (xy 21.982412 -52.618131) (xy 22.037849 -52.624231)
			(xy 22.091806 -52.638337) (xy 22.143135 -52.660149) (xy 22.190741 -52.689203) (xy 22.198125 -52.695348)
			(xy 29.315662 -52.695348) (xy 29.319733 -52.639726) (xy 29.331859 -52.585289) (xy 29.351782 -52.533198)
			(xy 29.379078 -52.484563) (xy 29.413164 -52.44042) (xy 29.453313 -52.401711) (xy 29.498671 -52.36926)
			(xy 29.548271 -52.343759) (xy 29.601055 -52.325752) (xy 29.655898 -52.315622) (xy 29.711632 -52.313585)
			(xy 29.767069 -52.319685) (xy 29.821026 -52.333791) (xy 29.872355 -52.355603) (xy 29.919961 -52.384657)
			(xy 29.962829 -52.420332) (xy 30.000046 -52.461869) (xy 30.030819 -52.508382) (xy 30.054491 -52.558879)
			(xy 30.070559 -52.612286) (xy 30.078679 -52.667462) (xy 30.078724 -52.669948) (xy 30.605982 -52.669948)
			(xy 30.610053 -52.614326) (xy 30.622179 -52.559889) (xy 30.642102 -52.507798) (xy 30.669398 -52.459163)
			(xy 30.703484 -52.41502) (xy 30.743633 -52.376311) (xy 30.788991 -52.34386) (xy 30.838591 -52.318359)
			(xy 30.891375 -52.300352) (xy 30.946218 -52.290222) (xy 31.001952 -52.288185) (xy 31.057389 -52.294285)
			(xy 31.111346 -52.308391) (xy 31.162675 -52.330203) (xy 31.210281 -52.359257) (xy 31.253149 -52.394932)
			(xy 31.290366 -52.436469) (xy 31.321139 -52.482982) (xy 31.344811 -52.533479) (xy 31.360879 -52.586886)
			(xy 31.368999 -52.642062) (xy 31.369508 -52.669948) (xy 31.368999 -52.697834) (xy 31.360879 -52.75301)
			(xy 31.344811 -52.806417) (xy 31.321139 -52.856914) (xy 31.290366 -52.903427) (xy 31.253149 -52.944964)
			(xy 31.210281 -52.980639) (xy 31.162675 -53.009693) (xy 31.111346 -53.031505) (xy 31.057389 -53.045611)
			(xy 31.001952 -53.051711) (xy 30.946218 -53.049674) (xy 30.891375 -53.039544) (xy 30.838591 -53.021537)
			(xy 30.788991 -52.996036) (xy 30.743633 -52.963585) (xy 30.703484 -52.924876) (xy 30.669398 -52.880733)
			(xy 30.642102 -52.832098) (xy 30.622179 -52.780007) (xy 30.610053 -52.72557) (xy 30.605982 -52.669948)
			(xy 30.078724 -52.669948) (xy 30.079188 -52.695348) (xy 30.078679 -52.723234) (xy 30.070559 -52.77841)
			(xy 30.054491 -52.831817) (xy 30.030819 -52.882314) (xy 30.000046 -52.928827) (xy 29.962829 -52.970364)
			(xy 29.919961 -53.006039) (xy 29.872355 -53.035093) (xy 29.821026 -53.056905) (xy 29.767069 -53.071011)
			(xy 29.711632 -53.077111) (xy 29.655898 -53.075074) (xy 29.601055 -53.064944) (xy 29.548271 -53.046937)
			(xy 29.498671 -53.021436) (xy 29.453313 -52.988985) (xy 29.413164 -52.950276) (xy 29.379078 -52.906133)
			(xy 29.351782 -52.857498) (xy 29.331859 -52.805407) (xy 29.319733 -52.75097) (xy 29.315662 -52.695348)
			(xy 22.198125 -52.695348) (xy 22.233609 -52.724878) (xy 22.270826 -52.766415) (xy 22.301599 -52.812928)
			(xy 22.325271 -52.863425) (xy 22.341339 -52.916832) (xy 22.349459 -52.972008) (xy 22.349968 -52.999894)
			(xy 22.349459 -53.02778) (xy 22.341339 -53.082956) (xy 22.325271 -53.136363) (xy 22.301599 -53.18686)
			(xy 22.270826 -53.233373) (xy 22.233609 -53.27491) (xy 22.190741 -53.310585) (xy 22.143135 -53.339639)
			(xy 22.091806 -53.361451) (xy 22.037849 -53.375557) (xy 21.982412 -53.381657) (xy 21.926678 -53.37962)
			(xy 21.871835 -53.36949) (xy 21.819051 -53.351483) (xy 21.769451 -53.325982) (xy 21.724093 -53.293531)
			(xy 21.683944 -53.254822) (xy 21.649858 -53.210679) (xy 21.622562 -53.162044) (xy 21.602639 -53.109953)
			(xy 21.590513 -53.055516) (xy 21.586442 -52.999894) (xy 8.926106 -52.999894) (xy 8.925059 -53.00701)
			(xy 8.908991 -53.060417) (xy 8.885319 -53.110914) (xy 8.854546 -53.157427) (xy 8.817329 -53.198964)
			(xy 8.774461 -53.234639) (xy 8.726855 -53.263693) (xy 8.675526 -53.285505) (xy 8.621569 -53.299611)
			(xy 8.566132 -53.305711) (xy 8.510398 -53.303674) (xy 8.455555 -53.293544) (xy 8.402771 -53.275537)
			(xy 8.353171 -53.250036) (xy 8.307813 -53.217585) (xy 8.267664 -53.178876) (xy 8.233578 -53.134733)
			(xy 8.206282 -53.086098) (xy 8.186359 -53.034007) (xy 8.174233 -52.97957) (xy 8.170162 -52.923948)
			(xy 6.055868 -52.923948) (xy 6.055868 -53.50383) (xy 81.739738 -53.50383) (xy 81.743809 -53.448208)
			(xy 81.755935 -53.393771) (xy 81.775858 -53.34168) (xy 81.803154 -53.293045) (xy 81.83724 -53.248902)
			(xy 81.877389 -53.210193) (xy 81.922747 -53.177742) (xy 81.972347 -53.152241) (xy 82.025131 -53.134234)
			(xy 82.079974 -53.124104) (xy 82.135708 -53.122067) (xy 82.191145 -53.128167) (xy 82.245102 -53.142273)
			(xy 82.296431 -53.164085) (xy 82.344037 -53.193139) (xy 82.386905 -53.228814) (xy 82.413018 -53.257958)
			(xy 83.079334 -53.257958) (xy 83.083405 -53.202336) (xy 83.095531 -53.147899) (xy 83.115454 -53.095808)
			(xy 83.14275 -53.047173) (xy 83.176836 -53.00303) (xy 83.216985 -52.964321) (xy 83.262343 -52.93187)
			(xy 83.311943 -52.906369) (xy 83.364727 -52.888362) (xy 83.41957 -52.878232) (xy 83.475304 -52.876195)
			(xy 83.530741 -52.882295) (xy 83.584698 -52.896401) (xy 83.636027 -52.918213) (xy 83.683633 -52.947267)
			(xy 83.726501 -52.982942) (xy 83.763718 -53.024479) (xy 83.794491 -53.070992) (xy 83.818163 -53.121489)
			(xy 83.834231 -53.174896) (xy 83.842351 -53.230072) (xy 83.84286 -53.257958) (xy 83.842351 -53.285844)
			(xy 83.834231 -53.34102) (xy 83.818163 -53.394427) (xy 83.794491 -53.444924) (xy 83.763718 -53.491437)
			(xy 83.736377 -53.521952) (xy 84.019364 -53.521952) (xy 84.019364 -53.467448) (xy 84.02712 -53.413499)
			(xy 84.042476 -53.361203) (xy 84.065117 -53.311625) (xy 84.094583 -53.265774) (xy 84.130275 -53.224582)
			(xy 84.171466 -53.188889) (xy 84.217316 -53.159422) (xy 84.266894 -53.136779) (xy 84.31919 -53.121422)
			(xy 84.373138 -53.113664) (xy 84.40039 -53.113178) (xy 84.429308 -53.113674) (xy 84.486482 -53.122403)
			(xy 84.541682 -53.139664) (xy 84.593645 -53.16506) (xy 84.641178 -53.198008) (xy 84.683192 -53.237755)
			(xy 84.70138 -53.260244) (xy 84.711277 -53.272049) (xy 84.736601 -53.289568) (xy 84.765994 -53.298744)
			(xy 84.796786 -53.298744) (xy 84.826179 -53.289568) (xy 84.851503 -53.272049) (xy 84.8614 -53.260244)
			(xy 84.879602 -53.23777) (xy 84.921618 -53.198032) (xy 84.96915 -53.165091) (xy 85.02111 -53.1397)
			(xy 85.076306 -53.122443) (xy 85.133474 -53.113713) (xy 85.16239 -53.113178) (xy 85.189642 -53.113669)
			(xy 85.243592 -53.121424) (xy 85.295889 -53.136779) (xy 85.345469 -53.15942) (xy 85.391322 -53.188886)
			(xy 85.432514 -53.224579) (xy 85.468208 -53.26577) (xy 85.497675 -53.311622) (xy 85.520318 -53.361201)
			(xy 85.535674 -53.413498) (xy 85.543431 -53.467448) (xy 85.543431 -53.521952) (xy 85.541764 -53.533548)
			(xy 91.360242 -53.533548) (xy 91.364313 -53.477926) (xy 91.376439 -53.423489) (xy 91.396362 -53.371398)
			(xy 91.423658 -53.322763) (xy 91.457744 -53.27862) (xy 91.497893 -53.239911) (xy 91.543251 -53.20746)
			(xy 91.592851 -53.181959) (xy 91.645635 -53.163952) (xy 91.700478 -53.153822) (xy 91.756212 -53.151785)
			(xy 91.811649 -53.157885) (xy 91.865606 -53.171991) (xy 91.916935 -53.193803) (xy 91.964541 -53.222857)
			(xy 92.007409 -53.258532) (xy 92.044626 -53.300069) (xy 92.062474 -53.327046) (xy 98.415092 -53.327046)
			(xy 98.419163 -53.271424) (xy 98.431289 -53.216987) (xy 98.451212 -53.164896) (xy 98.478508 -53.116261)
			(xy 98.512594 -53.072118) (xy 98.552743 -53.033409) (xy 98.598101 -53.000958) (xy 98.647701 -52.975457)
			(xy 98.700485 -52.95745) (xy 98.755328 -52.94732) (xy 98.811062 -52.945283) (xy 98.866499 -52.951383)
			(xy 98.920456 -52.965489) (xy 98.971785 -52.987301) (xy 99.019391 -53.016355) (xy 99.062259 -53.05203)
			(xy 99.099476 -53.093567) (xy 99.130249 -53.14008) (xy 99.153921 -53.190577) (xy 99.169989 -53.243984)
			(xy 99.178109 -53.29916) (xy 99.178215 -53.304948) (xy 109.776512 -53.304948) (xy 109.780583 -53.249326)
			(xy 109.792709 -53.194889) (xy 109.812632 -53.142798) (xy 109.839928 -53.094163) (xy 109.874014 -53.05002)
			(xy 109.914163 -53.011311) (xy 109.959521 -52.97886) (xy 110.009121 -52.953359) (xy 110.061905 -52.935352)
			(xy 110.116748 -52.925222) (xy 110.172482 -52.923185) (xy 110.227919 -52.929285) (xy 110.281876 -52.943391)
			(xy 110.333205 -52.965203) (xy 110.380811 -52.994257) (xy 110.423679 -53.029932) (xy 110.460896 -53.071469)
			(xy 110.491669 -53.117982) (xy 110.515341 -53.168479) (xy 110.531409 -53.221886) (xy 110.539529 -53.277062)
			(xy 110.540038 -53.304948) (xy 129.792982 -53.304948) (xy 129.797053 -53.249326) (xy 129.809179 -53.194889)
			(xy 129.829102 -53.142798) (xy 129.856398 -53.094163) (xy 129.890484 -53.05002) (xy 129.930633 -53.011311)
			(xy 129.975991 -52.97886) (xy 130.025591 -52.953359) (xy 130.078375 -52.935352) (xy 130.133218 -52.925222)
			(xy 130.188952 -52.923185) (xy 130.244389 -52.929285) (xy 130.298346 -52.943391) (xy 130.349675 -52.965203)
			(xy 130.397281 -52.994257) (xy 130.440149 -53.029932) (xy 130.477366 -53.071469) (xy 130.508139 -53.117982)
			(xy 130.531811 -53.168479) (xy 130.547879 -53.221886) (xy 130.555999 -53.277062) (xy 130.556508 -53.304948)
			(xy 130.555999 -53.332834) (xy 130.547879 -53.38801) (xy 130.533437 -53.436012) (xy 146.806156 -53.436012)
			(xy 146.810227 -53.38039) (xy 146.822353 -53.325953) (xy 146.842276 -53.273862) (xy 146.869572 -53.225227)
			(xy 146.903658 -53.181084) (xy 146.943807 -53.142375) (xy 146.989165 -53.109924) (xy 147.038765 -53.084423)
			(xy 147.091549 -53.066416) (xy 147.146392 -53.056286) (xy 147.202126 -53.054249) (xy 147.257563 -53.060349)
			(xy 147.31152 -53.074455) (xy 147.362849 -53.096267) (xy 147.410455 -53.125321) (xy 147.453323 -53.160996)
			(xy 147.49054 -53.202533) (xy 147.521313 -53.249046) (xy 147.544985 -53.299543) (xy 147.556028 -53.336249)
			(xy 154.90979 -53.336249) (xy 154.90979 -53.281751) (xy 154.917546 -53.227807) (xy 154.932899 -53.175516)
			(xy 154.955538 -53.125942) (xy 154.985 -53.080095) (xy 155.020688 -53.038906) (xy 155.061874 -53.003216)
			(xy 155.107719 -52.97375) (xy 155.157292 -52.951108) (xy 155.209582 -52.935751) (xy 155.263525 -52.927992)
			(xy 155.290774 -52.927504) (xy 155.317377 -52.927971) (xy 155.37007 -52.935349) (xy 155.421225 -52.94998)
			(xy 155.46985 -52.97158) (xy 155.515001 -52.999728) (xy 155.5558 -53.03388) (xy 155.591457 -53.073371)
			(xy 155.60675 -53.095144) (xy 155.615084 -53.106624) (xy 155.636828 -53.124828) (xy 155.662741 -53.136346)
			(xy 155.690824 -53.140286) (xy 155.718907 -53.136346) (xy 155.74482 -53.124828) (xy 155.766564 -53.106624)
			(xy 155.774898 -53.095144) (xy 155.790183 -53.073367) (xy 155.825851 -53.033888) (xy 155.866656 -52.999745)
			(xy 155.911808 -52.9716) (xy 155.960431 -52.949999) (xy 156.011582 -52.93536) (xy 156.064271 -52.927967)
			(xy 156.090874 -52.927504) (xy 156.118129 -52.927941) (xy 156.172084 -52.935695) (xy 156.224387 -52.95105)
			(xy 156.273972 -52.973691) (xy 156.31983 -53.00316) (xy 156.361027 -53.038854) (xy 156.396725 -53.080049)
			(xy 156.426196 -53.125905) (xy 156.448841 -53.175488) (xy 156.464199 -53.22779) (xy 156.471957 -53.281745)
			(xy 156.471957 -53.336255) (xy 156.464199 -53.39021) (xy 156.448841 -53.442512) (xy 156.426196 -53.492095)
			(xy 156.399555 -53.533548) (xy 167.228012 -53.533548) (xy 167.228503 -53.506179) (xy 167.236315 -53.452001)
			(xy 167.251798 -53.399498) (xy 167.274634 -53.34975) (xy 167.304353 -53.303782) (xy 167.321992 -53.28285)
			(xy 167.331183 -53.271488) (xy 167.343367 -53.244943) (xy 167.347549 -53.216036) (xy 167.343387 -53.187127)
			(xy 167.331222 -53.160573) (xy 167.321992 -53.149246) (xy 167.3044 -53.128274) (xy 167.274676 -53.082313)
			(xy 167.25183 -53.032573) (xy 167.236331 -52.980077) (xy 167.228499 -52.925904) (xy 167.228494 -52.871168)
			(xy 167.236316 -52.816994) (xy 167.251804 -52.764495) (xy 167.274641 -52.714751) (xy 167.304356 -52.668783)
			(xy 167.321992 -52.64785) (xy 167.331183 -52.636488) (xy 167.343367 -52.609943) (xy 167.347549 -52.581036)
			(xy 167.343387 -52.552127) (xy 167.331222 -52.525573) (xy 167.321992 -52.514246) (xy 167.30436 -52.493308)
			(xy 167.274647 -52.447337) (xy 167.25181 -52.397591) (xy 167.236317 -52.345091) (xy 167.228487 -52.290917)
			(xy 167.228012 -52.263548) (xy 167.2285 -52.236295) (xy 167.236251 -52.182344) (xy 167.251602 -52.130046)
			(xy 167.27424 -52.080464) (xy 167.303705 -52.03461) (xy 167.339397 -51.993416) (xy 167.380588 -51.957722)
			(xy 167.42644 -51.928254) (xy 167.476019 -51.905612) (xy 167.528317 -51.890257) (xy 167.582267 -51.882502)
			(xy 167.60952 -51.88204) (xy 167.637807 -51.882567) (xy 167.693761 -51.890924) (xy 167.747868 -51.907452)
			(xy 167.798941 -51.931788) (xy 167.845861 -51.963399) (xy 167.867076 -51.982116) (xy 167.878402 -51.991824)
			(xy 167.905263 -52.004773) (xy 167.934719 -52.00941) (xy 167.964258 -52.00534) (xy 167.991363 -51.99291)
			(xy 168.013721 -51.97318) (xy 168.022016 -51.96078) (xy 168.037031 -51.937522) (xy 168.072706 -51.895191)
			(xy 168.114126 -51.858464) (xy 168.160421 -51.828111) (xy 168.210619 -51.804771) (xy 168.263664 -51.788934)
			(xy 168.318441 -51.780933) (xy 168.34612 -51.78044) (xy 168.373376 -51.780836) (xy 168.427331 -51.788597)
			(xy 168.479634 -51.803958) (xy 168.529217 -51.826607) (xy 168.575072 -51.856081) (xy 168.616266 -51.891782)
			(xy 168.65196 -51.932982) (xy 168.681426 -51.978843) (xy 168.704065 -52.02843) (xy 168.719417 -52.080735)
			(xy 168.727168 -52.134692) (xy 168.727628 -52.161948) (xy 168.727149 -52.189318) (xy 168.719337 -52.243497)
			(xy 168.703852 -52.296001) (xy 168.681013 -52.345748) (xy 168.651289 -52.391715) (xy 168.633648 -52.412646)
			(xy 168.624369 -52.42394) (xy 168.612203 -52.450511) (xy 168.608042 -52.479436) (xy 168.612224 -52.508359)
			(xy 168.624408 -52.534921) (xy 168.633648 -52.54625) (xy 168.651337 -52.567144) (xy 168.681062 -52.613118)
			(xy 168.703906 -52.662871) (xy 168.719399 -52.715379) (xy 168.727224 -52.769563) (xy 168.727219 -52.824309)
			(xy 168.719384 -52.878492) (xy 168.70388 -52.930997) (xy 168.681027 -52.980745) (xy 168.651293 -53.026714)
			(xy 168.633648 -53.047646) (xy 168.624369 -53.05894) (xy 168.612203 -53.085511) (xy 168.608042 -53.114436)
			(xy 168.612224 -53.143359) (xy 168.624408 -53.169921) (xy 168.633648 -53.18125) (xy 168.651269 -53.202197)
			(xy 168.680985 -53.248165) (xy 168.703826 -53.297908) (xy 168.719321 -53.350406) (xy 168.727152 -53.40458)
			(xy 168.727628 -53.431948) (xy 168.727167 -53.4592) (xy 168.719404 -53.513147) (xy 168.704044 -53.565441)
			(xy 168.681399 -53.615017) (xy 168.651929 -53.660866) (xy 168.616236 -53.702055) (xy 168.575044 -53.737746)
			(xy 168.529193 -53.767212) (xy 168.479615 -53.789854) (xy 168.42732 -53.80521) (xy 168.373372 -53.812969)
			(xy 168.34612 -53.813456) (xy 168.317831 -53.812966) (xy 168.261876 -53.8046) (xy 168.207769 -53.788064)
			(xy 168.156696 -53.76372) (xy 168.109778 -53.732101) (xy 168.088564 -53.71338) (xy 168.077202 -53.703717)
			(xy 168.050353 -53.690765) (xy 168.020907 -53.686122) (xy 167.991375 -53.690184) (xy 167.964276 -53.702603)
			(xy 167.94192 -53.722322) (xy 167.933624 -53.734716) (xy 167.918648 -53.758001) (xy 167.882967 -53.800331)
			(xy 167.84154 -53.837057) (xy 167.795238 -53.867407) (xy 167.745034 -53.890742) (xy 167.691984 -53.906573)
			(xy 167.637201 -53.914567) (xy 167.60952 -53.915056) (xy 167.582271 -53.914503) (xy 167.528329 -53.906751)
			(xy 167.476038 -53.891401) (xy 167.426464 -53.868765) (xy 167.380616 -53.839306) (xy 167.339427 -53.803621)
			(xy 167.303735 -53.762438) (xy 167.274267 -53.716595) (xy 167.251623 -53.667026) (xy 167.236264 -53.614738)
			(xy 167.228502 -53.560796) (xy 167.228012 -53.533548) (xy 156.399555 -53.533548) (xy 156.396725 -53.537951)
			(xy 156.361027 -53.579146) (xy 156.31983 -53.61484) (xy 156.273972 -53.644309) (xy 156.224387 -53.66695)
			(xy 156.172084 -53.682305) (xy 156.118129 -53.690059) (xy 156.090874 -53.69052) (xy 156.06427 -53.690082)
			(xy 156.011577 -53.682697) (xy 155.960421 -53.66806) (xy 155.911796 -53.646456) (xy 155.866646 -53.618303)
			(xy 155.825847 -53.584148) (xy 155.790191 -53.544654) (xy 155.774898 -53.52288) (xy 155.766564 -53.5114)
			(xy 155.74482 -53.493196) (xy 155.718907 -53.481678) (xy 155.690824 -53.477738) (xy 155.662741 -53.481678)
			(xy 155.636828 -53.493196) (xy 155.615084 -53.5114) (xy 155.60675 -53.52288) (xy 155.591442 -53.54464)
			(xy 155.555777 -53.584119) (xy 155.514975 -53.618262) (xy 155.469828 -53.646408) (xy 155.421209 -53.668012)
			(xy 155.370061 -53.682656) (xy 155.317375 -53.690054) (xy 155.290774 -53.69052) (xy 155.263525 -53.690008)
			(xy 155.209582 -53.682249) (xy 155.157292 -53.666892) (xy 155.107719 -53.64425) (xy 155.061874 -53.614784)
			(xy 155.020688 -53.579094) (xy 154.985 -53.537905) (xy 154.955538 -53.492058) (xy 154.932899 -53.442484)
			(xy 154.917546 -53.390193) (xy 154.90979 -53.336249) (xy 147.556028 -53.336249) (xy 147.561053 -53.35295)
			(xy 147.569173 -53.408126) (xy 147.569682 -53.436012) (xy 147.569173 -53.463898) (xy 147.561053 -53.519074)
			(xy 147.544985 -53.572481) (xy 147.521313 -53.622978) (xy 147.49054 -53.669491) (xy 147.453323 -53.711028)
			(xy 147.410455 -53.746703) (xy 147.362849 -53.775757) (xy 147.31152 -53.797569) (xy 147.257563 -53.811675)
			(xy 147.202126 -53.817775) (xy 147.146392 -53.815738) (xy 147.091549 -53.805608) (xy 147.038765 -53.787601)
			(xy 146.989165 -53.7621) (xy 146.943807 -53.729649) (xy 146.903658 -53.69094) (xy 146.869572 -53.646797)
			(xy 146.842276 -53.598162) (xy 146.822353 -53.546071) (xy 146.810227 -53.491634) (xy 146.806156 -53.436012)
			(xy 130.533437 -53.436012) (xy 130.531811 -53.441417) (xy 130.508139 -53.491914) (xy 130.477366 -53.538427)
			(xy 130.440149 -53.579964) (xy 130.397281 -53.615639) (xy 130.349675 -53.644693) (xy 130.298346 -53.666505)
			(xy 130.244389 -53.680611) (xy 130.188952 -53.686711) (xy 130.133218 -53.684674) (xy 130.078375 -53.674544)
			(xy 130.025591 -53.656537) (xy 129.975991 -53.631036) (xy 129.930633 -53.598585) (xy 129.890484 -53.559876)
			(xy 129.856398 -53.515733) (xy 129.829102 -53.467098) (xy 129.809179 -53.415007) (xy 129.797053 -53.36057)
			(xy 129.792982 -53.304948) (xy 110.540038 -53.304948) (xy 110.539529 -53.332834) (xy 110.531409 -53.38801)
			(xy 110.515341 -53.441417) (xy 110.491669 -53.491914) (xy 110.460896 -53.538427) (xy 110.423679 -53.579964)
			(xy 110.380811 -53.615639) (xy 110.333205 -53.644693) (xy 110.281876 -53.666505) (xy 110.227919 -53.680611)
			(xy 110.172482 -53.686711) (xy 110.116748 -53.684674) (xy 110.061905 -53.674544) (xy 110.009121 -53.656537)
			(xy 109.959521 -53.631036) (xy 109.914163 -53.598585) (xy 109.874014 -53.559876) (xy 109.839928 -53.515733)
			(xy 109.812632 -53.467098) (xy 109.792709 -53.415007) (xy 109.780583 -53.36057) (xy 109.776512 -53.304948)
			(xy 99.178215 -53.304948) (xy 99.178618 -53.327046) (xy 99.178109 -53.354932) (xy 99.169989 -53.410108)
			(xy 99.153921 -53.463515) (xy 99.130249 -53.514012) (xy 99.099476 -53.560525) (xy 99.062259 -53.602062)
			(xy 99.019391 -53.637737) (xy 98.971785 -53.666791) (xy 98.920456 -53.688603) (xy 98.866499 -53.702709)
			(xy 98.811062 -53.708809) (xy 98.755328 -53.706772) (xy 98.700485 -53.696642) (xy 98.647701 -53.678635)
			(xy 98.598101 -53.653134) (xy 98.552743 -53.620683) (xy 98.512594 -53.581974) (xy 98.478508 -53.537831)
			(xy 98.451212 -53.489196) (xy 98.431289 -53.437105) (xy 98.419163 -53.382668) (xy 98.415092 -53.327046)
			(xy 92.062474 -53.327046) (xy 92.075399 -53.346582) (xy 92.099071 -53.397079) (xy 92.115139 -53.450486)
			(xy 92.123259 -53.505662) (xy 92.123768 -53.533548) (xy 92.123259 -53.561434) (xy 92.115139 -53.61661)
			(xy 92.099071 -53.670017) (xy 92.075399 -53.720514) (xy 92.044626 -53.767027) (xy 92.007409 -53.808564)
			(xy 91.964541 -53.844239) (xy 91.916935 -53.873293) (xy 91.865606 -53.895105) (xy 91.811649 -53.909211)
			(xy 91.756212 -53.915311) (xy 91.700478 -53.913274) (xy 91.645635 -53.903144) (xy 91.592851 -53.885137)
			(xy 91.543251 -53.859636) (xy 91.497893 -53.827185) (xy 91.457744 -53.788476) (xy 91.423658 -53.744333)
			(xy 91.396362 -53.695698) (xy 91.376439 -53.643607) (xy 91.364313 -53.58917) (xy 91.360242 -53.533548)
			(xy 85.541764 -53.533548) (xy 85.535674 -53.575902) (xy 85.520318 -53.628199) (xy 85.497675 -53.677778)
			(xy 85.468208 -53.72363) (xy 85.432514 -53.764821) (xy 85.391322 -53.800514) (xy 85.345469 -53.82998)
			(xy 85.295889 -53.852621) (xy 85.243592 -53.867976) (xy 85.189642 -53.875731) (xy 85.16239 -53.876194)
			(xy 85.133475 -53.875614) (xy 85.076307 -53.866898) (xy 85.021109 -53.849652) (xy 84.969147 -53.824272)
			(xy 84.921612 -53.79134) (xy 84.879592 -53.751609) (xy 84.8614 -53.729128) (xy 84.851503 -53.717323)
			(xy 84.826179 -53.699804) (xy 84.796786 -53.690628) (xy 84.765994 -53.690628) (xy 84.736601 -53.699804)
			(xy 84.711277 -53.717323) (xy 84.70138 -53.729128) (xy 84.683207 -53.751627) (xy 84.641183 -53.79136)
			(xy 84.593644 -53.824296) (xy 84.541679 -53.849682) (xy 84.486479 -53.866935) (xy 84.429307 -53.875661)
			(xy 84.40039 -53.876194) (xy 84.373138 -53.875736) (xy 84.31919 -53.867978) (xy 84.266894 -53.852621)
			(xy 84.217316 -53.829978) (xy 84.171466 -53.800511) (xy 84.130275 -53.764818) (xy 84.094583 -53.723626)
			(xy 84.065117 -53.677775) (xy 84.042476 -53.628197) (xy 84.02712 -53.575901) (xy 84.019364 -53.521952)
			(xy 83.736377 -53.521952) (xy 83.726501 -53.532974) (xy 83.683633 -53.568649) (xy 83.636027 -53.597703)
			(xy 83.584698 -53.619515) (xy 83.530741 -53.633621) (xy 83.475304 -53.639721) (xy 83.41957 -53.637684)
			(xy 83.364727 -53.627554) (xy 83.311943 -53.609547) (xy 83.262343 -53.584046) (xy 83.216985 -53.551595)
			(xy 83.176836 -53.512886) (xy 83.14275 -53.468743) (xy 83.115454 -53.420108) (xy 83.095531 -53.368017)
			(xy 83.083405 -53.31358) (xy 83.079334 -53.257958) (xy 82.413018 -53.257958) (xy 82.424122 -53.270351)
			(xy 82.454895 -53.316864) (xy 82.478567 -53.367361) (xy 82.494635 -53.420768) (xy 82.502755 -53.475944)
			(xy 82.503264 -53.50383) (xy 82.502755 -53.531716) (xy 82.494635 -53.586892) (xy 82.478567 -53.640299)
			(xy 82.454895 -53.690796) (xy 82.424122 -53.737309) (xy 82.386905 -53.778846) (xy 82.344037 -53.814521)
			(xy 82.296431 -53.843575) (xy 82.245102 -53.865387) (xy 82.191145 -53.879493) (xy 82.135708 -53.885593)
			(xy 82.079974 -53.883556) (xy 82.025131 -53.873426) (xy 81.972347 -53.855419) (xy 81.922747 -53.829918)
			(xy 81.877389 -53.797467) (xy 81.83724 -53.758758) (xy 81.803154 -53.714615) (xy 81.775858 -53.66598)
			(xy 81.755935 -53.613889) (xy 81.743809 -53.559452) (xy 81.739738 -53.50383) (xy 6.055868 -53.50383)
			(xy 6.055868 -54.192932) (xy 7.439912 -54.192932) (xy 7.443983 -54.13731) (xy 7.456109 -54.082873)
			(xy 7.476032 -54.030782) (xy 7.503328 -53.982147) (xy 7.537414 -53.938004) (xy 7.577563 -53.899295)
			(xy 7.622921 -53.866844) (xy 7.672521 -53.841343) (xy 7.725305 -53.823336) (xy 7.780148 -53.813206)
			(xy 7.835882 -53.811169) (xy 7.891319 -53.817269) (xy 7.945276 -53.831375) (xy 7.996605 -53.853187)
			(xy 8.044211 -53.882241) (xy 8.087079 -53.917916) (xy 8.111371 -53.945028) (xy 33.549842 -53.945028)
			(xy 33.553913 -53.889406) (xy 33.566039 -53.834969) (xy 33.585962 -53.782878) (xy 33.613258 -53.734243)
			(xy 33.647344 -53.6901) (xy 33.687493 -53.651391) (xy 33.732851 -53.61894) (xy 33.782451 -53.593439)
			(xy 33.835235 -53.575432) (xy 33.890078 -53.565302) (xy 33.945812 -53.563265) (xy 34.001249 -53.569365)
			(xy 34.055206 -53.583471) (xy 34.106535 -53.605283) (xy 34.154141 -53.634337) (xy 34.197009 -53.670012)
			(xy 34.234226 -53.711549) (xy 34.264999 -53.758062) (xy 34.288671 -53.808559) (xy 34.304739 -53.861966)
			(xy 34.312859 -53.917142) (xy 34.313368 -53.945028) (xy 34.312859 -53.972914) (xy 34.304739 -54.02809)
			(xy 34.288671 -54.081497) (xy 34.264999 -54.131994) (xy 34.234226 -54.178507) (xy 34.197009 -54.220044)
			(xy 34.154141 -54.255719) (xy 34.106535 -54.284773) (xy 34.055206 -54.306585) (xy 34.001249 -54.320691)
			(xy 33.945812 -54.326791) (xy 33.890078 -54.324754) (xy 33.835235 -54.314624) (xy 33.782451 -54.296617)
			(xy 33.732851 -54.271116) (xy 33.687493 -54.238665) (xy 33.647344 -54.199956) (xy 33.613258 -54.155813)
			(xy 33.585962 -54.107178) (xy 33.566039 -54.055087) (xy 33.553913 -54.00065) (xy 33.549842 -53.945028)
			(xy 8.111371 -53.945028) (xy 8.124296 -53.959453) (xy 8.155069 -54.005966) (xy 8.178741 -54.056463)
			(xy 8.194809 -54.10987) (xy 8.202929 -54.165046) (xy 8.203438 -54.192932) (xy 8.202929 -54.220818)
			(xy 8.194809 -54.275994) (xy 8.178741 -54.329401) (xy 8.155069 -54.379898) (xy 8.153739 -54.381908)
			(xy 71.408542 -54.381908) (xy 71.412613 -54.326286) (xy 71.424739 -54.271849) (xy 71.444662 -54.219758)
			(xy 71.471958 -54.171123) (xy 71.506044 -54.12698) (xy 71.546193 -54.088271) (xy 71.591551 -54.05582)
			(xy 71.641151 -54.030319) (xy 71.693935 -54.012312) (xy 71.748778 -54.002182) (xy 71.804512 -54.000145)
			(xy 71.859949 -54.006245) (xy 71.913906 -54.020351) (xy 71.965235 -54.042163) (xy 72.012841 -54.071217)
			(xy 72.055709 -54.106892) (xy 72.092926 -54.148429) (xy 72.123699 -54.194942) (xy 72.147371 -54.245439)
			(xy 72.163439 -54.298846) (xy 72.171559 -54.354022) (xy 72.172068 -54.381908) (xy 72.171559 -54.409794)
			(xy 72.163439 -54.46497) (xy 72.147371 -54.518377) (xy 72.123699 -54.568874) (xy 72.092926 -54.615387)
			(xy 72.055709 -54.656924) (xy 72.012841 -54.692599) (xy 71.965235 -54.721653) (xy 71.913906 -54.743465)
			(xy 71.859949 -54.757571) (xy 71.804512 -54.763671) (xy 71.748778 -54.761634) (xy 71.693935 -54.751504)
			(xy 71.641151 -54.733497) (xy 71.591551 -54.707996) (xy 71.546193 -54.675545) (xy 71.506044 -54.636836)
			(xy 71.471958 -54.592693) (xy 71.444662 -54.544058) (xy 71.424739 -54.491967) (xy 71.412613 -54.43753)
			(xy 71.408542 -54.381908) (xy 8.153739 -54.381908) (xy 8.124296 -54.426411) (xy 8.087079 -54.467948)
			(xy 8.044211 -54.503623) (xy 7.996605 -54.532677) (xy 7.945276 -54.554489) (xy 7.891319 -54.568595)
			(xy 7.835882 -54.574695) (xy 7.780148 -54.572658) (xy 7.725305 -54.562528) (xy 7.672521 -54.544521)
			(xy 7.622921 -54.51902) (xy 7.577563 -54.486569) (xy 7.537414 -54.44786) (xy 7.503328 -54.403717)
			(xy 7.476032 -54.355082) (xy 7.456109 -54.302991) (xy 7.443983 -54.248554) (xy 7.439912 -54.192932)
			(xy 6.055868 -54.192932) (xy 6.055868 -54.488334) (xy 6.056404 -54.503813) (xy 6.065657 -54.533356)
			(xy 6.083334 -54.55877) (xy 6.107812 -54.577724) (xy 6.136842 -54.588475) (xy 6.167761 -54.590038)
			(xy 6.182868 -54.586632) (xy 6.206456 -54.580905) (xy 6.254609 -54.574789) (xy 6.27888 -54.57444)
			(xy 6.306131 -54.574926) (xy 6.360079 -54.582682) (xy 6.412374 -54.598038) (xy 6.461952 -54.620679)
			(xy 6.507803 -54.650145) (xy 6.548993 -54.685837) (xy 6.584685 -54.727027) (xy 6.614151 -54.772878)
			(xy 6.636792 -54.822456) (xy 6.652148 -54.874751) (xy 6.659904 -54.928699) (xy 6.659904 -54.983201)
			(xy 6.655277 -55.015384) (xy 28.444442 -55.015384) (xy 28.448513 -54.959762) (xy 28.460639 -54.905325)
			(xy 28.480562 -54.853234) (xy 28.507858 -54.804599) (xy 28.541944 -54.760456) (xy 28.582093 -54.721747)
			(xy 28.627451 -54.689296) (xy 28.677051 -54.663795) (xy 28.729835 -54.645788) (xy 28.784678 -54.635658)
			(xy 28.840412 -54.633621) (xy 28.895849 -54.639721) (xy 28.949806 -54.653827) (xy 29.001135 -54.675639)
			(xy 29.048741 -54.704693) (xy 29.091609 -54.740368) (xy 29.128826 -54.781905) (xy 29.159599 -54.828418)
			(xy 29.183271 -54.878915) (xy 29.199339 -54.932322) (xy 29.207459 -54.987498) (xy 29.207968 -55.015384)
			(xy 29.207459 -55.04327) (xy 29.199339 -55.098446) (xy 29.183271 -55.151853) (xy 29.159599 -55.20235)
			(xy 29.128826 -55.248863) (xy 29.091609 -55.2904) (xy 29.048741 -55.326075) (xy 29.001135 -55.355129)
			(xy 28.949806 -55.376941) (xy 28.895849 -55.391047) (xy 28.840412 -55.397147) (xy 28.784678 -55.39511)
			(xy 28.729835 -55.38498) (xy 28.677051 -55.366973) (xy 28.627451 -55.341472) (xy 28.582093 -55.309021)
			(xy 28.541944 -55.270312) (xy 28.507858 -55.226169) (xy 28.480562 -55.177534) (xy 28.460639 -55.125443)
			(xy 28.448513 -55.071006) (xy 28.444442 -55.015384) (xy 6.655277 -55.015384) (xy 6.652148 -55.037149)
			(xy 6.636792 -55.089444) (xy 6.614151 -55.139022) (xy 6.584685 -55.184873) (xy 6.548993 -55.226063)
			(xy 6.507803 -55.261755) (xy 6.461952 -55.291221) (xy 6.412374 -55.313862) (xy 6.360079 -55.329218)
			(xy 6.306131 -55.336974) (xy 6.27888 -55.337456) (xy 6.25461 -55.337092) (xy 6.206458 -55.330978)
			(xy 6.182868 -55.325264) (xy 6.167754 -55.32193) (xy 6.136859 -55.323519) (xy 6.107852 -55.334271)
			(xy 6.083387 -55.353205) (xy 6.065701 -55.378586) (xy 6.056412 -55.408095) (xy 6.055868 -55.423562)
			(xy 6.055868 -55.470552) (xy 6.056269 -55.483961) (xy 6.063246 -55.509854) (xy 6.076729 -55.533035)
			(xy 6.095787 -55.5519) (xy 6.119103 -55.565148) (xy 6.145066 -55.571861) (xy 6.171881 -55.571576)
			(xy 6.1849 -55.568342) (xy 6.210046 -55.56179) (xy 6.261534 -55.554776) (xy 6.287516 -55.554372)
			(xy 6.314769 -55.554835) (xy 6.36872 -55.562592) (xy 6.384919 -55.567348) (xy 65.836826 -55.567348)
			(xy 65.836826 -55.512852) (xy 65.844582 -55.458911) (xy 65.859935 -55.406623) (xy 65.882573 -55.357052)
			(xy 65.912036 -55.311208) (xy 65.947723 -55.270023) (xy 65.988908 -55.234336) (xy 66.034752 -55.204873)
			(xy 66.084323 -55.182235) (xy 66.136611 -55.166882) (xy 66.190552 -55.159126) (xy 66.2178 -55.15864)
			(xy 66.244727 -55.159116) (xy 66.298043 -55.1667) (xy 66.349765 -55.181704) (xy 66.398863 -55.20383)
			(xy 66.444363 -55.232638) (xy 66.485362 -55.267557) (xy 66.50355 -55.287418) (xy 66.513515 -55.298081)
			(xy 66.538225 -55.313595) (xy 66.566311 -55.321501) (xy 66.595486 -55.321156) (xy 66.623376 -55.312587)
			(xy 66.647713 -55.296492) (xy 66.657474 -55.28564) (xy 66.675706 -55.26477) (xy 66.717138 -55.227971)
			(xy 66.763458 -55.197555) (xy 66.813693 -55.174161) (xy 66.866783 -55.158282) (xy 66.921613 -55.150252)
			(xy 66.94932 -55.14975) (xy 66.976567 -55.150322) (xy 67.030507 -55.158079) (xy 67.082793 -55.173435)
			(xy 67.132363 -55.196074) (xy 67.178205 -55.225538) (xy 67.219389 -55.261226) (xy 67.255074 -55.302411)
			(xy 67.284535 -55.348255) (xy 67.293291 -55.367428) (xy 67.928742 -55.367428) (xy 67.932813 -55.311806)
			(xy 67.944939 -55.257369) (xy 67.964862 -55.205278) (xy 67.992158 -55.156643) (xy 68.026244 -55.1125)
			(xy 68.066393 -55.073791) (xy 68.111751 -55.04134) (xy 68.161351 -55.015839) (xy 68.214135 -54.997832)
			(xy 68.268978 -54.987702) (xy 68.324712 -54.985665) (xy 68.380149 -54.991765) (xy 68.434106 -55.005871)
			(xy 68.485435 -55.027683) (xy 68.533041 -55.056737) (xy 68.575909 -55.092412) (xy 68.613126 -55.133949)
			(xy 68.643899 -55.180462) (xy 68.667571 -55.230959) (xy 68.671184 -55.242968) (xy 79.976472 -55.242968)
			(xy 79.977012 -55.214052) (xy 79.985733 -55.15688) (xy 80.002985 -55.101681) (xy 80.028372 -55.049718)
			(xy 80.061313 -55.002184) (xy 80.101053 -54.960168) (xy 80.123538 -54.941978) (xy 80.13538 -54.932118)
			(xy 80.152905 -54.906786) (xy 80.162082 -54.877382) (xy 80.162076 -54.846579) (xy 80.152888 -54.817178)
			(xy 80.135353 -54.791853) (xy 80.123538 -54.781958) (xy 80.101042 -54.763781) (xy 80.061306 -54.72176)
			(xy 80.028367 -54.674222) (xy 80.002981 -54.622258) (xy 79.985728 -54.567057) (xy 79.977004 -54.509885)
			(xy 79.976472 -54.480968) (xy 79.976948 -54.453717) (xy 79.984708 -54.39977) (xy 80.000067 -54.347476)
			(xy 80.02271 -54.2979) (xy 80.052178 -54.252051) (xy 80.08787 -54.210862) (xy 80.12906 -54.17517)
			(xy 80.174911 -54.145704) (xy 80.224487 -54.123062) (xy 80.276782 -54.107706) (xy 80.330729 -54.099947)
			(xy 80.35798 -54.09946) (xy 80.386897 -54.09997) (xy 80.44407 -54.108697) (xy 80.49927 -54.125956)
			(xy 80.551232 -54.151349) (xy 80.598766 -54.184295) (xy 80.640781 -54.224039) (xy 80.65897 -54.246526)
			(xy 80.668867 -54.258331) (xy 80.694191 -54.27585) (xy 80.723584 -54.285026) (xy 80.754376 -54.285026)
			(xy 80.783769 -54.27585) (xy 80.809093 -54.258331) (xy 80.81899 -54.246526) (xy 80.837193 -54.224053)
			(xy 80.87921 -54.184316) (xy 80.926742 -54.151375) (xy 80.978701 -54.125984) (xy 81.033897 -54.108726)
			(xy 81.091065 -54.099996) (xy 81.11998 -54.09946) (xy 81.147229 -54.099997) (xy 81.201173 -54.10775)
			(xy 81.253465 -54.123101) (xy 81.30304 -54.145737) (xy 81.348889 -54.175198) (xy 81.390079 -54.210884)
			(xy 81.42577 -54.252069) (xy 81.455238 -54.297914) (xy 81.477881 -54.347486) (xy 81.493064 -54.39918)
			(xy 84.854032 -54.39918) (xy 84.858103 -54.343558) (xy 84.870229 -54.289121) (xy 84.890152 -54.23703)
			(xy 84.917448 -54.188395) (xy 84.951534 -54.144252) (xy 84.991683 -54.105543) (xy 85.037041 -54.073092)
			(xy 85.086641 -54.047591) (xy 85.139425 -54.029584) (xy 85.194268 -54.019454) (xy 85.250002 -54.017417)
			(xy 85.305439 -54.023517) (xy 85.359396 -54.037623) (xy 85.410725 -54.059435) (xy 85.458331 -54.088489)
			(xy 85.501199 -54.124164) (xy 85.538416 -54.165701) (xy 85.569189 -54.212214) (xy 85.592861 -54.262711)
			(xy 85.608929 -54.316118) (xy 85.617049 -54.371294) (xy 85.617558 -54.39918) (xy 85.617049 -54.427066)
			(xy 85.608929 -54.482242) (xy 85.592861 -54.535649) (xy 85.569189 -54.586146) (xy 85.538416 -54.632659)
			(xy 85.501199 -54.674196) (xy 85.458331 -54.709871) (xy 85.410725 -54.738925) (xy 85.359396 -54.760737)
			(xy 85.305439 -54.774843) (xy 85.250002 -54.780943) (xy 85.194268 -54.778906) (xy 85.139425 -54.768776)
			(xy 85.086641 -54.750769) (xy 85.037041 -54.725268) (xy 84.991683 -54.692817) (xy 84.951534 -54.654108)
			(xy 84.917448 -54.609965) (xy 84.890152 -54.56133) (xy 84.870229 -54.509239) (xy 84.858103 -54.454802)
			(xy 84.854032 -54.39918) (xy 81.493064 -54.39918) (xy 81.493239 -54.399776) (xy 81.501 -54.453719)
			(xy 81.501488 -54.480968) (xy 81.500951 -54.509884) (xy 81.492227 -54.567055) (xy 81.474973 -54.622253)
			(xy 81.449585 -54.674215) (xy 81.416644 -54.72175) (xy 81.376906 -54.763767) (xy 81.354422 -54.781958)
			(xy 81.342648 -54.79189) (xy 81.325128 -54.817204) (xy 81.315948 -54.846588) (xy 81.315942 -54.877373)
			(xy 81.325111 -54.906761) (xy 81.342621 -54.932081) (xy 81.354422 -54.941978) (xy 81.365403 -54.950868)
			(xy 90.105992 -54.950868) (xy 90.106428 -54.924179) (xy 90.113847 -54.871321) (xy 90.128564 -54.820013)
			(xy 90.15029 -54.771258) (xy 90.178602 -54.726008) (xy 90.212946 -54.685148) (xy 90.252652 -54.649475)
			(xy 90.296944 -54.619688) (xy 90.344957 -54.596366) (xy 90.395752 -54.579967) (xy 90.421968 -54.574948)
			(xy 90.435421 -54.572215) (xy 90.460232 -54.560487) (xy 90.481023 -54.542573) (xy 90.49629 -54.519768)
			(xy 90.504929 -54.493719) (xy 90.506317 -54.466311) (xy 90.500353 -54.439523) (xy 90.487468 -54.415292)
			(xy 90.478356 -54.405022) (xy 90.458767 -54.383647) (xy 90.425651 -54.336058) (xy 90.400123 -54.284004)
			(xy 90.38277 -54.228684) (xy 90.373994 -54.171375) (xy 90.373454 -54.142386) (xy 90.37394 -54.115135)
			(xy 90.381696 -54.061187) (xy 90.397051 -54.008892) (xy 90.419693 -53.959315) (xy 90.449159 -53.913465)
			(xy 90.48485 -53.872274) (xy 90.526041 -53.836583) (xy 90.571891 -53.807117) (xy 90.621468 -53.784475)
			(xy 90.673763 -53.76912) (xy 90.727711 -53.761364) (xy 90.782213 -53.761364) (xy 90.836161 -53.76912)
			(xy 90.888456 -53.784475) (xy 90.938033 -53.807117) (xy 90.983883 -53.836583) (xy 91.025074 -53.872274)
			(xy 91.060765 -53.913465) (xy 91.090231 -53.959315) (xy 91.112873 -54.008892) (xy 91.128228 -54.061187)
			(xy 91.129056 -54.066948) (xy 95.184212 -54.066948) (xy 95.188283 -54.011326) (xy 95.200409 -53.956889)
			(xy 95.220332 -53.904798) (xy 95.247628 -53.856163) (xy 95.281714 -53.81202) (xy 95.321863 -53.773311)
			(xy 95.367221 -53.74086) (xy 95.416821 -53.715359) (xy 95.469605 -53.697352) (xy 95.524448 -53.687222)
			(xy 95.580182 -53.685185) (xy 95.635619 -53.691285) (xy 95.689576 -53.705391) (xy 95.740905 -53.727203)
			(xy 95.788511 -53.756257) (xy 95.831379 -53.791932) (xy 95.868596 -53.833469) (xy 95.899369 -53.879982)
			(xy 95.923041 -53.930479) (xy 95.939109 -53.983886) (xy 95.947229 -54.039062) (xy 95.947738 -54.066948)
			(xy 95.947229 -54.094834) (xy 95.939109 -54.15001) (xy 95.923041 -54.203417) (xy 95.899369 -54.253914)
			(xy 95.868596 -54.300427) (xy 95.831379 -54.341964) (xy 95.788511 -54.377639) (xy 95.740905 -54.406693)
			(xy 95.689576 -54.428505) (xy 95.635619 -54.442611) (xy 95.580182 -54.448711) (xy 95.524448 -54.446674)
			(xy 95.469605 -54.436544) (xy 95.416821 -54.418537) (xy 95.367221 -54.393036) (xy 95.321863 -54.360585)
			(xy 95.281714 -54.321876) (xy 95.247628 -54.277733) (xy 95.220332 -54.229098) (xy 95.200409 -54.177007)
			(xy 95.188283 -54.12257) (xy 95.184212 -54.066948) (xy 91.129056 -54.066948) (xy 91.135984 -54.115135)
			(xy 91.13647 -54.142386) (xy 91.136114 -54.169077) (xy 91.128687 -54.221941) (xy 91.113962 -54.273252)
			(xy 91.092227 -54.32201) (xy 91.063906 -54.367261) (xy 91.029552 -54.408121) (xy 90.989837 -54.443792)
			(xy 90.945537 -54.473577) (xy 90.897516 -54.496895) (xy 90.846714 -54.51329) (xy 90.820494 -54.518306)
			(xy 90.807064 -54.521139) (xy 90.782255 -54.532848) (xy 90.761464 -54.550744) (xy 90.746195 -54.573535)
			(xy 90.737551 -54.59957) (xy 90.736159 -54.626968) (xy 90.742118 -54.653745) (xy 90.754998 -54.677967)
			(xy 90.764106 -54.688232) (xy 90.783667 -54.709632) (xy 90.816788 -54.757213) (xy 90.842322 -54.809261)
			(xy 90.859681 -54.864576) (xy 90.868465 -54.921881) (xy 90.869008 -54.950868) (xy 90.868455 -54.979572)
			(xy 90.859852 -55.036331) (xy 90.842849 -55.091164) (xy 90.817831 -55.142833) (xy 90.78536 -55.190175)
			(xy 90.766887 -55.209948) (xy 95.184212 -55.209948) (xy 95.188283 -55.154326) (xy 95.200409 -55.099889)
			(xy 95.220332 -55.047798) (xy 95.247628 -54.999163) (xy 95.281714 -54.95502) (xy 95.321863 -54.916311)
			(xy 95.367221 -54.88386) (xy 95.416821 -54.858359) (xy 95.469605 -54.840352) (xy 95.524448 -54.830222)
			(xy 95.580182 -54.828185) (xy 95.635619 -54.834285) (xy 95.689576 -54.848391) (xy 95.740905 -54.870203)
			(xy 95.788511 -54.899257) (xy 95.831379 -54.934932) (xy 95.868596 -54.976469) (xy 95.899369 -55.022982)
			(xy 95.923041 -55.073479) (xy 95.939109 -55.126886) (xy 95.947229 -55.182062) (xy 95.947738 -55.209948)
			(xy 95.947229 -55.237834) (xy 95.939109 -55.29301) (xy 95.923041 -55.346417) (xy 95.899369 -55.396914)
			(xy 95.868596 -55.443427) (xy 95.831379 -55.484964) (xy 95.788511 -55.520639) (xy 95.740905 -55.549693)
			(xy 95.689576 -55.571505) (xy 95.635619 -55.585611) (xy 95.580182 -55.591711) (xy 95.524448 -55.589674)
			(xy 95.469605 -55.579544) (xy 95.416821 -55.561537) (xy 95.367221 -55.536036) (xy 95.321863 -55.503585)
			(xy 95.281714 -55.464876) (xy 95.247628 -55.420733) (xy 95.220332 -55.372098) (xy 95.200409 -55.320007)
			(xy 95.188283 -55.26557) (xy 95.184212 -55.209948) (xy 90.766887 -55.209948) (xy 90.746168 -55.232124)
			(xy 90.723974 -55.250334) (xy 90.713747 -55.258901) (xy 90.697801 -55.28028) (xy 90.687937 -55.30506)
			(xy 90.684829 -55.331549) (xy 90.688688 -55.357939) (xy 90.699251 -55.382429) (xy 90.715797 -55.403346)
			(xy 90.72626 -55.411624) (xy 90.749754 -55.429732) (xy 90.79135 -55.472017) (xy 90.825897 -55.520233)
			(xy 90.852562 -55.573216) (xy 90.870701 -55.62969) (xy 90.879878 -55.68829) (xy 90.880438 -55.717948)
			(xy 90.879952 -55.745199) (xy 90.872196 -55.799147) (xy 90.856841 -55.851442) (xy 90.834199 -55.901019)
			(xy 90.804733 -55.946869) (xy 90.769042 -55.98806) (xy 90.727851 -56.023751) (xy 90.682001 -56.053217)
			(xy 90.632424 -56.075859) (xy 90.580129 -56.091214) (xy 90.526181 -56.09897) (xy 90.471679 -56.09897)
			(xy 90.417731 -56.091214) (xy 90.365436 -56.075859) (xy 90.315859 -56.053217) (xy 90.270009 -56.023751)
			(xy 90.228818 -55.98806) (xy 90.193127 -55.946869) (xy 90.163661 -55.901019) (xy 90.141019 -55.851442)
			(xy 90.125664 -55.799147) (xy 90.117908 -55.745199) (xy 90.117422 -55.717948) (xy 90.117975 -55.689244)
			(xy 90.126577 -55.632484) (xy 90.143578 -55.577651) (xy 90.168597 -55.525981) (xy 90.201068 -55.478639)
			(xy 90.240261 -55.436691) (xy 90.262456 -55.418482) (xy 90.272664 -55.409895) (xy 90.288605 -55.388519)
			(xy 90.298467 -55.363745) (xy 90.301576 -55.337261) (xy 90.297722 -55.310876) (xy 90.287165 -55.286389)
			(xy 90.270628 -55.265471) (xy 90.26017 -55.257192) (xy 90.23669 -55.239067) (xy 90.195092 -55.196786)
			(xy 90.160542 -55.148574) (xy 90.133875 -55.095594) (xy 90.115733 -55.039123) (xy 90.106553 -54.980525)
			(xy 90.105992 -54.950868) (xy 81.365403 -54.950868) (xy 81.3769 -54.960176) (xy 81.416634 -55.002195)
			(xy 81.449573 -55.049729) (xy 81.474962 -55.101688) (xy 81.49222 -55.156884) (xy 81.500952 -55.214053)
			(xy 81.501488 -55.242968) (xy 81.501015 -55.270221) (xy 81.493262 -55.324173) (xy 81.477909 -55.376471)
			(xy 81.455269 -55.426053) (xy 81.425802 -55.471907) (xy 81.390109 -55.513101) (xy 81.348917 -55.548795)
			(xy 81.303063 -55.578263) (xy 81.253483 -55.600905) (xy 81.201184 -55.616259) (xy 81.147233 -55.624014)
			(xy 81.11998 -55.624476) (xy 81.091065 -55.62391) (xy 81.033895 -55.615192) (xy 80.978697 -55.597944)
			(xy 80.926735 -55.572562) (xy 80.8792 -55.539626) (xy 80.837181 -55.499892) (xy 80.81899 -55.47741)
			(xy 80.809093 -55.465605) (xy 80.783769 -55.448086) (xy 80.754376 -55.43891) (xy 80.723584 -55.43891)
			(xy 80.694191 -55.448086) (xy 80.668867 -55.465605) (xy 80.65897 -55.47741) (xy 80.640798 -55.49991)
			(xy 80.598774 -55.539644) (xy 80.551235 -55.57258) (xy 80.49927 -55.597966) (xy 80.444069 -55.615219)
			(xy 80.386897 -55.623943) (xy 80.35798 -55.624476) (xy 80.330725 -55.624064) (xy 80.276771 -55.616303)
			(xy 80.22447 -55.600943) (xy 80.174888 -55.578296) (xy 80.129033 -55.548823) (xy 80.08784 -55.513124)
			(xy 80.052146 -55.471925) (xy 80.022679 -55.426067) (xy 80.000039 -55.376481) (xy 79.984686 -55.324178)
			(xy 79.976933 -55.270223) (xy 79.976472 -55.242968) (xy 68.671184 -55.242968) (xy 68.683639 -55.284366)
			(xy 68.691759 -55.339542) (xy 68.692268 -55.367428) (xy 68.691759 -55.395314) (xy 68.683639 -55.45049)
			(xy 68.667571 -55.503897) (xy 68.643899 -55.554394) (xy 68.613126 -55.600907) (xy 68.575909 -55.642444)
			(xy 68.533041 -55.678119) (xy 68.485435 -55.707173) (xy 68.434106 -55.728985) (xy 68.380149 -55.743091)
			(xy 68.324712 -55.749191) (xy 68.268978 -55.747154) (xy 68.214135 -55.737024) (xy 68.161351 -55.719017)
			(xy 68.111751 -55.693516) (xy 68.066393 -55.661065) (xy 68.026244 -55.622356) (xy 67.992158 -55.578213)
			(xy 67.964862 -55.529578) (xy 67.944939 -55.477487) (xy 67.932813 -55.42305) (xy 67.928742 -55.367428)
			(xy 67.293291 -55.367428) (xy 67.307172 -55.397825) (xy 67.322525 -55.450113) (xy 67.33028 -55.504053)
			(xy 67.33028 -55.558547) (xy 67.322525 -55.612487) (xy 67.307172 -55.664775) (xy 67.284535 -55.714345)
			(xy 67.255074 -55.760189) (xy 67.219389 -55.801374) (xy 67.178205 -55.837062) (xy 67.132363 -55.866526)
			(xy 67.082793 -55.889165) (xy 67.030507 -55.904521) (xy 66.976567 -55.912278) (xy 66.94932 -55.912766)
			(xy 66.922394 -55.912275) (xy 66.869078 -55.904693) (xy 66.817357 -55.889692) (xy 66.768259 -55.867569)
			(xy 66.722758 -55.838764) (xy 66.681758 -55.803848) (xy 66.66357 -55.783988) (xy 66.653586 -55.773345)
			(xy 66.628881 -55.757829) (xy 66.6008 -55.74992) (xy 66.571629 -55.750261) (xy 66.543741 -55.758826)
			(xy 66.519407 -55.774916) (xy 66.509646 -55.785766) (xy 66.491458 -55.806676) (xy 66.450017 -55.843471)
			(xy 66.403687 -55.873883) (xy 66.353444 -55.89727) (xy 66.300346 -55.91314) (xy 66.24551 -55.92116)
			(xy 66.2178 -55.921656) (xy 66.190552 -55.921074) (xy 66.136611 -55.913318) (xy 66.084323 -55.897965)
			(xy 66.034752 -55.875327) (xy 65.988908 -55.845864) (xy 65.947723 -55.810177) (xy 65.912036 -55.768992)
			(xy 65.882573 -55.723148) (xy 65.859935 -55.673577) (xy 65.844582 -55.621289) (xy 65.836826 -55.567348)
			(xy 6.384919 -55.567348) (xy 6.421019 -55.577947) (xy 6.470599 -55.60059) (xy 6.516453 -55.630057)
			(xy 6.557646 -55.665751) (xy 6.59334 -55.706944) (xy 6.622809 -55.752797) (xy 6.645451 -55.802378)
			(xy 6.660808 -55.854676) (xy 6.668565 -55.908627) (xy 6.668565 -55.963133) (xy 6.660808 -56.017084)
			(xy 6.645451 -56.069382) (xy 6.622809 -56.118963) (xy 6.59334 -56.164816) (xy 6.557646 -56.206009)
			(xy 6.516453 -56.241703) (xy 6.470599 -56.27117) (xy 6.421019 -56.293813) (xy 6.36872 -56.309168)
			(xy 6.314769 -56.316925) (xy 6.287516 -56.317388) (xy 6.261535 -56.316967) (xy 6.210047 -56.309962)
			(xy 6.1849 -56.303418) (xy 6.171883 -56.300195) (xy 6.145077 -56.299936) (xy 6.119127 -56.306661)
			(xy 6.095821 -56.319908) (xy 6.076765 -56.338763) (xy 6.063272 -56.361927) (xy 6.056273 -56.387805)
			(xy 6.055868 -56.401208) (xy 6.055868 -56.432704) (xy 84.81263 -56.432704) (xy 84.816701 -56.377082)
			(xy 84.828827 -56.322645) (xy 84.84875 -56.270554) (xy 84.876046 -56.221919) (xy 84.910132 -56.177776)
			(xy 84.950281 -56.139067) (xy 84.995639 -56.106616) (xy 85.045239 -56.081115) (xy 85.098023 -56.063108)
			(xy 85.152866 -56.052978) (xy 85.2086 -56.050941) (xy 85.264037 -56.057041) (xy 85.317994 -56.071147)
			(xy 85.369323 -56.092959) (xy 85.416929 -56.122013) (xy 85.459797 -56.157688) (xy 85.497014 -56.199225)
			(xy 85.514694 -56.225948) (xy 95.184212 -56.225948) (xy 95.188283 -56.170326) (xy 95.200409 -56.115889)
			(xy 95.220332 -56.063798) (xy 95.247628 -56.015163) (xy 95.281714 -55.97102) (xy 95.321863 -55.932311)
			(xy 95.367221 -55.89986) (xy 95.416821 -55.874359) (xy 95.469605 -55.856352) (xy 95.524448 -55.846222)
			(xy 95.580182 -55.844185) (xy 95.635619 -55.850285) (xy 95.689576 -55.864391) (xy 95.740905 -55.886203)
			(xy 95.788511 -55.915257) (xy 95.811712 -55.934565) (xy 97.693465 -55.934565) (xy 97.701219 -55.880616)
			(xy 97.716572 -55.828319) (xy 97.739211 -55.778739) (xy 97.768676 -55.732886) (xy 97.804367 -55.691693)
			(xy 97.845556 -55.655999) (xy 97.891406 -55.626529) (xy 97.940984 -55.603885) (xy 97.993279 -55.588527)
			(xy 98.047228 -55.580767) (xy 98.07448 -55.58028) (xy 98.098738 -55.580652) (xy 98.14686 -55.586814)
			(xy 98.193813 -55.599029) (xy 98.216466 -55.607712) (xy 98.230535 -55.612787) (xy 98.260309 -55.615444)
			(xy 98.289577 -55.609365) (xy 98.315831 -55.59507) (xy 98.33682 -55.573786) (xy 98.350747 -55.547335)
			(xy 98.356417 -55.517985) (xy 98.355404 -55.503064) (xy 98.354461 -55.493312) (xy 98.353443 -55.473745)
			(xy 98.353372 -55.463948) (xy 98.353845 -55.43707) (xy 98.361378 -55.383843) (xy 98.376316 -55.332204)
			(xy 98.398363 -55.283176) (xy 98.427081 -55.237733) (xy 98.461899 -55.196776) (xy 98.502127 -55.161119)
			(xy 98.546967 -55.131468) (xy 98.57105 -55.119524) (xy 98.584635 -55.112436) (xy 98.607146 -55.091673)
			(xy 98.622492 -55.06517) (xy 98.629296 -55.035311) (xy 98.626944 -55.004776) (xy 98.615649 -54.97631)
			(xy 98.596426 -54.952471) (xy 98.584004 -54.943502) (xy 98.562118 -54.928256) (xy 98.522466 -54.892579)
			(xy 98.488168 -54.851729) (xy 98.459891 -54.806502) (xy 98.438186 -54.757778) (xy 98.423476 -54.706507)
			(xy 98.416047 -54.653688) (xy 98.415602 -54.627018) (xy 98.416088 -54.599767) (xy 98.423844 -54.545819)
			(xy 98.439199 -54.493524) (xy 98.461841 -54.443947) (xy 98.491307 -54.398097) (xy 98.526998 -54.356906)
			(xy 98.568189 -54.321215) (xy 98.614039 -54.291749) (xy 98.663616 -54.269107) (xy 98.715911 -54.253752)
			(xy 98.769859 -54.245996) (xy 98.824361 -54.245996) (xy 98.878309 -54.253752) (xy 98.930604 -54.269107)
			(xy 98.980181 -54.291749) (xy 99.026031 -54.321215) (xy 99.067222 -54.356906) (xy 99.102913 -54.398097)
			(xy 99.132379 -54.443947) (xy 99.155021 -54.493524) (xy 99.170376 -54.545819) (xy 99.178132 -54.599767)
			(xy 99.178618 -54.627018) (xy 106.517692 -54.627018) (xy 106.521763 -54.571396) (xy 106.533889 -54.516959)
			(xy 106.553812 -54.464868) (xy 106.581108 -54.416233) (xy 106.615194 -54.37209) (xy 106.655343 -54.333381)
			(xy 106.700701 -54.30093) (xy 106.750301 -54.275429) (xy 106.803085 -54.257422) (xy 106.857928 -54.247292)
			(xy 106.913662 -54.245255) (xy 106.969099 -54.251355) (xy 107.023056 -54.265461) (xy 107.074385 -54.287273)
			(xy 107.121991 -54.316327) (xy 107.164859 -54.352002) (xy 107.202076 -54.393539) (xy 107.232849 -54.440052)
			(xy 107.256521 -54.490549) (xy 107.272589 -54.543956) (xy 107.27715 -54.574948) (xy 109.776512 -54.574948)
			(xy 109.780583 -54.519326) (xy 109.792709 -54.464889) (xy 109.812632 -54.412798) (xy 109.839928 -54.364163)
			(xy 109.874014 -54.32002) (xy 109.914163 -54.281311) (xy 109.959521 -54.24886) (xy 110.009121 -54.223359)
			(xy 110.061905 -54.205352) (xy 110.116748 -54.195222) (xy 110.172482 -54.193185) (xy 110.179416 -54.193948)
			(xy 114.552982 -54.193948) (xy 114.557053 -54.138326) (xy 114.569179 -54.083889) (xy 114.589102 -54.031798)
			(xy 114.616398 -53.983163) (xy 114.650484 -53.93902) (xy 114.690633 -53.900311) (xy 114.735991 -53.86786)
			(xy 114.785591 -53.842359) (xy 114.838375 -53.824352) (xy 114.893218 -53.814222) (xy 114.948952 -53.812185)
			(xy 115.004389 -53.818285) (xy 115.058346 -53.832391) (xy 115.109675 -53.854203) (xy 115.157281 -53.883257)
			(xy 115.200149 -53.918932) (xy 115.237366 -53.960469) (xy 115.268139 -54.006982) (xy 115.275174 -54.02199)
			(xy 120.394982 -54.02199) (xy 120.399053 -53.966368) (xy 120.411179 -53.911931) (xy 120.431102 -53.85984)
			(xy 120.458398 -53.811205) (xy 120.492484 -53.767062) (xy 120.532633 -53.728353) (xy 120.577991 -53.695902)
			(xy 120.627591 -53.670401) (xy 120.680375 -53.652394) (xy 120.735218 -53.642264) (xy 120.790952 -53.640227)
			(xy 120.846389 -53.646327) (xy 120.900346 -53.660433) (xy 120.951675 -53.682245) (xy 120.999281 -53.711299)
			(xy 121.042149 -53.746974) (xy 121.079366 -53.788511) (xy 121.110139 -53.835024) (xy 121.133811 -53.885521)
			(xy 121.149879 -53.938928) (xy 121.157999 -53.994104) (xy 121.158508 -54.02199) (xy 126.287782 -54.02199)
			(xy 126.291853 -53.966368) (xy 126.303979 -53.911931) (xy 126.323902 -53.85984) (xy 126.351198 -53.811205)
			(xy 126.385284 -53.767062) (xy 126.425433 -53.728353) (xy 126.470791 -53.695902) (xy 126.520391 -53.670401)
			(xy 126.573175 -53.652394) (xy 126.628018 -53.642264) (xy 126.683752 -53.640227) (xy 126.739189 -53.646327)
			(xy 126.793146 -53.660433) (xy 126.844475 -53.682245) (xy 126.892081 -53.711299) (xy 126.934949 -53.746974)
			(xy 126.972166 -53.788511) (xy 127.002939 -53.835024) (xy 127.011641 -53.853588) (xy 139.950188 -53.853588)
			(xy 139.954259 -53.797966) (xy 139.966385 -53.743529) (xy 139.986308 -53.691438) (xy 140.013604 -53.642803)
			(xy 140.04769 -53.59866) (xy 140.087839 -53.559951) (xy 140.133197 -53.5275) (xy 140.182797 -53.501999)
			(xy 140.235581 -53.483992) (xy 140.290424 -53.473862) (xy 140.346158 -53.471825) (xy 140.401595 -53.477925)
			(xy 140.455552 -53.492031) (xy 140.506881 -53.513843) (xy 140.554487 -53.542897) (xy 140.597355 -53.578572)
			(xy 140.634572 -53.620109) (xy 140.665345 -53.666622) (xy 140.689017 -53.717119) (xy 140.705085 -53.770526)
			(xy 140.713205 -53.825702) (xy 140.713714 -53.853588) (xy 140.713205 -53.881474) (xy 140.705085 -53.93665)
			(xy 140.689017 -53.990057) (xy 140.665345 -54.040554) (xy 140.634572 -54.087067) (xy 140.597355 -54.128604)
			(xy 140.554487 -54.164279) (xy 140.506881 -54.193333) (xy 140.455552 -54.215145) (xy 140.401595 -54.229251)
			(xy 140.346158 -54.235351) (xy 140.290424 -54.233314) (xy 140.235581 -54.223184) (xy 140.182797 -54.205177)
			(xy 140.133197 -54.179676) (xy 140.087839 -54.147225) (xy 140.04769 -54.108516) (xy 140.013604 -54.064373)
			(xy 139.986308 -54.015738) (xy 139.966385 -53.963647) (xy 139.954259 -53.90921) (xy 139.950188 -53.853588)
			(xy 127.011641 -53.853588) (xy 127.026611 -53.885521) (xy 127.042679 -53.938928) (xy 127.050799 -53.994104)
			(xy 127.051308 -54.02199) (xy 127.050799 -54.049876) (xy 127.042679 -54.105052) (xy 127.026611 -54.158459)
			(xy 127.002939 -54.208956) (xy 126.972166 -54.255469) (xy 126.934949 -54.297006) (xy 126.892081 -54.332681)
			(xy 126.844475 -54.361735) (xy 126.793146 -54.383547) (xy 126.739189 -54.397653) (xy 126.683752 -54.403753)
			(xy 126.628018 -54.401716) (xy 126.573175 -54.391586) (xy 126.520391 -54.373579) (xy 126.470791 -54.348078)
			(xy 126.425433 -54.315627) (xy 126.385284 -54.276918) (xy 126.351198 -54.232775) (xy 126.323902 -54.18414)
			(xy 126.303979 -54.132049) (xy 126.291853 -54.077612) (xy 126.287782 -54.02199) (xy 121.158508 -54.02199)
			(xy 121.157999 -54.049876) (xy 121.149879 -54.105052) (xy 121.133811 -54.158459) (xy 121.110139 -54.208956)
			(xy 121.079366 -54.255469) (xy 121.042149 -54.297006) (xy 120.999281 -54.332681) (xy 120.951675 -54.361735)
			(xy 120.900346 -54.383547) (xy 120.846389 -54.397653) (xy 120.790952 -54.403753) (xy 120.735218 -54.401716)
			(xy 120.680375 -54.391586) (xy 120.627591 -54.373579) (xy 120.577991 -54.348078) (xy 120.532633 -54.315627)
			(xy 120.492484 -54.276918) (xy 120.458398 -54.232775) (xy 120.431102 -54.18414) (xy 120.411179 -54.132049)
			(xy 120.399053 -54.077612) (xy 120.394982 -54.02199) (xy 115.275174 -54.02199) (xy 115.291811 -54.057479)
			(xy 115.307879 -54.110886) (xy 115.315999 -54.166062) (xy 115.316508 -54.193948) (xy 115.315999 -54.221834)
			(xy 115.307879 -54.27701) (xy 115.291811 -54.330417) (xy 115.268139 -54.380914) (xy 115.237366 -54.427427)
			(xy 115.200149 -54.468964) (xy 115.157281 -54.504639) (xy 115.109675 -54.533693) (xy 115.058346 -54.555505)
			(xy 115.004389 -54.569611) (xy 114.948952 -54.575711) (xy 114.893218 -54.573674) (xy 114.838375 -54.563544)
			(xy 114.785591 -54.545537) (xy 114.735991 -54.520036) (xy 114.690633 -54.487585) (xy 114.650484 -54.448876)
			(xy 114.616398 -54.404733) (xy 114.589102 -54.356098) (xy 114.569179 -54.304007) (xy 114.557053 -54.24957)
			(xy 114.552982 -54.193948) (xy 110.179416 -54.193948) (xy 110.227919 -54.199285) (xy 110.281876 -54.213391)
			(xy 110.333205 -54.235203) (xy 110.380811 -54.264257) (xy 110.423679 -54.299932) (xy 110.460896 -54.341469)
			(xy 110.491669 -54.387982) (xy 110.515341 -54.438479) (xy 110.531409 -54.491886) (xy 110.539529 -54.547062)
			(xy 110.540038 -54.574948) (xy 110.539529 -54.602834) (xy 110.531409 -54.65801) (xy 110.527207 -54.671976)
			(xy 116.940582 -54.671976) (xy 116.944653 -54.616354) (xy 116.956779 -54.561917) (xy 116.976702 -54.509826)
			(xy 117.003998 -54.461191) (xy 117.038084 -54.417048) (xy 117.078233 -54.378339) (xy 117.123591 -54.345888)
			(xy 117.173191 -54.320387) (xy 117.225975 -54.30238) (xy 117.280818 -54.29225) (xy 117.336552 -54.290213)
			(xy 117.391989 -54.296313) (xy 117.445946 -54.310419) (xy 117.497275 -54.332231) (xy 117.544881 -54.361285)
			(xy 117.587749 -54.39696) (xy 117.624966 -54.438497) (xy 117.655739 -54.48501) (xy 117.679411 -54.535507)
			(xy 117.695479 -54.588914) (xy 117.703599 -54.64409) (xy 117.704108 -54.671976) (xy 127.405382 -54.671976)
			(xy 127.409453 -54.616354) (xy 127.421579 -54.561917) (xy 127.441502 -54.509826) (xy 127.468798 -54.461191)
			(xy 127.502884 -54.417048) (xy 127.543033 -54.378339) (xy 127.588391 -54.345888) (xy 127.637991 -54.320387)
			(xy 127.690775 -54.30238) (xy 127.745618 -54.29225) (xy 127.801352 -54.290213) (xy 127.856789 -54.296313)
			(xy 127.910746 -54.310419) (xy 127.962075 -54.332231) (xy 128.009681 -54.361285) (xy 128.049723 -54.394608)
			(xy 167.908222 -54.394608) (xy 167.912293 -54.338986) (xy 167.924419 -54.284549) (xy 167.944342 -54.232458)
			(xy 167.971638 -54.183823) (xy 168.005724 -54.13968) (xy 168.045873 -54.100971) (xy 168.091231 -54.06852)
			(xy 168.140831 -54.043019) (xy 168.193615 -54.025012) (xy 168.248458 -54.014882) (xy 168.304192 -54.012845)
			(xy 168.359629 -54.018945) (xy 168.413586 -54.033051) (xy 168.464915 -54.054863) (xy 168.512521 -54.083917)
			(xy 168.555389 -54.119592) (xy 168.592606 -54.161129) (xy 168.623379 -54.207642) (xy 168.647051 -54.258139)
			(xy 168.663119 -54.311546) (xy 168.671239 -54.366722) (xy 168.671748 -54.394608) (xy 168.671239 -54.422494)
			(xy 168.663119 -54.47767) (xy 168.647051 -54.531077) (xy 168.623379 -54.581574) (xy 168.592606 -54.628087)
			(xy 168.555389 -54.669624) (xy 168.512521 -54.705299) (xy 168.464915 -54.734353) (xy 168.413586 -54.756165)
			(xy 168.359629 -54.770271) (xy 168.304192 -54.776371) (xy 168.248458 -54.774334) (xy 168.193615 -54.764204)
			(xy 168.140831 -54.746197) (xy 168.091231 -54.720696) (xy 168.045873 -54.688245) (xy 168.005724 -54.649536)
			(xy 167.971638 -54.605393) (xy 167.944342 -54.556758) (xy 167.924419 -54.504667) (xy 167.912293 -54.45023)
			(xy 167.908222 -54.394608) (xy 128.049723 -54.394608) (xy 128.052549 -54.39696) (xy 128.089766 -54.438497)
			(xy 128.120539 -54.48501) (xy 128.144211 -54.535507) (xy 128.160279 -54.588914) (xy 128.168399 -54.64409)
			(xy 128.168908 -54.671976) (xy 128.168399 -54.699862) (xy 128.160279 -54.755038) (xy 128.144211 -54.808445)
			(xy 128.132814 -54.832758) (xy 147.11883 -54.832758) (xy 147.122901 -54.777136) (xy 147.135027 -54.722699)
			(xy 147.15495 -54.670608) (xy 147.182246 -54.621973) (xy 147.216332 -54.57783) (xy 147.256481 -54.539121)
			(xy 147.301839 -54.50667) (xy 147.351439 -54.481169) (xy 147.404223 -54.463162) (xy 147.459066 -54.453032)
			(xy 147.5148 -54.450995) (xy 147.570237 -54.457095) (xy 147.624194 -54.471201) (xy 147.675523 -54.493013)
			(xy 147.723129 -54.522067) (xy 147.765997 -54.557742) (xy 147.803214 -54.599279) (xy 147.833987 -54.645792)
			(xy 147.857659 -54.696289) (xy 147.873727 -54.749696) (xy 147.881847 -54.804872) (xy 147.882356 -54.832758)
			(xy 147.881847 -54.860644) (xy 147.873727 -54.91582) (xy 147.857659 -54.969227) (xy 147.838004 -55.011155)
			(xy 159.316343 -55.011155) (xy 159.316343 -54.956645) (xy 159.324101 -54.902691) (xy 159.339458 -54.85039)
			(xy 159.362103 -54.800807) (xy 159.391574 -54.754951) (xy 159.427271 -54.713757) (xy 159.468467 -54.678062)
			(xy 159.514324 -54.648593) (xy 159.563909 -54.625951) (xy 159.61621 -54.610596) (xy 159.670165 -54.602842)
			(xy 159.69742 -54.60238) (xy 159.726336 -54.602926) (xy 159.783508 -54.611645) (xy 159.838707 -54.628895)
			(xy 159.89067 -54.654282) (xy 159.938204 -54.687222) (xy 159.98022 -54.726961) (xy 159.99841 -54.749446)
			(xy 160.008307 -54.761251) (xy 160.033631 -54.77877) (xy 160.063024 -54.787946) (xy 160.093816 -54.787946)
			(xy 160.123209 -54.77877) (xy 160.148533 -54.761251) (xy 160.15843 -54.749446) (xy 160.17659 -54.726937)
			(xy 160.218618 -54.687206) (xy 160.26616 -54.654271) (xy 160.318127 -54.628888) (xy 160.373329 -54.611637)
			(xy 160.430502 -54.602913) (xy 160.45942 -54.60238) (xy 160.486669 -54.602892) (xy 160.540613 -54.61065)
			(xy 160.592904 -54.626007) (xy 160.642477 -54.648648) (xy 160.688323 -54.678114) (xy 160.72951 -54.713804)
			(xy 160.765198 -54.754993) (xy 160.794662 -54.800841) (xy 160.8173 -54.850415) (xy 160.832654 -54.902706)
			(xy 160.84041 -54.956651) (xy 160.84041 -55.011149) (xy 160.832654 -55.065094) (xy 160.8173 -55.117385)
			(xy 160.794662 -55.166959) (xy 160.765198 -55.212807) (xy 160.72951 -55.253996) (xy 160.688323 -55.289686)
			(xy 160.642477 -55.319152) (xy 160.592904 -55.341793) (xy 160.540613 -55.35715) (xy 160.486669 -55.364908)
			(xy 160.45942 -55.365396) (xy 160.430504 -55.364865) (xy 160.373333 -55.356139) (xy 160.318134 -55.338883)
			(xy 160.266173 -55.313494) (xy 160.218638 -55.280553) (xy 160.176621 -55.240814) (xy 160.15843 -55.21833)
			(xy 160.148533 -55.206525) (xy 160.123209 -55.189006) (xy 160.093816 -55.17983) (xy 160.063024 -55.17983)
			(xy 160.033631 -55.189006) (xy 160.008307 -55.206525) (xy 159.99841 -55.21833) (xy 159.980221 -55.240815)
			(xy 159.9382 -55.280549) (xy 159.890664 -55.313487) (xy 159.838703 -55.338874) (xy 159.783505 -55.356131)
			(xy 159.726336 -55.36486) (xy 159.69742 -55.365396) (xy 159.670165 -55.364958) (xy 159.61621 -55.357204)
			(xy 159.563909 -55.341849) (xy 159.514324 -55.319207) (xy 159.468467 -55.289738) (xy 159.427271 -55.254043)
			(xy 159.391574 -55.212849) (xy 159.362103 -55.166993) (xy 159.339458 -55.11741) (xy 159.324101 -55.065109)
			(xy 159.316343 -55.011155) (xy 147.838004 -55.011155) (xy 147.833987 -55.019724) (xy 147.803214 -55.066237)
			(xy 147.765997 -55.107774) (xy 147.723129 -55.143449) (xy 147.675523 -55.172503) (xy 147.624194 -55.194315)
			(xy 147.570237 -55.208421) (xy 147.5148 -55.214521) (xy 147.459066 -55.212484) (xy 147.404223 -55.202354)
			(xy 147.351439 -55.184347) (xy 147.301839 -55.158846) (xy 147.256481 -55.126395) (xy 147.216332 -55.087686)
			(xy 147.182246 -55.043543) (xy 147.15495 -54.994908) (xy 147.135027 -54.942817) (xy 147.122901 -54.88838)
			(xy 147.11883 -54.832758) (xy 128.132814 -54.832758) (xy 128.120539 -54.858942) (xy 128.089766 -54.905455)
			(xy 128.052549 -54.946992) (xy 128.009681 -54.982667) (xy 127.962075 -55.011721) (xy 127.910746 -55.033533)
			(xy 127.856789 -55.047639) (xy 127.801352 -55.053739) (xy 127.745618 -55.051702) (xy 127.690775 -55.041572)
			(xy 127.637991 -55.023565) (xy 127.588391 -54.998064) (xy 127.543033 -54.965613) (xy 127.502884 -54.926904)
			(xy 127.468798 -54.882761) (xy 127.441502 -54.834126) (xy 127.421579 -54.782035) (xy 127.409453 -54.727598)
			(xy 127.405382 -54.671976) (xy 117.704108 -54.671976) (xy 117.703599 -54.699862) (xy 117.695479 -54.755038)
			(xy 117.679411 -54.808445) (xy 117.655739 -54.858942) (xy 117.624966 -54.905455) (xy 117.587749 -54.946992)
			(xy 117.544881 -54.982667) (xy 117.497275 -55.011721) (xy 117.445946 -55.033533) (xy 117.391989 -55.047639)
			(xy 117.336552 -55.053739) (xy 117.280818 -55.051702) (xy 117.225975 -55.041572) (xy 117.173191 -55.023565)
			(xy 117.123591 -54.998064) (xy 117.078233 -54.965613) (xy 117.038084 -54.926904) (xy 117.003998 -54.882761)
			(xy 116.976702 -54.834126) (xy 116.956779 -54.782035) (xy 116.944653 -54.727598) (xy 116.940582 -54.671976)
			(xy 110.527207 -54.671976) (xy 110.515341 -54.711417) (xy 110.491669 -54.761914) (xy 110.460896 -54.808427)
			(xy 110.423679 -54.849964) (xy 110.380811 -54.885639) (xy 110.333205 -54.914693) (xy 110.281876 -54.936505)
			(xy 110.227919 -54.950611) (xy 110.172482 -54.956711) (xy 110.116748 -54.954674) (xy 110.061905 -54.944544)
			(xy 110.009121 -54.926537) (xy 109.959521 -54.901036) (xy 109.914163 -54.868585) (xy 109.874014 -54.829876)
			(xy 109.839928 -54.785733) (xy 109.812632 -54.737098) (xy 109.792709 -54.685007) (xy 109.780583 -54.63057)
			(xy 109.776512 -54.574948) (xy 107.27715 -54.574948) (xy 107.280709 -54.599132) (xy 107.281218 -54.627018)
			(xy 107.280709 -54.654904) (xy 107.272589 -54.71008) (xy 107.256521 -54.763487) (xy 107.232849 -54.813984)
			(xy 107.202076 -54.860497) (xy 107.164859 -54.902034) (xy 107.121991 -54.937709) (xy 107.074385 -54.966763)
			(xy 107.023056 -54.988575) (xy 106.969099 -55.002681) (xy 106.913662 -55.008781) (xy 106.857928 -55.006744)
			(xy 106.803085 -54.996614) (xy 106.750301 -54.978607) (xy 106.700701 -54.953106) (xy 106.655343 -54.920655)
			(xy 106.615194 -54.881946) (xy 106.581108 -54.837803) (xy 106.553812 -54.789168) (xy 106.533889 -54.737077)
			(xy 106.521763 -54.68264) (xy 106.517692 -54.627018) (xy 99.178618 -54.627018) (xy 99.178206 -54.653899)
			(xy 99.170664 -54.707128) (xy 99.155716 -54.758769) (xy 99.133661 -54.807797) (xy 99.104935 -54.85324)
			(xy 99.070109 -54.894196) (xy 99.029873 -54.929851) (xy 98.985026 -54.9595) (xy 98.96094 -54.971442)
			(xy 98.947301 -54.978435) (xy 98.924785 -54.999218) (xy 98.909439 -55.02574) (xy 98.902642 -55.055618)
			(xy 98.905004 -55.086168) (xy 98.908769 -55.095648) (xy 103.120442 -55.095648) (xy 103.124513 -55.040026)
			(xy 103.136639 -54.985589) (xy 103.156562 -54.933498) (xy 103.183858 -54.884863) (xy 103.217944 -54.84072)
			(xy 103.258093 -54.802011) (xy 103.303451 -54.76956) (xy 103.353051 -54.744059) (xy 103.405835 -54.726052)
			(xy 103.460678 -54.715922) (xy 103.516412 -54.713885) (xy 103.571849 -54.719985) (xy 103.625806 -54.734091)
			(xy 103.677135 -54.755903) (xy 103.724741 -54.784957) (xy 103.767609 -54.820632) (xy 103.804826 -54.862169)
			(xy 103.835599 -54.908682) (xy 103.859271 -54.959179) (xy 103.875339 -55.012586) (xy 103.883459 -55.067762)
			(xy 103.883968 -55.095648) (xy 103.883459 -55.123534) (xy 103.875339 -55.17871) (xy 103.859271 -55.232117)
			(xy 103.835599 -55.282614) (xy 103.804826 -55.329127) (xy 103.767609 -55.370664) (xy 103.724741 -55.406339)
			(xy 103.677135 -55.435393) (xy 103.625806 -55.457205) (xy 103.571849 -55.471311) (xy 103.516412 -55.477411)
			(xy 103.460678 -55.475374) (xy 103.405835 -55.465244) (xy 103.353051 -55.447237) (xy 103.303451 -55.421736)
			(xy 103.258093 -55.389285) (xy 103.217944 -55.350576) (xy 103.183858 -55.306433) (xy 103.156562 -55.257798)
			(xy 103.136639 -55.205707) (xy 103.124513 -55.15127) (xy 103.120442 -55.095648) (xy 98.908769 -55.095648)
			(xy 98.916314 -55.114646) (xy 98.935555 -55.138494) (xy 98.947986 -55.147464) (xy 98.969854 -55.162735)
			(xy 99.009506 -55.198407) (xy 99.043806 -55.239253) (xy 99.072086 -55.284476) (xy 99.093794 -55.333195)
			(xy 99.108507 -55.384463) (xy 99.11594 -55.43728) (xy 99.116388 -55.463948) (xy 99.115967 -55.491201)
			(xy 99.108203 -55.545152) (xy 99.09684 -55.583836) (xy 104.010966 -55.583836) (xy 104.015037 -55.528214)
			(xy 104.027163 -55.473777) (xy 104.047086 -55.421686) (xy 104.074382 -55.373051) (xy 104.108468 -55.328908)
			(xy 104.148617 -55.290199) (xy 104.193975 -55.257748) (xy 104.243575 -55.232247) (xy 104.296359 -55.21424)
			(xy 104.351202 -55.20411) (xy 104.406936 -55.202073) (xy 104.462373 -55.208173) (xy 104.51633 -55.222279)
			(xy 104.567659 -55.244091) (xy 104.615265 -55.273145) (xy 104.658133 -55.30882) (xy 104.669908 -55.321962)
			(xy 118.058182 -55.321962) (xy 118.062253 -55.26634) (xy 118.074379 -55.211903) (xy 118.094302 -55.159812)
			(xy 118.121598 -55.111177) (xy 118.155684 -55.067034) (xy 118.195833 -55.028325) (xy 118.241191 -54.995874)
			(xy 118.290791 -54.970373) (xy 118.343575 -54.952366) (xy 118.398418 -54.942236) (xy 118.454152 -54.940199)
			(xy 118.509589 -54.946299) (xy 118.563546 -54.960405) (xy 118.614875 -54.982217) (xy 118.662481 -55.011271)
			(xy 118.705349 -55.046946) (xy 118.742566 -55.088483) (xy 118.773339 -55.134996) (xy 118.797011 -55.185493)
			(xy 118.813079 -55.2389) (xy 118.821199 -55.294076) (xy 118.821708 -55.321962) (xy 118.821199 -55.349848)
			(xy 118.813079 -55.405024) (xy 118.797011 -55.458431) (xy 118.773339 -55.508928) (xy 118.742566 -55.555441)
			(xy 118.705349 -55.596978) (xy 118.662481 -55.632653) (xy 118.614875 -55.661707) (xy 118.563546 -55.683519)
			(xy 118.509589 -55.697625) (xy 118.454152 -55.703725) (xy 118.398418 -55.701688) (xy 118.343575 -55.691558)
			(xy 118.290791 -55.673551) (xy 118.241191 -55.64805) (xy 118.195833 -55.615599) (xy 118.155684 -55.57689)
			(xy 118.121598 -55.532747) (xy 118.094302 -55.484112) (xy 118.074379 -55.432021) (xy 118.062253 -55.377584)
			(xy 118.058182 -55.321962) (xy 104.669908 -55.321962) (xy 104.69535 -55.350357) (xy 104.726123 -55.39687)
			(xy 104.749795 -55.447367) (xy 104.765863 -55.500774) (xy 104.773983 -55.55595) (xy 104.774492 -55.583836)
			(xy 104.773983 -55.611722) (xy 104.765863 -55.666898) (xy 104.749795 -55.720305) (xy 104.726123 -55.770802)
			(xy 104.69535 -55.817315) (xy 104.658133 -55.858852) (xy 104.615265 -55.894527) (xy 104.567659 -55.923581)
			(xy 104.51633 -55.945393) (xy 104.462373 -55.959499) (xy 104.406936 -55.965599) (xy 104.351202 -55.963562)
			(xy 104.296359 -55.953432) (xy 104.243575 -55.935425) (xy 104.193975 -55.909924) (xy 104.148617 -55.877473)
			(xy 104.108468 -55.838764) (xy 104.074382 -55.794621) (xy 104.047086 -55.745986) (xy 104.027163 -55.693895)
			(xy 104.015037 -55.639458) (xy 104.010966 -55.583836) (xy 99.09684 -55.583836) (xy 99.092841 -55.59745)
			(xy 99.070193 -55.647028) (xy 99.04072 -55.692879) (xy 99.005021 -55.73407) (xy 98.963825 -55.76976)
			(xy 98.917969 -55.799225) (xy 98.868386 -55.821865) (xy 98.816086 -55.837218) (xy 98.762133 -55.844972)
			(xy 98.73488 -55.845456) (xy 98.710623 -55.84507) (xy 98.662501 -55.838914) (xy 98.615548 -55.826705)
			(xy 98.592894 -55.818024) (xy 98.578852 -55.812865) (xy 98.549063 -55.810214) (xy 98.519782 -55.816304)
			(xy 98.493521 -55.830612) (xy 98.472527 -55.851912) (xy 98.458602 -55.878379) (xy 98.452939 -55.907744)
			(xy 98.453956 -55.922672) (xy 98.454901 -55.932423) (xy 98.455918 -55.951991) (xy 98.455988 -55.961788)
			(xy 98.455535 -55.98904) (xy 98.44778 -56.042989) (xy 98.432426 -56.095286) (xy 98.409786 -56.144865)
			(xy 98.380321 -56.190718) (xy 98.34463 -56.231911) (xy 98.325131 -56.248808) (xy 106.859322 -56.248808)
			(xy 106.863393 -56.193186) (xy 106.875519 -56.138749) (xy 106.895442 -56.086658) (xy 106.922738 -56.038023)
			(xy 106.956824 -55.99388) (xy 106.996973 -55.955171) (xy 107.042331 -55.92272) (xy 107.091931 -55.897219)
			(xy 107.144715 -55.879212) (xy 107.199558 -55.869082) (xy 107.255292 -55.867045) (xy 107.310729 -55.873145)
			(xy 107.364686 -55.887251) (xy 107.416015 -55.909063) (xy 107.463621 -55.938117) (xy 107.504273 -55.971948)
			(xy 126.287782 -55.971948) (xy 126.291853 -55.916326) (xy 126.303979 -55.861889) (xy 126.323902 -55.809798)
			(xy 126.351198 -55.761163) (xy 126.385284 -55.71702) (xy 126.425433 -55.678311) (xy 126.470791 -55.64586)
			(xy 126.520391 -55.620359) (xy 126.573175 -55.602352) (xy 126.628018 -55.592222) (xy 126.683752 -55.590185)
			(xy 126.739189 -55.596285) (xy 126.793146 -55.610391) (xy 126.844475 -55.632203) (xy 126.892081 -55.661257)
			(xy 126.908316 -55.674768) (xy 131.360162 -55.674768) (xy 131.364233 -55.619146) (xy 131.376359 -55.564709)
			(xy 131.396282 -55.512618) (xy 131.423578 -55.463983) (xy 131.457664 -55.41984) (xy 131.497813 -55.381131)
			(xy 131.543171 -55.34868) (xy 131.592771 -55.323179) (xy 131.645555 -55.305172) (xy 131.700398 -55.295042)
			(xy 131.756132 -55.293005) (xy 131.811569 -55.299105) (xy 131.865526 -55.313211) (xy 131.916855 -55.335023)
			(xy 131.942483 -55.350664) (xy 143.927828 -55.350664) (xy 143.931899 -55.295042) (xy 143.944025 -55.240605)
			(xy 143.963948 -55.188514) (xy 143.991244 -55.139879) (xy 144.02533 -55.095736) (xy 144.065479 -55.057027)
			(xy 144.110837 -55.024576) (xy 144.160437 -54.999075) (xy 144.213221 -54.981068) (xy 144.268064 -54.970938)
			(xy 144.323798 -54.968901) (xy 144.379235 -54.975001) (xy 144.433192 -54.989107) (xy 144.484521 -55.010919)
			(xy 144.532127 -55.039973) (xy 144.574995 -55.075648) (xy 144.612212 -55.117185) (xy 144.642985 -55.163698)
			(xy 144.666657 -55.214195) (xy 144.682725 -55.267602) (xy 144.690845 -55.322778) (xy 144.691354 -55.350664)
			(xy 144.690845 -55.37855) (xy 144.682725 -55.433726) (xy 144.666657 -55.487133) (xy 144.653712 -55.514748)
			(xy 146.544792 -55.514748) (xy 146.545278 -55.487497) (xy 146.553034 -55.433549) (xy 146.568389 -55.381254)
			(xy 146.591031 -55.331677) (xy 146.620497 -55.285827) (xy 146.656188 -55.244636) (xy 146.697379 -55.208945)
			(xy 146.743229 -55.179479) (xy 146.792806 -55.156837) (xy 146.845101 -55.141482) (xy 146.899049 -55.133726)
			(xy 146.953551 -55.133726) (xy 147.007499 -55.141482) (xy 147.059794 -55.156837) (xy 147.109371 -55.179479)
			(xy 147.155221 -55.208945) (xy 147.196412 -55.244636) (xy 147.232103 -55.285827) (xy 147.261569 -55.331677)
			(xy 147.284211 -55.381254) (xy 147.299566 -55.433549) (xy 147.307322 -55.487497) (xy 147.307808 -55.514748)
			(xy 147.307279 -55.543108) (xy 147.298865 -55.5992) (xy 147.282232 -55.653425) (xy 147.257744 -55.704587)
			(xy 147.242276 -55.728362) (xy 147.234399 -55.740895) (xy 147.225489 -55.769108) (xy 147.225419 -55.773828)
			(xy 149.810722 -55.773828) (xy 149.814793 -55.718206) (xy 149.826919 -55.663769) (xy 149.846842 -55.611678)
			(xy 149.874138 -55.563043) (xy 149.908224 -55.5189) (xy 149.948373 -55.480191) (xy 149.993731 -55.44774)
			(xy 150.043331 -55.422239) (xy 150.096115 -55.404232) (xy 150.150958 -55.394102) (xy 150.206692 -55.392065)
			(xy 150.262129 -55.398165) (xy 150.316086 -55.412271) (xy 150.367415 -55.434083) (xy 150.415021 -55.463137)
			(xy 150.457889 -55.498812) (xy 150.495106 -55.540349) (xy 150.525879 -55.586862) (xy 150.549551 -55.637359)
			(xy 150.565619 -55.690766) (xy 150.573739 -55.745942) (xy 150.574248 -55.773828) (xy 150.573739 -55.801714)
			(xy 150.565619 -55.85689) (xy 150.549551 -55.910297) (xy 150.525879 -55.960794) (xy 150.495106 -56.007307)
			(xy 150.477322 -56.027155) (xy 159.316343 -56.027155) (xy 159.316343 -55.972645) (xy 159.324101 -55.918691)
			(xy 159.339458 -55.86639) (xy 159.362103 -55.816807) (xy 159.391574 -55.770951) (xy 159.427271 -55.729757)
			(xy 159.468467 -55.694062) (xy 159.514324 -55.664593) (xy 159.563909 -55.641951) (xy 159.61621 -55.626596)
			(xy 159.670165 -55.618842) (xy 159.69742 -55.61838) (xy 159.726336 -55.618926) (xy 159.783508 -55.627645)
			(xy 159.838707 -55.644895) (xy 159.89067 -55.670282) (xy 159.938204 -55.703222) (xy 159.98022 -55.742961)
			(xy 159.99841 -55.765446) (xy 160.008307 -55.777251) (xy 160.033631 -55.79477) (xy 160.063024 -55.803946)
			(xy 160.093816 -55.803946) (xy 160.123209 -55.79477) (xy 160.148533 -55.777251) (xy 160.15843 -55.765446)
			(xy 160.17659 -55.742937) (xy 160.218618 -55.703206) (xy 160.26616 -55.670271) (xy 160.318127 -55.644888)
			(xy 160.373329 -55.627637) (xy 160.430502 -55.618913) (xy 160.45942 -55.61838) (xy 160.486669 -55.618892)
			(xy 160.540613 -55.62665) (xy 160.592904 -55.642007) (xy 160.642477 -55.664648) (xy 160.688323 -55.694114)
			(xy 160.72951 -55.729804) (xy 160.765198 -55.770993) (xy 160.794662 -55.816841) (xy 160.8173 -55.866415)
			(xy 160.832654 -55.918706) (xy 160.84041 -55.972651) (xy 160.84041 -56.027149) (xy 160.832654 -56.081094)
			(xy 160.8173 -56.133385) (xy 160.794662 -56.182959) (xy 160.765198 -56.228807) (xy 160.72951 -56.269996)
			(xy 160.688323 -56.305686) (xy 160.642477 -56.335152) (xy 160.592904 -56.357793) (xy 160.540613 -56.37315)
			(xy 160.486669 -56.380908) (xy 160.45942 -56.381396) (xy 160.430504 -56.380865) (xy 160.373333 -56.372139)
			(xy 160.318134 -56.354883) (xy 160.266173 -56.329494) (xy 160.218638 -56.296553) (xy 160.176621 -56.256814)
			(xy 160.15843 -56.23433) (xy 160.148533 -56.222525) (xy 160.123209 -56.205006) (xy 160.093816 -56.19583)
			(xy 160.063024 -56.19583) (xy 160.033631 -56.205006) (xy 160.008307 -56.222525) (xy 159.99841 -56.23433)
			(xy 159.980221 -56.256815) (xy 159.9382 -56.296549) (xy 159.890664 -56.329487) (xy 159.838703 -56.354874)
			(xy 159.783505 -56.372131) (xy 159.726336 -56.38086) (xy 159.69742 -56.381396) (xy 159.670165 -56.380958)
			(xy 159.61621 -56.373204) (xy 159.563909 -56.357849) (xy 159.514324 -56.335207) (xy 159.468467 -56.305738)
			(xy 159.427271 -56.270043) (xy 159.391574 -56.228849) (xy 159.362103 -56.182993) (xy 159.339458 -56.13341)
			(xy 159.324101 -56.081109) (xy 159.316343 -56.027155) (xy 150.477322 -56.027155) (xy 150.457889 -56.048844)
			(xy 150.415021 -56.084519) (xy 150.367415 -56.113573) (xy 150.316086 -56.135385) (xy 150.262129 -56.149491)
			(xy 150.206692 -56.155591) (xy 150.150958 -56.153554) (xy 150.096115 -56.143424) (xy 150.043331 -56.125417)
			(xy 149.993731 -56.099916) (xy 149.948373 -56.067465) (xy 149.908224 -56.028756) (xy 149.874138 -55.984613)
			(xy 149.846842 -55.935978) (xy 149.826919 -55.883887) (xy 149.814793 -55.82945) (xy 149.810722 -55.773828)
			(xy 147.225419 -55.773828) (xy 147.225049 -55.798692) (xy 147.233117 -55.827158) (xy 147.249014 -55.852112)
			(xy 147.271402 -55.871454) (xy 147.284694 -55.877968) (xy 147.30948 -55.889639) (xy 147.355712 -55.919031)
			(xy 147.397267 -55.954732) (xy 147.43329 -55.996007) (xy 147.46304 -56.04201) (xy 147.485907 -56.091794)
			(xy 147.501421 -56.144336) (xy 147.509262 -56.198556) (xy 147.509738 -56.225948) (xy 147.509252 -56.253199)
			(xy 147.501496 -56.307147) (xy 147.486141 -56.359442) (xy 147.463499 -56.409019) (xy 147.434033 -56.454869)
			(xy 147.398342 -56.49606) (xy 147.357151 -56.531751) (xy 147.311301 -56.561217) (xy 147.261724 -56.583859)
			(xy 147.209429 -56.599214) (xy 147.155481 -56.60697) (xy 147.100979 -56.60697) (xy 147.047031 -56.599214)
			(xy 146.994736 -56.583859) (xy 146.945159 -56.561217) (xy 146.899309 -56.531751) (xy 146.858118 -56.49606)
			(xy 146.822427 -56.454869) (xy 146.792961 -56.409019) (xy 146.770319 -56.359442) (xy 146.754964 -56.307147)
			(xy 146.747208 -56.253199) (xy 146.746722 -56.225948) (xy 146.747244 -56.197588) (xy 146.755659 -56.141496)
			(xy 146.772295 -56.08727) (xy 146.796784 -56.036109) (xy 146.812254 -56.012334) (xy 146.820123 -55.999797)
			(xy 146.829028 -55.971585) (xy 146.829466 -55.942005) (xy 146.8214 -55.913542) (xy 146.805508 -55.888589)
			(xy 146.783125 -55.869244) (xy 146.769836 -55.862728) (xy 146.745055 -55.851046) (xy 146.698822 -55.821657)
			(xy 146.657266 -55.785959) (xy 146.621242 -55.744685) (xy 146.59149 -55.698684) (xy 146.568623 -55.648901)
			(xy 146.553109 -55.59636) (xy 146.545268 -55.54214) (xy 146.544792 -55.514748) (xy 144.653712 -55.514748)
			(xy 144.642985 -55.53763) (xy 144.612212 -55.584143) (xy 144.574995 -55.62568) (xy 144.532127 -55.661355)
			(xy 144.484521 -55.690409) (xy 144.433192 -55.712221) (xy 144.379235 -55.726327) (xy 144.323798 -55.732427)
			(xy 144.268064 -55.73039) (xy 144.213221 -55.72026) (xy 144.160437 -55.702253) (xy 144.110837 -55.676752)
			(xy 144.065479 -55.644301) (xy 144.02533 -55.605592) (xy 143.991244 -55.561449) (xy 143.963948 -55.512814)
			(xy 143.944025 -55.460723) (xy 143.931899 -55.406286) (xy 143.927828 -55.350664) (xy 131.942483 -55.350664)
			(xy 131.964461 -55.364077) (xy 132.007329 -55.399752) (xy 132.044546 -55.441289) (xy 132.075319 -55.487802)
			(xy 132.098991 -55.538299) (xy 132.115059 -55.591706) (xy 132.123179 -55.646882) (xy 132.123688 -55.674768)
			(xy 132.123179 -55.702654) (xy 132.115059 -55.75783) (xy 132.098991 -55.811237) (xy 132.075319 -55.861734)
			(xy 132.044546 -55.908247) (xy 132.007329 -55.949784) (xy 131.964461 -55.985459) (xy 131.916855 -56.014513)
			(xy 131.865526 -56.036325) (xy 131.811569 -56.050431) (xy 131.756132 -56.056531) (xy 131.700398 -56.054494)
			(xy 131.645555 -56.044364) (xy 131.592771 -56.026357) (xy 131.543171 -56.000856) (xy 131.497813 -55.968405)
			(xy 131.457664 -55.929696) (xy 131.423578 -55.885553) (xy 131.396282 -55.836918) (xy 131.376359 -55.784827)
			(xy 131.364233 -55.73039) (xy 131.360162 -55.674768) (xy 126.908316 -55.674768) (xy 126.934949 -55.696932)
			(xy 126.972166 -55.738469) (xy 127.002939 -55.784982) (xy 127.026611 -55.835479) (xy 127.042679 -55.888886)
			(xy 127.050799 -55.944062) (xy 127.051308 -55.971948) (xy 127.050799 -55.999834) (xy 127.042679 -56.05501)
			(xy 127.026611 -56.108417) (xy 127.002939 -56.158914) (xy 126.972166 -56.205427) (xy 126.953779 -56.225948)
			(xy 143.821402 -56.225948) (xy 143.825473 -56.170326) (xy 143.837599 -56.115889) (xy 143.857522 -56.063798)
			(xy 143.884818 -56.015163) (xy 143.918904 -55.97102) (xy 143.959053 -55.932311) (xy 144.004411 -55.89986)
			(xy 144.054011 -55.874359) (xy 144.106795 -55.856352) (xy 144.161638 -55.846222) (xy 144.217372 -55.844185)
			(xy 144.272809 -55.850285) (xy 144.326766 -55.864391) (xy 144.378095 -55.886203) (xy 144.425701 -55.915257)
			(xy 144.468569 -55.950932) (xy 144.505786 -55.992469) (xy 144.536559 -56.038982) (xy 144.560231 -56.089479)
			(xy 144.576299 -56.142886) (xy 144.584419 -56.198062) (xy 144.584928 -56.225948) (xy 144.584419 -56.253834)
			(xy 144.576299 -56.30901) (xy 144.560231 -56.362417) (xy 144.536559 -56.412914) (xy 144.505786 -56.459427)
			(xy 144.468569 -56.500964) (xy 144.425701 -56.536639) (xy 144.378095 -56.565693) (xy 144.326766 -56.587505)
			(xy 144.272809 -56.601611) (xy 144.217372 -56.607711) (xy 144.161638 -56.605674) (xy 144.106795 -56.595544)
			(xy 144.054011 -56.577537) (xy 144.004411 -56.552036) (xy 143.959053 -56.519585) (xy 143.918904 -56.480876)
			(xy 143.884818 -56.436733) (xy 143.857522 -56.388098) (xy 143.837599 -56.336007) (xy 143.825473 -56.28157)
			(xy 143.821402 -56.225948) (xy 126.953779 -56.225948) (xy 126.934949 -56.246964) (xy 126.892081 -56.282639)
			(xy 126.844475 -56.311693) (xy 126.793146 -56.333505) (xy 126.739189 -56.347611) (xy 126.683752 -56.353711)
			(xy 126.628018 -56.351674) (xy 126.573175 -56.341544) (xy 126.520391 -56.323537) (xy 126.470791 -56.298036)
			(xy 126.425433 -56.265585) (xy 126.385284 -56.226876) (xy 126.351198 -56.182733) (xy 126.323902 -56.134098)
			(xy 126.303979 -56.082007) (xy 126.291853 -56.02757) (xy 126.287782 -55.971948) (xy 107.504273 -55.971948)
			(xy 107.506489 -55.973792) (xy 107.543706 -56.015329) (xy 107.574479 -56.061842) (xy 107.598151 -56.112339)
			(xy 107.614219 -56.165746) (xy 107.622339 -56.220922) (xy 107.622848 -56.248808) (xy 107.622339 -56.276694)
			(xy 107.614219 -56.33187) (xy 107.598151 -56.385277) (xy 107.574479 -56.435774) (xy 107.545253 -56.479948)
			(xy 114.552982 -56.479948) (xy 114.557053 -56.424326) (xy 114.569179 -56.369889) (xy 114.589102 -56.317798)
			(xy 114.616398 -56.269163) (xy 114.650484 -56.22502) (xy 114.690633 -56.186311) (xy 114.735991 -56.15386)
			(xy 114.785591 -56.128359) (xy 114.838375 -56.110352) (xy 114.893218 -56.100222) (xy 114.948952 -56.098185)
			(xy 115.004389 -56.104285) (xy 115.058346 -56.118391) (xy 115.109675 -56.140203) (xy 115.157281 -56.169257)
			(xy 115.200149 -56.204932) (xy 115.237366 -56.246469) (xy 115.268139 -56.292982) (xy 115.291811 -56.343479)
			(xy 115.307879 -56.396886) (xy 115.315999 -56.452062) (xy 115.316508 -56.479948) (xy 115.315999 -56.507834)
			(xy 115.307879 -56.56301) (xy 115.291811 -56.616417) (xy 115.289225 -56.621934) (xy 116.940582 -56.621934)
			(xy 116.944653 -56.566312) (xy 116.956779 -56.511875) (xy 116.976702 -56.459784) (xy 117.003998 -56.411149)
			(xy 117.038084 -56.367006) (xy 117.078233 -56.328297) (xy 117.123591 -56.295846) (xy 117.173191 -56.270345)
			(xy 117.225975 -56.252338) (xy 117.280818 -56.242208) (xy 117.336552 -56.240171) (xy 117.391989 -56.246271)
			(xy 117.445946 -56.260377) (xy 117.497275 -56.282189) (xy 117.544881 -56.311243) (xy 117.587749 -56.346918)
			(xy 117.624966 -56.388455) (xy 117.655739 -56.434968) (xy 117.679411 -56.485465) (xy 117.695479 -56.538872)
			(xy 117.703599 -56.594048) (xy 117.704108 -56.621934) (xy 127.405382 -56.621934) (xy 127.409453 -56.566312)
			(xy 127.421579 -56.511875) (xy 127.441502 -56.459784) (xy 127.468798 -56.411149) (xy 127.502884 -56.367006)
			(xy 127.543033 -56.328297) (xy 127.588391 -56.295846) (xy 127.637991 -56.270345) (xy 127.690775 -56.252338)
			(xy 127.745618 -56.242208) (xy 127.801352 -56.240171) (xy 127.856789 -56.246271) (xy 127.910746 -56.260377)
			(xy 127.962075 -56.282189) (xy 128.009681 -56.311243) (xy 128.052549 -56.346918) (xy 128.089766 -56.388455)
			(xy 128.120539 -56.434968) (xy 128.144211 -56.485465) (xy 128.160279 -56.538872) (xy 128.168399 -56.594048)
			(xy 128.168908 -56.621934) (xy 128.168399 -56.64982) (xy 128.160279 -56.704996) (xy 128.151569 -56.733948)
			(xy 129.792982 -56.733948) (xy 129.797053 -56.678326) (xy 129.809179 -56.623889) (xy 129.829102 -56.571798)
			(xy 129.856398 -56.523163) (xy 129.890484 -56.47902) (xy 129.930633 -56.440311) (xy 129.975991 -56.40786)
			(xy 130.025591 -56.382359) (xy 130.078375 -56.364352) (xy 130.133218 -56.354222) (xy 130.188952 -56.352185)
			(xy 130.244389 -56.358285) (xy 130.298346 -56.372391) (xy 130.349675 -56.394203) (xy 130.397281 -56.423257)
			(xy 130.440149 -56.458932) (xy 130.477366 -56.500469) (xy 130.508139 -56.546982) (xy 130.531811 -56.597479)
			(xy 130.547879 -56.650886) (xy 130.555999 -56.706062) (xy 130.556508 -56.733948) (xy 130.555999 -56.761834)
			(xy 130.547879 -56.81701) (xy 130.531811 -56.870417) (xy 130.508139 -56.920914) (xy 130.477366 -56.967427)
			(xy 130.440149 -57.008964) (xy 130.397281 -57.044639) (xy 130.349675 -57.073693) (xy 130.298346 -57.095505)
			(xy 130.244389 -57.109611) (xy 130.188952 -57.115711) (xy 130.133218 -57.113674) (xy 130.078375 -57.103544)
			(xy 130.025591 -57.085537) (xy 129.975991 -57.060036) (xy 129.930633 -57.027585) (xy 129.890484 -56.988876)
			(xy 129.856398 -56.944733) (xy 129.829102 -56.896098) (xy 129.809179 -56.844007) (xy 129.797053 -56.78957)
			(xy 129.792982 -56.733948) (xy 128.151569 -56.733948) (xy 128.144211 -56.758403) (xy 128.120539 -56.8089)
			(xy 128.089766 -56.855413) (xy 128.052549 -56.89695) (xy 128.009681 -56.932625) (xy 127.962075 -56.961679)
			(xy 127.910746 -56.983491) (xy 127.856789 -56.997597) (xy 127.801352 -57.003697) (xy 127.745618 -57.00166)
			(xy 127.690775 -56.99153) (xy 127.637991 -56.973523) (xy 127.588391 -56.948022) (xy 127.543033 -56.915571)
			(xy 127.502884 -56.876862) (xy 127.468798 -56.832719) (xy 127.441502 -56.784084) (xy 127.421579 -56.731993)
			(xy 127.409453 -56.677556) (xy 127.405382 -56.621934) (xy 117.704108 -56.621934) (xy 117.703599 -56.64982)
			(xy 117.695479 -56.704996) (xy 117.679411 -56.758403) (xy 117.655739 -56.8089) (xy 117.624966 -56.855413)
			(xy 117.587749 -56.89695) (xy 117.544881 -56.932625) (xy 117.497275 -56.961679) (xy 117.445946 -56.983491)
			(xy 117.391989 -56.997597) (xy 117.336552 -57.003697) (xy 117.280818 -57.00166) (xy 117.225975 -56.99153)
			(xy 117.173191 -56.973523) (xy 117.123591 -56.948022) (xy 117.078233 -56.915571) (xy 117.038084 -56.876862)
			(xy 117.003998 -56.832719) (xy 116.976702 -56.784084) (xy 116.956779 -56.731993) (xy 116.944653 -56.677556)
			(xy 116.940582 -56.621934) (xy 115.289225 -56.621934) (xy 115.268139 -56.666914) (xy 115.237366 -56.713427)
			(xy 115.200149 -56.754964) (xy 115.157281 -56.790639) (xy 115.109675 -56.819693) (xy 115.058346 -56.841505)
			(xy 115.004389 -56.855611) (xy 114.948952 -56.861711) (xy 114.893218 -56.859674) (xy 114.838375 -56.849544)
			(xy 114.785591 -56.831537) (xy 114.735991 -56.806036) (xy 114.690633 -56.773585) (xy 114.650484 -56.734876)
			(xy 114.616398 -56.690733) (xy 114.589102 -56.642098) (xy 114.569179 -56.590007) (xy 114.557053 -56.53557)
			(xy 114.552982 -56.479948) (xy 107.545253 -56.479948) (xy 107.543706 -56.482287) (xy 107.506489 -56.523824)
			(xy 107.463621 -56.559499) (xy 107.416015 -56.588553) (xy 107.364686 -56.610365) (xy 107.310729 -56.624471)
			(xy 107.255292 -56.630571) (xy 107.199558 -56.628534) (xy 107.144715 -56.618404) (xy 107.091931 -56.600397)
			(xy 107.042331 -56.574896) (xy 106.996973 -56.542445) (xy 106.956824 -56.503736) (xy 106.922738 -56.459593)
			(xy 106.895442 -56.410958) (xy 106.875519 -56.358867) (xy 106.863393 -56.30443) (xy 106.859322 -56.248808)
			(xy 98.325131 -56.248808) (xy 98.303439 -56.267605) (xy 98.257589 -56.297073) (xy 98.208011 -56.319717)
			(xy 98.155716 -56.335074) (xy 98.101767 -56.342833) (xy 98.047263 -56.342835) (xy 97.993313 -56.335081)
			(xy 97.941016 -56.319727) (xy 97.891437 -56.297087) (xy 97.845584 -56.267622) (xy 97.804391 -56.231931)
			(xy 97.768697 -56.190742) (xy 97.739228 -56.144891) (xy 97.716584 -56.095314) (xy 97.701226 -56.043018)
			(xy 97.693467 -55.989069) (xy 97.693465 -55.934565) (xy 95.811712 -55.934565) (xy 95.831379 -55.950932)
			(xy 95.868596 -55.992469) (xy 95.899369 -56.038982) (xy 95.923041 -56.089479) (xy 95.939109 -56.142886)
			(xy 95.947229 -56.198062) (xy 95.947738 -56.225948) (xy 95.947229 -56.253834) (xy 95.939109 -56.30901)
			(xy 95.923041 -56.362417) (xy 95.899369 -56.412914) (xy 95.868596 -56.459427) (xy 95.831379 -56.500964)
			(xy 95.788511 -56.536639) (xy 95.740905 -56.565693) (xy 95.689576 -56.587505) (xy 95.635619 -56.601611)
			(xy 95.580182 -56.607711) (xy 95.524448 -56.605674) (xy 95.469605 -56.595544) (xy 95.416821 -56.577537)
			(xy 95.367221 -56.552036) (xy 95.321863 -56.519585) (xy 95.281714 -56.480876) (xy 95.247628 -56.436733)
			(xy 95.220332 -56.388098) (xy 95.200409 -56.336007) (xy 95.188283 -56.28157) (xy 95.184212 -56.225948)
			(xy 85.514694 -56.225948) (xy 85.527787 -56.245738) (xy 85.551459 -56.296235) (xy 85.567527 -56.349642)
			(xy 85.575647 -56.404818) (xy 85.576156 -56.432704) (xy 85.575647 -56.46059) (xy 85.567527 -56.515766)
			(xy 85.551459 -56.569173) (xy 85.527787 -56.61967) (xy 85.497014 -56.666183) (xy 85.459797 -56.70772)
			(xy 85.416929 -56.743395) (xy 85.369323 -56.772449) (xy 85.317994 -56.794261) (xy 85.264037 -56.808367)
			(xy 85.2086 -56.814467) (xy 85.152866 -56.81243) (xy 85.098023 -56.8023) (xy 85.045239 -56.784293)
			(xy 84.995639 -56.758792) (xy 84.950281 -56.726341) (xy 84.910132 -56.687632) (xy 84.876046 -56.643489)
			(xy 84.84875 -56.594854) (xy 84.828827 -56.542763) (xy 84.816701 -56.488326) (xy 84.81263 -56.432704)
			(xy 6.055868 -56.432704) (xy 6.055868 -56.520334) (xy 6.056404 -56.535813) (xy 6.065657 -56.565356)
			(xy 6.083334 -56.59077) (xy 6.107812 -56.609724) (xy 6.136842 -56.620475) (xy 6.167761 -56.622038)
			(xy 6.182868 -56.618632) (xy 6.206456 -56.612905) (xy 6.254609 -56.606789) (xy 6.27888 -56.60644)
			(xy 6.306131 -56.606926) (xy 6.360079 -56.614682) (xy 6.412374 -56.630038) (xy 6.461952 -56.652679)
			(xy 6.507803 -56.682145) (xy 6.548993 -56.717837) (xy 6.584685 -56.759027) (xy 6.614151 -56.804878)
			(xy 6.636792 -56.854456) (xy 6.652148 -56.906751) (xy 6.659904 -56.960699) (xy 6.659904 -56.999886)
			(xy 10.412982 -56.999886) (xy 10.417053 -56.944264) (xy 10.429179 -56.889827) (xy 10.449102 -56.837736)
			(xy 10.476398 -56.789101) (xy 10.510484 -56.744958) (xy 10.550633 -56.706249) (xy 10.595991 -56.673798)
			(xy 10.645591 -56.648297) (xy 10.698375 -56.63029) (xy 10.753218 -56.62016) (xy 10.808952 -56.618123)
			(xy 10.864389 -56.624223) (xy 10.918346 -56.638329) (xy 10.969675 -56.660141) (xy 11.017281 -56.689195)
			(xy 11.060149 -56.72487) (xy 11.097366 -56.766407) (xy 11.128139 -56.81292) (xy 11.151811 -56.863417)
			(xy 11.167879 -56.916824) (xy 11.175999 -56.972) (xy 11.176508 -56.999886) (xy 21.451822 -56.999886)
			(xy 21.455893 -56.944264) (xy 21.468019 -56.889827) (xy 21.487942 -56.837736) (xy 21.515238 -56.789101)
			(xy 21.549324 -56.744958) (xy 21.589473 -56.706249) (xy 21.634831 -56.673798) (xy 21.684431 -56.648297)
			(xy 21.737215 -56.63029) (xy 21.792058 -56.62016) (xy 21.847792 -56.618123) (xy 21.903229 -56.624223)
			(xy 21.957186 -56.638329) (xy 22.008515 -56.660141) (xy 22.056121 -56.689195) (xy 22.098989 -56.72487)
			(xy 22.136206 -56.766407) (xy 22.166979 -56.81292) (xy 22.190651 -56.863417) (xy 22.206719 -56.916824)
			(xy 22.214839 -56.972) (xy 22.215348 -56.999886) (xy 22.214839 -57.027772) (xy 22.206719 -57.082948)
			(xy 22.190651 -57.136355) (xy 22.166979 -57.186852) (xy 22.136206 -57.233365) (xy 22.098989 -57.274902)
			(xy 22.056121 -57.310577) (xy 22.008515 -57.339631) (xy 21.957186 -57.361443) (xy 21.903229 -57.375549)
			(xy 21.847792 -57.381649) (xy 21.792058 -57.379612) (xy 21.737215 -57.369482) (xy 21.684431 -57.351475)
			(xy 21.634831 -57.325974) (xy 21.589473 -57.293523) (xy 21.549324 -57.254814) (xy 21.515238 -57.210671)
			(xy 21.487942 -57.162036) (xy 21.468019 -57.109945) (xy 21.455893 -57.055508) (xy 21.451822 -56.999886)
			(xy 11.176508 -56.999886) (xy 11.175999 -57.027772) (xy 11.167879 -57.082948) (xy 11.151811 -57.136355)
			(xy 11.128139 -57.186852) (xy 11.097366 -57.233365) (xy 11.060149 -57.274902) (xy 11.017281 -57.310577)
			(xy 10.969675 -57.339631) (xy 10.918346 -57.361443) (xy 10.864389 -57.375549) (xy 10.808952 -57.381649)
			(xy 10.753218 -57.379612) (xy 10.698375 -57.369482) (xy 10.645591 -57.351475) (xy 10.595991 -57.325974)
			(xy 10.550633 -57.293523) (xy 10.510484 -57.254814) (xy 10.476398 -57.210671) (xy 10.449102 -57.162036)
			(xy 10.429179 -57.109945) (xy 10.417053 -57.055508) (xy 10.412982 -56.999886) (xy 6.659904 -56.999886)
			(xy 6.659904 -57.015201) (xy 6.652148 -57.069149) (xy 6.636792 -57.121444) (xy 6.614151 -57.171022)
			(xy 6.584685 -57.216873) (xy 6.548993 -57.258063) (xy 6.507803 -57.293755) (xy 6.461952 -57.323221)
			(xy 6.412374 -57.345862) (xy 6.360079 -57.361218) (xy 6.306131 -57.368974) (xy 6.27888 -57.369456)
			(xy 6.25461 -57.369092) (xy 6.206458 -57.362978) (xy 6.182868 -57.357264) (xy 6.167754 -57.35393)
			(xy 6.136859 -57.355519) (xy 6.107852 -57.366271) (xy 6.083387 -57.385205) (xy 6.065701 -57.410586)
			(xy 6.056412 -57.440095) (xy 6.055868 -57.455562) (xy 6.055868 -57.750964) (xy 7.439912 -57.750964)
			(xy 7.443983 -57.695342) (xy 7.456109 -57.640905) (xy 7.476032 -57.588814) (xy 7.503328 -57.540179)
			(xy 7.537414 -57.496036) (xy 7.577563 -57.457327) (xy 7.622921 -57.424876) (xy 7.672521 -57.399375)
			(xy 7.725305 -57.381368) (xy 7.780148 -57.371238) (xy 7.835882 -57.369201) (xy 7.891319 -57.375301)
			(xy 7.945276 -57.389407) (xy 7.996605 -57.411219) (xy 8.044211 -57.440273) (xy 8.087079 -57.475948)
			(xy 8.124296 -57.517485) (xy 8.155069 -57.563998) (xy 8.178741 -57.614495) (xy 8.194809 -57.667902)
			(xy 8.202929 -57.723078) (xy 8.203438 -57.750964) (xy 8.203373 -57.75452) (xy 8.660382 -57.75452)
			(xy 8.664453 -57.698898) (xy 8.676579 -57.644461) (xy 8.696502 -57.59237) (xy 8.723798 -57.543735)
			(xy 8.757884 -57.499592) (xy 8.798033 -57.460883) (xy 8.843391 -57.428432) (xy 8.892991 -57.402931)
			(xy 8.945775 -57.384924) (xy 9.000618 -57.374794) (xy 9.056352 -57.372757) (xy 9.111789 -57.378857)
			(xy 9.165746 -57.392963) (xy 9.217075 -57.414775) (xy 9.264681 -57.443829) (xy 9.307549 -57.479504)
			(xy 9.344766 -57.521041) (xy 9.375539 -57.567554) (xy 9.399211 -57.618051) (xy 9.415279 -57.671458)
			(xy 9.423399 -57.726634) (xy 9.423908 -57.75452) (xy 9.423399 -57.782406) (xy 9.415279 -57.837582)
			(xy 9.399211 -57.890989) (xy 9.375539 -57.941486) (xy 9.367823 -57.953148) (xy 77.573632 -57.953148)
			(xy 77.574173 -57.924232) (xy 77.582895 -57.867061) (xy 77.600148 -57.811862) (xy 77.625535 -57.7599)
			(xy 77.658476 -57.712366) (xy 77.698214 -57.670348) (xy 77.720698 -57.652158) (xy 77.732454 -57.642207)
			(xy 77.749971 -57.616898) (xy 77.75915 -57.587519) (xy 77.759159 -57.55674) (xy 77.749997 -57.527355)
			(xy 77.732495 -57.502036) (xy 77.720698 -57.492138) (xy 77.698232 -57.473926) (xy 77.658496 -57.431911)
			(xy 77.625555 -57.38438) (xy 77.600164 -57.332423) (xy 77.582903 -57.277229) (xy 77.57417 -57.220063)
			(xy 77.573632 -57.191148) (xy 77.5741 -57.163895) (xy 77.581852 -57.109942) (xy 77.597204 -57.057641)
			(xy 77.619843 -57.008059) (xy 77.64931 -56.962204) (xy 77.685004 -56.921009) (xy 77.726197 -56.885315)
			(xy 77.772052 -56.855847) (xy 77.821634 -56.833206) (xy 77.873934 -56.817853) (xy 77.927887 -56.810101)
			(xy 77.95514 -56.80964) (xy 77.984056 -56.810186) (xy 78.041227 -56.818907) (xy 78.096426 -56.836159)
			(xy 78.148388 -56.861545) (xy 78.195922 -56.894484) (xy 78.23794 -56.934222) (xy 78.25613 -56.956706)
			(xy 78.266027 -56.968511) (xy 78.291351 -56.98603) (xy 78.320744 -56.995206) (xy 78.351536 -56.995206)
			(xy 78.380929 -56.98603) (xy 78.406253 -56.968511) (xy 78.41615 -56.956706) (xy 78.434371 -56.934248)
			(xy 78.476384 -56.894511) (xy 78.523913 -56.861569) (xy 78.575868 -56.836176) (xy 78.631061 -56.818914)
			(xy 78.688226 -56.810179) (xy 78.71714 -56.80964) (xy 78.744396 -56.810018) (xy 78.798353 -56.817781)
			(xy 78.848459 -56.8325) (xy 80.826354 -56.8325) (xy 80.830425 -56.776878) (xy 80.842551 -56.722441)
			(xy 80.862474 -56.67035) (xy 80.88977 -56.621715) (xy 80.923856 -56.577572) (xy 80.964005 -56.538863)
			(xy 81.009363 -56.506412) (xy 81.058963 -56.480911) (xy 81.111747 -56.462904) (xy 81.16659 -56.452774)
			(xy 81.222324 -56.450737) (xy 81.277761 -56.456837) (xy 81.331718 -56.470943) (xy 81.383047 -56.492755)
			(xy 81.430653 -56.521809) (xy 81.473521 -56.557484) (xy 81.510738 -56.599021) (xy 81.541511 -56.645534)
			(xy 81.565183 -56.696031) (xy 81.581251 -56.749438) (xy 81.589371 -56.804614) (xy 81.58988 -56.8325)
			(xy 81.589371 -56.860386) (xy 81.581251 -56.915562) (xy 81.565183 -56.968969) (xy 81.541511 -57.019466)
			(xy 81.510738 -57.065979) (xy 81.473521 -57.107516) (xy 81.464591 -57.114948) (xy 93.991936 -57.114948)
			(xy 93.996007 -57.059326) (xy 94.008133 -57.004889) (xy 94.028056 -56.952798) (xy 94.055352 -56.904163)
			(xy 94.089438 -56.86002) (xy 94.129587 -56.821311) (xy 94.174945 -56.78886) (xy 94.224545 -56.763359)
			(xy 94.277329 -56.745352) (xy 94.332172 -56.735222) (xy 94.387906 -56.733185) (xy 94.443343 -56.739285)
			(xy 94.4973 -56.753391) (xy 94.548629 -56.775203) (xy 94.596235 -56.804257) (xy 94.639103 -56.839932)
			(xy 94.67632 -56.881469) (xy 94.707093 -56.927982) (xy 94.730765 -56.978479) (xy 94.746833 -57.031886)
			(xy 94.754953 -57.087062) (xy 94.755462 -57.114948) (xy 94.754953 -57.142834) (xy 94.746833 -57.19801)
			(xy 94.733614 -57.241948) (xy 95.184212 -57.241948) (xy 95.188283 -57.186326) (xy 95.200409 -57.131889)
			(xy 95.220332 -57.079798) (xy 95.247628 -57.031163) (xy 95.281714 -56.98702) (xy 95.321863 -56.948311)
			(xy 95.367221 -56.91586) (xy 95.416821 -56.890359) (xy 95.469605 -56.872352) (xy 95.524448 -56.862222)
			(xy 95.580182 -56.860185) (xy 95.635619 -56.866285) (xy 95.689576 -56.880391) (xy 95.740905 -56.902203)
			(xy 95.788511 -56.931257) (xy 95.831379 -56.966932) (xy 95.868596 -57.008469) (xy 95.899369 -57.054982)
			(xy 95.923041 -57.105479) (xy 95.939109 -57.158886) (xy 95.947229 -57.214062) (xy 95.947738 -57.241948)
			(xy 95.947229 -57.269834) (xy 95.946922 -57.27192) (xy 118.058182 -57.27192) (xy 118.062253 -57.216298)
			(xy 118.074379 -57.161861) (xy 118.094302 -57.10977) (xy 118.121598 -57.061135) (xy 118.155684 -57.016992)
			(xy 118.195833 -56.978283) (xy 118.241191 -56.945832) (xy 118.290791 -56.920331) (xy 118.343575 -56.902324)
			(xy 118.398418 -56.892194) (xy 118.454152 -56.890157) (xy 118.509589 -56.896257) (xy 118.563546 -56.910363)
			(xy 118.614875 -56.932175) (xy 118.662481 -56.961229) (xy 118.705349 -56.996904) (xy 118.742566 -57.038441)
			(xy 118.773339 -57.084954) (xy 118.797011 -57.135451) (xy 118.813079 -57.188858) (xy 118.820892 -57.241948)
			(xy 143.821402 -57.241948) (xy 143.825473 -57.186326) (xy 143.837599 -57.131889) (xy 143.857522 -57.079798)
			(xy 143.884818 -57.031163) (xy 143.918904 -56.98702) (xy 143.959053 -56.948311) (xy 144.004411 -56.91586)
			(xy 144.054011 -56.890359) (xy 144.106795 -56.872352) (xy 144.161638 -56.862222) (xy 144.217372 -56.860185)
			(xy 144.272809 -56.866285) (xy 144.326766 -56.880391) (xy 144.378095 -56.902203) (xy 144.425701 -56.931257)
			(xy 144.468569 -56.966932) (xy 144.505786 -57.008469) (xy 144.536559 -57.054982) (xy 144.560231 -57.105479)
			(xy 144.576299 -57.158886) (xy 144.584419 -57.214062) (xy 144.584928 -57.241948) (xy 146.529042 -57.241948)
			(xy 146.533113 -57.186326) (xy 146.545239 -57.131889) (xy 146.565162 -57.079798) (xy 146.592458 -57.031163)
			(xy 146.626544 -56.98702) (xy 146.666693 -56.948311) (xy 146.712051 -56.91586) (xy 146.761651 -56.890359)
			(xy 146.814435 -56.872352) (xy 146.869278 -56.862222) (xy 146.925012 -56.860185) (xy 146.980449 -56.866285)
			(xy 147.034406 -56.880391) (xy 147.085735 -56.902203) (xy 147.133341 -56.931257) (xy 147.176209 -56.966932)
			(xy 147.213426 -57.008469) (xy 147.236374 -57.043155) (xy 159.316343 -57.043155) (xy 159.316343 -56.988645)
			(xy 159.324101 -56.934691) (xy 159.339458 -56.88239) (xy 159.362103 -56.832807) (xy 159.391574 -56.786951)
			(xy 159.427271 -56.745757) (xy 159.468467 -56.710062) (xy 159.514324 -56.680593) (xy 159.563909 -56.657951)
			(xy 159.61621 -56.642596) (xy 159.670165 -56.634842) (xy 159.69742 -56.63438) (xy 159.726336 -56.634926)
			(xy 159.783508 -56.643645) (xy 159.838707 -56.660895) (xy 159.89067 -56.686282) (xy 159.938204 -56.719222)
			(xy 159.98022 -56.758961) (xy 159.99841 -56.781446) (xy 160.008307 -56.793251) (xy 160.033631 -56.81077)
			(xy 160.063024 -56.819946) (xy 160.093816 -56.819946) (xy 160.123209 -56.81077) (xy 160.148533 -56.793251)
			(xy 160.15843 -56.781446) (xy 160.17659 -56.758937) (xy 160.218618 -56.719206) (xy 160.26616 -56.686271)
			(xy 160.318127 -56.660888) (xy 160.373329 -56.643637) (xy 160.430502 -56.634913) (xy 160.45942 -56.63438)
			(xy 160.486669 -56.634892) (xy 160.540613 -56.64265) (xy 160.592904 -56.658007) (xy 160.642477 -56.680648)
			(xy 160.688323 -56.710114) (xy 160.72951 -56.745804) (xy 160.765198 -56.786993) (xy 160.794662 -56.832841)
			(xy 160.8173 -56.882415) (xy 160.832654 -56.934706) (xy 160.84041 -56.988651) (xy 160.84041 -57.043149)
			(xy 160.832654 -57.097094) (xy 160.8173 -57.149385) (xy 160.794662 -57.198959) (xy 160.765198 -57.244807)
			(xy 160.72951 -57.285996) (xy 160.688323 -57.321686) (xy 160.642477 -57.351152) (xy 160.592904 -57.373793)
			(xy 160.540613 -57.38915) (xy 160.486669 -57.396908) (xy 160.45942 -57.397396) (xy 160.430504 -57.396865)
			(xy 160.373333 -57.388139) (xy 160.318134 -57.370883) (xy 160.266173 -57.345494) (xy 160.218638 -57.312553)
			(xy 160.176621 -57.272814) (xy 160.15843 -57.25033) (xy 160.148533 -57.238525) (xy 160.123209 -57.221006)
			(xy 160.093816 -57.21183) (xy 160.063024 -57.21183) (xy 160.033631 -57.221006) (xy 160.008307 -57.238525)
			(xy 159.99841 -57.25033) (xy 159.980221 -57.272815) (xy 159.9382 -57.312549) (xy 159.890664 -57.345487)
			(xy 159.838703 -57.370874) (xy 159.783505 -57.388131) (xy 159.726336 -57.39686) (xy 159.69742 -57.397396)
			(xy 159.670165 -57.396958) (xy 159.61621 -57.389204) (xy 159.563909 -57.373849) (xy 159.514324 -57.351207)
			(xy 159.468467 -57.321738) (xy 159.427271 -57.286043) (xy 159.391574 -57.244849) (xy 159.362103 -57.198993)
			(xy 159.339458 -57.14941) (xy 159.324101 -57.097109) (xy 159.316343 -57.043155) (xy 147.236374 -57.043155)
			(xy 147.244199 -57.054982) (xy 147.267871 -57.105479) (xy 147.283939 -57.158886) (xy 147.292059 -57.214062)
			(xy 147.292568 -57.241948) (xy 147.292059 -57.269834) (xy 147.283939 -57.32501) (xy 147.267871 -57.378417)
			(xy 147.244199 -57.428914) (xy 147.213426 -57.475427) (xy 147.176209 -57.516964) (xy 147.133341 -57.552639)
			(xy 147.085735 -57.581693) (xy 147.034406 -57.603505) (xy 146.980449 -57.617611) (xy 146.925012 -57.623711)
			(xy 146.869278 -57.621674) (xy 146.814435 -57.611544) (xy 146.761651 -57.593537) (xy 146.712051 -57.568036)
			(xy 146.666693 -57.535585) (xy 146.626544 -57.496876) (xy 146.592458 -57.452733) (xy 146.565162 -57.404098)
			(xy 146.545239 -57.352007) (xy 146.533113 -57.29757) (xy 146.529042 -57.241948) (xy 144.584928 -57.241948)
			(xy 144.584419 -57.269834) (xy 144.576299 -57.32501) (xy 144.560231 -57.378417) (xy 144.536559 -57.428914)
			(xy 144.505786 -57.475427) (xy 144.468569 -57.516964) (xy 144.425701 -57.552639) (xy 144.378095 -57.581693)
			(xy 144.326766 -57.603505) (xy 144.272809 -57.617611) (xy 144.217372 -57.623711) (xy 144.161638 -57.621674)
			(xy 144.106795 -57.611544) (xy 144.054011 -57.593537) (xy 144.004411 -57.568036) (xy 143.959053 -57.535585)
			(xy 143.918904 -57.496876) (xy 143.884818 -57.452733) (xy 143.857522 -57.404098) (xy 143.837599 -57.352007)
			(xy 143.825473 -57.29757) (xy 143.821402 -57.241948) (xy 118.820892 -57.241948) (xy 118.821199 -57.244034)
			(xy 118.821708 -57.27192) (xy 118.821199 -57.299806) (xy 118.813079 -57.354982) (xy 118.797011 -57.408389)
			(xy 118.773339 -57.458886) (xy 118.742566 -57.505399) (xy 118.705349 -57.546936) (xy 118.662481 -57.582611)
			(xy 118.614875 -57.611665) (xy 118.563546 -57.633477) (xy 118.509589 -57.647583) (xy 118.454152 -57.653683)
			(xy 118.398418 -57.651646) (xy 118.343575 -57.641516) (xy 118.290791 -57.623509) (xy 118.241191 -57.598008)
			(xy 118.195833 -57.565557) (xy 118.155684 -57.526848) (xy 118.121598 -57.482705) (xy 118.094302 -57.43407)
			(xy 118.074379 -57.381979) (xy 118.062253 -57.327542) (xy 118.058182 -57.27192) (xy 95.946922 -57.27192)
			(xy 95.939109 -57.32501) (xy 95.923041 -57.378417) (xy 95.899369 -57.428914) (xy 95.868596 -57.475427)
			(xy 95.831379 -57.516964) (xy 95.788511 -57.552639) (xy 95.740905 -57.581693) (xy 95.689576 -57.603505)
			(xy 95.635619 -57.617611) (xy 95.580182 -57.623711) (xy 95.524448 -57.621674) (xy 95.469605 -57.611544)
			(xy 95.416821 -57.593537) (xy 95.367221 -57.568036) (xy 95.321863 -57.535585) (xy 95.281714 -57.496876)
			(xy 95.247628 -57.452733) (xy 95.220332 -57.404098) (xy 95.200409 -57.352007) (xy 95.188283 -57.29757)
			(xy 95.184212 -57.241948) (xy 94.733614 -57.241948) (xy 94.730765 -57.251417) (xy 94.707093 -57.301914)
			(xy 94.67632 -57.348427) (xy 94.639103 -57.389964) (xy 94.596235 -57.425639) (xy 94.548629 -57.454693)
			(xy 94.4973 -57.476505) (xy 94.443343 -57.490611) (xy 94.387906 -57.496711) (xy 94.332172 -57.494674)
			(xy 94.277329 -57.484544) (xy 94.224545 -57.466537) (xy 94.174945 -57.441036) (xy 94.129587 -57.408585)
			(xy 94.089438 -57.369876) (xy 94.055352 -57.325733) (xy 94.028056 -57.277098) (xy 94.008133 -57.225007)
			(xy 93.996007 -57.17057) (xy 93.991936 -57.114948) (xy 81.464591 -57.114948) (xy 81.430653 -57.143191)
			(xy 81.383047 -57.172245) (xy 81.331718 -57.194057) (xy 81.277761 -57.208163) (xy 81.222324 -57.214263)
			(xy 81.16659 -57.212226) (xy 81.111747 -57.202096) (xy 81.058963 -57.184089) (xy 81.009363 -57.158588)
			(xy 80.964005 -57.126137) (xy 80.923856 -57.087428) (xy 80.88977 -57.043285) (xy 80.862474 -56.99465)
			(xy 80.842551 -56.942559) (xy 80.830425 -56.888122) (xy 80.826354 -56.8325) (xy 78.848459 -56.8325)
			(xy 78.850655 -56.833145) (xy 78.900239 -56.855796) (xy 78.946094 -56.885272) (xy 78.987287 -56.920975)
			(xy 79.02298 -56.962177) (xy 79.052447 -57.008039) (xy 79.075086 -57.057628) (xy 79.090437 -57.109934)
			(xy 79.098188 -57.163892) (xy 79.098648 -57.191148) (xy 79.098112 -57.220065) (xy 79.08939 -57.277236)
			(xy 79.072136 -57.332435) (xy 79.046748 -57.384397) (xy 79.013807 -57.431932) (xy 78.974067 -57.473948)
			(xy 78.951582 -57.492138) (xy 78.939732 -57.501985) (xy 78.92222 -57.527324) (xy 78.913053 -57.556729)
			(xy 78.913062 -57.58753) (xy 78.922246 -57.61693) (xy 78.939773 -57.642259) (xy 78.951582 -57.652158)
			(xy 78.974042 -57.670377) (xy 79.013779 -57.712391) (xy 79.046721 -57.759919) (xy 79.072114 -57.811875)
			(xy 79.089375 -57.867068) (xy 79.09811 -57.924234) (xy 79.098648 -57.953148) (xy 79.098167 -57.980399)
			(xy 79.090405 -58.034344) (xy 79.075046 -58.086637) (xy 79.052402 -58.136212) (xy 79.022934 -58.18206)
			(xy 78.987243 -58.223248) (xy 78.978855 -58.230516) (xy 81.573114 -58.230516) (xy 81.577185 -58.174894)
			(xy 81.589311 -58.120457) (xy 81.609234 -58.068366) (xy 81.63653 -58.019731) (xy 81.670616 -57.975588)
			(xy 81.710765 -57.936879) (xy 81.756123 -57.904428) (xy 81.805723 -57.878927) (xy 81.858507 -57.86092)
			(xy 81.91335 -57.85079) (xy 81.969084 -57.848753) (xy 82.024521 -57.854853) (xy 82.078478 -57.868959)
			(xy 82.129807 -57.890771) (xy 82.177413 -57.919825) (xy 82.220281 -57.9555) (xy 82.257498 -57.997037)
			(xy 82.288271 -58.04355) (xy 82.311943 -58.094047) (xy 82.328011 -58.147454) (xy 82.336131 -58.20263)
			(xy 82.33664 -58.230516) (xy 82.336131 -58.258402) (xy 82.328011 -58.313578) (xy 82.311943 -58.366985)
			(xy 82.288271 -58.417482) (xy 82.257498 -58.463995) (xy 82.220281 -58.505532) (xy 82.177413 -58.541207)
			(xy 82.129807 -58.570261) (xy 82.078478 -58.592073) (xy 82.038112 -58.602626) (xy 82.360262 -58.602626)
			(xy 82.360752 -58.575761) (xy 82.368275 -58.522561) (xy 82.38319 -58.470943) (xy 82.405202 -58.42193)
			(xy 82.433875 -58.376491) (xy 82.468641 -58.335526) (xy 82.508813 -58.299845) (xy 82.53095 -58.284618)
			(xy 82.542236 -58.27655) (xy 82.560401 -58.255601) (xy 82.572251 -58.230532) (xy 82.576907 -58.203197)
			(xy 82.574027 -58.175619) (xy 82.563824 -58.149837) (xy 82.547051 -58.127757) (xy 82.536284 -58.11901)
			(xy 82.513279 -58.100862) (xy 82.472606 -58.058685) (xy 82.438859 -58.010784) (xy 82.412833 -57.958288)
			(xy 82.395138 -57.90243) (xy 82.386191 -57.844523) (xy 82.385662 -57.815226) (xy 82.386148 -57.787975)
			(xy 82.393904 -57.734027) (xy 82.409259 -57.681732) (xy 82.431901 -57.632155) (xy 82.461367 -57.586305)
			(xy 82.497058 -57.545114) (xy 82.538249 -57.509423) (xy 82.584099 -57.479957) (xy 82.633676 -57.457315)
			(xy 82.685971 -57.44196) (xy 82.739919 -57.434204) (xy 82.794421 -57.434204) (xy 82.848369 -57.44196)
			(xy 82.900664 -57.457315) (xy 82.950241 -57.479957) (xy 82.996091 -57.509423) (xy 83.037282 -57.545114)
			(xy 83.072973 -57.586305) (xy 83.102439 -57.632155) (xy 83.125081 -57.681732) (xy 83.140436 -57.734027)
			(xy 83.148192 -57.787975) (xy 83.148678 -57.815226) (xy 83.148254 -57.842093) (xy 83.140723 -57.895298)
			(xy 83.125798 -57.946918) (xy 83.103776 -57.995932) (xy 83.075092 -58.041371) (xy 83.040315 -58.082334)
			(xy 83.000132 -58.11801) (xy 82.97799 -58.133234) (xy 82.966652 -58.141237) (xy 82.948479 -58.162198)
			(xy 82.936627 -58.187282) (xy 82.934241 -58.201306) (xy 83.168488 -58.201306) (xy 83.172559 -58.145684)
			(xy 83.184685 -58.091247) (xy 83.204608 -58.039156) (xy 83.231904 -57.990521) (xy 83.26599 -57.946378)
			(xy 83.306139 -57.907669) (xy 83.351497 -57.875218) (xy 83.401097 -57.849717) (xy 83.453881 -57.83171)
			(xy 83.508724 -57.82158) (xy 83.564458 -57.819543) (xy 83.619895 -57.825643) (xy 83.673852 -57.839749)
			(xy 83.725181 -57.861561) (xy 83.772787 -57.890615) (xy 83.815655 -57.92629) (xy 83.852872 -57.967827)
			(xy 83.883645 -58.01434) (xy 83.907317 -58.064837) (xy 83.923385 -58.118244) (xy 83.931505 -58.17342)
			(xy 83.932014 -58.201306) (xy 83.931505 -58.229192) (xy 83.923385 -58.284368) (xy 83.9201 -58.295286)
			(xy 85.720172 -58.295286) (xy 85.724243 -58.239664) (xy 85.736369 -58.185227) (xy 85.756292 -58.133136)
			(xy 85.783588 -58.084501) (xy 85.817674 -58.040358) (xy 85.857823 -58.001649) (xy 85.903181 -57.969198)
			(xy 85.952781 -57.943697) (xy 86.005565 -57.92569) (xy 86.060408 -57.91556) (xy 86.116142 -57.913523)
			(xy 86.171579 -57.919623) (xy 86.225536 -57.933729) (xy 86.276865 -57.955541) (xy 86.324471 -57.984595)
			(xy 86.347726 -58.003948) (xy 89.316812 -58.003948) (xy 89.320883 -57.948326) (xy 89.333009 -57.893889)
			(xy 89.352932 -57.841798) (xy 89.380228 -57.793163) (xy 89.414314 -57.74902) (xy 89.454463 -57.710311)
			(xy 89.499821 -57.67786) (xy 89.549421 -57.652359) (xy 89.602205 -57.634352) (xy 89.657048 -57.624222)
			(xy 89.712782 -57.622185) (xy 89.768219 -57.628285) (xy 89.822176 -57.642391) (xy 89.873505 -57.664203)
			(xy 89.921111 -57.693257) (xy 89.963979 -57.728932) (xy 90.001196 -57.770469) (xy 90.031969 -57.816982)
			(xy 90.055641 -57.867479) (xy 90.05849 -57.876948) (xy 107.896912 -57.876948) (xy 107.900983 -57.821326)
			(xy 107.913109 -57.766889) (xy 107.933032 -57.714798) (xy 107.960328 -57.666163) (xy 107.994414 -57.62202)
			(xy 108.034563 -57.583311) (xy 108.079921 -57.55086) (xy 108.129521 -57.525359) (xy 108.182305 -57.507352)
			(xy 108.237148 -57.497222) (xy 108.292882 -57.495185) (xy 108.348319 -57.501285) (xy 108.402276 -57.515391)
			(xy 108.453605 -57.537203) (xy 108.501211 -57.566257) (xy 108.544079 -57.601932) (xy 108.581296 -57.643469)
			(xy 108.612069 -57.689982) (xy 108.635741 -57.740479) (xy 108.651809 -57.793886) (xy 108.659929 -57.849062)
			(xy 108.660438 -57.876948) (xy 108.659929 -57.904834) (xy 108.651809 -57.96001) (xy 108.635741 -58.013417)
			(xy 108.612069 -58.063914) (xy 108.581296 -58.110427) (xy 108.544079 -58.151964) (xy 108.501211 -58.187639)
			(xy 108.453605 -58.216693) (xy 108.402276 -58.238505) (xy 108.348319 -58.252611) (xy 108.292882 -58.258711)
			(xy 108.237148 -58.256674) (xy 108.182305 -58.246544) (xy 108.129521 -58.228537) (xy 108.079921 -58.203036)
			(xy 108.034563 -58.170585) (xy 107.994414 -58.131876) (xy 107.960328 -58.087733) (xy 107.933032 -58.039098)
			(xy 107.913109 -57.987007) (xy 107.900983 -57.93257) (xy 107.896912 -57.876948) (xy 90.05849 -57.876948)
			(xy 90.071709 -57.920886) (xy 90.079829 -57.976062) (xy 90.080338 -58.003948) (xy 90.079829 -58.031834)
			(xy 90.071709 -58.08701) (xy 90.055641 -58.140417) (xy 90.031969 -58.190914) (xy 90.001196 -58.237427)
			(xy 89.963979 -58.278964) (xy 89.921111 -58.314639) (xy 89.873505 -58.343693) (xy 89.822176 -58.365505)
			(xy 89.768219 -58.379611) (xy 89.712782 -58.385711) (xy 89.657048 -58.383674) (xy 89.602205 -58.373544)
			(xy 89.549421 -58.355537) (xy 89.499821 -58.330036) (xy 89.454463 -58.297585) (xy 89.414314 -58.258876)
			(xy 89.380228 -58.214733) (xy 89.352932 -58.166098) (xy 89.333009 -58.114007) (xy 89.320883 -58.05957)
			(xy 89.316812 -58.003948) (xy 86.347726 -58.003948) (xy 86.367339 -58.02027) (xy 86.404556 -58.061807)
			(xy 86.435329 -58.10832) (xy 86.459001 -58.158817) (xy 86.475069 -58.212224) (xy 86.483189 -58.2674)
			(xy 86.483698 -58.295286) (xy 86.483189 -58.323172) (xy 86.475069 -58.378348) (xy 86.459001 -58.431755)
			(xy 86.435329 -58.482252) (xy 86.404556 -58.528765) (xy 86.367339 -58.570302) (xy 86.324471 -58.605977)
			(xy 86.276865 -58.635031) (xy 86.225536 -58.656843) (xy 86.171579 -58.670949) (xy 86.116142 -58.677049)
			(xy 86.060408 -58.675012) (xy 86.005565 -58.664882) (xy 85.952781 -58.646875) (xy 85.903181 -58.621374)
			(xy 85.857823 -58.588923) (xy 85.817674 -58.550214) (xy 85.783588 -58.506071) (xy 85.756292 -58.457436)
			(xy 85.736369 -58.405345) (xy 85.724243 -58.350908) (xy 85.720172 -58.295286) (xy 83.9201 -58.295286)
			(xy 83.907317 -58.337775) (xy 83.883645 -58.388272) (xy 83.852872 -58.434785) (xy 83.815655 -58.476322)
			(xy 83.772787 -58.511997) (xy 83.725181 -58.541051) (xy 83.673852 -58.562863) (xy 83.619895 -58.576969)
			(xy 83.564458 -58.583069) (xy 83.508724 -58.581032) (xy 83.453881 -58.570902) (xy 83.401097 -58.552895)
			(xy 83.351497 -58.527394) (xy 83.306139 -58.494943) (xy 83.26599 -58.456234) (xy 83.231904 -58.412091)
			(xy 83.204608 -58.363456) (xy 83.184685 -58.311365) (xy 83.172559 -58.256928) (xy 83.168488 -58.201306)
			(xy 82.934241 -58.201306) (xy 82.931974 -58.214631) (xy 82.934865 -58.242223) (xy 82.945085 -58.268014)
			(xy 82.961878 -58.290097) (xy 82.972656 -58.298842) (xy 82.995647 -58.317007) (xy 83.036319 -58.359182)
			(xy 83.070066 -58.407079) (xy 83.096094 -58.459572) (xy 83.113793 -58.515427) (xy 83.122745 -58.57333)
			(xy 83.123278 -58.602626) (xy 83.122792 -58.629877) (xy 83.115036 -58.683825) (xy 83.099681 -58.73612)
			(xy 83.077039 -58.785697) (xy 83.047573 -58.831547) (xy 83.011882 -58.872738) (xy 82.970969 -58.908188)
			(xy 104.474262 -58.908188) (xy 104.478333 -58.852566) (xy 104.490459 -58.798129) (xy 104.510382 -58.746038)
			(xy 104.537678 -58.697403) (xy 104.571764 -58.65326) (xy 104.611913 -58.614551) (xy 104.657271 -58.5821)
			(xy 104.706871 -58.556599) (xy 104.759655 -58.538592) (xy 104.814498 -58.528462) (xy 104.870232 -58.526425)
			(xy 104.925669 -58.532525) (xy 104.979626 -58.546631) (xy 105.030955 -58.568443) (xy 105.078561 -58.597497)
			(xy 105.121429 -58.633172) (xy 105.158646 -58.674709) (xy 105.189419 -58.721222) (xy 105.213091 -58.771719)
			(xy 105.229159 -58.825126) (xy 105.237279 -58.880302) (xy 105.237788 -58.908188) (xy 105.237279 -58.936074)
			(xy 105.229159 -58.99125) (xy 105.213091 -59.044657) (xy 105.20086 -59.070748) (xy 108.684312 -59.070748)
			(xy 108.688383 -59.015126) (xy 108.700509 -58.960689) (xy 108.720432 -58.908598) (xy 108.747728 -58.859963)
			(xy 108.781814 -58.81582) (xy 108.821963 -58.777111) (xy 108.867321 -58.74466) (xy 108.916921 -58.719159)
			(xy 108.969705 -58.701152) (xy 109.024548 -58.691022) (xy 109.080282 -58.688985) (xy 109.135719 -58.695085)
			(xy 109.189676 -58.709191) (xy 109.241005 -58.731003) (xy 109.256645 -58.740548) (xy 127.653032 -58.740548)
			(xy 127.657103 -58.684926) (xy 127.669229 -58.630489) (xy 127.689152 -58.578398) (xy 127.716448 -58.529763)
			(xy 127.750534 -58.48562) (xy 127.790683 -58.446911) (xy 127.836041 -58.41446) (xy 127.885641 -58.388959)
			(xy 127.938425 -58.370952) (xy 127.993268 -58.360822) (xy 128.049002 -58.358785) (xy 128.104439 -58.364885)
			(xy 128.158396 -58.378991) (xy 128.209725 -58.400803) (xy 128.257331 -58.429857) (xy 128.300199 -58.465532)
			(xy 128.337416 -58.507069) (xy 128.368189 -58.553582) (xy 128.391861 -58.604079) (xy 128.407929 -58.657486)
			(xy 128.416049 -58.712662) (xy 128.416558 -58.740548) (xy 128.416049 -58.768434) (xy 128.407929 -58.82361)
			(xy 128.391861 -58.877017) (xy 128.368189 -58.927514) (xy 128.337416 -58.974027) (xy 128.300199 -59.015564)
			(xy 128.257331 -59.051239) (xy 128.209725 -59.080293) (xy 128.158396 -59.102105) (xy 128.104439 -59.116211)
			(xy 128.049002 -59.122311) (xy 127.993268 -59.120274) (xy 127.938425 -59.110144) (xy 127.885641 -59.092137)
			(xy 127.836041 -59.066636) (xy 127.790683 -59.034185) (xy 127.750534 -58.995476) (xy 127.716448 -58.951333)
			(xy 127.689152 -58.902698) (xy 127.669229 -58.850607) (xy 127.657103 -58.79617) (xy 127.653032 -58.740548)
			(xy 109.256645 -58.740548) (xy 109.288611 -58.760057) (xy 109.331479 -58.795732) (xy 109.368696 -58.837269)
			(xy 109.399469 -58.883782) (xy 109.423141 -58.934279) (xy 109.439209 -58.987686) (xy 109.447329 -59.042862)
			(xy 109.447838 -59.070748) (xy 109.447329 -59.098634) (xy 109.440219 -59.146948) (xy 128.776982 -59.146948)
			(xy 128.781053 -59.091326) (xy 128.793179 -59.036889) (xy 128.813102 -58.984798) (xy 128.840398 -58.936163)
			(xy 128.874484 -58.89202) (xy 128.914633 -58.853311) (xy 128.959991 -58.82086) (xy 129.009591 -58.795359)
			(xy 129.062375 -58.777352) (xy 129.117218 -58.767222) (xy 129.172952 -58.765185) (xy 129.228389 -58.771285)
			(xy 129.282346 -58.785391) (xy 129.333675 -58.807203) (xy 129.381281 -58.836257) (xy 129.406673 -58.857388)
			(xy 137.298682 -58.857388) (xy 137.302753 -58.801766) (xy 137.314879 -58.747329) (xy 137.334802 -58.695238)
			(xy 137.362098 -58.646603) (xy 137.396184 -58.60246) (xy 137.436333 -58.563751) (xy 137.481691 -58.5313)
			(xy 137.531291 -58.505799) (xy 137.584075 -58.487792) (xy 137.638918 -58.477662) (xy 137.694652 -58.475625)
			(xy 137.750089 -58.481725) (xy 137.804046 -58.495831) (xy 137.855375 -58.517643) (xy 137.902981 -58.546697)
			(xy 137.945849 -58.582372) (xy 137.983066 -58.623909) (xy 138.013839 -58.670422) (xy 138.037511 -58.720919)
			(xy 138.053579 -58.774326) (xy 138.061699 -58.829502) (xy 138.062208 -58.857388) (xy 138.062115 -58.862468)
			(xy 138.401042 -58.862468) (xy 138.405113 -58.806846) (xy 138.417239 -58.752409) (xy 138.437162 -58.700318)
			(xy 138.464458 -58.651683) (xy 138.498544 -58.60754) (xy 138.538693 -58.568831) (xy 138.584051 -58.53638)
			(xy 138.633651 -58.510879) (xy 138.686435 -58.492872) (xy 138.741278 -58.482742) (xy 138.797012 -58.480705)
			(xy 138.852449 -58.486805) (xy 138.906406 -58.500911) (xy 138.957735 -58.522723) (xy 139.005341 -58.551777)
			(xy 139.048209 -58.587452) (xy 139.085426 -58.628989) (xy 139.116199 -58.675502) (xy 139.139871 -58.725999)
			(xy 139.155939 -58.779406) (xy 139.164059 -58.834582) (xy 139.164568 -58.862468) (xy 139.16407 -58.889752)
			(xy 139.418046 -58.889752) (xy 139.418046 -58.835248) (xy 139.425802 -58.7813) (xy 139.441156 -58.729004)
			(xy 139.463796 -58.679425) (xy 139.493261 -58.633573) (xy 139.528952 -58.59238) (xy 139.570141 -58.556685)
			(xy 139.61599 -58.527216) (xy 139.665566 -58.50457) (xy 139.71786 -58.48921) (xy 139.771808 -58.481449)
			(xy 139.79906 -58.48096) (xy 139.828822 -58.481552) (xy 139.887622 -58.490803) (xy 139.944273 -58.509071)
			(xy 139.997401 -58.535913) (xy 140.045717 -58.570679) (xy 140.067284 -58.591196) (xy 140.077202 -58.600373)
			(xy 140.100691 -58.613701) (xy 140.126853 -58.620405) (xy 140.153858 -58.620017) (xy 140.179816 -58.612563)
			(xy 140.202913 -58.598565) (xy 140.221532 -58.579001) (xy 140.22832 -58.56732) (xy 140.242676 -58.541708)
			(xy 140.278093 -58.494879) (xy 140.320269 -58.454033) (xy 140.368208 -58.420133) (xy 140.420776 -58.393983)
			(xy 140.476731 -58.376198) (xy 140.534751 -58.3672) (xy 140.564108 -58.36666) (xy 140.591357 -58.367211)
			(xy 140.626384 -58.372248) (xy 144.313654 -58.372248) (xy 144.317725 -58.316626) (xy 144.329851 -58.262189)
			(xy 144.349774 -58.210098) (xy 144.37707 -58.161463) (xy 144.411156 -58.11732) (xy 144.451305 -58.078611)
			(xy 144.496663 -58.04616) (xy 144.546263 -58.020659) (xy 144.599047 -58.002652) (xy 144.65389 -57.992522)
			(xy 144.709624 -57.990485) (xy 144.765061 -57.996585) (xy 144.819018 -58.010691) (xy 144.870347 -58.032503)
			(xy 144.917953 -58.061557) (xy 144.960821 -58.097232) (xy 144.998038 -58.138769) (xy 145.028811 -58.185282)
			(xy 145.052483 -58.235779) (xy 145.068551 -58.289186) (xy 145.076671 -58.344362) (xy 145.07718 -58.372248)
			(xy 145.076671 -58.400134) (xy 145.069673 -58.447686) (xy 146.610576 -58.447686) (xy 146.614647 -58.392064)
			(xy 146.626773 -58.337627) (xy 146.646696 -58.285536) (xy 146.673992 -58.236901) (xy 146.708078 -58.192758)
			(xy 146.748227 -58.154049) (xy 146.793585 -58.121598) (xy 146.843185 -58.096097) (xy 146.895969 -58.07809)
			(xy 146.950812 -58.06796) (xy 147.006546 -58.065923) (xy 147.061983 -58.072023) (xy 147.11594 -58.086129)
			(xy 147.167269 -58.107941) (xy 147.214875 -58.136995) (xy 147.257743 -58.17267) (xy 147.29496 -58.214207)
			(xy 147.325733 -58.26072) (xy 147.349405 -58.311217) (xy 147.365473 -58.364624) (xy 147.372314 -58.41111)
			(xy 150.485346 -58.41111) (xy 150.489417 -58.355488) (xy 150.501543 -58.301051) (xy 150.521466 -58.24896)
			(xy 150.548762 -58.200325) (xy 150.582848 -58.156182) (xy 150.622997 -58.117473) (xy 150.668355 -58.085022)
			(xy 150.717955 -58.059521) (xy 150.770739 -58.041514) (xy 150.825582 -58.031384) (xy 150.881316 -58.029347)
			(xy 150.936753 -58.035447) (xy 150.99071 -58.049553) (xy 151.042039 -58.071365) (xy 151.089645 -58.100419)
			(xy 151.132513 -58.136094) (xy 151.16973 -58.177631) (xy 151.200503 -58.224144) (xy 151.224175 -58.274641)
			(xy 151.240243 -58.328048) (xy 151.248363 -58.383224) (xy 151.248872 -58.41111) (xy 151.248363 -58.438996)
			(xy 151.240243 -58.494172) (xy 151.234895 -58.511948) (xy 157.791402 -58.511948) (xy 157.795473 -58.456326)
			(xy 157.807599 -58.401889) (xy 157.827522 -58.349798) (xy 157.854818 -58.301163) (xy 157.888904 -58.25702)
			(xy 157.929053 -58.218311) (xy 157.974411 -58.18586) (xy 158.024011 -58.160359) (xy 158.076795 -58.142352)
			(xy 158.131638 -58.132222) (xy 158.187372 -58.130185) (xy 158.242809 -58.136285) (xy 158.296766 -58.150391)
			(xy 158.348095 -58.172203) (xy 158.395701 -58.201257) (xy 158.438569 -58.236932) (xy 158.475786 -58.278469)
			(xy 158.506559 -58.324982) (xy 158.530231 -58.375479) (xy 158.546299 -58.428886) (xy 158.554419 -58.484062)
			(xy 158.554928 -58.511948) (xy 158.554419 -58.539834) (xy 158.546299 -58.59501) (xy 158.530231 -58.648417)
			(xy 158.506559 -58.698914) (xy 158.475786 -58.745427) (xy 158.438569 -58.786964) (xy 158.395701 -58.822639)
			(xy 158.348095 -58.851693) (xy 158.296766 -58.873505) (xy 158.242809 -58.887611) (xy 158.187372 -58.893711)
			(xy 158.131638 -58.891674) (xy 158.076795 -58.881544) (xy 158.024011 -58.863537) (xy 157.974411 -58.838036)
			(xy 157.929053 -58.805585) (xy 157.888904 -58.766876) (xy 157.854818 -58.722733) (xy 157.827522 -58.674098)
			(xy 157.807599 -58.622007) (xy 157.795473 -58.56757) (xy 157.791402 -58.511948) (xy 151.234895 -58.511948)
			(xy 151.224175 -58.547579) (xy 151.200503 -58.598076) (xy 151.16973 -58.644589) (xy 151.132513 -58.686126)
			(xy 151.089645 -58.721801) (xy 151.042039 -58.750855) (xy 150.99071 -58.772667) (xy 150.936753 -58.786773)
			(xy 150.881316 -58.792873) (xy 150.825582 -58.790836) (xy 150.770739 -58.780706) (xy 150.717955 -58.762699)
			(xy 150.668355 -58.737198) (xy 150.622997 -58.704747) (xy 150.582848 -58.666038) (xy 150.548762 -58.621895)
			(xy 150.521466 -58.57326) (xy 150.501543 -58.521169) (xy 150.489417 -58.466732) (xy 150.485346 -58.41111)
			(xy 147.372314 -58.41111) (xy 147.373593 -58.4198) (xy 147.374102 -58.447686) (xy 147.373593 -58.475572)
			(xy 147.365473 -58.530748) (xy 147.349405 -58.584155) (xy 147.325733 -58.634652) (xy 147.29496 -58.681165)
			(xy 147.257743 -58.722702) (xy 147.214875 -58.758377) (xy 147.167269 -58.787431) (xy 147.11594 -58.809243)
			(xy 147.061983 -58.823349) (xy 147.006546 -58.829449) (xy 146.950812 -58.827412) (xy 146.895969 -58.817282)
			(xy 146.843185 -58.799275) (xy 146.793585 -58.773774) (xy 146.748227 -58.741323) (xy 146.708078 -58.702614)
			(xy 146.673992 -58.658471) (xy 146.646696 -58.609836) (xy 146.626773 -58.557745) (xy 146.614647 -58.503308)
			(xy 146.610576 -58.447686) (xy 145.069673 -58.447686) (xy 145.068551 -58.45531) (xy 145.052483 -58.508717)
			(xy 145.028811 -58.559214) (xy 144.998038 -58.605727) (xy 144.960821 -58.647264) (xy 144.917953 -58.682939)
			(xy 144.870347 -58.711993) (xy 144.819018 -58.733805) (xy 144.765061 -58.747911) (xy 144.709624 -58.754011)
			(xy 144.65389 -58.751974) (xy 144.599047 -58.741844) (xy 144.546263 -58.723837) (xy 144.496663 -58.698336)
			(xy 144.451305 -58.665885) (xy 144.411156 -58.627176) (xy 144.37707 -58.583033) (xy 144.349774 -58.534398)
			(xy 144.329851 -58.482307) (xy 144.317725 -58.42787) (xy 144.313654 -58.372248) (xy 140.626384 -58.372248)
			(xy 140.645299 -58.374968) (xy 140.697588 -58.390322) (xy 140.74716 -58.412962) (xy 140.793006 -58.442426)
			(xy 140.834191 -58.478114) (xy 140.869879 -58.519301) (xy 140.899342 -58.565147) (xy 140.921981 -58.614719)
			(xy 140.937334 -58.667009) (xy 140.94509 -58.720951) (xy 140.94509 -58.775449) (xy 140.937334 -58.829391)
			(xy 140.921981 -58.881681) (xy 140.899342 -58.931253) (xy 140.869879 -58.977099) (xy 140.834191 -59.018286)
			(xy 140.793006 -59.053974) (xy 140.74716 -59.083438) (xy 140.697588 -59.106078) (xy 140.645299 -59.121432)
			(xy 140.591357 -59.129189) (xy 140.564108 -59.129676) (xy 140.534346 -59.129094) (xy 140.475546 -59.119839)
			(xy 140.418895 -59.101568) (xy 140.365767 -59.074724) (xy 140.317451 -59.039957) (xy 140.295884 -59.01944)
			(xy 140.286004 -59.010218) (xy 140.262505 -58.996886) (xy 140.236333 -58.990182) (xy 140.209318 -58.990575)
			(xy 140.183352 -58.998039) (xy 140.160252 -59.01205) (xy 140.141634 -59.031628) (xy 140.134848 -59.043316)
			(xy 140.120418 -59.068884) (xy 140.085015 -59.115715) (xy 140.042852 -59.156566) (xy 139.994927 -59.190471)
			(xy 139.94237 -59.21663) (xy 139.886425 -59.234423) (xy 139.828413 -59.243431) (xy 139.79906 -59.243976)
			(xy 139.771808 -59.243551) (xy 139.71786 -59.23579) (xy 139.665566 -59.22043) (xy 139.61599 -59.197784)
			(xy 139.570141 -59.168315) (xy 139.528952 -59.13262) (xy 139.493261 -59.091427) (xy 139.463796 -59.045575)
			(xy 139.441156 -58.995996) (xy 139.425802 -58.9437) (xy 139.418046 -58.889752) (xy 139.16407 -58.889752)
			(xy 139.164059 -58.890354) (xy 139.155939 -58.94553) (xy 139.139871 -58.998937) (xy 139.116199 -59.049434)
			(xy 139.085426 -59.095947) (xy 139.048209 -59.137484) (xy 139.005341 -59.173159) (xy 138.957735 -59.202213)
			(xy 138.906406 -59.224025) (xy 138.852449 -59.238131) (xy 138.797012 -59.244231) (xy 138.741278 -59.242194)
			(xy 138.686435 -59.232064) (xy 138.633651 -59.214057) (xy 138.584051 -59.188556) (xy 138.538693 -59.156105)
			(xy 138.498544 -59.117396) (xy 138.464458 -59.073253) (xy 138.437162 -59.024618) (xy 138.417239 -58.972527)
			(xy 138.405113 -58.91809) (xy 138.401042 -58.862468) (xy 138.062115 -58.862468) (xy 138.061699 -58.885274)
			(xy 138.053579 -58.94045) (xy 138.037511 -58.993857) (xy 138.013839 -59.044354) (xy 137.983066 -59.090867)
			(xy 137.945849 -59.132404) (xy 137.902981 -59.168079) (xy 137.855375 -59.197133) (xy 137.804046 -59.218945)
			(xy 137.750089 -59.233051) (xy 137.694652 -59.239151) (xy 137.638918 -59.237114) (xy 137.584075 -59.226984)
			(xy 137.531291 -59.208977) (xy 137.481691 -59.183476) (xy 137.436333 -59.151025) (xy 137.396184 -59.112316)
			(xy 137.362098 -59.068173) (xy 137.334802 -59.019538) (xy 137.314879 -58.967447) (xy 137.302753 -58.91301)
			(xy 137.298682 -58.857388) (xy 129.406673 -58.857388) (xy 129.424149 -58.871932) (xy 129.461366 -58.913469)
			(xy 129.492139 -58.959982) (xy 129.515811 -59.010479) (xy 129.531879 -59.063886) (xy 129.539999 -59.119062)
			(xy 129.540508 -59.146948) (xy 129.539999 -59.174834) (xy 129.531879 -59.23001) (xy 129.515811 -59.283417)
			(xy 129.507498 -59.301151) (xy 147.356803 -59.301151) (xy 147.356803 -59.246649) (xy 147.36456 -59.192702)
			(xy 147.379916 -59.140409) (xy 147.402558 -59.090833) (xy 147.432025 -59.044984) (xy 147.467717 -59.003796)
			(xy 147.508908 -58.968107) (xy 147.554759 -58.938643) (xy 147.604337 -58.916005) (xy 147.656632 -58.900654)
			(xy 147.710579 -58.892901) (xy 147.73783 -58.89244) (xy 147.764433 -58.892924) (xy 147.817125 -58.900298)
			(xy 147.868281 -58.914924) (xy 147.916906 -58.936521) (xy 147.962057 -58.964667) (xy 148.002857 -58.998817)
			(xy 148.038513 -59.038307) (xy 148.053806 -59.06008) (xy 148.06214 -59.07156) (xy 148.083884 -59.089764)
			(xy 148.109797 -59.101282) (xy 148.13788 -59.105222) (xy 148.165963 -59.101282) (xy 148.191876 -59.089764)
			(xy 148.21362 -59.07156) (xy 148.221954 -59.06008) (xy 148.237279 -59.038331) (xy 148.272938 -58.99885)
			(xy 148.313736 -58.964704) (xy 148.358881 -58.936555) (xy 148.407498 -58.914949) (xy 148.458645 -58.900305)
			(xy 148.511329 -58.892906) (xy 148.53793 -58.89244) (xy 148.565183 -58.892832) (xy 148.619135 -58.900593)
			(xy 148.671432 -58.915953) (xy 148.721012 -58.938598) (xy 148.766864 -58.968069) (xy 148.808056 -59.003765)
			(xy 148.843749 -59.04496) (xy 148.873216 -59.090814) (xy 148.895858 -59.140396) (xy 148.911213 -59.192695)
			(xy 148.91897 -59.246647) (xy 148.91897 -59.301153) (xy 148.911213 -59.355105) (xy 148.895858 -59.407404)
			(xy 148.873216 -59.456986) (xy 148.848017 -59.496198) (xy 162.252912 -59.496198) (xy 162.256983 -59.440576)
			(xy 162.269109 -59.386139) (xy 162.289032 -59.334048) (xy 162.316328 -59.285413) (xy 162.350414 -59.24127)
			(xy 162.390563 -59.202561) (xy 162.435921 -59.17011) (xy 162.485521 -59.144609) (xy 162.538305 -59.126602)
			(xy 162.593148 -59.116472) (xy 162.648882 -59.114435) (xy 162.704319 -59.120535) (xy 162.758276 -59.134641)
			(xy 162.809605 -59.156453) (xy 162.857211 -59.185507) (xy 162.900079 -59.221182) (xy 162.937296 -59.262719)
			(xy 162.968069 -59.309232) (xy 162.991741 -59.359729) (xy 163.007809 -59.413136) (xy 163.015929 -59.468312)
			(xy 163.016438 -59.496198) (xy 163.015929 -59.524084) (xy 163.007809 -59.57926) (xy 162.991741 -59.632667)
			(xy 162.968069 -59.683164) (xy 162.937296 -59.729677) (xy 162.900079 -59.771214) (xy 162.857211 -59.806889)
			(xy 162.809605 -59.835943) (xy 162.758276 -59.857755) (xy 162.73054 -59.865006) (xy 163.514784 -59.865006)
			(xy 163.518855 -59.809384) (xy 163.530981 -59.754947) (xy 163.550904 -59.702856) (xy 163.5782 -59.654221)
			(xy 163.612286 -59.610078) (xy 163.652435 -59.571369) (xy 163.697793 -59.538918) (xy 163.747393 -59.513417)
			(xy 163.800177 -59.49541) (xy 163.85502 -59.48528) (xy 163.910754 -59.483243) (xy 163.966191 -59.489343)
			(xy 164.020148 -59.503449) (xy 164.071477 -59.525261) (xy 164.119083 -59.554315) (xy 164.161951 -59.58999)
			(xy 164.199168 -59.631527) (xy 164.229941 -59.67804) (xy 164.253613 -59.728537) (xy 164.269681 -59.781944)
			(xy 164.277801 -59.83712) (xy 164.27831 -59.865006) (xy 164.277801 -59.892892) (xy 164.269681 -59.948068)
			(xy 164.253613 -60.001475) (xy 164.229941 -60.051972) (xy 164.199168 -60.098485) (xy 164.161951 -60.140022)
			(xy 164.119083 -60.175697) (xy 164.071477 -60.204751) (xy 164.020148 -60.226563) (xy 163.966191 -60.240669)
			(xy 163.910754 -60.246769) (xy 163.85502 -60.244732) (xy 163.800177 -60.234602) (xy 163.747393 -60.216595)
			(xy 163.697793 -60.191094) (xy 163.652435 -60.158643) (xy 163.612286 -60.119934) (xy 163.5782 -60.075791)
			(xy 163.550904 -60.027156) (xy 163.530981 -59.975065) (xy 163.518855 -59.920628) (xy 163.514784 -59.865006)
			(xy 162.73054 -59.865006) (xy 162.704319 -59.871861) (xy 162.648882 -59.877961) (xy 162.593148 -59.875924)
			(xy 162.538305 -59.865794) (xy 162.485521 -59.847787) (xy 162.435921 -59.822286) (xy 162.390563 -59.789835)
			(xy 162.350414 -59.751126) (xy 162.316328 -59.706983) (xy 162.289032 -59.658348) (xy 162.269109 -59.606257)
			(xy 162.256983 -59.55182) (xy 162.252912 -59.496198) (xy 148.848017 -59.496198) (xy 148.843749 -59.50284)
			(xy 148.808056 -59.544035) (xy 148.766864 -59.579731) (xy 148.721012 -59.609202) (xy 148.671432 -59.631847)
			(xy 148.619135 -59.647207) (xy 148.565183 -59.654968) (xy 148.53793 -59.655456) (xy 148.511326 -59.655004)
			(xy 148.458632 -59.647625) (xy 148.407476 -59.632993) (xy 148.35885 -59.611391) (xy 148.3137 -59.58324)
			(xy 148.272901 -59.549085) (xy 148.237246 -59.509591) (xy 148.221954 -59.487816) (xy 148.21362 -59.476336)
			(xy 148.191876 -59.458132) (xy 148.165963 -59.446614) (xy 148.13788 -59.442674) (xy 148.109797 -59.446614)
			(xy 148.083884 -59.458132) (xy 148.06214 -59.476336) (xy 148.053806 -59.487816) (xy 148.038506 -59.509582)
			(xy 148.002842 -59.549064) (xy 147.96204 -59.583209) (xy 147.916891 -59.611355) (xy 147.86827 -59.632958)
			(xy 147.81712 -59.647599) (xy 147.764432 -59.654993) (xy 147.73783 -59.655456) (xy 147.710579 -59.654899)
			(xy 147.656632 -59.647146) (xy 147.604337 -59.631795) (xy 147.554759 -59.609157) (xy 147.508908 -59.579693)
			(xy 147.467717 -59.544004) (xy 147.432025 -59.502816) (xy 147.402558 -59.456967) (xy 147.379916 -59.407391)
			(xy 147.36456 -59.355098) (xy 147.356803 -59.301151) (xy 129.507498 -59.301151) (xy 129.492139 -59.333914)
			(xy 129.461366 -59.380427) (xy 129.424149 -59.421964) (xy 129.381281 -59.457639) (xy 129.333675 -59.486693)
			(xy 129.282346 -59.508505) (xy 129.228389 -59.522611) (xy 129.172952 -59.528711) (xy 129.117218 -59.526674)
			(xy 129.062375 -59.516544) (xy 129.009591 -59.498537) (xy 128.959991 -59.473036) (xy 128.914633 -59.440585)
			(xy 128.874484 -59.401876) (xy 128.840398 -59.357733) (xy 128.813102 -59.309098) (xy 128.793179 -59.257007)
			(xy 128.781053 -59.20257) (xy 128.776982 -59.146948) (xy 109.440219 -59.146948) (xy 109.439209 -59.15381)
			(xy 109.423141 -59.207217) (xy 109.399469 -59.257714) (xy 109.368696 -59.304227) (xy 109.331479 -59.345764)
			(xy 109.288611 -59.381439) (xy 109.241005 -59.410493) (xy 109.189676 -59.432305) (xy 109.135719 -59.446411)
			(xy 109.080282 -59.452511) (xy 109.024548 -59.450474) (xy 108.969705 -59.440344) (xy 108.916921 -59.422337)
			(xy 108.867321 -59.396836) (xy 108.821963 -59.364385) (xy 108.781814 -59.325676) (xy 108.747728 -59.281533)
			(xy 108.720432 -59.232898) (xy 108.700509 -59.180807) (xy 108.688383 -59.12637) (xy 108.684312 -59.070748)
			(xy 105.20086 -59.070748) (xy 105.189419 -59.095154) (xy 105.158646 -59.141667) (xy 105.121429 -59.183204)
			(xy 105.078561 -59.218879) (xy 105.030955 -59.247933) (xy 104.979626 -59.269745) (xy 104.925669 -59.283851)
			(xy 104.870232 -59.289951) (xy 104.814498 -59.287914) (xy 104.759655 -59.277784) (xy 104.706871 -59.259777)
			(xy 104.657271 -59.234276) (xy 104.611913 -59.201825) (xy 104.571764 -59.163116) (xy 104.537678 -59.118973)
			(xy 104.510382 -59.070338) (xy 104.490459 -59.018247) (xy 104.478333 -58.96381) (xy 104.474262 -58.908188)
			(xy 82.970969 -58.908188) (xy 82.970691 -58.908429) (xy 82.924841 -58.937895) (xy 82.875264 -58.960537)
			(xy 82.822969 -58.975892) (xy 82.769021 -58.983648) (xy 82.714519 -58.983648) (xy 82.660571 -58.975892)
			(xy 82.608276 -58.960537) (xy 82.558699 -58.937895) (xy 82.512849 -58.908429) (xy 82.471658 -58.872738)
			(xy 82.435967 -58.831547) (xy 82.406501 -58.785697) (xy 82.383859 -58.73612) (xy 82.368504 -58.683825)
			(xy 82.360748 -58.629877) (xy 82.360262 -58.602626) (xy 82.038112 -58.602626) (xy 82.024521 -58.606179)
			(xy 81.969084 -58.612279) (xy 81.91335 -58.610242) (xy 81.858507 -58.600112) (xy 81.805723 -58.582105)
			(xy 81.756123 -58.556604) (xy 81.710765 -58.524153) (xy 81.670616 -58.485444) (xy 81.63653 -58.441301)
			(xy 81.609234 -58.392666) (xy 81.589311 -58.340575) (xy 81.577185 -58.286138) (xy 81.573114 -58.230516)
			(xy 78.978855 -58.230516) (xy 78.946053 -58.258939) (xy 78.900205 -58.288406) (xy 78.850629 -58.311049)
			(xy 78.798337 -58.326407) (xy 78.744391 -58.334168) (xy 78.71714 -58.334656) (xy 78.688223 -58.334126)
			(xy 78.631052 -58.325402) (xy 78.575853 -58.308147) (xy 78.52389 -58.282758) (xy 78.476356 -58.249816)
			(xy 78.43434 -58.210075) (xy 78.41615 -58.18759) (xy 78.406253 -58.175785) (xy 78.380929 -58.158266)
			(xy 78.351536 -58.14909) (xy 78.320744 -58.14909) (xy 78.291351 -58.158266) (xy 78.266027 -58.175785)
			(xy 78.25613 -58.18759) (xy 78.23792 -58.210057) (xy 78.195904 -58.249794) (xy 78.148373 -58.282735)
			(xy 78.096416 -58.308126) (xy 78.041222 -58.325386) (xy 77.984055 -58.334119) (xy 77.95514 -58.334656)
			(xy 77.927892 -58.334085) (xy 77.87395 -58.326335) (xy 77.82166 -58.310987) (xy 77.772086 -58.288354)
			(xy 77.726238 -58.258897) (xy 77.685048 -58.223214) (xy 77.649356 -58.182033) (xy 77.619888 -58.136191)
			(xy 77.597244 -58.086623) (xy 77.581884 -58.034336) (xy 77.574122 -57.980396) (xy 77.573632 -57.953148)
			(xy 9.367823 -57.953148) (xy 9.344766 -57.987999) (xy 9.307549 -58.029536) (xy 9.264681 -58.065211)
			(xy 9.217075 -58.094265) (xy 9.165746 -58.116077) (xy 9.111789 -58.130183) (xy 9.056352 -58.136283)
			(xy 9.000618 -58.134246) (xy 8.945775 -58.124116) (xy 8.892991 -58.106109) (xy 8.843391 -58.080608)
			(xy 8.798033 -58.048157) (xy 8.757884 -58.009448) (xy 8.723798 -57.965305) (xy 8.696502 -57.91667)
			(xy 8.676579 -57.864579) (xy 8.664453 -57.810142) (xy 8.660382 -57.75452) (xy 8.203373 -57.75452)
			(xy 8.202929 -57.77885) (xy 8.194809 -57.834026) (xy 8.178741 -57.887433) (xy 8.155069 -57.93793)
			(xy 8.124296 -57.984443) (xy 8.087079 -58.02598) (xy 8.044211 -58.061655) (xy 7.996605 -58.090709)
			(xy 7.945276 -58.112521) (xy 7.891319 -58.126627) (xy 7.835882 -58.132727) (xy 7.780148 -58.13069)
			(xy 7.725305 -58.12056) (xy 7.672521 -58.102553) (xy 7.622921 -58.077052) (xy 7.577563 -58.044601)
			(xy 7.537414 -58.005892) (xy 7.503328 -57.961749) (xy 7.476032 -57.913114) (xy 7.456109 -57.861023)
			(xy 7.443983 -57.806586) (xy 7.439912 -57.750964) (xy 6.055868 -57.750964) (xy 6.055868 -58.552334)
			(xy 6.056404 -58.567813) (xy 6.065657 -58.597356) (xy 6.083334 -58.62277) (xy 6.107812 -58.641724)
			(xy 6.136842 -58.652475) (xy 6.167761 -58.654038) (xy 6.182868 -58.650632) (xy 6.206456 -58.644905)
			(xy 6.254609 -58.638789) (xy 6.27888 -58.63844) (xy 6.306131 -58.638926) (xy 6.360079 -58.646682)
			(xy 6.412374 -58.662038) (xy 6.461952 -58.684679) (xy 6.507803 -58.714145) (xy 6.548993 -58.749837)
			(xy 6.584685 -58.791027) (xy 6.614151 -58.836878) (xy 6.636792 -58.886456) (xy 6.652148 -58.938751)
			(xy 6.659904 -58.992699) (xy 6.659904 -59.019948) (xy 8.170162 -59.019948) (xy 8.174233 -58.964326)
			(xy 8.186359 -58.909889) (xy 8.206282 -58.857798) (xy 8.233578 -58.809163) (xy 8.267664 -58.76502)
			(xy 8.307813 -58.726311) (xy 8.353171 -58.69386) (xy 8.402771 -58.668359) (xy 8.455555 -58.650352)
			(xy 8.510398 -58.640222) (xy 8.566132 -58.638185) (xy 8.621569 -58.644285) (xy 8.675526 -58.658391)
			(xy 8.726855 -58.680203) (xy 8.774461 -58.709257) (xy 8.817329 -58.744932) (xy 8.854546 -58.786469)
			(xy 8.885319 -58.832982) (xy 8.908991 -58.883479) (xy 8.925059 -58.936886) (xy 8.928536 -58.960512)
			(xy 28.421582 -58.960512) (xy 28.425653 -58.90489) (xy 28.437779 -58.850453) (xy 28.457702 -58.798362)
			(xy 28.484998 -58.749727) (xy 28.519084 -58.705584) (xy 28.559233 -58.666875) (xy 28.604591 -58.634424)
			(xy 28.654191 -58.608923) (xy 28.706975 -58.590916) (xy 28.761818 -58.580786) (xy 28.817552 -58.578749)
			(xy 28.872989 -58.584849) (xy 28.926946 -58.598955) (xy 28.978275 -58.620767) (xy 29.025881 -58.649821)
			(xy 29.03296 -58.655712) (xy 43.89704 -58.655712) (xy 43.901111 -58.60009) (xy 43.913237 -58.545653)
			(xy 43.93316 -58.493562) (xy 43.960456 -58.444927) (xy 43.994542 -58.400784) (xy 44.034691 -58.362075)
			(xy 44.080049 -58.329624) (xy 44.129649 -58.304123) (xy 44.182433 -58.286116) (xy 44.237276 -58.275986)
			(xy 44.29301 -58.273949) (xy 44.348447 -58.280049) (xy 44.402404 -58.294155) (xy 44.453733 -58.315967)
			(xy 44.501339 -58.345021) (xy 44.544207 -58.380696) (xy 44.581424 -58.422233) (xy 44.612197 -58.468746)
			(xy 44.635869 -58.519243) (xy 44.651937 -58.57265) (xy 44.660057 -58.627826) (xy 44.660566 -58.655712)
			(xy 44.660057 -58.683598) (xy 44.651937 -58.738774) (xy 44.635869 -58.792181) (xy 44.612197 -58.842678)
			(xy 44.581424 -58.889191) (xy 44.544207 -58.930728) (xy 44.501339 -58.966403) (xy 44.453733 -58.995457)
			(xy 44.402404 -59.017269) (xy 44.348447 -59.031375) (xy 44.29301 -59.037475) (xy 44.237276 -59.035438)
			(xy 44.182433 -59.025308) (xy 44.129649 -59.007301) (xy 44.080049 -58.9818) (xy 44.034691 -58.949349)
			(xy 43.994542 -58.91064) (xy 43.960456 -58.866497) (xy 43.93316 -58.817862) (xy 43.913237 -58.765771)
			(xy 43.901111 -58.711334) (xy 43.89704 -58.655712) (xy 29.03296 -58.655712) (xy 29.068749 -58.685496)
			(xy 29.105966 -58.727033) (xy 29.136739 -58.773546) (xy 29.160411 -58.824043) (xy 29.176479 -58.87745)
			(xy 29.184599 -58.932626) (xy 29.185108 -58.960512) (xy 29.184599 -58.988398) (xy 29.176479 -59.043574)
			(xy 29.160411 -59.096981) (xy 29.136739 -59.147478) (xy 29.105966 -59.193991) (xy 29.068749 -59.235528)
			(xy 29.025881 -59.271203) (xy 28.978275 -59.300257) (xy 28.926946 -59.322069) (xy 28.872989 -59.336175)
			(xy 28.817552 -59.342275) (xy 28.761818 -59.340238) (xy 28.706975 -59.330108) (xy 28.654191 -59.312101)
			(xy 28.604591 -59.2866) (xy 28.559233 -59.254149) (xy 28.519084 -59.21544) (xy 28.484998 -59.171297)
			(xy 28.457702 -59.122662) (xy 28.437779 -59.070571) (xy 28.425653 -59.016134) (xy 28.421582 -58.960512)
			(xy 8.928536 -58.960512) (xy 8.933179 -58.992062) (xy 8.933688 -59.019948) (xy 8.933179 -59.047834)
			(xy 8.925059 -59.10301) (xy 8.908991 -59.156417) (xy 8.885319 -59.206914) (xy 8.854546 -59.253427)
			(xy 8.817329 -59.294964) (xy 8.774461 -59.330639) (xy 8.726855 -59.359693) (xy 8.675526 -59.381505)
			(xy 8.621569 -59.395611) (xy 8.566132 -59.401711) (xy 8.510398 -59.399674) (xy 8.455555 -59.389544)
			(xy 8.402771 -59.371537) (xy 8.353171 -59.346036) (xy 8.307813 -59.313585) (xy 8.267664 -59.274876)
			(xy 8.233578 -59.230733) (xy 8.206282 -59.182098) (xy 8.186359 -59.130007) (xy 8.174233 -59.07557)
			(xy 8.170162 -59.019948) (xy 6.659904 -59.019948) (xy 6.659904 -59.047201) (xy 6.652148 -59.101149)
			(xy 6.636792 -59.153444) (xy 6.614151 -59.203022) (xy 6.584685 -59.248873) (xy 6.548993 -59.290063)
			(xy 6.507803 -59.325755) (xy 6.461952 -59.355221) (xy 6.412374 -59.377862) (xy 6.360079 -59.393218)
			(xy 6.306131 -59.400974) (xy 6.27888 -59.401456) (xy 6.25461 -59.401092) (xy 6.206458 -59.394978)
			(xy 6.182868 -59.389264) (xy 6.167754 -59.38593) (xy 6.136859 -59.387519) (xy 6.107852 -59.398271)
			(xy 6.083387 -59.417205) (xy 6.065701 -59.442586) (xy 6.056412 -59.472095) (xy 6.055868 -59.487562)
			(xy 6.055868 -59.603132) (xy 6.056308 -59.616769) (xy 6.06353 -59.64307) (xy 6.077449 -59.666525)
			(xy 6.097077 -59.685464) (xy 6.121014 -59.698538) (xy 6.147556 -59.704815) (xy 6.174813 -59.70385)
			(xy 6.187948 -59.70016) (xy 6.215929 -59.691895) (xy 6.273585 -59.682974) (xy 6.302756 -59.68238)
			(xy 6.330009 -59.682843) (xy 6.383961 -59.6906) (xy 6.436259 -59.705955) (xy 6.48584 -59.728598)
			(xy 6.531694 -59.758066) (xy 6.572888 -59.79376) (xy 6.608582 -59.834953) (xy 6.63805 -59.880806)
			(xy 6.660693 -59.930387) (xy 6.67605 -59.982685) (xy 6.678522 -59.99988) (xy 16.984223 -59.99988)
			(xy 16.988246 -59.914136) (xy 17.000281 -59.829145) (xy 17.020222 -59.745655) (xy 17.047893 -59.664398)
			(xy 17.083052 -59.58609) (xy 17.125389 -59.511419) (xy 17.174532 -59.44104) (xy 17.23005 -59.375572)
			(xy 17.291454 -59.315591) (xy 17.358206 -59.261623) (xy 17.429717 -59.214143) (xy 17.505361 -59.173568)
			(xy 17.584472 -59.140255) (xy 17.666354 -59.114496) (xy 17.750289 -59.096518) (xy 17.835539 -59.086478)
			(xy 17.921354 -59.084466) (xy 18.00698 -59.090499) (xy 18.091665 -59.104523) (xy 18.174665 -59.126415)
			(xy 18.25525 -59.155984) (xy 18.332713 -59.192968) (xy 18.406371 -59.237044) (xy 18.475579 -59.287824)
			(xy 18.539727 -59.344861) (xy 18.598253 -59.407655) (xy 18.650641 -59.475653) (xy 18.696431 -59.548258)
			(xy 18.735222 -59.624832) (xy 18.766671 -59.704702) (xy 18.785105 -59.768486) (xy 84.805772 -59.768486)
			(xy 84.809843 -59.712864) (xy 84.821969 -59.658427) (xy 84.841892 -59.606336) (xy 84.869188 -59.557701)
			(xy 84.903274 -59.513558) (xy 84.943423 -59.474849) (xy 84.988781 -59.442398) (xy 85.038381 -59.416897)
			(xy 85.091165 -59.39889) (xy 85.146008 -59.38876) (xy 85.201742 -59.386723) (xy 85.257179 -59.392823)
			(xy 85.311136 -59.406929) (xy 85.362465 -59.428741) (xy 85.410071 -59.457795) (xy 85.434852 -59.478418)
			(xy 101.903782 -59.478418) (xy 101.907853 -59.422796) (xy 101.919979 -59.368359) (xy 101.939902 -59.316268)
			(xy 101.967198 -59.267633) (xy 102.001284 -59.22349) (xy 102.041433 -59.184781) (xy 102.086791 -59.15233)
			(xy 102.136391 -59.126829) (xy 102.189175 -59.108822) (xy 102.244018 -59.098692) (xy 102.299752 -59.096655)
			(xy 102.355189 -59.102755) (xy 102.409146 -59.116861) (xy 102.460475 -59.138673) (xy 102.508081 -59.167727)
			(xy 102.550949 -59.203402) (xy 102.588166 -59.244939) (xy 102.618939 -59.291452) (xy 102.642611 -59.341949)
			(xy 102.658679 -59.395356) (xy 102.666799 -59.450532) (xy 102.667308 -59.478418) (xy 102.666799 -59.506304)
			(xy 102.658679 -59.56148) (xy 102.642611 -59.614887) (xy 102.618939 -59.665384) (xy 102.588166 -59.711897)
			(xy 102.550949 -59.753434) (xy 102.508081 -59.789109) (xy 102.460475 -59.818163) (xy 102.409146 -59.839975)
			(xy 102.355189 -59.854081) (xy 102.299752 -59.860181) (xy 102.244018 -59.858144) (xy 102.189175 -59.848014)
			(xy 102.136391 -59.830007) (xy 102.086791 -59.804506) (xy 102.041433 -59.772055) (xy 102.001284 -59.733346)
			(xy 101.967198 -59.689203) (xy 101.939902 -59.640568) (xy 101.919979 -59.588477) (xy 101.907853 -59.53404)
			(xy 101.903782 -59.478418) (xy 85.434852 -59.478418) (xy 85.452939 -59.49347) (xy 85.490156 -59.535007)
			(xy 85.520929 -59.58152) (xy 85.544601 -59.632017) (xy 85.560669 -59.685424) (xy 85.568789 -59.7406)
			(xy 85.569298 -59.768486) (xy 85.568789 -59.796372) (xy 85.560669 -59.851548) (xy 85.544601 -59.904955)
			(xy 85.520929 -59.955452) (xy 85.490156 -60.001965) (xy 85.452939 -60.043502) (xy 85.410071 -60.079177)
			(xy 85.362465 -60.108231) (xy 85.311136 -60.130043) (xy 85.257179 -60.144149) (xy 85.201742 -60.150249)
			(xy 85.146008 -60.148212) (xy 85.091165 -60.138082) (xy 85.038381 -60.120075) (xy 84.988781 -60.094574)
			(xy 84.943423 -60.062123) (xy 84.903274 -60.023414) (xy 84.869188 -59.979271) (xy 84.841892 -59.930636)
			(xy 84.821969 -59.878545) (xy 84.809843 -59.824108) (xy 84.805772 -59.768486) (xy 18.785105 -59.768486)
			(xy 18.790504 -59.787166) (xy 18.806509 -59.871499) (xy 18.814547 -59.956961) (xy 18.81505 -59.99988)
			(xy 18.814547 -60.042799) (xy 18.806509 -60.128261) (xy 18.790504 -60.212594) (xy 18.766671 -60.295058)
			(xy 18.735222 -60.374928) (xy 18.731692 -60.381896) (xy 79.372712 -60.381896) (xy 79.376783 -60.326274)
			(xy 79.388909 -60.271837) (xy 79.408832 -60.219746) (xy 79.436128 -60.171111) (xy 79.470214 -60.126968)
			(xy 79.510363 -60.088259) (xy 79.555721 -60.055808) (xy 79.605321 -60.030307) (xy 79.658105 -60.0123)
			(xy 79.712948 -60.00217) (xy 79.768682 -60.000133) (xy 79.824119 -60.006233) (xy 79.878076 -60.020339)
			(xy 79.929405 -60.042151) (xy 79.977011 -60.071205) (xy 80.019879 -60.10688) (xy 80.057096 -60.148417)
			(xy 80.087869 -60.19493) (xy 80.111541 -60.245427) (xy 80.127609 -60.298834) (xy 80.135729 -60.35401)
			(xy 80.136238 -60.381896) (xy 80.135729 -60.409782) (xy 80.127609 -60.464958) (xy 80.111541 -60.518365)
			(xy 80.098357 -60.546488) (xy 81.136742 -60.546488) (xy 81.140813 -60.490866) (xy 81.152939 -60.436429)
			(xy 81.172862 -60.384338) (xy 81.200158 -60.335703) (xy 81.234244 -60.29156) (xy 81.274393 -60.252851)
			(xy 81.319751 -60.2204) (xy 81.369351 -60.194899) (xy 81.422135 -60.176892) (xy 81.476978 -60.166762)
			(xy 81.532712 -60.164725) (xy 81.588149 -60.170825) (xy 81.642106 -60.184931) (xy 81.693435 -60.206743)
			(xy 81.741041 -60.235797) (xy 81.762465 -60.253626) (xy 82.181952 -60.253626) (xy 82.186023 -60.198004)
			(xy 82.198149 -60.143567) (xy 82.218072 -60.091476) (xy 82.245368 -60.042841) (xy 82.279454 -59.998698)
			(xy 82.319603 -59.959989) (xy 82.364961 -59.927538) (xy 82.414561 -59.902037) (xy 82.467345 -59.88403)
			(xy 82.522188 -59.8739) (xy 82.577922 -59.871863) (xy 82.633359 -59.877963) (xy 82.687316 -59.892069)
			(xy 82.738645 -59.913881) (xy 82.786251 -59.942935) (xy 82.829119 -59.97861) (xy 82.866336 -60.020147)
			(xy 82.897109 -60.06666) (xy 82.920781 -60.117157) (xy 82.936849 -60.170564) (xy 82.944969 -60.22574)
			(xy 82.945455 -60.252356) (xy 83.175092 -60.252356) (xy 83.179163 -60.196734) (xy 83.191289 -60.142297)
			(xy 83.211212 -60.090206) (xy 83.238508 -60.041571) (xy 83.272594 -59.997428) (xy 83.312743 -59.958719)
			(xy 83.358101 -59.926268) (xy 83.407701 -59.900767) (xy 83.460485 -59.88276) (xy 83.515328 -59.87263)
			(xy 83.571062 -59.870593) (xy 83.626499 -59.876693) (xy 83.680456 -59.890799) (xy 83.731785 -59.912611)
			(xy 83.779391 -59.941665) (xy 83.822259 -59.97734) (xy 83.859476 -60.018877) (xy 83.890249 -60.06539)
			(xy 83.913921 -60.115887) (xy 83.929989 -60.169294) (xy 83.938109 -60.22447) (xy 83.938618 -60.252356)
			(xy 84.064092 -60.252356) (xy 84.068163 -60.196734) (xy 84.080289 -60.142297) (xy 84.100212 -60.090206)
			(xy 84.127508 -60.041571) (xy 84.161594 -59.997428) (xy 84.201743 -59.958719) (xy 84.247101 -59.926268)
			(xy 84.296701 -59.900767) (xy 84.349485 -59.88276) (xy 84.404328 -59.87263) (xy 84.460062 -59.870593)
			(xy 84.515499 -59.876693) (xy 84.569456 -59.890799) (xy 84.620785 -59.912611) (xy 84.668391 -59.941665)
			(xy 84.711259 -59.97734) (xy 84.748476 -60.018877) (xy 84.779249 -60.06539) (xy 84.802921 -60.115887)
			(xy 84.818989 -60.169294) (xy 84.827109 -60.22447) (xy 84.827618 -60.252356) (xy 84.827109 -60.280242)
			(xy 84.818989 -60.335418) (xy 84.802921 -60.388825) (xy 84.779249 -60.439322) (xy 84.748476 -60.485835)
			(xy 84.711259 -60.527372) (xy 84.668391 -60.563047) (xy 84.620785 -60.592101) (xy 84.569456 -60.613913)
			(xy 84.515499 -60.628019) (xy 84.460062 -60.634119) (xy 84.404328 -60.632082) (xy 84.349485 -60.621952)
			(xy 84.296701 -60.603945) (xy 84.247101 -60.578444) (xy 84.201743 -60.545993) (xy 84.161594 -60.507284)
			(xy 84.127508 -60.463141) (xy 84.100212 -60.414506) (xy 84.080289 -60.362415) (xy 84.068163 -60.307978)
			(xy 84.064092 -60.252356) (xy 83.938618 -60.252356) (xy 83.938109 -60.280242) (xy 83.929989 -60.335418)
			(xy 83.913921 -60.388825) (xy 83.890249 -60.439322) (xy 83.859476 -60.485835) (xy 83.822259 -60.527372)
			(xy 83.779391 -60.563047) (xy 83.731785 -60.592101) (xy 83.680456 -60.613913) (xy 83.626499 -60.628019)
			(xy 83.571062 -60.634119) (xy 83.515328 -60.632082) (xy 83.460485 -60.621952) (xy 83.407701 -60.603945)
			(xy 83.358101 -60.578444) (xy 83.312743 -60.545993) (xy 83.272594 -60.507284) (xy 83.238508 -60.463141)
			(xy 83.211212 -60.414506) (xy 83.191289 -60.362415) (xy 83.179163 -60.307978) (xy 83.175092 -60.252356)
			(xy 82.945455 -60.252356) (xy 82.945478 -60.253626) (xy 82.944969 -60.281512) (xy 82.936849 -60.336688)
			(xy 82.920781 -60.390095) (xy 82.897109 -60.440592) (xy 82.866336 -60.487105) (xy 82.829119 -60.528642)
			(xy 82.786251 -60.564317) (xy 82.738645 -60.593371) (xy 82.687316 -60.615183) (xy 82.633359 -60.629289)
			(xy 82.577922 -60.635389) (xy 82.522188 -60.633352) (xy 82.467345 -60.623222) (xy 82.414561 -60.605215)
			(xy 82.364961 -60.579714) (xy 82.319603 -60.547263) (xy 82.279454 -60.508554) (xy 82.245368 -60.464411)
			(xy 82.218072 -60.415776) (xy 82.198149 -60.363685) (xy 82.186023 -60.309248) (xy 82.181952 -60.253626)
			(xy 81.762465 -60.253626) (xy 81.783909 -60.271472) (xy 81.821126 -60.313009) (xy 81.851899 -60.359522)
			(xy 81.875571 -60.410019) (xy 81.891639 -60.463426) (xy 81.899759 -60.518602) (xy 81.900268 -60.546488)
			(xy 81.899759 -60.574374) (xy 81.891639 -60.62955) (xy 81.875571 -60.682957) (xy 81.851899 -60.733454)
			(xy 81.821126 -60.779967) (xy 81.783909 -60.821504) (xy 81.741041 -60.857179) (xy 81.693435 -60.886233)
			(xy 81.642106 -60.908045) (xy 81.588149 -60.922151) (xy 81.532712 -60.928251) (xy 81.476978 -60.926214)
			(xy 81.422135 -60.916084) (xy 81.369351 -60.898077) (xy 81.319751 -60.872576) (xy 81.274393 -60.840125)
			(xy 81.234244 -60.801416) (xy 81.200158 -60.757273) (xy 81.172862 -60.708638) (xy 81.152939 -60.656547)
			(xy 81.140813 -60.60211) (xy 81.136742 -60.546488) (xy 80.098357 -60.546488) (xy 80.087869 -60.568862)
			(xy 80.057096 -60.615375) (xy 80.019879 -60.656912) (xy 79.977011 -60.692587) (xy 79.929405 -60.721641)
			(xy 79.878076 -60.743453) (xy 79.824119 -60.757559) (xy 79.768682 -60.763659) (xy 79.712948 -60.761622)
			(xy 79.658105 -60.751492) (xy 79.605321 -60.733485) (xy 79.555721 -60.707984) (xy 79.510363 -60.675533)
			(xy 79.470214 -60.636824) (xy 79.436128 -60.592681) (xy 79.408832 -60.544046) (xy 79.388909 -60.491955)
			(xy 79.376783 -60.437518) (xy 79.372712 -60.381896) (xy 18.731692 -60.381896) (xy 18.696431 -60.451502)
			(xy 18.650641 -60.524107) (xy 18.598253 -60.592105) (xy 18.539727 -60.654899) (xy 18.475579 -60.711936)
			(xy 18.406371 -60.762716) (xy 18.332713 -60.806792) (xy 18.25525 -60.843776) (xy 18.174665 -60.873345)
			(xy 18.091665 -60.895237) (xy 18.00698 -60.909261) (xy 17.921354 -60.915294) (xy 17.835539 -60.913282)
			(xy 17.750289 -60.903242) (xy 17.666354 -60.885264) (xy 17.584472 -60.859505) (xy 17.505361 -60.826192)
			(xy 17.429717 -60.785617) (xy 17.358206 -60.738137) (xy 17.291454 -60.684169) (xy 17.23005 -60.624188)
			(xy 17.174532 -60.55872) (xy 17.125389 -60.488341) (xy 17.083052 -60.41367) (xy 17.047893 -60.335362)
			(xy 17.020222 -60.254105) (xy 17.000281 -60.170615) (xy 16.988246 -60.085624) (xy 16.984223 -59.99988)
			(xy 6.678522 -59.99988) (xy 6.683807 -60.036637) (xy 6.683807 -60.091143) (xy 6.67605 -60.145095)
			(xy 6.660693 -60.197393) (xy 6.63805 -60.246974) (xy 6.608582 -60.292827) (xy 6.572888 -60.33402)
			(xy 6.531694 -60.369714) (xy 6.48584 -60.399182) (xy 6.436259 -60.421825) (xy 6.383961 -60.43718)
			(xy 6.330009 -60.444937) (xy 6.302756 -60.445396) (xy 6.273584 -60.444821) (xy 6.215929 -60.435886)
			(xy 6.187948 -60.427616) (xy 6.1748 -60.423931) (xy 6.147524 -60.422916) (xy 6.120954 -60.429166)
			(xy 6.096991 -60.442234) (xy 6.077348 -60.461186) (xy 6.063431 -60.484667) (xy 6.056234 -60.510996)
			(xy 6.055868 -60.524644) (xy 6.055868 -60.584334) (xy 6.056404 -60.599813) (xy 6.065657 -60.629356)
			(xy 6.083334 -60.65477) (xy 6.107812 -60.673724) (xy 6.136842 -60.684475) (xy 6.167761 -60.686038)
			(xy 6.182868 -60.682632) (xy 6.206456 -60.676905) (xy 6.254609 -60.670789) (xy 6.27888 -60.67044)
			(xy 6.306131 -60.670926) (xy 6.360079 -60.678682) (xy 6.412374 -60.694038) (xy 6.461952 -60.716679)
			(xy 6.507803 -60.746145) (xy 6.548993 -60.781837) (xy 6.584685 -60.823027) (xy 6.614151 -60.868878)
			(xy 6.636792 -60.918456) (xy 6.652148 -60.970751) (xy 6.659904 -61.024699) (xy 6.659904 -61.051948)
			(xy 8.170162 -61.051948) (xy 8.174233 -60.996326) (xy 8.186359 -60.941889) (xy 8.206282 -60.889798)
			(xy 8.233578 -60.841163) (xy 8.267664 -60.79702) (xy 8.307813 -60.758311) (xy 8.353171 -60.72586)
			(xy 8.402771 -60.700359) (xy 8.455555 -60.682352) (xy 8.510398 -60.672222) (xy 8.566132 -60.670185)
			(xy 8.621569 -60.676285) (xy 8.675526 -60.690391) (xy 8.726855 -60.712203) (xy 8.774461 -60.741257)
			(xy 8.817329 -60.776932) (xy 8.854546 -60.818469) (xy 8.885319 -60.864982) (xy 8.908991 -60.915479)
			(xy 8.925059 -60.968886) (xy 8.92962 -60.999878) (xy 21.408134 -60.999878) (xy 21.412205 -60.944256)
			(xy 21.424331 -60.889819) (xy 21.444254 -60.837728) (xy 21.47155 -60.789093) (xy 21.505636 -60.74495)
			(xy 21.545785 -60.706241) (xy 21.591143 -60.67379) (xy 21.640743 -60.648289) (xy 21.693527 -60.630282)
			(xy 21.74837 -60.620152) (xy 21.804104 -60.618115) (xy 21.859541 -60.624215) (xy 21.913498 -60.638321)
			(xy 21.964827 -60.660133) (xy 22.012433 -60.689187) (xy 22.055301 -60.724862) (xy 22.092518 -60.766399)
			(xy 22.123291 -60.812912) (xy 22.146963 -60.863409) (xy 22.163031 -60.916816) (xy 22.171151 -60.971992)
			(xy 22.17166 -60.999878) (xy 22.171151 -61.027764) (xy 22.163031 -61.08294) (xy 22.146963 -61.136347)
			(xy 22.123291 -61.186844) (xy 22.092518 -61.233357) (xy 22.055301 -61.274894) (xy 22.012433 -61.310569)
			(xy 21.964827 -61.339623) (xy 21.913498 -61.361435) (xy 21.859541 -61.375541) (xy 21.804104 -61.381641)
			(xy 21.74837 -61.379604) (xy 21.693527 -61.369474) (xy 21.640743 -61.351467) (xy 21.591143 -61.325966)
			(xy 21.545785 -61.293515) (xy 21.505636 -61.254806) (xy 21.47155 -61.210663) (xy 21.444254 -61.162028)
			(xy 21.424331 -61.109937) (xy 21.412205 -61.0555) (xy 21.408134 -60.999878) (xy 8.92962 -60.999878)
			(xy 8.933179 -61.024062) (xy 8.933688 -61.051948) (xy 8.933179 -61.079834) (xy 8.925059 -61.13501)
			(xy 8.908991 -61.188417) (xy 8.885319 -61.238914) (xy 8.854546 -61.285427) (xy 8.817329 -61.326964)
			(xy 8.774461 -61.362639) (xy 8.726855 -61.391693) (xy 8.675526 -61.413505) (xy 8.621569 -61.427611)
			(xy 8.566132 -61.433711) (xy 8.510398 -61.431674) (xy 8.455555 -61.421544) (xy 8.402771 -61.403537)
			(xy 8.353171 -61.378036) (xy 8.307813 -61.345585) (xy 8.267664 -61.306876) (xy 8.233578 -61.262733)
			(xy 8.206282 -61.214098) (xy 8.186359 -61.162007) (xy 8.174233 -61.10757) (xy 8.170162 -61.051948)
			(xy 6.659904 -61.051948) (xy 6.659904 -61.079201) (xy 6.652148 -61.133149) (xy 6.636792 -61.185444)
			(xy 6.614151 -61.235022) (xy 6.584685 -61.280873) (xy 6.548993 -61.322063) (xy 6.507803 -61.357755)
			(xy 6.461952 -61.387221) (xy 6.412374 -61.409862) (xy 6.360079 -61.425218) (xy 6.306131 -61.432974)
			(xy 6.27888 -61.433456) (xy 6.25461 -61.433092) (xy 6.206458 -61.426978) (xy 6.182868 -61.421264)
			(xy 6.167754 -61.41793) (xy 6.136859 -61.419519) (xy 6.107852 -61.430271) (xy 6.083387 -61.449205)
			(xy 6.065701 -61.474586) (xy 6.056412 -61.504095) (xy 6.055868 -61.519562) (xy 6.055868 -70.814692)
			(xy 21.930612 -70.814692) (xy 21.934683 -70.75907) (xy 21.946809 -70.704633) (xy 21.966732 -70.652542)
			(xy 21.994028 -70.603907) (xy 22.028114 -70.559764) (xy 22.068263 -70.521055) (xy 22.113621 -70.488604)
			(xy 22.163221 -70.463103) (xy 22.216005 -70.445096) (xy 22.270848 -70.434966) (xy 22.326582 -70.432929)
			(xy 22.382019 -70.439029) (xy 22.435976 -70.453135) (xy 22.487305 -70.474947) (xy 22.534911 -70.504001)
			(xy 22.577779 -70.539676) (xy 22.614996 -70.581213) (xy 22.645769 -70.627726) (xy 22.669441 -70.678223)
			(xy 22.685509 -70.73163) (xy 22.693629 -70.786806) (xy 22.694138 -70.814692) (xy 22.693781 -70.83425)
			(xy 29.823662 -70.83425) (xy 29.827733 -70.778628) (xy 29.839859 -70.724191) (xy 29.859782 -70.6721)
			(xy 29.887078 -70.623465) (xy 29.921164 -70.579322) (xy 29.961313 -70.540613) (xy 30.006671 -70.508162)
			(xy 30.056271 -70.482661) (xy 30.109055 -70.464654) (xy 30.163898 -70.454524) (xy 30.219632 -70.452487)
			(xy 30.275069 -70.458587) (xy 30.329026 -70.472693) (xy 30.380355 -70.494505) (xy 30.427961 -70.523559)
			(xy 30.470829 -70.559234) (xy 30.508046 -70.600771) (xy 30.538819 -70.647284) (xy 30.562491 -70.697781)
			(xy 30.578559 -70.751188) (xy 30.586679 -70.806364) (xy 30.587188 -70.83425) (xy 30.586679 -70.862136)
			(xy 30.578559 -70.917312) (xy 30.562491 -70.970719) (xy 30.538819 -71.021216) (xy 30.508046 -71.067729)
			(xy 30.470829 -71.109266) (xy 30.427961 -71.144941) (xy 30.380355 -71.173995) (xy 30.329026 -71.195807)
			(xy 30.275069 -71.209913) (xy 30.219632 -71.216013) (xy 30.163898 -71.213976) (xy 30.109055 -71.203846)
			(xy 30.056271 -71.185839) (xy 30.006671 -71.160338) (xy 29.961313 -71.127887) (xy 29.921164 -71.089178)
			(xy 29.887078 -71.045035) (xy 29.859782 -70.9964) (xy 29.839859 -70.944309) (xy 29.827733 -70.889872)
			(xy 29.823662 -70.83425) (xy 22.693781 -70.83425) (xy 22.693629 -70.842578) (xy 22.685509 -70.897754)
			(xy 22.669441 -70.951161) (xy 22.645769 -71.001658) (xy 22.614996 -71.048171) (xy 22.577779 -71.089708)
			(xy 22.534911 -71.125383) (xy 22.487305 -71.154437) (xy 22.435976 -71.176249) (xy 22.382019 -71.190355)
			(xy 22.326582 -71.196455) (xy 22.270848 -71.194418) (xy 22.216005 -71.184288) (xy 22.163221 -71.166281)
			(xy 22.113621 -71.14078) (xy 22.068263 -71.108329) (xy 22.028114 -71.06962) (xy 21.994028 -71.025477)
			(xy 21.966732 -70.976842) (xy 21.946809 -70.924751) (xy 21.934683 -70.870314) (xy 21.930612 -70.814692)
			(xy 6.055868 -70.814692) (xy 6.055868 -71.821548) (xy 22.655782 -71.821548) (xy 22.659853 -71.765926)
			(xy 22.671979 -71.711489) (xy 22.691902 -71.659398) (xy 22.719198 -71.610763) (xy 22.753284 -71.56662)
			(xy 22.793433 -71.527911) (xy 22.838791 -71.49546) (xy 22.888391 -71.469959) (xy 22.941175 -71.451952)
			(xy 22.996018 -71.441822) (xy 23.051752 -71.439785) (xy 23.107189 -71.445885) (xy 23.161146 -71.459991)
			(xy 23.212475 -71.481803) (xy 23.260081 -71.510857) (xy 23.302949 -71.546532) (xy 23.340166 -71.588069)
			(xy 23.370939 -71.634582) (xy 23.394611 -71.685079) (xy 23.410679 -71.738486) (xy 23.418799 -71.793662)
			(xy 23.419308 -71.821548) (xy 23.418799 -71.849434) (xy 23.410679 -71.90461) (xy 23.394611 -71.958017)
			(xy 23.370939 -72.008514) (xy 23.340166 -72.055027) (xy 23.302949 -72.096564) (xy 23.260081 -72.132239)
			(xy 23.212475 -72.161293) (xy 23.161146 -72.183105) (xy 23.107189 -72.197211) (xy 23.051752 -72.203311)
			(xy 22.996018 -72.201274) (xy 22.941175 -72.191144) (xy 22.888391 -72.173137) (xy 22.838791 -72.147636)
			(xy 22.793433 -72.115185) (xy 22.753284 -72.076476) (xy 22.719198 -72.032333) (xy 22.691902 -71.983698)
			(xy 22.671979 -71.931607) (xy 22.659853 -71.87717) (xy 22.655782 -71.821548) (xy 6.055868 -71.821548)
			(xy 6.055868 -72.471534) (xy 21.873462 -72.471534) (xy 21.877533 -72.415912) (xy 21.889659 -72.361475)
			(xy 21.909582 -72.309384) (xy 21.936878 -72.260749) (xy 21.970964 -72.216606) (xy 22.011113 -72.177897)
			(xy 22.056471 -72.145446) (xy 22.106071 -72.119945) (xy 22.158855 -72.101938) (xy 22.213698 -72.091808)
			(xy 22.269432 -72.089771) (xy 22.324869 -72.095871) (xy 22.378826 -72.109977) (xy 22.430155 -72.131789)
			(xy 22.477761 -72.160843) (xy 22.520629 -72.196518) (xy 22.557846 -72.238055) (xy 22.588619 -72.284568)
			(xy 22.612291 -72.335065) (xy 22.628359 -72.388472) (xy 22.636479 -72.443648) (xy 22.636988 -72.471534)
			(xy 22.636479 -72.49942) (xy 22.634079 -72.51573) (xy 28.59608 -72.51573) (xy 28.600151 -72.460108)
			(xy 28.612277 -72.405671) (xy 28.6322 -72.35358) (xy 28.659496 -72.304945) (xy 28.693582 -72.260802)
			(xy 28.733731 -72.222093) (xy 28.779089 -72.189642) (xy 28.828689 -72.164141) (xy 28.881473 -72.146134)
			(xy 28.936316 -72.136004) (xy 28.99205 -72.133967) (xy 29.047487 -72.140067) (xy 29.101444 -72.154173)
			(xy 29.152773 -72.175985) (xy 29.200379 -72.205039) (xy 29.243247 -72.240714) (xy 29.280464 -72.282251)
			(xy 29.311237 -72.328764) (xy 29.334909 -72.379261) (xy 29.350977 -72.432668) (xy 29.359097 -72.487844)
			(xy 29.359606 -72.51573) (xy 29.359097 -72.543616) (xy 29.350977 -72.598792) (xy 29.334909 -72.652199)
			(xy 29.311237 -72.702696) (xy 29.280464 -72.749209) (xy 29.243247 -72.790746) (xy 29.200379 -72.826421)
			(xy 29.152773 -72.855475) (xy 29.101444 -72.877287) (xy 29.047487 -72.891393) (xy 28.99205 -72.897493)
			(xy 28.936316 -72.895456) (xy 28.881473 -72.885326) (xy 28.828689 -72.867319) (xy 28.779089 -72.841818)
			(xy 28.733731 -72.809367) (xy 28.693582 -72.770658) (xy 28.659496 -72.726515) (xy 28.6322 -72.67788)
			(xy 28.612277 -72.625789) (xy 28.600151 -72.571352) (xy 28.59608 -72.51573) (xy 22.634079 -72.51573)
			(xy 22.628359 -72.554596) (xy 22.612291 -72.608003) (xy 22.588619 -72.6585) (xy 22.557846 -72.705013)
			(xy 22.520629 -72.74655) (xy 22.477761 -72.782225) (xy 22.430155 -72.811279) (xy 22.378826 -72.833091)
			(xy 22.324869 -72.847197) (xy 22.269432 -72.853297) (xy 22.213698 -72.85126) (xy 22.158855 -72.84113)
			(xy 22.106071 -72.823123) (xy 22.056471 -72.797622) (xy 22.011113 -72.765171) (xy 21.970964 -72.726462)
			(xy 21.936878 -72.682319) (xy 21.909582 -72.633684) (xy 21.889659 -72.581593) (xy 21.877533 -72.527156)
			(xy 21.873462 -72.471534) (xy 6.055868 -72.471534) (xy 6.055868 -74.521568) (xy 9.778492 -74.521568)
			(xy 9.778894 -74.493623) (xy 9.78703 -74.438329) (xy 9.803154 -74.384815) (xy 9.82692 -74.33423)
			(xy 9.857817 -74.287657) (xy 9.895184 -74.246095) (xy 9.938219 -74.210435) (xy 9.986 -74.181441)
			(xy 10.037503 -74.159735) (xy 10.091623 -74.145783) (xy 10.11936 -74.142346) (xy 10.133332 -74.140443)
			(xy 10.15948 -74.129912) (xy 10.181756 -74.112638) (xy 10.198464 -74.089935) (xy 10.208334 -74.06353)
			(xy 10.210612 -74.035433) (xy 10.205127 -74.007782) (xy 10.199116 -73.995026) (xy 10.185978 -73.968061)
			(xy 10.167408 -73.911028) (xy 10.158015 -73.851788) (xy 10.15746 -73.821798) (xy 10.157946 -73.794547)
			(xy 10.165702 -73.740599) (xy 10.181057 -73.688304) (xy 10.203699 -73.638727) (xy 10.233165 -73.592877)
			(xy 10.268856 -73.551686) (xy 10.310047 -73.515995) (xy 10.355897 -73.486529) (xy 10.405474 -73.463887)
			(xy 10.457769 -73.448532) (xy 10.511717 -73.440776) (xy 10.566219 -73.440776) (xy 10.620167 -73.448532)
			(xy 10.672462 -73.463887) (xy 10.722039 -73.486529) (xy 10.767889 -73.515995) (xy 10.80908 -73.551686)
			(xy 10.844771 -73.592877) (xy 10.874237 -73.638727) (xy 10.896879 -73.688304) (xy 10.912234 -73.740599)
			(xy 10.91999 -73.794547) (xy 10.920476 -73.821798) (xy 10.919983 -73.849739) (xy 10.911852 -73.905027)
			(xy 10.895736 -73.958535) (xy 10.87198 -74.009116) (xy 10.841093 -74.055687) (xy 10.803737 -74.097248)
			(xy 10.760713 -74.13291) (xy 10.712943 -74.161907) (xy 10.661451 -74.183618) (xy 10.607341 -74.197578)
			(xy 10.579608 -74.20102) (xy 10.565643 -74.20295) (xy 10.539502 -74.213482) (xy 10.517233 -74.230754)
			(xy 10.500528 -74.253452) (xy 10.490657 -74.279849) (xy 10.488373 -74.307939) (xy 10.493847 -74.335584)
			(xy 10.499852 -74.34834) (xy 10.512976 -74.375312) (xy 10.531552 -74.432341) (xy 10.540951 -74.491579)
			(xy 10.541508 -74.521568) (xy 10.541022 -74.548819) (xy 10.533266 -74.602767) (xy 10.517911 -74.655062)
			(xy 10.495269 -74.704639) (xy 10.465803 -74.750489) (xy 10.430112 -74.79168) (xy 10.388921 -74.827371)
			(xy 10.343071 -74.856837) (xy 10.293494 -74.879479) (xy 10.241199 -74.894834) (xy 10.187251 -74.90259)
			(xy 10.132749 -74.90259) (xy 10.078801 -74.894834) (xy 10.026506 -74.879479) (xy 9.976929 -74.856837)
			(xy 9.931079 -74.827371) (xy 9.889888 -74.79168) (xy 9.854197 -74.750489) (xy 9.824731 -74.704639)
			(xy 9.802089 -74.655062) (xy 9.786734 -74.602767) (xy 9.778978 -74.548819) (xy 9.778492 -74.521568)
			(xy 6.055868 -74.521568) (xy 6.055868 -75.171808) (xy 8.761982 -75.171808) (xy 8.766053 -75.116186)
			(xy 8.778179 -75.061749) (xy 8.798102 -75.009658) (xy 8.825398 -74.961023) (xy 8.859484 -74.91688)
			(xy 8.899633 -74.878171) (xy 8.944991 -74.84572) (xy 8.994591 -74.820219) (xy 9.047375 -74.802212)
			(xy 9.102218 -74.792082) (xy 9.157952 -74.790045) (xy 9.213389 -74.796145) (xy 9.267346 -74.810251)
			(xy 9.318675 -74.832063) (xy 9.366281 -74.861117) (xy 9.409149 -74.896792) (xy 9.446366 -74.938329)
			(xy 9.477139 -74.984842) (xy 9.500811 -75.035339) (xy 9.516879 -75.088746) (xy 9.524999 -75.143922)
			(xy 9.525508 -75.171808) (xy 15.371062 -75.171808) (xy 15.375133 -75.116186) (xy 15.387259 -75.061749)
			(xy 15.407182 -75.009658) (xy 15.434478 -74.961023) (xy 15.468564 -74.91688) (xy 15.508713 -74.878171)
			(xy 15.554071 -74.84572) (xy 15.603671 -74.820219) (xy 15.656455 -74.802212) (xy 15.711298 -74.792082)
			(xy 15.767032 -74.790045) (xy 15.822469 -74.796145) (xy 15.876426 -74.810251) (xy 15.927755 -74.832063)
			(xy 15.975361 -74.861117) (xy 16.018229 -74.896792) (xy 16.055446 -74.938329) (xy 16.086219 -74.984842)
			(xy 16.109891 -75.035339) (xy 16.125959 -75.088746) (xy 16.132426 -75.132692) (xy 21.930612 -75.132692)
			(xy 21.934683 -75.07707) (xy 21.946809 -75.022633) (xy 21.966732 -74.970542) (xy 21.994028 -74.921907)
			(xy 22.028114 -74.877764) (xy 22.068263 -74.839055) (xy 22.113621 -74.806604) (xy 22.163221 -74.781103)
			(xy 22.216005 -74.763096) (xy 22.270848 -74.752966) (xy 22.326582 -74.750929) (xy 22.382019 -74.757029)
			(xy 22.396581 -74.760836) (xy 39.554404 -74.760836) (xy 39.554404 -66.060828) (xy 39.554909 -65.955304)
			(xy 39.562993 -65.74441) (xy 39.579149 -65.533981) (xy 39.603352 -65.324324) (xy 39.635569 -65.115749)
			(xy 39.675751 -64.908561) (xy 39.723839 -64.703064) (xy 39.779763 -64.49956) (xy 39.84344 -64.298347)
			(xy 39.914778 -64.09972) (xy 39.993672 -63.903972) (xy 40.080005 -63.71139) (xy 40.173652 -63.522255)
			(xy 40.274474 -63.336846) (xy 40.382324 -63.155435) (xy 40.497043 -62.978288) (xy 40.618463 -62.805666)
			(xy 40.746406 -62.63782) (xy 40.880684 -62.474998) (xy 41.0211 -62.317439) (xy 41.167448 -62.165374)
			(xy 41.319513 -62.019026) (xy 41.477072 -61.87861) (xy 41.639894 -61.744332) (xy 41.80774 -61.616389)
			(xy 41.980362 -61.494969) (xy 42.157509 -61.38025) (xy 42.33892 -61.2724) (xy 42.524329 -61.171578)
			(xy 42.713464 -61.077931) (xy 42.906046 -60.991598) (xy 43.101794 -60.912704) (xy 43.300421 -60.841366)
			(xy 43.501634 -60.777689) (xy 43.705138 -60.721765) (xy 43.910635 -60.673677) (xy 44.117823 -60.633495)
			(xy 44.326398 -60.601278) (xy 44.536055 -60.577075) (xy 44.746484 -60.560919) (xy 44.957378 -60.552835)
			(xy 45.168426 -60.552835) (xy 45.37932 -60.560919) (xy 45.589749 -60.577075) (xy 45.799406 -60.601278)
			(xy 46.007981 -60.633495) (xy 46.215169 -60.673677) (xy 46.420666 -60.721765) (xy 46.62417 -60.777689)
			(xy 46.825383 -60.841366) (xy 47.02401 -60.912704) (xy 47.083379 -60.936632) (xy 102.523798 -60.936632)
			(xy 102.524275 -60.910269) (xy 102.531556 -60.858048) (xy 102.545955 -60.807326) (xy 102.567199 -60.759069)
			(xy 102.594882 -60.714195) (xy 102.628479 -60.673559) (xy 102.66735 -60.637935) (xy 102.710754 -60.607999)
			(xy 102.73411 -60.595764) (xy 102.746922 -60.588823) (xy 102.768255 -60.568992) (xy 102.78313 -60.543949)
			(xy 102.790338 -60.515728) (xy 102.789294 -60.48662) (xy 102.780083 -60.458988) (xy 102.763454 -60.435075)
			(xy 102.752398 -60.425584) (xy 102.730582 -60.407375) (xy 102.692073 -60.36559) (xy 102.660183 -60.318558)
			(xy 102.635616 -60.267319) (xy 102.618915 -60.213005) (xy 102.610448 -60.156816) (xy 102.609904 -60.128404)
			(xy 102.61039 -60.101153) (xy 102.618146 -60.047205) (xy 102.633501 -59.99491) (xy 102.656143 -59.945333)
			(xy 102.685609 -59.899483) (xy 102.7213 -59.858292) (xy 102.762491 -59.822601) (xy 102.808341 -59.793135)
			(xy 102.857918 -59.770493) (xy 102.910213 -59.755138) (xy 102.964161 -59.747382) (xy 103.018663 -59.747382)
			(xy 103.072611 -59.755138) (xy 103.124906 -59.770493) (xy 103.174483 -59.793135) (xy 103.220333 -59.822601)
			(xy 103.261524 -59.858292) (xy 103.297215 -59.899483) (xy 103.326681 -59.945333) (xy 103.349323 -59.99491)
			(xy 103.364678 -60.047205) (xy 103.370363 -60.086748) (xy 108.684312 -60.086748) (xy 108.688383 -60.031126)
			(xy 108.700509 -59.976689) (xy 108.720432 -59.924598) (xy 108.747728 -59.875963) (xy 108.781814 -59.83182)
			(xy 108.821963 -59.793111) (xy 108.867321 -59.76066) (xy 108.916921 -59.735159) (xy 108.969705 -59.717152)
			(xy 109.024548 -59.707022) (xy 109.080282 -59.704985) (xy 109.135719 -59.711085) (xy 109.189676 -59.725191)
			(xy 109.241005 -59.747003) (xy 109.288611 -59.776057) (xy 109.331479 -59.811732) (xy 109.368696 -59.853269)
			(xy 109.399469 -59.899782) (xy 109.423141 -59.950279) (xy 109.439209 -60.003686) (xy 109.447329 -60.058862)
			(xy 109.447838 -60.086748) (xy 109.447329 -60.114634) (xy 109.439209 -60.16981) (xy 109.423141 -60.223217)
			(xy 109.399469 -60.273714) (xy 109.368696 -60.320227) (xy 109.331479 -60.361764) (xy 109.288611 -60.397439)
			(xy 109.256645 -60.416948) (xy 128.649982 -60.416948) (xy 128.654053 -60.361326) (xy 128.666179 -60.306889)
			(xy 128.686102 -60.254798) (xy 128.713398 -60.206163) (xy 128.747484 -60.16202) (xy 128.787633 -60.123311)
			(xy 128.832991 -60.09086) (xy 128.882591 -60.065359) (xy 128.935375 -60.047352) (xy 128.990218 -60.037222)
			(xy 129.045952 -60.035185) (xy 129.101389 -60.041285) (xy 129.155346 -60.055391) (xy 129.199251 -60.074048)
			(xy 137.893042 -60.074048) (xy 137.897113 -60.018426) (xy 137.909239 -59.963989) (xy 137.929162 -59.911898)
			(xy 137.956458 -59.863263) (xy 137.990544 -59.81912) (xy 138.030693 -59.780411) (xy 138.076051 -59.74796)
			(xy 138.125651 -59.722459) (xy 138.178435 -59.704452) (xy 138.233278 -59.694322) (xy 138.289012 -59.692285)
			(xy 138.344449 -59.698385) (xy 138.398406 -59.712491) (xy 138.449735 -59.734303) (xy 138.497341 -59.763357)
			(xy 138.540209 -59.799032) (xy 138.577426 -59.840569) (xy 138.608199 -59.887082) (xy 138.631871 -59.937579)
			(xy 138.647939 -59.990986) (xy 138.656059 -60.046162) (xy 138.656568 -60.074048) (xy 138.909042 -60.074048)
			(xy 138.913113 -60.018426) (xy 138.925239 -59.963989) (xy 138.945162 -59.911898) (xy 138.972458 -59.863263)
			(xy 139.006544 -59.81912) (xy 139.046693 -59.780411) (xy 139.092051 -59.74796) (xy 139.141651 -59.722459)
			(xy 139.194435 -59.704452) (xy 139.249278 -59.694322) (xy 139.305012 -59.692285) (xy 139.360449 -59.698385)
			(xy 139.414406 -59.712491) (xy 139.465735 -59.734303) (xy 139.513341 -59.763357) (xy 139.556209 -59.799032)
			(xy 139.593426 -59.840569) (xy 139.624199 -59.887082) (xy 139.647871 -59.937579) (xy 139.663939 -59.990986)
			(xy 139.672059 -60.046162) (xy 139.672568 -60.074048) (xy 139.672059 -60.101934) (xy 139.663939 -60.15711)
			(xy 139.653318 -60.192412) (xy 147.383752 -60.192412) (xy 147.387823 -60.13679) (xy 147.399949 -60.082353)
			(xy 147.419872 -60.030262) (xy 147.447168 -59.981627) (xy 147.481254 -59.937484) (xy 147.521403 -59.898775)
			(xy 147.566761 -59.866324) (xy 147.616361 -59.840823) (xy 147.669145 -59.822816) (xy 147.723988 -59.812686)
			(xy 147.779722 -59.810649) (xy 147.835159 -59.816749) (xy 147.889116 -59.830855) (xy 147.940445 -59.852667)
			(xy 147.988051 -59.881721) (xy 148.030919 -59.917396) (xy 148.068136 -59.958933) (xy 148.098909 -60.005446)
			(xy 148.122581 -60.055943) (xy 148.138649 -60.10935) (xy 148.146537 -60.162948) (xy 159.039812 -60.162948)
			(xy 159.043883 -60.107326) (xy 159.056009 -60.052889) (xy 159.075932 -60.000798) (xy 159.103228 -59.952163)
			(xy 159.137314 -59.90802) (xy 159.177463 -59.869311) (xy 159.222821 -59.83686) (xy 159.272421 -59.811359)
			(xy 159.325205 -59.793352) (xy 159.380048 -59.783222) (xy 159.435782 -59.781185) (xy 159.491219 -59.787285)
			(xy 159.545176 -59.801391) (xy 159.596505 -59.823203) (xy 159.644111 -59.852257) (xy 159.686979 -59.887932)
			(xy 159.724196 -59.929469) (xy 159.754969 -59.975982) (xy 159.778641 -60.026479) (xy 159.794709 -60.079886)
			(xy 159.802829 -60.135062) (xy 159.803338 -60.162948) (xy 159.802829 -60.190834) (xy 159.794709 -60.24601)
			(xy 159.778641 -60.299417) (xy 159.754969 -60.349914) (xy 159.724196 -60.396427) (xy 159.686979 -60.437964)
			(xy 159.644111 -60.473639) (xy 159.596505 -60.502693) (xy 159.545176 -60.524505) (xy 159.491219 -60.538611)
			(xy 159.435782 -60.544711) (xy 159.380048 -60.542674) (xy 159.325205 -60.532544) (xy 159.272421 -60.514537)
			(xy 159.222821 -60.489036) (xy 159.177463 -60.456585) (xy 159.137314 -60.417876) (xy 159.103228 -60.373733)
			(xy 159.075932 -60.325098) (xy 159.056009 -60.273007) (xy 159.043883 -60.21857) (xy 159.039812 -60.162948)
			(xy 148.146537 -60.162948) (xy 148.146769 -60.164526) (xy 148.147278 -60.192412) (xy 148.146769 -60.220298)
			(xy 148.138649 -60.275474) (xy 148.122581 -60.328881) (xy 148.098909 -60.379378) (xy 148.068136 -60.425891)
			(xy 148.030919 -60.467428) (xy 147.988051 -60.503103) (xy 147.940445 -60.532157) (xy 147.889116 -60.553969)
			(xy 147.835159 -60.568075) (xy 147.779722 -60.574175) (xy 147.723988 -60.572138) (xy 147.669145 -60.562008)
			(xy 147.616361 -60.544001) (xy 147.566761 -60.5185) (xy 147.521403 -60.486049) (xy 147.481254 -60.44734)
			(xy 147.447168 -60.403197) (xy 147.419872 -60.354562) (xy 147.399949 -60.302471) (xy 147.387823 -60.248034)
			(xy 147.383752 -60.192412) (xy 139.653318 -60.192412) (xy 139.647871 -60.210517) (xy 139.624199 -60.261014)
			(xy 139.593426 -60.307527) (xy 139.556209 -60.349064) (xy 139.513341 -60.384739) (xy 139.465735 -60.413793)
			(xy 139.414406 -60.435605) (xy 139.360449 -60.449711) (xy 139.305012 -60.455811) (xy 139.249278 -60.453774)
			(xy 139.194435 -60.443644) (xy 139.141651 -60.425637) (xy 139.092051 -60.400136) (xy 139.046693 -60.367685)
			(xy 139.006544 -60.328976) (xy 138.972458 -60.284833) (xy 138.945162 -60.236198) (xy 138.925239 -60.184107)
			(xy 138.913113 -60.12967) (xy 138.909042 -60.074048) (xy 138.656568 -60.074048) (xy 138.656059 -60.101934)
			(xy 138.647939 -60.15711) (xy 138.631871 -60.210517) (xy 138.608199 -60.261014) (xy 138.577426 -60.307527)
			(xy 138.540209 -60.349064) (xy 138.497341 -60.384739) (xy 138.449735 -60.413793) (xy 138.398406 -60.435605)
			(xy 138.344449 -60.449711) (xy 138.289012 -60.455811) (xy 138.233278 -60.453774) (xy 138.178435 -60.443644)
			(xy 138.125651 -60.425637) (xy 138.076051 -60.400136) (xy 138.030693 -60.367685) (xy 137.990544 -60.328976)
			(xy 137.956458 -60.284833) (xy 137.929162 -60.236198) (xy 137.909239 -60.184107) (xy 137.897113 -60.12967)
			(xy 137.893042 -60.074048) (xy 129.199251 -60.074048) (xy 129.206675 -60.077203) (xy 129.254281 -60.106257)
			(xy 129.297149 -60.141932) (xy 129.334366 -60.183469) (xy 129.365139 -60.229982) (xy 129.388811 -60.280479)
			(xy 129.404879 -60.333886) (xy 129.412999 -60.389062) (xy 129.413508 -60.416948) (xy 129.412999 -60.444834)
			(xy 129.404879 -60.50001) (xy 129.388811 -60.553417) (xy 129.365139 -60.603914) (xy 129.334366 -60.650427)
			(xy 129.297149 -60.691964) (xy 129.254281 -60.727639) (xy 129.206675 -60.756693) (xy 129.155346 -60.778505)
			(xy 129.101389 -60.792611) (xy 129.045952 -60.798711) (xy 128.990218 -60.796674) (xy 128.935375 -60.786544)
			(xy 128.882591 -60.768537) (xy 128.832991 -60.743036) (xy 128.787633 -60.710585) (xy 128.747484 -60.671876)
			(xy 128.713398 -60.627733) (xy 128.686102 -60.579098) (xy 128.666179 -60.527007) (xy 128.654053 -60.47257)
			(xy 128.649982 -60.416948) (xy 109.256645 -60.416948) (xy 109.241005 -60.426493) (xy 109.189676 -60.448305)
			(xy 109.135719 -60.462411) (xy 109.080282 -60.468511) (xy 109.024548 -60.466474) (xy 108.969705 -60.456344)
			(xy 108.916921 -60.438337) (xy 108.867321 -60.412836) (xy 108.821963 -60.380385) (xy 108.781814 -60.341676)
			(xy 108.747728 -60.297533) (xy 108.720432 -60.248898) (xy 108.700509 -60.196807) (xy 108.688383 -60.14237)
			(xy 108.684312 -60.086748) (xy 103.370363 -60.086748) (xy 103.372434 -60.101153) (xy 103.37292 -60.128404)
			(xy 103.372517 -60.15477) (xy 103.36523 -60.206996) (xy 103.350823 -60.257722) (xy 103.32957 -60.305981)
			(xy 103.301875 -60.350856) (xy 103.268267 -60.39149) (xy 103.229385 -60.427111) (xy 103.18597 -60.457041)
			(xy 103.162608 -60.469272) (xy 103.149766 -60.476165) (xy 103.128427 -60.496004) (xy 103.11355 -60.521056)
			(xy 103.106344 -60.549288) (xy 103.107394 -60.578406) (xy 103.116615 -60.606045) (xy 103.133257 -60.629961)
			(xy 103.14432 -60.639452) (xy 103.166109 -60.657691) (xy 103.204619 -60.699471) (xy 103.236511 -60.746497)
			(xy 103.261083 -60.797729) (xy 103.27779 -60.852038) (xy 103.286265 -60.908222) (xy 103.286814 -60.936632)
			(xy 103.286328 -60.963883) (xy 103.278572 -61.017831) (xy 103.263217 -61.070126) (xy 103.240575 -61.119703)
			(xy 103.211109 -61.165553) (xy 103.175418 -61.206744) (xy 103.134227 -61.242435) (xy 103.088377 -61.271901)
			(xy 103.0388 -61.294543) (xy 102.986505 -61.309898) (xy 102.932557 -61.317654) (xy 102.878055 -61.317654)
			(xy 102.824107 -61.309898) (xy 102.771812 -61.294543) (xy 102.722235 -61.271901) (xy 102.676385 -61.242435)
			(xy 102.635194 -61.206744) (xy 102.599503 -61.165553) (xy 102.570037 -61.119703) (xy 102.547395 -61.070126)
			(xy 102.53204 -61.017831) (xy 102.524284 -60.963883) (xy 102.523798 -60.936632) (xy 47.083379 -60.936632)
			(xy 47.219758 -60.991598) (xy 47.41234 -61.077931) (xy 47.601475 -61.171578) (xy 47.786884 -61.2724)
			(xy 47.968295 -61.38025) (xy 48.077126 -61.450728) (xy 103.780842 -61.450728) (xy 103.784913 -61.395106)
			(xy 103.797039 -61.340669) (xy 103.816962 -61.288578) (xy 103.844258 -61.239943) (xy 103.878344 -61.1958)
			(xy 103.918493 -61.157091) (xy 103.963851 -61.12464) (xy 104.013451 -61.099139) (xy 104.066235 -61.081132)
			(xy 104.121078 -61.071002) (xy 104.176812 -61.068965) (xy 104.232249 -61.075065) (xy 104.286206 -61.089171)
			(xy 104.337535 -61.110983) (xy 104.385141 -61.140037) (xy 104.428009 -61.175712) (xy 104.465226 -61.217249)
			(xy 104.495999 -61.263762) (xy 104.519671 -61.314259) (xy 104.535739 -61.367666) (xy 104.543859 -61.422842)
			(xy 104.544368 -61.450728) (xy 104.543859 -61.478614) (xy 104.535739 -61.53379) (xy 104.519671 -61.587197)
			(xy 104.518156 -61.590428) (xy 106.478832 -61.590428) (xy 106.47936 -61.562131) (xy 106.487723 -61.506158)
			(xy 106.504256 -61.452033) (xy 106.528597 -61.400941) (xy 106.560212 -61.354001) (xy 106.598408 -61.312241)
			(xy 106.620056 -61.29401) (xy 106.631278 -61.284281) (xy 106.647968 -61.259725) (xy 106.656904 -61.231411)
			(xy 106.657334 -61.201724) (xy 106.649223 -61.173163) (xy 106.633252 -61.148134) (xy 106.622342 -61.138054)
			(xy 106.601869 -61.119867) (xy 106.565867 -61.078605) (xy 106.536137 -61.032617) (xy 106.513289 -60.98285)
			(xy 106.497793 -60.930328) (xy 106.489969 -60.876129) (xy 106.4895 -60.848748) (xy 106.489986 -60.821497)
			(xy 106.497742 -60.767549) (xy 106.513097 -60.715254) (xy 106.535739 -60.665677) (xy 106.565205 -60.619827)
			(xy 106.600896 -60.578636) (xy 106.642087 -60.542945) (xy 106.687937 -60.513479) (xy 106.737514 -60.490837)
			(xy 106.789809 -60.475482) (xy 106.843757 -60.467726) (xy 106.898259 -60.467726) (xy 106.952207 -60.475482)
			(xy 107.004502 -60.490837) (xy 107.054079 -60.513479) (xy 107.099929 -60.542945) (xy 107.14112 -60.578636)
			(xy 107.176811 -60.619827) (xy 107.206277 -60.665677) (xy 107.228919 -60.715254) (xy 107.244274 -60.767549)
			(xy 107.25203 -60.821497) (xy 107.252516 -60.848748) (xy 107.251954 -60.877043) (xy 107.243595 -60.933014)
			(xy 107.227067 -60.987137) (xy 107.202733 -61.038229) (xy 107.171126 -61.085171) (xy 107.155052 -61.102748)
			(xy 108.684312 -61.102748) (xy 108.688383 -61.047126) (xy 108.700509 -60.992689) (xy 108.720432 -60.940598)
			(xy 108.747728 -60.891963) (xy 108.781814 -60.84782) (xy 108.821963 -60.809111) (xy 108.867321 -60.77666)
			(xy 108.916921 -60.751159) (xy 108.969705 -60.733152) (xy 109.024548 -60.723022) (xy 109.080282 -60.720985)
			(xy 109.135719 -60.727085) (xy 109.189676 -60.741191) (xy 109.241005 -60.763003) (xy 109.288611 -60.792057)
			(xy 109.331479 -60.827732) (xy 109.368696 -60.869269) (xy 109.399469 -60.915782) (xy 109.423141 -60.966279)
			(xy 109.439209 -61.019686) (xy 109.447329 -61.074862) (xy 109.447838 -61.102748) (xy 109.447329 -61.130634)
			(xy 109.439209 -61.18581) (xy 109.423141 -61.239217) (xy 109.399469 -61.289714) (xy 109.368696 -61.336227)
			(xy 109.331479 -61.377764) (xy 109.288611 -61.413439) (xy 109.241005 -61.442493) (xy 109.189676 -61.464305)
			(xy 109.135719 -61.478411) (xy 109.080282 -61.484511) (xy 109.024548 -61.482474) (xy 108.969705 -61.472344)
			(xy 108.916921 -61.454337) (xy 108.867321 -61.428836) (xy 108.821963 -61.396385) (xy 108.781814 -61.357676)
			(xy 108.747728 -61.313533) (xy 108.720432 -61.264898) (xy 108.700509 -61.212807) (xy 108.688383 -61.15837)
			(xy 108.684312 -61.102748) (xy 107.155052 -61.102748) (xy 107.132936 -61.126933) (xy 107.111292 -61.145166)
			(xy 107.10009 -61.154919) (xy 107.083392 -61.179466) (xy 107.074448 -61.207775) (xy 107.074013 -61.23746)
			(xy 107.082123 -61.266019) (xy 107.098095 -61.291045) (xy 107.109006 -61.301122) (xy 107.129457 -61.319332)
			(xy 107.165463 -61.360589) (xy 107.195197 -61.406571) (xy 107.218049 -61.456333) (xy 107.233549 -61.508852)
			(xy 107.241377 -61.563049) (xy 107.241848 -61.590428) (xy 107.241362 -61.617679) (xy 107.233606 -61.671627)
			(xy 107.218251 -61.723922) (xy 107.195609 -61.773499) (xy 107.166143 -61.819349) (xy 107.130452 -61.86054)
			(xy 107.089261 -61.896231) (xy 107.043411 -61.925697) (xy 106.993834 -61.948339) (xy 106.941539 -61.963694)
			(xy 106.887591 -61.97145) (xy 106.833089 -61.97145) (xy 106.779141 -61.963694) (xy 106.726846 -61.948339)
			(xy 106.677269 -61.925697) (xy 106.631419 -61.896231) (xy 106.590228 -61.86054) (xy 106.554537 -61.819349)
			(xy 106.525071 -61.773499) (xy 106.502429 -61.723922) (xy 106.487074 -61.671627) (xy 106.479318 -61.617679)
			(xy 106.478832 -61.590428) (xy 104.518156 -61.590428) (xy 104.495999 -61.637694) (xy 104.465226 -61.684207)
			(xy 104.428009 -61.725744) (xy 104.385141 -61.761419) (xy 104.337535 -61.790473) (xy 104.286206 -61.812285)
			(xy 104.232249 -61.826391) (xy 104.176812 -61.832491) (xy 104.121078 -61.830454) (xy 104.066235 -61.820324)
			(xy 104.013451 -61.802317) (xy 103.963851 -61.776816) (xy 103.918493 -61.744365) (xy 103.878344 -61.705656)
			(xy 103.844258 -61.661513) (xy 103.816962 -61.612878) (xy 103.797039 -61.560787) (xy 103.784913 -61.50635)
			(xy 103.780842 -61.450728) (xy 48.077126 -61.450728) (xy 48.145442 -61.494969) (xy 48.318064 -61.616389)
			(xy 48.48591 -61.744332) (xy 48.648732 -61.87861) (xy 48.806291 -62.019026) (xy 48.882989 -62.09284)
			(xy 67.015104 -62.09284) (xy 67.019175 -62.037218) (xy 67.031301 -61.982781) (xy 67.051224 -61.93069)
			(xy 67.07852 -61.882055) (xy 67.112606 -61.837912) (xy 67.152755 -61.799203) (xy 67.198113 -61.766752)
			(xy 67.247713 -61.741251) (xy 67.300497 -61.723244) (xy 67.35534 -61.713114) (xy 67.411074 -61.711077)
			(xy 67.466511 -61.717177) (xy 67.520468 -61.731283) (xy 67.571797 -61.753095) (xy 67.619403 -61.782149)
			(xy 67.662271 -61.817824) (xy 67.699488 -61.859361) (xy 67.730261 -61.905874) (xy 67.753933 -61.956371)
			(xy 67.770001 -62.009778) (xy 67.778121 -62.064954) (xy 67.77863 -62.09284) (xy 67.778121 -62.120726)
			(xy 67.770001 -62.175902) (xy 67.753933 -62.229309) (xy 67.730261 -62.279806) (xy 67.707421 -62.314328)
			(xy 68.258942 -62.314328) (xy 68.263013 -62.258706) (xy 68.275139 -62.204269) (xy 68.295062 -62.152178)
			(xy 68.322358 -62.103543) (xy 68.356444 -62.0594) (xy 68.396593 -62.020691) (xy 68.441951 -61.98824)
			(xy 68.491551 -61.962739) (xy 68.544335 -61.944732) (xy 68.599178 -61.934602) (xy 68.654912 -61.932565)
			(xy 68.710349 -61.938665) (xy 68.764306 -61.952771) (xy 68.815635 -61.974583) (xy 68.863241 -62.003637)
			(xy 68.906109 -62.039312) (xy 68.909008 -62.042548) (xy 107.946442 -62.042548) (xy 107.950513 -61.986926)
			(xy 107.962639 -61.932489) (xy 107.982562 -61.880398) (xy 108.009858 -61.831763) (xy 108.043944 -61.78762)
			(xy 108.084093 -61.748911) (xy 108.129451 -61.71646) (xy 108.179051 -61.690959) (xy 108.231835 -61.672952)
			(xy 108.286678 -61.662822) (xy 108.342412 -61.660785) (xy 108.397849 -61.666885) (xy 108.451806 -61.680991)
			(xy 108.503135 -61.702803) (xy 108.550741 -61.731857) (xy 108.593609 -61.767532) (xy 108.630826 -61.809069)
			(xy 108.661599 -61.855582) (xy 108.685271 -61.906079) (xy 108.701339 -61.959486) (xy 108.709459 -62.014662)
			(xy 108.709968 -62.042548) (xy 108.709459 -62.070434) (xy 108.701339 -62.12561) (xy 108.685271 -62.179017)
			(xy 108.661599 -62.229514) (xy 108.630826 -62.276027) (xy 108.593609 -62.317564) (xy 108.550741 -62.353239)
			(xy 108.503135 -62.382293) (xy 108.451806 -62.404105) (xy 108.397849 -62.418211) (xy 108.342412 -62.424311)
			(xy 108.286678 -62.422274) (xy 108.231835 -62.412144) (xy 108.179051 -62.394137) (xy 108.129451 -62.368636)
			(xy 108.084093 -62.336185) (xy 108.043944 -62.297476) (xy 108.009858 -62.253333) (xy 107.982562 -62.204698)
			(xy 107.962639 -62.152607) (xy 107.950513 -62.09817) (xy 107.946442 -62.042548) (xy 68.909008 -62.042548)
			(xy 68.943326 -62.080849) (xy 68.974099 -62.127362) (xy 68.997771 -62.177859) (xy 69.013839 -62.231266)
			(xy 69.021959 -62.286442) (xy 69.022468 -62.314328) (xy 69.021959 -62.342214) (xy 69.013839 -62.39739)
			(xy 68.997771 -62.450797) (xy 68.974099 -62.501294) (xy 68.943326 -62.547807) (xy 68.918112 -62.575948)
			(xy 119.366296 -62.575948) (xy 119.370262 -62.491417) (xy 119.382127 -62.40763) (xy 119.401785 -62.325321)
			(xy 119.429065 -62.245215) (xy 119.463726 -62.168016) (xy 119.505464 -62.094401) (xy 119.553911 -62.025018)
			(xy 119.608643 -61.960477) (xy 119.669179 -61.901345) (xy 119.734985 -61.848141) (xy 119.805485 -61.801333)
			(xy 119.880057 -61.761332) (xy 119.958048 -61.72849) (xy 120.038772 -61.703096) (xy 120.121519 -61.685373)
			(xy 120.205561 -61.675475) (xy 120.290162 -61.673492) (xy 120.374576 -61.679439) (xy 120.458063 -61.693264)
			(xy 120.539888 -61.714847) (xy 120.619332 -61.743997) (xy 120.695698 -61.780458) (xy 120.768314 -61.82391)
			(xy 120.836542 -61.873971) (xy 120.899782 -61.930201) (xy 120.957479 -61.992106) (xy 121.009126 -62.059142)
			(xy 121.054268 -62.130719) (xy 121.09251 -62.206209) (xy 121.123514 -62.284948) (xy 121.147009 -62.366245)
			(xy 121.162788 -62.449384) (xy 121.170712 -62.533636) (xy 121.171208 -62.575948) (xy 121.906296 -62.575948)
			(xy 121.910262 -62.491417) (xy 121.922127 -62.40763) (xy 121.941785 -62.325321) (xy 121.969065 -62.245215)
			(xy 122.003726 -62.168016) (xy 122.045464 -62.094401) (xy 122.093911 -62.025018) (xy 122.148643 -61.960477)
			(xy 122.209179 -61.901345) (xy 122.274985 -61.848141) (xy 122.345485 -61.801333) (xy 122.420057 -61.761332)
			(xy 122.498048 -61.72849) (xy 122.578772 -61.703096) (xy 122.661519 -61.685373) (xy 122.745561 -61.675475)
			(xy 122.830162 -61.673492) (xy 122.914576 -61.679439) (xy 122.998063 -61.693264) (xy 123.079888 -61.714847)
			(xy 123.159332 -61.743997) (xy 123.235698 -61.780458) (xy 123.308314 -61.82391) (xy 123.376542 -61.873971)
			(xy 123.439782 -61.930201) (xy 123.497479 -61.992106) (xy 123.549126 -62.059142) (xy 123.594268 -62.130719)
			(xy 123.63251 -62.206209) (xy 123.663514 -62.284948) (xy 123.687009 -62.366245) (xy 123.702788 -62.449384)
			(xy 123.710712 -62.533636) (xy 123.711208 -62.575948) (xy 123.710712 -62.61826) (xy 123.702788 -62.702512)
			(xy 123.687009 -62.785651) (xy 123.663514 -62.866948) (xy 123.63251 -62.945687) (xy 123.594268 -63.021177)
			(xy 123.549126 -63.092754) (xy 123.497479 -63.15979) (xy 123.439782 -63.221695) (xy 123.376542 -63.277925)
			(xy 123.308314 -63.327986) (xy 123.235698 -63.371438) (xy 123.159332 -63.407899) (xy 123.079888 -63.437049)
			(xy 122.998063 -63.458632) (xy 122.914576 -63.472457) (xy 122.830162 -63.478404) (xy 122.745561 -63.476421)
			(xy 122.661519 -63.466523) (xy 122.578772 -63.4488) (xy 122.498048 -63.423406) (xy 122.420057 -63.390564)
			(xy 122.345485 -63.350563) (xy 122.274985 -63.303755) (xy 122.209179 -63.250551) (xy 122.148643 -63.191419)
			(xy 122.093911 -63.126878) (xy 122.045464 -63.057495) (xy 122.003726 -62.98388) (xy 121.969065 -62.906681)
			(xy 121.941785 -62.826575) (xy 121.922127 -62.744266) (xy 121.910262 -62.660479) (xy 121.906296 -62.575948)
			(xy 121.171208 -62.575948) (xy 121.170712 -62.61826) (xy 121.162788 -62.702512) (xy 121.147009 -62.785651)
			(xy 121.123514 -62.866948) (xy 121.09251 -62.945687) (xy 121.054268 -63.021177) (xy 121.009126 -63.092754)
			(xy 120.957479 -63.15979) (xy 120.899782 -63.221695) (xy 120.836542 -63.277925) (xy 120.768314 -63.327986)
			(xy 120.695698 -63.371438) (xy 120.619332 -63.407899) (xy 120.539888 -63.437049) (xy 120.458063 -63.458632)
			(xy 120.374576 -63.472457) (xy 120.290162 -63.478404) (xy 120.205561 -63.476421) (xy 120.121519 -63.466523)
			(xy 120.038772 -63.4488) (xy 119.958048 -63.423406) (xy 119.880057 -63.390564) (xy 119.805485 -63.350563)
			(xy 119.734985 -63.303755) (xy 119.669179 -63.250551) (xy 119.608643 -63.191419) (xy 119.553911 -63.126878)
			(xy 119.505464 -63.057495) (xy 119.463726 -62.98388) (xy 119.429065 -62.906681) (xy 119.401785 -62.826575)
			(xy 119.382127 -62.744266) (xy 119.370262 -62.660479) (xy 119.366296 -62.575948) (xy 68.918112 -62.575948)
			(xy 68.906109 -62.589344) (xy 68.863241 -62.625019) (xy 68.815635 -62.654073) (xy 68.764306 -62.675885)
			(xy 68.710349 -62.689991) (xy 68.654912 -62.696091) (xy 68.599178 -62.694054) (xy 68.544335 -62.683924)
			(xy 68.491551 -62.665917) (xy 68.441951 -62.640416) (xy 68.396593 -62.607965) (xy 68.356444 -62.569256)
			(xy 68.322358 -62.525113) (xy 68.295062 -62.476478) (xy 68.275139 -62.424387) (xy 68.263013 -62.36995)
			(xy 68.258942 -62.314328) (xy 67.707421 -62.314328) (xy 67.699488 -62.326319) (xy 67.662271 -62.367856)
			(xy 67.619403 -62.403531) (xy 67.571797 -62.432585) (xy 67.520468 -62.454397) (xy 67.466511 -62.468503)
			(xy 67.411074 -62.474603) (xy 67.35534 -62.472566) (xy 67.300497 -62.462436) (xy 67.247713 -62.444429)
			(xy 67.198113 -62.418928) (xy 67.152755 -62.386477) (xy 67.112606 -62.347768) (xy 67.07852 -62.303625)
			(xy 67.051224 -62.25499) (xy 67.031301 -62.202899) (xy 67.019175 -62.148462) (xy 67.015104 -62.09284)
			(xy 48.882989 -62.09284) (xy 48.958356 -62.165374) (xy 49.104704 -62.317439) (xy 49.24512 -62.474998)
			(xy 49.379398 -62.63782) (xy 49.507341 -62.805666) (xy 49.628761 -62.978288) (xy 49.74348 -63.155435)
			(xy 49.800644 -63.251588) (xy 69.948042 -63.251588) (xy 69.952113 -63.195966) (xy 69.964239 -63.141529)
			(xy 69.984162 -63.089438) (xy 70.011458 -63.040803) (xy 70.045544 -62.99666) (xy 70.085693 -62.957951)
			(xy 70.131051 -62.9255) (xy 70.180651 -62.899999) (xy 70.233435 -62.881992) (xy 70.288278 -62.871862)
			(xy 70.344012 -62.869825) (xy 70.399449 -62.875925) (xy 70.453406 -62.890031) (xy 70.504735 -62.911843)
			(xy 70.552341 -62.940897) (xy 70.595209 -62.976572) (xy 70.632426 -63.018109) (xy 70.663199 -63.064622)
			(xy 70.686871 -63.115119) (xy 70.699654 -63.157608) (xy 71.352662 -63.157608) (xy 71.356733 -63.101986)
			(xy 71.368859 -63.047549) (xy 71.388782 -62.995458) (xy 71.416078 -62.946823) (xy 71.450164 -62.90268)
			(xy 71.490313 -62.863971) (xy 71.535671 -62.83152) (xy 71.585271 -62.806019) (xy 71.638055 -62.788012)
			(xy 71.692898 -62.777882) (xy 71.748632 -62.775845) (xy 71.804069 -62.781945) (xy 71.858026 -62.796051)
			(xy 71.909355 -62.817863) (xy 71.956961 -62.846917) (xy 71.999829 -62.882592) (xy 72.037046 -62.924129)
			(xy 72.067819 -62.970642) (xy 72.091491 -63.021139) (xy 72.107559 -63.074546) (xy 72.115679 -63.129722)
			(xy 72.116188 -63.157608) (xy 72.115691 -63.18485) (xy 72.496686 -63.18485) (xy 72.496686 -63.13035)
			(xy 72.504442 -63.076405) (xy 72.519795 -63.024113) (xy 72.542435 -62.974538) (xy 72.571898 -62.92869)
			(xy 72.607587 -62.887501) (xy 72.648774 -62.85181) (xy 72.694621 -62.822344) (xy 72.744195 -62.799702)
			(xy 72.796486 -62.784346) (xy 72.85043 -62.776587) (xy 72.87768 -62.7761) (xy 72.906596 -62.776633)
			(xy 72.963767 -62.785359) (xy 73.018965 -62.802614) (xy 73.070927 -62.828003) (xy 73.118461 -62.860944)
			(xy 73.160479 -62.900682) (xy 73.17867 -62.923166) (xy 73.188567 -62.934971) (xy 73.213891 -62.95249)
			(xy 73.243284 -62.961666) (xy 73.274076 -62.961666) (xy 73.303469 -62.95249) (xy 73.328793 -62.934971)
			(xy 73.33869 -62.923166) (xy 73.356878 -62.90068) (xy 73.398899 -62.860947) (xy 73.446435 -62.828009)
			(xy 73.498397 -62.802621) (xy 73.553595 -62.785365) (xy 73.610764 -62.776636) (xy 73.63968 -62.7761)
			(xy 73.666934 -62.776546) (xy 73.720889 -62.784301) (xy 73.77319 -62.799655) (xy 73.822774 -62.822297)
			(xy 73.86863 -62.851765) (xy 73.909826 -62.88746) (xy 73.945523 -62.928654) (xy 73.974993 -62.974509)
			(xy 73.997638 -63.024091) (xy 74.012995 -63.076392) (xy 74.020753 -63.130346) (xy 74.020753 -63.184854)
			(xy 74.012995 -63.238808) (xy 73.997638 -63.291109) (xy 73.974993 -63.340691) (xy 73.945523 -63.386546)
			(xy 73.909826 -63.42774) (xy 73.86863 -63.463435) (xy 73.822774 -63.492903) (xy 73.77319 -63.515545)
			(xy 73.720889 -63.530899) (xy 73.666934 -63.538654) (xy 73.63968 -63.539116) (xy 73.610764 -63.538572)
			(xy 73.553592 -63.529853) (xy 73.498393 -63.512602) (xy 73.44643 -63.487215) (xy 73.398896 -63.454275)
			(xy 73.35688 -63.414535) (xy 73.33869 -63.39205) (xy 73.328793 -63.380245) (xy 73.303469 -63.362726)
			(xy 73.274076 -63.35355) (xy 73.243284 -63.35355) (xy 73.213891 -63.362726) (xy 73.188567 -63.380245)
			(xy 73.17867 -63.39205) (xy 73.160509 -63.414558) (xy 73.118481 -63.45429) (xy 73.07094 -63.487224)
			(xy 73.018973 -63.512608) (xy 72.963771 -63.529859) (xy 72.906598 -63.538583) (xy 72.87768 -63.539116)
			(xy 72.85043 -63.538613) (xy 72.796486 -63.530854) (xy 72.744195 -63.515498) (xy 72.694621 -63.492856)
			(xy 72.648774 -63.46339) (xy 72.607587 -63.427699) (xy 72.571898 -63.38651) (xy 72.542435 -63.340662)
			(xy 72.519795 -63.291087) (xy 72.504442 -63.238795) (xy 72.496686 -63.18485) (xy 72.115691 -63.18485)
			(xy 72.115679 -63.185494) (xy 72.107559 -63.24067) (xy 72.091491 -63.294077) (xy 72.067819 -63.344574)
			(xy 72.037046 -63.391087) (xy 71.999829 -63.432624) (xy 71.956961 -63.468299) (xy 71.909355 -63.497353)
			(xy 71.858026 -63.519165) (xy 71.804069 -63.533271) (xy 71.748632 -63.539371) (xy 71.692898 -63.537334)
			(xy 71.638055 -63.527204) (xy 71.585271 -63.509197) (xy 71.535671 -63.483696) (xy 71.490313 -63.451245)
			(xy 71.450164 -63.412536) (xy 71.416078 -63.368393) (xy 71.388782 -63.319758) (xy 71.368859 -63.267667)
			(xy 71.356733 -63.21323) (xy 71.352662 -63.157608) (xy 70.699654 -63.157608) (xy 70.702939 -63.168526)
			(xy 70.711059 -63.223702) (xy 70.711568 -63.251588) (xy 70.711059 -63.279474) (xy 70.702939 -63.33465)
			(xy 70.686871 -63.388057) (xy 70.663199 -63.438554) (xy 70.632426 -63.485067) (xy 70.595209 -63.526604)
			(xy 70.552341 -63.562279) (xy 70.504735 -63.591333) (xy 70.453406 -63.613145) (xy 70.399449 -63.627251)
			(xy 70.344012 -63.633351) (xy 70.288278 -63.631314) (xy 70.233435 -63.621184) (xy 70.180651 -63.603177)
			(xy 70.131051 -63.577676) (xy 70.085693 -63.545225) (xy 70.045544 -63.506516) (xy 70.011458 -63.462373)
			(xy 69.984162 -63.413738) (xy 69.964239 -63.361647) (xy 69.952113 -63.30721) (xy 69.948042 -63.251588)
			(xy 49.800644 -63.251588) (xy 49.85133 -63.336846) (xy 49.952152 -63.522255) (xy 50.018977 -63.657218)
			(xy 124.073924 -63.657218) (xy 124.073928 -63.602723) (xy 124.081688 -63.548784) (xy 124.097044 -63.496498)
			(xy 124.119686 -63.446929) (xy 124.149151 -63.401087) (xy 124.18484 -63.359905) (xy 124.226027 -63.324221)
			(xy 124.271872 -63.294762) (xy 124.321444 -63.272127) (xy 124.373732 -63.256777) (xy 124.427673 -63.249025)
			(xy 124.45492 -63.24854) (xy 124.469263 -63.248688) (xy 124.497868 -63.250846) (xy 124.51207 -63.252858)
			(xy 124.526828 -63.254527) (xy 124.556219 -63.250374) (xy 124.58317 -63.237938) (xy 124.605401 -63.218271)
			(xy 124.621031 -63.193037) (xy 124.628736 -63.164372) (xy 124.627865 -63.134703) (xy 124.618491 -63.106539)
			(xy 124.610368 -63.094108) (xy 124.584441 -63.056101) (xy 124.539552 -62.975787) (xy 124.503067 -62.891322)
			(xy 124.475365 -62.803584) (xy 124.456734 -62.713482) (xy 124.447368 -62.621952) (xy 124.446792 -62.575948)
			(xy 124.447232 -62.533421) (xy 124.455232 -62.448745) (xy 124.471165 -62.365197) (xy 124.49489 -62.28352)
			(xy 124.526197 -62.204438) (xy 124.564807 -62.128653) (xy 124.610377 -62.056838) (xy 124.662504 -61.98963)
			(xy 124.720724 -61.927627) (xy 124.784521 -61.871377) (xy 124.853328 -61.821381) (xy 124.926535 -61.778082)
			(xy 125.003493 -61.741865) (xy 125.083516 -61.713051) (xy 125.165897 -61.691896) (xy 125.249902 -61.678588)
			(xy 125.334788 -61.673244) (xy 125.419799 -61.675913) (xy 125.504182 -61.68657) (xy 125.587188 -61.705121)
			(xy 125.668079 -61.731402) (xy 125.746138 -61.765178) (xy 125.820672 -61.80615) (xy 125.89102 -61.853955)
			(xy 125.956556 -61.908169) (xy 126.016699 -61.968309) (xy 126.070916 -62.033842) (xy 126.118725 -62.104187)
			(xy 126.159701 -62.178719) (xy 126.193482 -62.256776) (xy 126.219766 -62.337666) (xy 126.238322 -62.42067)
			(xy 126.248983 -62.505053) (xy 126.251656 -62.590064) (xy 126.246317 -62.67495) (xy 126.233013 -62.758956)
			(xy 126.211863 -62.841338) (xy 126.189445 -62.903608) (xy 135.79424 -62.903608) (xy 135.798311 -62.847986)
			(xy 135.810437 -62.793549) (xy 135.83036 -62.741458) (xy 135.857656 -62.692823) (xy 135.891742 -62.64868)
			(xy 135.931891 -62.609971) (xy 135.977249 -62.57752) (xy 136.026849 -62.552019) (xy 136.079633 -62.534012)
			(xy 136.134476 -62.523882) (xy 136.19021 -62.521845) (xy 136.245647 -62.527945) (xy 136.299604 -62.542051)
			(xy 136.350933 -62.563863) (xy 136.398539 -62.592917) (xy 136.424846 -62.61481) (xy 150.853392 -62.61481)
			(xy 150.857463 -62.559188) (xy 150.869589 -62.504751) (xy 150.889512 -62.45266) (xy 150.916808 -62.404025)
			(xy 150.950894 -62.359882) (xy 150.991043 -62.321173) (xy 151.036401 -62.288722) (xy 151.086001 -62.263221)
			(xy 151.138785 -62.245214) (xy 151.193628 -62.235084) (xy 151.249362 -62.233047) (xy 151.304799 -62.239147)
			(xy 151.358756 -62.253253) (xy 151.410085 -62.275065) (xy 151.457691 -62.304119) (xy 151.500559 -62.339794)
			(xy 151.537776 -62.381331) (xy 151.568549 -62.427844) (xy 151.592221 -62.478341) (xy 151.608289 -62.531748)
			(xy 151.616409 -62.586924) (xy 151.616918 -62.61481) (xy 151.616409 -62.642696) (xy 151.608289 -62.697872)
			(xy 151.592221 -62.751279) (xy 151.568549 -62.801776) (xy 151.537776 -62.848289) (xy 151.500559 -62.889826)
			(xy 151.457691 -62.925501) (xy 151.410085 -62.954555) (xy 151.358756 -62.976367) (xy 151.304799 -62.990473)
			(xy 151.249362 -62.996573) (xy 151.193628 -62.994536) (xy 151.138785 -62.984406) (xy 151.086001 -62.966399)
			(xy 151.036401 -62.940898) (xy 150.991043 -62.908447) (xy 150.950894 -62.869738) (xy 150.916808 -62.825595)
			(xy 150.889512 -62.77696) (xy 150.869589 -62.724869) (xy 150.857463 -62.670432) (xy 150.853392 -62.61481)
			(xy 136.424846 -62.61481) (xy 136.441407 -62.628592) (xy 136.478624 -62.670129) (xy 136.509397 -62.716642)
			(xy 136.533069 -62.767139) (xy 136.549137 -62.820546) (xy 136.557257 -62.875722) (xy 136.557766 -62.903608)
			(xy 136.557257 -62.931494) (xy 136.549137 -62.98667) (xy 136.533069 -63.040077) (xy 136.509397 -63.090574)
			(xy 136.478624 -63.137087) (xy 136.441407 -63.178624) (xy 136.398539 -63.214299) (xy 136.350933 -63.243353)
			(xy 136.299604 -63.265165) (xy 136.245647 -63.279271) (xy 136.19021 -63.285371) (xy 136.134476 -63.283334)
			(xy 136.079633 -63.273204) (xy 136.026849 -63.255197) (xy 135.977249 -63.229696) (xy 135.931891 -63.197245)
			(xy 135.891742 -63.158536) (xy 135.857656 -63.114393) (xy 135.83036 -63.065758) (xy 135.810437 -63.013667)
			(xy 135.798311 -62.95923) (xy 135.79424 -62.903608) (xy 126.189445 -62.903608) (xy 126.183053 -62.921363)
			(xy 126.14684 -62.998322) (xy 126.103545 -63.071532) (xy 126.053553 -63.140342) (xy 125.997307 -63.204142)
			(xy 125.935306 -63.262365) (xy 125.868101 -63.314495) (xy 125.796289 -63.36007) (xy 125.720506 -63.398683)
			(xy 125.641425 -63.429994) (xy 125.559749 -63.453723) (xy 125.476202 -63.469661) (xy 125.391527 -63.477665)
			(xy 125.349 -63.478156) (xy 125.308592 -63.477708) (xy 125.228097 -63.470507) (xy 125.148571 -63.456126)
			(xy 125.070652 -63.434683) (xy 124.994966 -63.406348) (xy 124.958348 -63.389256) (xy 124.944729 -63.383345)
			(xy 124.915423 -63.378706) (xy 124.886022 -63.382698) (xy 124.859014 -63.394983) (xy 124.836684 -63.414521)
			(xy 124.820921 -63.439658) (xy 124.813061 -63.468269) (xy 124.813766 -63.497931) (xy 124.817886 -63.512192)
			(xy 124.826544 -63.540884) (xy 124.835859 -63.600084) (xy 124.836428 -63.630048) (xy 124.83587 -63.657295)
			(xy 124.828108 -63.711234) (xy 124.812749 -63.76352) (xy 124.790105 -63.813087) (xy 124.760638 -63.858928)
			(xy 124.724947 -63.900108) (xy 124.683758 -63.93579) (xy 124.637911 -63.965247) (xy 124.588339 -63.987879)
			(xy 124.53605 -64.003227) (xy 124.482109 -64.010977) (xy 124.427614 -64.010971) (xy 124.373675 -64.00321)
			(xy 124.321389 -63.987852) (xy 124.271821 -63.96521) (xy 124.22598 -63.935743) (xy 124.184799 -63.900053)
			(xy 124.149116 -63.858866) (xy 124.119658 -63.813019) (xy 124.097024 -63.763447) (xy 124.081675 -63.711159)
			(xy 124.073924 -63.657218) (xy 50.018977 -63.657218) (xy 50.045799 -63.71139) (xy 50.132132 -63.903972)
			(xy 50.19177 -64.051942) (xy 143.113758 -64.051942) (xy 143.117829 -63.99632) (xy 143.129955 -63.941883)
			(xy 143.149878 -63.889792) (xy 143.177174 -63.841157) (xy 143.21126 -63.797014) (xy 143.251409 -63.758305)
			(xy 143.296767 -63.725854) (xy 143.346367 -63.700353) (xy 143.399151 -63.682346) (xy 143.453994 -63.672216)
			(xy 143.509728 -63.670179) (xy 143.565165 -63.676279) (xy 143.619122 -63.690385) (xy 143.670451 -63.712197)
			(xy 143.718057 -63.741251) (xy 143.760925 -63.776926) (xy 143.798142 -63.818463) (xy 143.828915 -63.864976)
			(xy 143.852587 -63.915473) (xy 143.868655 -63.96888) (xy 143.876775 -64.024056) (xy 143.877284 -64.051942)
			(xy 143.87715 -64.059308) (xy 149.996398 -64.059308) (xy 149.996923 -64.030391) (xy 150.005651 -63.973221)
			(xy 150.022908 -63.918022) (xy 150.048298 -63.86606) (xy 150.08124 -63.818526) (xy 150.120979 -63.776509)
			(xy 150.143464 -63.758318) (xy 150.154454 -63.749101) (xy 150.171297 -63.725904) (xy 150.181016 -63.698935)
			(xy 150.182842 -63.670326) (xy 150.176631 -63.64234) (xy 150.162875 -63.61719) (xy 150.153116 -63.60668)
			(xy 150.132498 -63.585108) (xy 150.097561 -63.536733) (xy 150.070587 -63.483506) (xy 150.052232 -63.426728)
			(xy 150.042946 -63.367784) (xy 150.042372 -63.337948) (xy 150.042858 -63.310697) (xy 150.050614 -63.256749)
			(xy 150.065969 -63.204454) (xy 150.088611 -63.154877) (xy 150.118077 -63.109027) (xy 150.153768 -63.067836)
			(xy 150.194959 -63.032145) (xy 150.240809 -63.002679) (xy 150.290386 -62.980037) (xy 150.342681 -62.964682)
			(xy 150.396629 -62.956926) (xy 150.451131 -62.956926) (xy 150.505079 -62.964682) (xy 150.557374 -62.980037)
			(xy 150.606951 -63.002679) (xy 150.652801 -63.032145) (xy 150.693992 -63.067836) (xy 150.729683 -63.109027)
			(xy 150.759149 -63.154877) (xy 150.781791 -63.204454) (xy 150.797146 -63.256749) (xy 150.804902 -63.310697)
			(xy 150.805388 -63.337948) (xy 150.804837 -63.366864) (xy 150.796115 -63.424034) (xy 150.778864 -63.479232)
			(xy 150.753479 -63.531194) (xy 150.720541 -63.578729) (xy 150.680805 -63.620747) (xy 150.658322 -63.638938)
			(xy 150.64728 -63.648097) (xy 150.63044 -63.67131) (xy 150.620728 -63.698294) (xy 150.618912 -63.726914)
			(xy 150.625134 -63.754909) (xy 150.638904 -63.780065) (xy 150.64867 -63.790576) (xy 150.669265 -63.81217)
			(xy 150.704205 -63.860539) (xy 150.731184 -63.91376) (xy 150.749544 -63.970533) (xy 150.758837 -64.029474)
			(xy 150.759414 -64.059308) (xy 150.758928 -64.086559) (xy 150.751172 -64.140507) (xy 150.735817 -64.192802)
			(xy 150.713175 -64.242379) (xy 150.683709 -64.288229) (xy 150.648018 -64.32942) (xy 150.606827 -64.365111)
			(xy 150.560977 -64.394577) (xy 150.5114 -64.417219) (xy 150.459105 -64.432574) (xy 150.405157 -64.44033)
			(xy 150.350655 -64.44033) (xy 150.296707 -64.432574) (xy 150.244412 -64.417219) (xy 150.194835 -64.394577)
			(xy 150.148985 -64.365111) (xy 150.107794 -64.32942) (xy 150.072103 -64.288229) (xy 150.042637 -64.242379)
			(xy 150.019995 -64.192802) (xy 150.00464 -64.140507) (xy 149.996884 -64.086559) (xy 149.996398 -64.059308)
			(xy 143.87715 -64.059308) (xy 143.876775 -64.079828) (xy 143.868655 -64.135004) (xy 143.852587 -64.188411)
			(xy 143.828915 -64.238908) (xy 143.798142 -64.285421) (xy 143.760925 -64.326958) (xy 143.718057 -64.362633)
			(xy 143.670451 -64.391687) (xy 143.619122 -64.413499) (xy 143.565165 -64.427605) (xy 143.509728 -64.433705)
			(xy 143.453994 -64.431668) (xy 143.399151 -64.421538) (xy 143.346367 -64.403531) (xy 143.296767 -64.37803)
			(xy 143.251409 -64.345579) (xy 143.21126 -64.30687) (xy 143.177174 -64.262727) (xy 143.149878 -64.214092)
			(xy 143.129955 -64.162001) (xy 143.117829 -64.107564) (xy 143.113758 -64.051942) (xy 50.19177 -64.051942)
			(xy 50.211026 -64.09972) (xy 50.282364 -64.298347) (xy 50.346041 -64.49956) (xy 50.401965 -64.703064)
			(xy 50.409426 -64.734948) (xy 114.444016 -64.734948) (xy 114.448087 -64.679326) (xy 114.460213 -64.624889)
			(xy 114.480136 -64.572798) (xy 114.507432 -64.524163) (xy 114.541518 -64.48002) (xy 114.581667 -64.441311)
			(xy 114.627025 -64.40886) (xy 114.676625 -64.383359) (xy 114.729409 -64.365352) (xy 114.784252 -64.355222)
			(xy 114.839986 -64.353185) (xy 114.895423 -64.359285) (xy 114.94938 -64.373391) (xy 115.000709 -64.395203)
			(xy 115.048315 -64.424257) (xy 115.091183 -64.459932) (xy 115.1284 -64.501469) (xy 115.159173 -64.547982)
			(xy 115.182845 -64.598479) (xy 115.198913 -64.651886) (xy 115.207033 -64.707062) (xy 115.207542 -64.734948)
			(xy 116.017038 -64.734948) (xy 116.021109 -64.679326) (xy 116.033235 -64.624889) (xy 116.053158 -64.572798)
			(xy 116.080454 -64.524163) (xy 116.11454 -64.48002) (xy 116.154689 -64.441311) (xy 116.200047 -64.40886)
			(xy 116.249647 -64.383359) (xy 116.302431 -64.365352) (xy 116.357274 -64.355222) (xy 116.413008 -64.353185)
			(xy 116.468445 -64.359285) (xy 116.522402 -64.373391) (xy 116.573731 -64.395203) (xy 116.621337 -64.424257)
			(xy 116.664205 -64.459932) (xy 116.701422 -64.501469) (xy 116.732195 -64.547982) (xy 116.755867 -64.598479)
			(xy 116.771935 -64.651886) (xy 116.780055 -64.707062) (xy 116.780564 -64.734948) (xy 116.780082 -64.761364)
			(xy 153.724608 -64.761364) (xy 153.728679 -64.705742) (xy 153.740805 -64.651305) (xy 153.760728 -64.599214)
			(xy 153.788024 -64.550579) (xy 153.82211 -64.506436) (xy 153.862259 -64.467727) (xy 153.907617 -64.435276)
			(xy 153.957217 -64.409775) (xy 154.010001 -64.391768) (xy 154.064844 -64.381638) (xy 154.120578 -64.379601)
			(xy 154.176015 -64.385701) (xy 154.229972 -64.399807) (xy 154.281301 -64.421619) (xy 154.328907 -64.450673)
			(xy 154.371775 -64.486348) (xy 154.408992 -64.527885) (xy 154.439765 -64.574398) (xy 154.463437 -64.624895)
			(xy 154.479505 -64.678302) (xy 154.487625 -64.733478) (xy 154.488134 -64.761364) (xy 154.487625 -64.78925)
			(xy 154.479505 -64.844426) (xy 154.463437 -64.897833) (xy 154.439765 -64.94833) (xy 154.408992 -64.994843)
			(xy 154.371775 -65.03638) (xy 154.328907 -65.072055) (xy 154.292363 -65.094358) (xy 159.527238 -65.094358)
			(xy 159.531309 -65.038736) (xy 159.543435 -64.984299) (xy 159.563358 -64.932208) (xy 159.590654 -64.883573)
			(xy 159.62474 -64.83943) (xy 159.664889 -64.800721) (xy 159.710247 -64.76827) (xy 159.759847 -64.742769)
			(xy 159.812631 -64.724762) (xy 159.867474 -64.714632) (xy 159.923208 -64.712595) (xy 159.978645 -64.718695)
			(xy 160.032602 -64.732801) (xy 160.083931 -64.754613) (xy 160.131537 -64.783667) (xy 160.174405 -64.819342)
			(xy 160.211622 -64.860879) (xy 160.242395 -64.907392) (xy 160.266067 -64.957889) (xy 160.282135 -65.011296)
			(xy 160.290255 -65.066472) (xy 160.290764 -65.094358) (xy 160.290255 -65.122244) (xy 160.282135 -65.17742)
			(xy 160.266067 -65.230827) (xy 160.242395 -65.281324) (xy 160.211622 -65.327837) (xy 160.174405 -65.369374)
			(xy 160.131537 -65.405049) (xy 160.083931 -65.434103) (xy 160.032602 -65.455915) (xy 159.978645 -65.470021)
			(xy 159.923208 -65.476121) (xy 159.867474 -65.474084) (xy 159.812631 -65.463954) (xy 159.759847 -65.445947)
			(xy 159.710247 -65.420446) (xy 159.664889 -65.387995) (xy 159.62474 -65.349286) (xy 159.590654 -65.305143)
			(xy 159.563358 -65.256508) (xy 159.543435 -65.204417) (xy 159.531309 -65.14998) (xy 159.527238 -65.094358)
			(xy 154.292363 -65.094358) (xy 154.281301 -65.101109) (xy 154.229972 -65.122921) (xy 154.176015 -65.137027)
			(xy 154.120578 -65.143127) (xy 154.064844 -65.14109) (xy 154.010001 -65.13096) (xy 153.957217 -65.112953)
			(xy 153.907617 -65.087452) (xy 153.862259 -65.055001) (xy 153.82211 -65.016292) (xy 153.788024 -64.972149)
			(xy 153.760728 -64.923514) (xy 153.740805 -64.871423) (xy 153.728679 -64.816986) (xy 153.724608 -64.761364)
			(xy 116.780082 -64.761364) (xy 116.780055 -64.762834) (xy 116.771935 -64.81801) (xy 116.755867 -64.871417)
			(xy 116.732195 -64.921914) (xy 116.701422 -64.968427) (xy 116.664205 -65.009964) (xy 116.621337 -65.045639)
			(xy 116.573731 -65.074693) (xy 116.522402 -65.096505) (xy 116.468445 -65.110611) (xy 116.413008 -65.116711)
			(xy 116.357274 -65.114674) (xy 116.302431 -65.104544) (xy 116.249647 -65.086537) (xy 116.200047 -65.061036)
			(xy 116.154689 -65.028585) (xy 116.11454 -64.989876) (xy 116.080454 -64.945733) (xy 116.053158 -64.897098)
			(xy 116.033235 -64.845007) (xy 116.021109 -64.79057) (xy 116.017038 -64.734948) (xy 115.207542 -64.734948)
			(xy 115.207033 -64.762834) (xy 115.198913 -64.81801) (xy 115.182845 -64.871417) (xy 115.159173 -64.921914)
			(xy 115.1284 -64.968427) (xy 115.091183 -65.009964) (xy 115.048315 -65.045639) (xy 115.000709 -65.074693)
			(xy 114.94938 -65.096505) (xy 114.895423 -65.110611) (xy 114.839986 -65.116711) (xy 114.784252 -65.114674)
			(xy 114.729409 -65.104544) (xy 114.676625 -65.086537) (xy 114.627025 -65.061036) (xy 114.581667 -65.028585)
			(xy 114.541518 -64.989876) (xy 114.507432 -64.945733) (xy 114.480136 -64.897098) (xy 114.460213 -64.845007)
			(xy 114.448087 -64.79057) (xy 114.444016 -64.734948) (xy 50.409426 -64.734948) (xy 50.450053 -64.908561)
			(xy 50.490235 -65.115749) (xy 50.522452 -65.324324) (xy 50.546655 -65.533981) (xy 50.562811 -65.74441)
			(xy 50.563062 -65.750948) (xy 121.156982 -65.750948) (xy 121.161053 -65.695326) (xy 121.173179 -65.640889)
			(xy 121.193102 -65.588798) (xy 121.220398 -65.540163) (xy 121.254484 -65.49602) (xy 121.294633 -65.457311)
			(xy 121.339991 -65.42486) (xy 121.389591 -65.399359) (xy 121.442375 -65.381352) (xy 121.497218 -65.371222)
			(xy 121.552952 -65.369185) (xy 121.608389 -65.375285) (xy 121.662346 -65.389391) (xy 121.713675 -65.411203)
			(xy 121.761281 -65.440257) (xy 121.804149 -65.475932) (xy 121.841366 -65.517469) (xy 121.872139 -65.563982)
			(xy 121.895811 -65.614479) (xy 121.911879 -65.667886) (xy 121.919999 -65.723062) (xy 121.920508 -65.750948)
			(xy 121.919999 -65.778834) (xy 121.912889 -65.827148) (xy 123.265182 -65.827148) (xy 123.269253 -65.771526)
			(xy 123.281379 -65.717089) (xy 123.301302 -65.664998) (xy 123.328598 -65.616363) (xy 123.362684 -65.57222)
			(xy 123.402833 -65.533511) (xy 123.448191 -65.50106) (xy 123.497791 -65.475559) (xy 123.550575 -65.457552)
			(xy 123.605418 -65.447422) (xy 123.661152 -65.445385) (xy 123.716589 -65.451485) (xy 123.770546 -65.465591)
			(xy 123.821875 -65.487403) (xy 123.869481 -65.516457) (xy 123.912349 -65.552132) (xy 123.949566 -65.593669)
			(xy 123.980339 -65.640182) (xy 123.999877 -65.68186) (xy 125.609094 -65.68186) (xy 125.613165 -65.626238)
			(xy 125.625291 -65.571801) (xy 125.645214 -65.51971) (xy 125.67251 -65.471075) (xy 125.706596 -65.426932)
			(xy 125.746745 -65.388223) (xy 125.792103 -65.355772) (xy 125.841703 -65.330271) (xy 125.894487 -65.312264)
			(xy 125.94933 -65.302134) (xy 126.005064 -65.300097) (xy 126.060501 -65.306197) (xy 126.114458 -65.320303)
			(xy 126.135649 -65.329308) (xy 139.848588 -65.329308) (xy 139.852659 -65.273686) (xy 139.864785 -65.219249)
			(xy 139.884708 -65.167158) (xy 139.912004 -65.118523) (xy 139.94609 -65.07438) (xy 139.986239 -65.035671)
			(xy 140.031597 -65.00322) (xy 140.081197 -64.977719) (xy 140.133981 -64.959712) (xy 140.188824 -64.949582)
			(xy 140.244558 -64.947545) (xy 140.299995 -64.953645) (xy 140.353952 -64.967751) (xy 140.405281 -64.989563)
			(xy 140.452887 -65.018617) (xy 140.495755 -65.054292) (xy 140.532972 -65.095829) (xy 140.563745 -65.142342)
			(xy 140.587417 -65.192839) (xy 140.603485 -65.246246) (xy 140.611605 -65.301422) (xy 140.612114 -65.329308)
			(xy 140.611605 -65.357194) (xy 140.603485 -65.41237) (xy 140.587417 -65.465777) (xy 140.563745 -65.516274)
			(xy 140.532972 -65.562787) (xy 140.495755 -65.604324) (xy 140.452887 -65.639999) (xy 140.405281 -65.669053)
			(xy 140.353952 -65.690865) (xy 140.299995 -65.704971) (xy 140.244558 -65.711071) (xy 140.188824 -65.709034)
			(xy 140.133981 -65.698904) (xy 140.081197 -65.680897) (xy 140.031597 -65.655396) (xy 139.986239 -65.622945)
			(xy 139.94609 -65.584236) (xy 139.912004 -65.540093) (xy 139.884708 -65.491458) (xy 139.864785 -65.439367)
			(xy 139.852659 -65.38493) (xy 139.848588 -65.329308) (xy 126.135649 -65.329308) (xy 126.165787 -65.342115)
			(xy 126.213393 -65.371169) (xy 126.256261 -65.406844) (xy 126.293478 -65.448381) (xy 126.324251 -65.494894)
			(xy 126.347923 -65.545391) (xy 126.363991 -65.598798) (xy 126.372111 -65.653974) (xy 126.37262 -65.68186)
			(xy 126.372111 -65.709746) (xy 126.363991 -65.764922) (xy 126.347923 -65.818329) (xy 126.324251 -65.868826)
			(xy 126.293478 -65.915339) (xy 126.256261 -65.956876) (xy 126.213393 -65.992551) (xy 126.165787 -66.021605)
			(xy 126.114458 -66.043417) (xy 126.060501 -66.057523) (xy 126.005064 -66.063623) (xy 125.94933 -66.061586)
			(xy 125.894487 -66.051456) (xy 125.841703 -66.033449) (xy 125.792103 -66.007948) (xy 125.746745 -65.975497)
			(xy 125.706596 -65.936788) (xy 125.67251 -65.892645) (xy 125.645214 -65.84401) (xy 125.625291 -65.791919)
			(xy 125.613165 -65.737482) (xy 125.609094 -65.68186) (xy 123.999877 -65.68186) (xy 124.004011 -65.690679)
			(xy 124.020079 -65.744086) (xy 124.028199 -65.799262) (xy 124.028708 -65.827148) (xy 124.028199 -65.855034)
			(xy 124.020079 -65.91021) (xy 124.004011 -65.963617) (xy 123.980339 -66.014114) (xy 123.949566 -66.060627)
			(xy 123.912349 -66.102164) (xy 123.869481 -66.137839) (xy 123.821875 -66.166893) (xy 123.770546 -66.188705)
			(xy 123.716589 -66.202811) (xy 123.661152 -66.208911) (xy 123.605418 -66.206874) (xy 123.550575 -66.196744)
			(xy 123.497791 -66.178737) (xy 123.448191 -66.153236) (xy 123.402833 -66.120785) (xy 123.362684 -66.082076)
			(xy 123.328598 -66.037933) (xy 123.301302 -65.989298) (xy 123.281379 -65.937207) (xy 123.269253 -65.88277)
			(xy 123.265182 -65.827148) (xy 121.912889 -65.827148) (xy 121.911879 -65.83401) (xy 121.895811 -65.887417)
			(xy 121.872139 -65.937914) (xy 121.841366 -65.984427) (xy 121.804149 -66.025964) (xy 121.761281 -66.061639)
			(xy 121.713675 -66.090693) (xy 121.662346 -66.112505) (xy 121.608389 -66.126611) (xy 121.552952 -66.132711)
			(xy 121.497218 -66.130674) (xy 121.442375 -66.120544) (xy 121.389591 -66.102537) (xy 121.339991 -66.077036)
			(xy 121.294633 -66.044585) (xy 121.254484 -66.005876) (xy 121.220398 -65.961733) (xy 121.193102 -65.913098)
			(xy 121.173179 -65.861007) (xy 121.161053 -65.80657) (xy 121.156982 -65.750948) (xy 50.563062 -65.750948)
			(xy 50.570895 -65.955304) (xy 50.5714 -66.060828) (xy 50.5714 -67.343528) (xy 146.559268 -67.343528)
			(xy 146.563339 -67.287906) (xy 146.575465 -67.233469) (xy 146.595388 -67.181378) (xy 146.622684 -67.132743)
			(xy 146.65677 -67.0886) (xy 146.696919 -67.049891) (xy 146.742277 -67.01744) (xy 146.791877 -66.991939)
			(xy 146.844661 -66.973932) (xy 146.899504 -66.963802) (xy 146.955238 -66.961765) (xy 147.010675 -66.967865)
			(xy 147.064632 -66.981971) (xy 147.115961 -67.003783) (xy 147.163567 -67.032837) (xy 147.206435 -67.068512)
			(xy 147.243652 -67.110049) (xy 147.274425 -67.156562) (xy 147.298097 -67.207059) (xy 147.314165 -67.260466)
			(xy 147.322285 -67.315642) (xy 147.322794 -67.343528) (xy 147.322285 -67.371414) (xy 147.314165 -67.42659)
			(xy 147.298097 -67.479997) (xy 147.274425 -67.530494) (xy 147.243652 -67.577007) (xy 147.206435 -67.618544)
			(xy 147.163567 -67.654219) (xy 147.153511 -67.660356) (xy 154.891643 -67.660356) (xy 154.891643 -67.605844)
			(xy 154.899401 -67.551888) (xy 154.91476 -67.499585) (xy 154.937406 -67.450001) (xy 154.966879 -67.404145)
			(xy 155.002578 -67.362949) (xy 155.043777 -67.327255) (xy 155.089636 -67.297787) (xy 155.139223 -67.275146)
			(xy 155.191527 -67.259793) (xy 155.245484 -67.25204) (xy 155.27274 -67.25158) (xy 155.300002 -67.252044)
			(xy 155.35397 -67.259817) (xy 155.406284 -67.275187) (xy 155.455881 -67.297839) (xy 155.501752 -67.327315)
			(xy 155.522676 -67.344798) (xy 155.534284 -67.354198) (xy 155.561516 -67.366436) (xy 155.591123 -67.370273)
			(xy 155.620575 -67.365381) (xy 155.647352 -67.352178) (xy 155.669164 -67.331793) (xy 155.677108 -67.319144)
			(xy 155.691855 -67.294811) (xy 155.727486 -67.250453) (xy 155.769307 -67.211876) (xy 155.816392 -67.179935)
			(xy 155.867697 -67.155339) (xy 155.922086 -67.138632) (xy 155.978352 -67.130185) (xy 156.0068 -67.12966)
			(xy 156.034049 -67.13021) (xy 156.087992 -67.137966) (xy 156.140282 -67.15332) (xy 156.189855 -67.175959)
			(xy 156.235702 -67.205423) (xy 156.276889 -67.241111) (xy 156.312577 -67.282298) (xy 156.342041 -67.328145)
			(xy 156.36468 -67.377718) (xy 156.380034 -67.430008) (xy 156.38779 -67.483951) (xy 156.38779 -67.523148)
			(xy 156.710406 -67.523148) (xy 156.710406 -67.468652) (xy 156.718162 -67.41471) (xy 156.733515 -67.36242)
			(xy 156.756153 -67.312848) (xy 156.785615 -67.267002) (xy 156.821301 -67.225816) (xy 156.862486 -67.190127)
			(xy 156.908331 -67.160662) (xy 156.957902 -67.138022) (xy 157.01019 -67.122666) (xy 157.064132 -67.114908)
			(xy 157.09138 -67.11442) (xy 157.117744 -67.114876) (xy 157.169966 -67.122158) (xy 157.220689 -67.13656)
			(xy 157.268947 -67.157806) (xy 157.313821 -67.185493) (xy 157.354456 -67.219093) (xy 157.39008 -67.257967)
			(xy 157.420014 -67.301374) (xy 157.432248 -67.324732) (xy 157.439568 -67.337951) (xy 157.460432 -67.359781)
			(xy 157.486764 -67.374564) (xy 157.516265 -67.38101) (xy 157.546363 -67.378557) (xy 157.574431 -67.367419)
			(xy 157.598021 -67.348567) (xy 157.607 -67.336416) (xy 157.622329 -67.314828) (xy 157.657975 -67.275681)
			(xy 157.698692 -67.241838) (xy 157.743698 -67.213951) (xy 157.792127 -67.192555) (xy 157.84305 -67.178061)
			(xy 157.895487 -67.170748) (xy 157.92196 -67.1703) (xy 157.949215 -67.170745) (xy 158.003172 -67.178497)
			(xy 158.055475 -67.19385) (xy 158.105062 -67.216491) (xy 158.150921 -67.245958) (xy 158.192119 -67.281653)
			(xy 158.227818 -67.322847) (xy 158.25729 -67.368703) (xy 158.279936 -67.418287) (xy 158.295294 -67.470589)
			(xy 158.303053 -67.524545) (xy 158.303053 -67.579055) (xy 158.295294 -67.633011) (xy 158.279936 -67.685313)
			(xy 158.25729 -67.734897) (xy 158.227818 -67.780753) (xy 158.192119 -67.821947) (xy 158.150921 -67.857642)
			(xy 158.105062 -67.887109) (xy 158.055475 -67.90975) (xy 158.003172 -67.925103) (xy 157.949215 -67.932855)
			(xy 157.92196 -67.933316) (xy 157.895596 -67.932863) (xy 157.843372 -67.925584) (xy 157.792647 -67.911185)
			(xy 157.744388 -67.889939) (xy 157.699513 -67.862252) (xy 157.658878 -67.82865) (xy 157.623255 -67.789774)
			(xy 157.593324 -67.746363) (xy 157.581092 -67.723004) (xy 157.573857 -67.709732) (xy 157.552978 -67.687889)
			(xy 157.526628 -67.673101) (xy 157.497107 -67.666658) (xy 157.466992 -67.669123) (xy 157.438911 -67.68028)
			(xy 157.415317 -67.699156) (xy 157.40634 -67.71132) (xy 157.390996 -67.732897) (xy 157.355352 -67.772043)
			(xy 157.314637 -67.805885) (xy 157.269634 -67.833773) (xy 157.221207 -67.855171) (xy 157.170287 -67.869668)
			(xy 157.117852 -67.876985) (xy 157.09138 -67.877436) (xy 157.064132 -67.876892) (xy 157.01019 -67.869134)
			(xy 156.957902 -67.853778) (xy 156.908331 -67.831138) (xy 156.862486 -67.801673) (xy 156.821301 -67.765984)
			(xy 156.785615 -67.724798) (xy 156.756153 -67.678952) (xy 156.733515 -67.62938) (xy 156.718162 -67.57709)
			(xy 156.710406 -67.523148) (xy 156.38779 -67.523148) (xy 156.38779 -67.538449) (xy 156.380034 -67.592392)
			(xy 156.36468 -67.644682) (xy 156.342041 -67.694255) (xy 156.312577 -67.740102) (xy 156.276889 -67.781289)
			(xy 156.235702 -67.816977) (xy 156.189855 -67.846441) (xy 156.140282 -67.86908) (xy 156.087992 -67.884434)
			(xy 156.034049 -67.89219) (xy 156.0068 -67.892676) (xy 155.979538 -67.892199) (xy 155.92557 -67.88443)
			(xy 155.873256 -67.869064) (xy 155.823659 -67.846414) (xy 155.777788 -67.81694) (xy 155.756864 -67.799458)
			(xy 155.745214 -67.790116) (xy 155.717996 -67.77788) (xy 155.688402 -67.774039) (xy 155.658962 -67.77892)
			(xy 155.632192 -67.792107) (xy 155.610379 -67.812473) (xy 155.602432 -67.825112) (xy 155.587641 -67.849417)
			(xy 155.552019 -67.893777) (xy 155.510206 -67.932357) (xy 155.463129 -67.964302) (xy 155.41183 -67.988903)
			(xy 155.357447 -68.005615) (xy 155.301186 -68.014068) (xy 155.27274 -68.014596) (xy 155.245484 -68.01416)
			(xy 155.191527 -68.006407) (xy 155.139223 -67.991054) (xy 155.089636 -67.968413) (xy 155.043777 -67.938945)
			(xy 155.002578 -67.903251) (xy 154.966879 -67.862055) (xy 154.937406 -67.816199) (xy 154.91476 -67.766615)
			(xy 154.899401 -67.714312) (xy 154.891643 -67.660356) (xy 147.153511 -67.660356) (xy 147.115961 -67.683273)
			(xy 147.064632 -67.705085) (xy 147.010675 -67.719191) (xy 146.955238 -67.725291) (xy 146.899504 -67.723254)
			(xy 146.844661 -67.713124) (xy 146.791877 -67.695117) (xy 146.742277 -67.669616) (xy 146.696919 -67.637165)
			(xy 146.65677 -67.598456) (xy 146.622684 -67.554313) (xy 146.595388 -67.505678) (xy 146.575465 -67.453587)
			(xy 146.563339 -67.39915) (xy 146.559268 -67.343528) (xy 50.5714 -67.343528) (xy 50.5714 -69.128894)
			(xy 142.483076 -69.128894) (xy 142.487147 -69.073272) (xy 142.499273 -69.018835) (xy 142.519196 -68.966744)
			(xy 142.546492 -68.918109) (xy 142.580578 -68.873966) (xy 142.620727 -68.835257) (xy 142.666085 -68.802806)
			(xy 142.715685 -68.777305) (xy 142.768469 -68.759298) (xy 142.823312 -68.749168) (xy 142.879046 -68.747131)
			(xy 142.934483 -68.753231) (xy 142.98844 -68.767337) (xy 143.039769 -68.789149) (xy 143.087375 -68.818203)
			(xy 143.090181 -68.820538) (xy 164.897052 -68.820538) (xy 164.901123 -68.764916) (xy 164.913249 -68.710479)
			(xy 164.933172 -68.658388) (xy 164.960468 -68.609753) (xy 164.994554 -68.56561) (xy 165.034703 -68.526901)
			(xy 165.080061 -68.49445) (xy 165.129661 -68.468949) (xy 165.182445 -68.450942) (xy 165.237288 -68.440812)
			(xy 165.293022 -68.438775) (xy 165.348459 -68.444875) (xy 165.402416 -68.458981) (xy 165.453745 -68.480793)
			(xy 165.501351 -68.509847) (xy 165.544219 -68.545522) (xy 165.581436 -68.587059) (xy 165.612209 -68.633572)
			(xy 165.635881 -68.684069) (xy 165.651949 -68.737476) (xy 165.660069 -68.792652) (xy 165.660578 -68.820538)
			(xy 165.660069 -68.848424) (xy 165.651949 -68.9036) (xy 165.635881 -68.957007) (xy 165.612209 -69.007504)
			(xy 165.581436 -69.054017) (xy 165.544219 -69.095554) (xy 165.501351 -69.131229) (xy 165.453745 -69.160283)
			(xy 165.402416 -69.182095) (xy 165.348459 -69.196201) (xy 165.293022 -69.202301) (xy 165.237288 -69.200264)
			(xy 165.182445 -69.190134) (xy 165.129661 -69.172127) (xy 165.080061 -69.146626) (xy 165.034703 -69.114175)
			(xy 164.994554 -69.075466) (xy 164.960468 -69.031323) (xy 164.933172 -68.982688) (xy 164.913249 -68.930597)
			(xy 164.901123 -68.87616) (xy 164.897052 -68.820538) (xy 143.090181 -68.820538) (xy 143.130243 -68.853878)
			(xy 143.16746 -68.895415) (xy 143.198233 -68.941928) (xy 143.221905 -68.992425) (xy 143.237973 -69.045832)
			(xy 143.246093 -69.101008) (xy 143.246602 -69.128894) (xy 143.246093 -69.15678) (xy 143.237973 -69.211956)
			(xy 143.221905 -69.265363) (xy 143.198233 -69.31586) (xy 143.16746 -69.362373) (xy 143.14657 -69.385688)
			(xy 157.898082 -69.385688) (xy 157.902153 -69.330066) (xy 157.914279 -69.275629) (xy 157.934202 -69.223538)
			(xy 157.961498 -69.174903) (xy 157.995584 -69.13076) (xy 158.035733 -69.092051) (xy 158.081091 -69.0596)
			(xy 158.130691 -69.034099) (xy 158.183475 -69.016092) (xy 158.238318 -69.005962) (xy 158.294052 -69.003925)
			(xy 158.349489 -69.010025) (xy 158.403446 -69.024131) (xy 158.454775 -69.045943) (xy 158.502381 -69.074997)
			(xy 158.545249 -69.110672) (xy 158.582466 -69.152209) (xy 158.613239 -69.198722) (xy 158.636911 -69.249219)
			(xy 158.652979 -69.302626) (xy 158.661099 -69.357802) (xy 158.661608 -69.385688) (xy 158.661099 -69.413574)
			(xy 158.652979 -69.46875) (xy 158.636911 -69.522157) (xy 158.613239 -69.572654) (xy 158.582466 -69.619167)
			(xy 158.545249 -69.660704) (xy 158.502381 -69.696379) (xy 158.454775 -69.725433) (xy 158.403446 -69.747245)
			(xy 158.349489 -69.761351) (xy 158.294052 -69.767451) (xy 158.238318 -69.765414) (xy 158.183475 -69.755284)
			(xy 158.130691 -69.737277) (xy 158.081091 -69.711776) (xy 158.035733 -69.679325) (xy 157.995584 -69.640616)
			(xy 157.961498 -69.596473) (xy 157.934202 -69.547838) (xy 157.914279 -69.495747) (xy 157.902153 -69.44131)
			(xy 157.898082 -69.385688) (xy 143.14657 -69.385688) (xy 143.130243 -69.40391) (xy 143.087375 -69.439585)
			(xy 143.039769 -69.468639) (xy 142.98844 -69.490451) (xy 142.934483 -69.504557) (xy 142.879046 -69.510657)
			(xy 142.823312 -69.50862) (xy 142.768469 -69.49849) (xy 142.715685 -69.480483) (xy 142.666085 -69.454982)
			(xy 142.620727 -69.422531) (xy 142.580578 -69.383822) (xy 142.546492 -69.339679) (xy 142.519196 -69.291044)
			(xy 142.499273 -69.238953) (xy 142.487147 -69.184516) (xy 142.483076 -69.128894) (xy 50.5714 -69.128894)
			(xy 50.5714 -69.827648) (xy 136.734802 -69.827648) (xy 136.738873 -69.772026) (xy 136.750999 -69.717589)
			(xy 136.770922 -69.665498) (xy 136.798218 -69.616863) (xy 136.832304 -69.57272) (xy 136.872453 -69.534011)
			(xy 136.917811 -69.50156) (xy 136.967411 -69.476059) (xy 137.020195 -69.458052) (xy 137.075038 -69.447922)
			(xy 137.130772 -69.445885) (xy 137.186209 -69.451985) (xy 137.240166 -69.466091) (xy 137.291495 -69.487903)
			(xy 137.339101 -69.516957) (xy 137.381969 -69.552632) (xy 137.419186 -69.594169) (xy 137.449959 -69.640682)
			(xy 137.473631 -69.691179) (xy 137.489699 -69.744586) (xy 137.497819 -69.799762) (xy 137.498328 -69.827648)
			(xy 137.497819 -69.855534) (xy 137.489699 -69.91071) (xy 137.473631 -69.964117) (xy 137.449959 -70.014614)
			(xy 137.419186 -70.061127) (xy 137.381969 -70.102664) (xy 137.339101 -70.138339) (xy 137.291495 -70.167393)
			(xy 137.240166 -70.189205) (xy 137.186209 -70.203311) (xy 137.130772 -70.209411) (xy 137.075038 -70.207374)
			(xy 137.020195 -70.197244) (xy 136.967411 -70.179237) (xy 136.917811 -70.153736) (xy 136.872453 -70.121285)
			(xy 136.832304 -70.082576) (xy 136.798218 -70.038433) (xy 136.770922 -69.989798) (xy 136.750999 -69.937707)
			(xy 136.738873 -69.88327) (xy 136.734802 -69.827648) (xy 50.5714 -69.827648) (xy 50.5714 -70.749922)
			(xy 113.397296 -70.749922) (xy 113.401262 -70.665391) (xy 113.413127 -70.581604) (xy 113.432785 -70.499295)
			(xy 113.460065 -70.419189) (xy 113.494726 -70.34199) (xy 113.536464 -70.268375) (xy 113.584911 -70.198992)
			(xy 113.639643 -70.134451) (xy 113.700179 -70.075319) (xy 113.765985 -70.022115) (xy 113.836485 -69.975307)
			(xy 113.911057 -69.935306) (xy 113.989048 -69.902464) (xy 114.069772 -69.87707) (xy 114.152519 -69.859347)
			(xy 114.236561 -69.849449) (xy 114.321162 -69.847466) (xy 114.405576 -69.853413) (xy 114.489063 -69.867238)
			(xy 114.570888 -69.888821) (xy 114.650332 -69.917971) (xy 114.726698 -69.954432) (xy 114.799314 -69.997884)
			(xy 114.867542 -70.047945) (xy 114.930782 -70.104175) (xy 114.988479 -70.16608) (xy 115.040126 -70.233116)
			(xy 115.085268 -70.304693) (xy 115.12351 -70.380183) (xy 115.154514 -70.458922) (xy 115.178009 -70.540219)
			(xy 115.193788 -70.623358) (xy 115.201712 -70.70761) (xy 115.202208 -70.749922) (xy 115.937296 -70.749922)
			(xy 115.941262 -70.665391) (xy 115.953127 -70.581604) (xy 115.972785 -70.499295) (xy 116.000065 -70.419189)
			(xy 116.034726 -70.34199) (xy 116.076464 -70.268375) (xy 116.124911 -70.198992) (xy 116.179643 -70.134451)
			(xy 116.240179 -70.075319) (xy 116.305985 -70.022115) (xy 116.376485 -69.975307) (xy 116.451057 -69.935306)
			(xy 116.529048 -69.902464) (xy 116.609772 -69.87707) (xy 116.692519 -69.859347) (xy 116.776561 -69.849449)
			(xy 116.861162 -69.847466) (xy 116.945576 -69.853413) (xy 117.029063 -69.867238) (xy 117.110888 -69.888821)
			(xy 117.190332 -69.917971) (xy 117.266698 -69.954432) (xy 117.339314 -69.997884) (xy 117.407542 -70.047945)
			(xy 117.470782 -70.104175) (xy 117.528479 -70.16608) (xy 117.580126 -70.233116) (xy 117.625268 -70.304693)
			(xy 117.66351 -70.380183) (xy 117.694514 -70.458922) (xy 117.718009 -70.540219) (xy 117.733788 -70.623358)
			(xy 117.741712 -70.70761) (xy 117.742208 -70.749922) (xy 118.477296 -70.749922) (xy 118.481262 -70.665391)
			(xy 118.493127 -70.581604) (xy 118.512785 -70.499295) (xy 118.540065 -70.419189) (xy 118.574726 -70.34199)
			(xy 118.616464 -70.268375) (xy 118.664911 -70.198992) (xy 118.719643 -70.134451) (xy 118.780179 -70.075319)
			(xy 118.845985 -70.022115) (xy 118.916485 -69.975307) (xy 118.991057 -69.935306) (xy 119.069048 -69.902464)
			(xy 119.149772 -69.87707) (xy 119.232519 -69.859347) (xy 119.316561 -69.849449) (xy 119.401162 -69.847466)
			(xy 119.485576 -69.853413) (xy 119.569063 -69.867238) (xy 119.650888 -69.888821) (xy 119.730332 -69.917971)
			(xy 119.806698 -69.954432) (xy 119.879314 -69.997884) (xy 119.947542 -70.047945) (xy 120.010782 -70.104175)
			(xy 120.068479 -70.16608) (xy 120.120126 -70.233116) (xy 120.165268 -70.304693) (xy 120.20351 -70.380183)
			(xy 120.234514 -70.458922) (xy 120.258009 -70.540219) (xy 120.273788 -70.623358) (xy 120.281712 -70.70761)
			(xy 120.282208 -70.749922) (xy 121.017296 -70.749922) (xy 121.021262 -70.665391) (xy 121.033127 -70.581604)
			(xy 121.052785 -70.499295) (xy 121.080065 -70.419189) (xy 121.114726 -70.34199) (xy 121.156464 -70.268375)
			(xy 121.204911 -70.198992) (xy 121.259643 -70.134451) (xy 121.320179 -70.075319) (xy 121.385985 -70.022115)
			(xy 121.456485 -69.975307) (xy 121.531057 -69.935306) (xy 121.609048 -69.902464) (xy 121.689772 -69.87707)
			(xy 121.772519 -69.859347) (xy 121.856561 -69.849449) (xy 121.941162 -69.847466) (xy 122.025576 -69.853413)
			(xy 122.109063 -69.867238) (xy 122.190888 -69.888821) (xy 122.270332 -69.917971) (xy 122.346698 -69.954432)
			(xy 122.419314 -69.997884) (xy 122.487542 -70.047945) (xy 122.550782 -70.104175) (xy 122.608479 -70.16608)
			(xy 122.660126 -70.233116) (xy 122.705268 -70.304693) (xy 122.74351 -70.380183) (xy 122.774514 -70.458922)
			(xy 122.798009 -70.540219) (xy 122.813788 -70.623358) (xy 122.821712 -70.70761) (xy 122.822208 -70.749922)
			(xy 123.557296 -70.749922) (xy 123.561262 -70.665391) (xy 123.573127 -70.581604) (xy 123.592785 -70.499295)
			(xy 123.620065 -70.419189) (xy 123.654726 -70.34199) (xy 123.696464 -70.268375) (xy 123.744911 -70.198992)
			(xy 123.799643 -70.134451) (xy 123.860179 -70.075319) (xy 123.925985 -70.022115) (xy 123.996485 -69.975307)
			(xy 124.071057 -69.935306) (xy 124.149048 -69.902464) (xy 124.229772 -69.87707) (xy 124.312519 -69.859347)
			(xy 124.396561 -69.849449) (xy 124.481162 -69.847466) (xy 124.565576 -69.853413) (xy 124.649063 -69.867238)
			(xy 124.730888 -69.888821) (xy 124.810332 -69.917971) (xy 124.886698 -69.954432) (xy 124.959314 -69.997884)
			(xy 125.027542 -70.047945) (xy 125.090782 -70.104175) (xy 125.148479 -70.16608) (xy 125.200126 -70.233116)
			(xy 125.245268 -70.304693) (xy 125.28351 -70.380183) (xy 125.314514 -70.458922) (xy 125.338009 -70.540219)
			(xy 125.353788 -70.623358) (xy 125.361712 -70.70761) (xy 125.362208 -70.749922) (xy 126.097296 -70.749922)
			(xy 126.101262 -70.665391) (xy 126.113127 -70.581604) (xy 126.132785 -70.499295) (xy 126.160065 -70.419189)
			(xy 126.194726 -70.34199) (xy 126.236464 -70.268375) (xy 126.284911 -70.198992) (xy 126.339643 -70.134451)
			(xy 126.400179 -70.075319) (xy 126.465985 -70.022115) (xy 126.536485 -69.975307) (xy 126.611057 -69.935306)
			(xy 126.689048 -69.902464) (xy 126.769772 -69.87707) (xy 126.852519 -69.859347) (xy 126.936561 -69.849449)
			(xy 127.021162 -69.847466) (xy 127.105576 -69.853413) (xy 127.189063 -69.867238) (xy 127.270888 -69.888821)
			(xy 127.350332 -69.917971) (xy 127.426698 -69.954432) (xy 127.499314 -69.997884) (xy 127.567542 -70.047945)
			(xy 127.630782 -70.104175) (xy 127.688479 -70.16608) (xy 127.740126 -70.233116) (xy 127.785268 -70.304693)
			(xy 127.82351 -70.380183) (xy 127.854514 -70.458922) (xy 127.878009 -70.540219) (xy 127.893788 -70.623358)
			(xy 127.901712 -70.70761) (xy 127.902208 -70.749922) (xy 128.637296 -70.749922) (xy 128.641262 -70.665391)
			(xy 128.653127 -70.581604) (xy 128.672785 -70.499295) (xy 128.700065 -70.419189) (xy 128.734726 -70.34199)
			(xy 128.776464 -70.268375) (xy 128.824911 -70.198992) (xy 128.879643 -70.134451) (xy 128.940179 -70.075319)
			(xy 129.005985 -70.022115) (xy 129.076485 -69.975307) (xy 129.151057 -69.935306) (xy 129.229048 -69.902464)
			(xy 129.309772 -69.87707) (xy 129.392519 -69.859347) (xy 129.476561 -69.849449) (xy 129.561162 -69.847466)
			(xy 129.645576 -69.853413) (xy 129.729063 -69.867238) (xy 129.810888 -69.888821) (xy 129.890332 -69.917971)
			(xy 129.966698 -69.954432) (xy 130.039314 -69.997884) (xy 130.107542 -70.047945) (xy 130.170782 -70.104175)
			(xy 130.228479 -70.16608) (xy 130.280126 -70.233116) (xy 130.325268 -70.304693) (xy 130.36351 -70.380183)
			(xy 130.394514 -70.458922) (xy 130.418009 -70.540219) (xy 130.433788 -70.623358) (xy 130.441712 -70.70761)
			(xy 130.442208 -70.749922) (xy 131.177296 -70.749922) (xy 131.181262 -70.665391) (xy 131.193127 -70.581604)
			(xy 131.212785 -70.499295) (xy 131.240065 -70.419189) (xy 131.274726 -70.34199) (xy 131.316464 -70.268375)
			(xy 131.364911 -70.198992) (xy 131.419643 -70.134451) (xy 131.480179 -70.075319) (xy 131.545985 -70.022115)
			(xy 131.616485 -69.975307) (xy 131.691057 -69.935306) (xy 131.769048 -69.902464) (xy 131.849772 -69.87707)
			(xy 131.932519 -69.859347) (xy 132.016561 -69.849449) (xy 132.101162 -69.847466) (xy 132.185576 -69.853413)
			(xy 132.269063 -69.867238) (xy 132.350888 -69.888821) (xy 132.430332 -69.917971) (xy 132.506698 -69.954432)
			(xy 132.579314 -69.997884) (xy 132.647542 -70.047945) (xy 132.710782 -70.104175) (xy 132.768479 -70.16608)
			(xy 132.820126 -70.233116) (xy 132.865268 -70.304693) (xy 132.90351 -70.380183) (xy 132.934514 -70.458922)
			(xy 132.958009 -70.540219) (xy 132.973788 -70.623358) (xy 132.977784 -70.665848) (xy 136.198862 -70.665848)
			(xy 136.202933 -70.610226) (xy 136.215059 -70.555789) (xy 136.234982 -70.503698) (xy 136.262278 -70.455063)
			(xy 136.296364 -70.41092) (xy 136.336513 -70.372211) (xy 136.381871 -70.33976) (xy 136.431471 -70.314259)
			(xy 136.484255 -70.296252) (xy 136.539098 -70.286122) (xy 136.594832 -70.284085) (xy 136.650269 -70.290185)
			(xy 136.704226 -70.304291) (xy 136.755555 -70.326103) (xy 136.803161 -70.355157) (xy 136.846029 -70.390832)
			(xy 136.883246 -70.432369) (xy 136.914019 -70.478882) (xy 136.937691 -70.529379) (xy 136.953759 -70.582786)
			(xy 136.961879 -70.637962) (xy 136.962388 -70.665848) (xy 136.961879 -70.693734) (xy 136.953759 -70.74891)
			(xy 136.937691 -70.802317) (xy 136.914019 -70.852814) (xy 136.883246 -70.899327) (xy 136.846029 -70.940864)
			(xy 136.803161 -70.976539) (xy 136.755555 -71.005593) (xy 136.704226 -71.027405) (xy 136.650269 -71.041511)
			(xy 136.594832 -71.047611) (xy 136.539098 -71.045574) (xy 136.484255 -71.035444) (xy 136.431471 -71.017437)
			(xy 136.381871 -70.991936) (xy 136.336513 -70.959485) (xy 136.296364 -70.920776) (xy 136.262278 -70.876633)
			(xy 136.234982 -70.827998) (xy 136.215059 -70.775907) (xy 136.202933 -70.72147) (xy 136.198862 -70.665848)
			(xy 132.977784 -70.665848) (xy 132.981712 -70.70761) (xy 132.982208 -70.749922) (xy 132.981712 -70.792234)
			(xy 132.973788 -70.876486) (xy 132.958009 -70.959625) (xy 132.934514 -71.040922) (xy 132.90351 -71.119661)
			(xy 132.865268 -71.195151) (xy 132.820126 -71.266728) (xy 132.768479 -71.333764) (xy 132.710782 -71.395669)
			(xy 132.647542 -71.451899) (xy 132.579314 -71.50196) (xy 132.506698 -71.545412) (xy 132.430332 -71.581873)
			(xy 132.350888 -71.611023) (xy 132.269063 -71.632606) (xy 132.185576 -71.646431) (xy 132.101162 -71.652378)
			(xy 132.016561 -71.650395) (xy 131.932519 -71.640497) (xy 131.849772 -71.622774) (xy 131.769048 -71.59738)
			(xy 131.691057 -71.564538) (xy 131.616485 -71.524537) (xy 131.545985 -71.477729) (xy 131.480179 -71.424525)
			(xy 131.419643 -71.365393) (xy 131.364911 -71.300852) (xy 131.316464 -71.231469) (xy 131.274726 -71.157854)
			(xy 131.240065 -71.080655) (xy 131.212785 -71.000549) (xy 131.193127 -70.91824) (xy 131.181262 -70.834453)
			(xy 131.177296 -70.749922) (xy 130.442208 -70.749922) (xy 130.441712 -70.792234) (xy 130.433788 -70.876486)
			(xy 130.418009 -70.959625) (xy 130.394514 -71.040922) (xy 130.36351 -71.119661) (xy 130.325268 -71.195151)
			(xy 130.280126 -71.266728) (xy 130.228479 -71.333764) (xy 130.170782 -71.395669) (xy 130.107542 -71.451899)
			(xy 130.039314 -71.50196) (xy 129.966698 -71.545412) (xy 129.890332 -71.581873) (xy 129.810888 -71.611023)
			(xy 129.729063 -71.632606) (xy 129.645576 -71.646431) (xy 129.561162 -71.652378) (xy 129.476561 -71.650395)
			(xy 129.392519 -71.640497) (xy 129.309772 -71.622774) (xy 129.229048 -71.59738) (xy 129.151057 -71.564538)
			(xy 129.076485 -71.524537) (xy 129.005985 -71.477729) (xy 128.940179 -71.424525) (xy 128.879643 -71.365393)
			(xy 128.824911 -71.300852) (xy 128.776464 -71.231469) (xy 128.734726 -71.157854) (xy 128.700065 -71.080655)
			(xy 128.672785 -71.000549) (xy 128.653127 -70.91824) (xy 128.641262 -70.834453) (xy 128.637296 -70.749922)
			(xy 127.902208 -70.749922) (xy 127.901712 -70.792234) (xy 127.893788 -70.876486) (xy 127.878009 -70.959625)
			(xy 127.854514 -71.040922) (xy 127.82351 -71.119661) (xy 127.785268 -71.195151) (xy 127.740126 -71.266728)
			(xy 127.688479 -71.333764) (xy 127.630782 -71.395669) (xy 127.567542 -71.451899) (xy 127.499314 -71.50196)
			(xy 127.426698 -71.545412) (xy 127.350332 -71.581873) (xy 127.270888 -71.611023) (xy 127.189063 -71.632606)
			(xy 127.105576 -71.646431) (xy 127.021162 -71.652378) (xy 126.936561 -71.650395) (xy 126.852519 -71.640497)
			(xy 126.769772 -71.622774) (xy 126.689048 -71.59738) (xy 126.611057 -71.564538) (xy 126.536485 -71.524537)
			(xy 126.465985 -71.477729) (xy 126.400179 -71.424525) (xy 126.339643 -71.365393) (xy 126.284911 -71.300852)
			(xy 126.236464 -71.231469) (xy 126.194726 -71.157854) (xy 126.160065 -71.080655) (xy 126.132785 -71.000549)
			(xy 126.113127 -70.91824) (xy 126.101262 -70.834453) (xy 126.097296 -70.749922) (xy 125.362208 -70.749922)
			(xy 125.361712 -70.792234) (xy 125.353788 -70.876486) (xy 125.338009 -70.959625) (xy 125.314514 -71.040922)
			(xy 125.28351 -71.119661) (xy 125.245268 -71.195151) (xy 125.200126 -71.266728) (xy 125.148479 -71.333764)
			(xy 125.090782 -71.395669) (xy 125.027542 -71.451899) (xy 124.959314 -71.50196) (xy 124.886698 -71.545412)
			(xy 124.810332 -71.581873) (xy 124.730888 -71.611023) (xy 124.649063 -71.632606) (xy 124.565576 -71.646431)
			(xy 124.481162 -71.652378) (xy 124.396561 -71.650395) (xy 124.312519 -71.640497) (xy 124.229772 -71.622774)
			(xy 124.149048 -71.59738) (xy 124.071057 -71.564538) (xy 123.996485 -71.524537) (xy 123.925985 -71.477729)
			(xy 123.860179 -71.424525) (xy 123.799643 -71.365393) (xy 123.744911 -71.300852) (xy 123.696464 -71.231469)
			(xy 123.654726 -71.157854) (xy 123.620065 -71.080655) (xy 123.592785 -71.000549) (xy 123.573127 -70.91824)
			(xy 123.561262 -70.834453) (xy 123.557296 -70.749922) (xy 122.822208 -70.749922) (xy 122.821712 -70.792234)
			(xy 122.813788 -70.876486) (xy 122.798009 -70.959625) (xy 122.774514 -71.040922) (xy 122.74351 -71.119661)
			(xy 122.705268 -71.195151) (xy 122.660126 -71.266728) (xy 122.608479 -71.333764) (xy 122.550782 -71.395669)
			(xy 122.487542 -71.451899) (xy 122.419314 -71.50196) (xy 122.346698 -71.545412) (xy 122.270332 -71.581873)
			(xy 122.190888 -71.611023) (xy 122.109063 -71.632606) (xy 122.025576 -71.646431) (xy 121.941162 -71.652378)
			(xy 121.856561 -71.650395) (xy 121.772519 -71.640497) (xy 121.689772 -71.622774) (xy 121.609048 -71.59738)
			(xy 121.531057 -71.564538) (xy 121.456485 -71.524537) (xy 121.385985 -71.477729) (xy 121.320179 -71.424525)
			(xy 121.259643 -71.365393) (xy 121.204911 -71.300852) (xy 121.156464 -71.231469) (xy 121.114726 -71.157854)
			(xy 121.080065 -71.080655) (xy 121.052785 -71.000549) (xy 121.033127 -70.91824) (xy 121.021262 -70.834453)
			(xy 121.017296 -70.749922) (xy 120.282208 -70.749922) (xy 120.281712 -70.792234) (xy 120.273788 -70.876486)
			(xy 120.258009 -70.959625) (xy 120.234514 -71.040922) (xy 120.20351 -71.119661) (xy 120.165268 -71.195151)
			(xy 120.120126 -71.266728) (xy 120.068479 -71.333764) (xy 120.010782 -71.395669) (xy 119.947542 -71.451899)
			(xy 119.879314 -71.50196) (xy 119.806698 -71.545412) (xy 119.730332 -71.581873) (xy 119.650888 -71.611023)
			(xy 119.569063 -71.632606) (xy 119.485576 -71.646431) (xy 119.401162 -71.652378) (xy 119.316561 -71.650395)
			(xy 119.232519 -71.640497) (xy 119.149772 -71.622774) (xy 119.069048 -71.59738) (xy 118.991057 -71.564538)
			(xy 118.916485 -71.524537) (xy 118.845985 -71.477729) (xy 118.780179 -71.424525) (xy 118.719643 -71.365393)
			(xy 118.664911 -71.300852) (xy 118.616464 -71.231469) (xy 118.574726 -71.157854) (xy 118.540065 -71.080655)
			(xy 118.512785 -71.000549) (xy 118.493127 -70.91824) (xy 118.481262 -70.834453) (xy 118.477296 -70.749922)
			(xy 117.742208 -70.749922) (xy 117.741712 -70.792234) (xy 117.733788 -70.876486) (xy 117.718009 -70.959625)
			(xy 117.694514 -71.040922) (xy 117.66351 -71.119661) (xy 117.625268 -71.195151) (xy 117.580126 -71.266728)
			(xy 117.528479 -71.333764) (xy 117.470782 -71.395669) (xy 117.407542 -71.451899) (xy 117.339314 -71.50196)
			(xy 117.266698 -71.545412) (xy 117.190332 -71.581873) (xy 117.110888 -71.611023) (xy 117.029063 -71.632606)
			(xy 116.945576 -71.646431) (xy 116.861162 -71.652378) (xy 116.776561 -71.650395) (xy 116.692519 -71.640497)
			(xy 116.609772 -71.622774) (xy 116.529048 -71.59738) (xy 116.451057 -71.564538) (xy 116.376485 -71.524537)
			(xy 116.305985 -71.477729) (xy 116.240179 -71.424525) (xy 116.179643 -71.365393) (xy 116.124911 -71.300852)
			(xy 116.076464 -71.231469) (xy 116.034726 -71.157854) (xy 116.000065 -71.080655) (xy 115.972785 -71.000549)
			(xy 115.953127 -70.91824) (xy 115.941262 -70.834453) (xy 115.937296 -70.749922) (xy 115.202208 -70.749922)
			(xy 115.201712 -70.792234) (xy 115.193788 -70.876486) (xy 115.178009 -70.959625) (xy 115.154514 -71.040922)
			(xy 115.12351 -71.119661) (xy 115.085268 -71.195151) (xy 115.040126 -71.266728) (xy 114.988479 -71.333764)
			(xy 114.930782 -71.395669) (xy 114.867542 -71.451899) (xy 114.799314 -71.50196) (xy 114.726698 -71.545412)
			(xy 114.650332 -71.581873) (xy 114.570888 -71.611023) (xy 114.489063 -71.632606) (xy 114.405576 -71.646431)
			(xy 114.321162 -71.652378) (xy 114.236561 -71.650395) (xy 114.152519 -71.640497) (xy 114.069772 -71.622774)
			(xy 113.989048 -71.59738) (xy 113.911057 -71.564538) (xy 113.836485 -71.524537) (xy 113.765985 -71.477729)
			(xy 113.700179 -71.424525) (xy 113.639643 -71.365393) (xy 113.584911 -71.300852) (xy 113.536464 -71.231469)
			(xy 113.494726 -71.157854) (xy 113.460065 -71.080655) (xy 113.432785 -71.000549) (xy 113.413127 -70.91824)
			(xy 113.401262 -70.834453) (xy 113.397296 -70.749922) (xy 50.5714 -70.749922) (xy 50.5714 -71.52259)
			(xy 100.276658 -71.52259) (xy 100.280729 -71.466968) (xy 100.292855 -71.412531) (xy 100.312778 -71.36044)
			(xy 100.340074 -71.311805) (xy 100.37416 -71.267662) (xy 100.414309 -71.228953) (xy 100.459667 -71.196502)
			(xy 100.509267 -71.171001) (xy 100.562051 -71.152994) (xy 100.616894 -71.142864) (xy 100.672628 -71.140827)
			(xy 100.728065 -71.146927) (xy 100.782022 -71.161033) (xy 100.833351 -71.182845) (xy 100.880957 -71.211899)
			(xy 100.923825 -71.247574) (xy 100.961042 -71.289111) (xy 100.991815 -71.335624) (xy 101.015487 -71.386121)
			(xy 101.031555 -71.439528) (xy 101.039675 -71.494704) (xy 101.040184 -71.52259) (xy 101.039675 -71.550476)
			(xy 101.031555 -71.605652) (xy 101.015487 -71.659059) (xy 100.991815 -71.709556) (xy 100.961042 -71.756069)
			(xy 100.923825 -71.797606) (xy 100.880957 -71.833281) (xy 100.833351 -71.862335) (xy 100.782022 -71.884147)
			(xy 100.728065 -71.898253) (xy 100.672628 -71.904353) (xy 100.616894 -71.902316) (xy 100.562051 -71.892186)
			(xy 100.509267 -71.874179) (xy 100.459667 -71.848678) (xy 100.414309 -71.816227) (xy 100.37416 -71.777518)
			(xy 100.340074 -71.733375) (xy 100.312778 -71.68474) (xy 100.292855 -71.632649) (xy 100.280729 -71.578212)
			(xy 100.276658 -71.52259) (xy 50.5714 -71.52259) (xy 50.5714 -72.20712) (xy 134.567674 -72.20712)
			(xy 134.571745 -72.151498) (xy 134.583871 -72.097061) (xy 134.603794 -72.04497) (xy 134.63109 -71.996335)
			(xy 134.665176 -71.952192) (xy 134.705325 -71.913483) (xy 134.750683 -71.881032) (xy 134.800283 -71.855531)
			(xy 134.853067 -71.837524) (xy 134.90791 -71.827394) (xy 134.963644 -71.825357) (xy 135.019081 -71.831457)
			(xy 135.073038 -71.845563) (xy 135.124367 -71.867375) (xy 135.171973 -71.896429) (xy 135.214841 -71.932104)
			(xy 135.252058 -71.973641) (xy 135.282831 -72.020154) (xy 135.306503 -72.070651) (xy 135.322571 -72.124058)
			(xy 135.330691 -72.179234) (xy 135.3312 -72.20712) (xy 135.330691 -72.235006) (xy 135.322571 -72.290182)
			(xy 135.306503 -72.343589) (xy 135.282831 -72.394086) (xy 135.252058 -72.440599) (xy 135.214841 -72.482136)
			(xy 135.171973 -72.517811) (xy 135.124367 -72.546865) (xy 135.073038 -72.568677) (xy 135.019081 -72.582783)
			(xy 134.963644 -72.588883) (xy 134.90791 -72.586846) (xy 134.853067 -72.576716) (xy 134.800283 -72.558709)
			(xy 134.750683 -72.533208) (xy 134.705325 -72.500757) (xy 134.665176 -72.462048) (xy 134.63109 -72.417905)
			(xy 134.603794 -72.36927) (xy 134.583871 -72.317179) (xy 134.571745 -72.262742) (xy 134.567674 -72.20712)
			(xy 50.5714 -72.20712) (xy 50.5714 -72.608948) (xy 149.11654 -72.608948) (xy 149.120611 -72.553326)
			(xy 149.132737 -72.498889) (xy 149.15266 -72.446798) (xy 149.179956 -72.398163) (xy 149.214042 -72.35402)
			(xy 149.254191 -72.315311) (xy 149.299549 -72.28286) (xy 149.349149 -72.257359) (xy 149.401933 -72.239352)
			(xy 149.456776 -72.229222) (xy 149.51251 -72.227185) (xy 149.567947 -72.233285) (xy 149.621904 -72.247391)
			(xy 149.673233 -72.269203) (xy 149.720839 -72.298257) (xy 149.763707 -72.333932) (xy 149.800924 -72.375469)
			(xy 149.831697 -72.421982) (xy 149.855369 -72.472479) (xy 149.871437 -72.525886) (xy 149.879557 -72.581062)
			(xy 149.880066 -72.608948) (xy 149.879557 -72.636834) (xy 149.871437 -72.69201) (xy 149.855369 -72.745417)
			(xy 149.831697 -72.795914) (xy 149.800924 -72.842427) (xy 149.763707 -72.883964) (xy 149.720839 -72.919639)
			(xy 149.673233 -72.948693) (xy 149.621904 -72.970505) (xy 149.567947 -72.984611) (xy 149.51251 -72.990711)
			(xy 149.456776 -72.988674) (xy 149.401933 -72.978544) (xy 149.349149 -72.960537) (xy 149.299549 -72.935036)
			(xy 149.254191 -72.902585) (xy 149.214042 -72.863876) (xy 149.179956 -72.819733) (xy 149.15266 -72.771098)
			(xy 149.132737 -72.719007) (xy 149.120611 -72.66457) (xy 149.11654 -72.608948) (xy 50.5714 -72.608948)
			(xy 50.5714 -73.720706) (xy 86.306912 -73.720706) (xy 86.310983 -73.665084) (xy 86.323109 -73.610647)
			(xy 86.343032 -73.558556) (xy 86.370328 -73.509921) (xy 86.404414 -73.465778) (xy 86.444563 -73.427069)
			(xy 86.489921 -73.394618) (xy 86.539521 -73.369117) (xy 86.592305 -73.35111) (xy 86.647148 -73.34098)
			(xy 86.702882 -73.338943) (xy 86.758319 -73.345043) (xy 86.812276 -73.359149) (xy 86.863605 -73.380961)
			(xy 86.911211 -73.410015) (xy 86.954079 -73.44569) (xy 86.991296 -73.487227) (xy 87.022069 -73.53374)
			(xy 87.045741 -73.584237) (xy 87.061809 -73.637644) (xy 87.069929 -73.69282) (xy 87.070438 -73.720706)
			(xy 87.069929 -73.748592) (xy 87.061809 -73.803768) (xy 87.0599 -73.810114) (xy 89.570812 -73.810114)
			(xy 89.574883 -73.754492) (xy 89.587009 -73.700055) (xy 89.606932 -73.647964) (xy 89.634228 -73.599329)
			(xy 89.668314 -73.555186) (xy 89.708463 -73.516477) (xy 89.753821 -73.484026) (xy 89.803421 -73.458525)
			(xy 89.856205 -73.440518) (xy 89.911048 -73.430388) (xy 89.966782 -73.428351) (xy 90.022219 -73.434451)
			(xy 90.076176 -73.448557) (xy 90.127505 -73.470369) (xy 90.175111 -73.499423) (xy 90.217979 -73.535098)
			(xy 90.255196 -73.576635) (xy 90.285969 -73.623148) (xy 90.309641 -73.673645) (xy 90.325709 -73.727052)
			(xy 90.333829 -73.782228) (xy 90.334338 -73.810114) (xy 90.333829 -73.838) (xy 90.325709 -73.893176)
			(xy 90.324105 -73.898506) (xy 111.953292 -73.898506) (xy 111.957363 -73.842884) (xy 111.969489 -73.788447)
			(xy 111.989412 -73.736356) (xy 112.016708 -73.687721) (xy 112.050794 -73.643578) (xy 112.090943 -73.604869)
			(xy 112.136301 -73.572418) (xy 112.185901 -73.546917) (xy 112.238685 -73.52891) (xy 112.293528 -73.51878)
			(xy 112.349262 -73.516743) (xy 112.404699 -73.522843) (xy 112.458656 -73.536949) (xy 112.509985 -73.558761)
			(xy 112.557591 -73.587815) (xy 112.600459 -73.62349) (xy 112.637676 -73.665027) (xy 112.668449 -73.71154)
			(xy 112.692121 -73.762037) (xy 112.708189 -73.815444) (xy 112.716309 -73.87062) (xy 112.716818 -73.898506)
			(xy 112.716309 -73.926392) (xy 112.708189 -73.981568) (xy 112.692121 -74.034975) (xy 112.668449 -74.085472)
			(xy 112.637676 -74.131985) (xy 112.600459 -74.173522) (xy 112.557591 -74.209197) (xy 112.509985 -74.238251)
			(xy 112.458656 -74.260063) (xy 112.404699 -74.274169) (xy 112.349262 -74.280269) (xy 112.293528 -74.278232)
			(xy 112.238685 -74.268102) (xy 112.185901 -74.250095) (xy 112.136301 -74.224594) (xy 112.090943 -74.192143)
			(xy 112.050794 -74.153434) (xy 112.016708 -74.109291) (xy 111.989412 -74.060656) (xy 111.969489 -74.008565)
			(xy 111.957363 -73.954128) (xy 111.953292 -73.898506) (xy 90.324105 -73.898506) (xy 90.309641 -73.946583)
			(xy 90.285969 -73.99708) (xy 90.255196 -74.043593) (xy 90.217979 -74.08513) (xy 90.175111 -74.120805)
			(xy 90.127505 -74.149859) (xy 90.076176 -74.171671) (xy 90.022219 -74.185777) (xy 89.966782 -74.191877)
			(xy 89.911048 -74.18984) (xy 89.856205 -74.17971) (xy 89.803421 -74.161703) (xy 89.753821 -74.136202)
			(xy 89.708463 -74.103751) (xy 89.668314 -74.065042) (xy 89.634228 -74.020899) (xy 89.606932 -73.972264)
			(xy 89.587009 -73.920173) (xy 89.574883 -73.865736) (xy 89.570812 -73.810114) (xy 87.0599 -73.810114)
			(xy 87.045741 -73.857175) (xy 87.022069 -73.907672) (xy 86.991296 -73.954185) (xy 86.954079 -73.995722)
			(xy 86.911211 -74.031397) (xy 86.863605 -74.060451) (xy 86.812276 -74.082263) (xy 86.758319 -74.096369)
			(xy 86.702882 -74.102469) (xy 86.647148 -74.100432) (xy 86.592305 -74.090302) (xy 86.539521 -74.072295)
			(xy 86.489921 -74.046794) (xy 86.444563 -74.014343) (xy 86.404414 -73.975634) (xy 86.370328 -73.931491)
			(xy 86.343032 -73.882856) (xy 86.323109 -73.830765) (xy 86.310983 -73.776328) (xy 86.306912 -73.720706)
			(xy 50.5714 -73.720706) (xy 50.5714 -74.631042) (xy 117.787926 -74.631042) (xy 117.791997 -74.57542)
			(xy 117.804123 -74.520983) (xy 117.824046 -74.468892) (xy 117.851342 -74.420257) (xy 117.885428 -74.376114)
			(xy 117.925577 -74.337405) (xy 117.970935 -74.304954) (xy 118.020535 -74.279453) (xy 118.073319 -74.261446)
			(xy 118.128162 -74.251316) (xy 118.183896 -74.249279) (xy 118.239333 -74.255379) (xy 118.29329 -74.269485)
			(xy 118.344619 -74.291297) (xy 118.392225 -74.320351) (xy 118.435093 -74.356026) (xy 118.47231 -74.397563)
			(xy 118.503083 -74.444076) (xy 118.526755 -74.494573) (xy 118.542823 -74.54798) (xy 118.550943 -74.603156)
			(xy 118.551285 -74.621898) (xy 123.847096 -74.621898) (xy 123.851167 -74.566276) (xy 123.863293 -74.511839)
			(xy 123.883216 -74.459748) (xy 123.910512 -74.411113) (xy 123.944598 -74.36697) (xy 123.984747 -74.328261)
			(xy 124.030105 -74.29581) (xy 124.079705 -74.270309) (xy 124.132489 -74.252302) (xy 124.187332 -74.242172)
			(xy 124.243066 -74.240135) (xy 124.298503 -74.246235) (xy 124.35246 -74.260341) (xy 124.403789 -74.282153)
			(xy 124.451395 -74.311207) (xy 124.494263 -74.346882) (xy 124.53148 -74.388419) (xy 124.562253 -74.434932)
			(xy 124.570836 -74.453242) (xy 126.271526 -74.453242) (xy 126.275597 -74.39762) (xy 126.287723 -74.343183)
			(xy 126.307646 -74.291092) (xy 126.334942 -74.242457) (xy 126.369028 -74.198314) (xy 126.409177 -74.159605)
			(xy 126.454535 -74.127154) (xy 126.504135 -74.101653) (xy 126.556919 -74.083646) (xy 126.611762 -74.073516)
			(xy 126.667496 -74.071479) (xy 126.672122 -74.071988) (xy 149.186392 -74.071988) (xy 149.186878 -74.044737)
			(xy 149.194634 -73.990789) (xy 149.209989 -73.938494) (xy 149.232631 -73.888917) (xy 149.262097 -73.843067)
			(xy 149.297788 -73.801876) (xy 149.338979 -73.766185) (xy 149.384829 -73.736719) (xy 149.434406 -73.714077)
			(xy 149.486701 -73.698722) (xy 149.540649 -73.690966) (xy 149.595151 -73.690966) (xy 149.649099 -73.698722)
			(xy 149.701394 -73.714077) (xy 149.750971 -73.736719) (xy 149.796821 -73.766185) (xy 149.838012 -73.801876)
			(xy 149.873703 -73.843067) (xy 149.903169 -73.888917) (xy 149.925811 -73.938494) (xy 149.941166 -73.990789)
			(xy 149.948922 -74.044737) (xy 149.949408 -74.071988) (xy 149.948825 -74.102833) (xy 149.938896 -74.163719)
			(xy 149.91931 -74.222218) (xy 149.905466 -74.249788) (xy 149.899323 -74.262644) (xy 149.893522 -74.290521)
			(xy 149.895638 -74.318917) (xy 149.905506 -74.345627) (xy 149.922361 -74.368577) (xy 149.944893 -74.385987)
			(xy 149.971355 -74.396503) (xy 149.985476 -74.398378) (xy 150.013447 -74.401549) (xy 150.068079 -74.415122)
			(xy 150.120123 -74.436575) (xy 150.168449 -74.465442) (xy 150.21201 -74.501098) (xy 150.249858 -74.542768)
			(xy 150.281172 -74.589546) (xy 150.305272 -74.640419) (xy 150.316004 -74.675746) (xy 150.433784 -74.675746)
			(xy 150.437855 -74.620124) (xy 150.449981 -74.565687) (xy 150.469904 -74.513596) (xy 150.4972 -74.464961)
			(xy 150.531286 -74.420818) (xy 150.571435 -74.382109) (xy 150.616793 -74.349658) (xy 150.666393 -74.324157)
			(xy 150.719177 -74.30615) (xy 150.77402 -74.29602) (xy 150.829754 -74.293983) (xy 150.885191 -74.300083)
			(xy 150.939148 -74.314189) (xy 150.990477 -74.336001) (xy 151.038083 -74.365055) (xy 151.080951 -74.40073)
			(xy 151.118168 -74.442267) (xy 151.12022 -74.445368) (xy 153.376882 -74.445368) (xy 153.380953 -74.389746)
			(xy 153.393079 -74.335309) (xy 153.413002 -74.283218) (xy 153.440298 -74.234583) (xy 153.474384 -74.19044)
			(xy 153.514533 -74.151731) (xy 153.559891 -74.11928) (xy 153.609491 -74.093779) (xy 153.662275 -74.075772)
			(xy 153.717118 -74.065642) (xy 153.772852 -74.063605) (xy 153.828289 -74.069705) (xy 153.882246 -74.083811)
			(xy 153.933575 -74.105623) (xy 153.981181 -74.134677) (xy 154.024049 -74.170352) (xy 154.061266 -74.211889)
			(xy 154.092039 -74.258402) (xy 154.115711 -74.308899) (xy 154.131779 -74.362306) (xy 154.139899 -74.417482)
			(xy 154.140408 -74.445368) (xy 154.139899 -74.473254) (xy 154.131779 -74.52843) (xy 154.115711 -74.581837)
			(xy 154.092039 -74.632334) (xy 154.061266 -74.678847) (xy 154.024049 -74.720384) (xy 153.981181 -74.756059)
			(xy 153.933575 -74.785113) (xy 153.882246 -74.806925) (xy 153.828289 -74.821031) (xy 153.772852 -74.827131)
			(xy 153.717118 -74.825094) (xy 153.662275 -74.814964) (xy 153.609491 -74.796957) (xy 153.559891 -74.771456)
			(xy 153.514533 -74.739005) (xy 153.474384 -74.700296) (xy 153.440298 -74.656153) (xy 153.413002 -74.607518)
			(xy 153.393079 -74.555427) (xy 153.380953 -74.50099) (xy 153.376882 -74.445368) (xy 151.12022 -74.445368)
			(xy 151.148941 -74.48878) (xy 151.172613 -74.539277) (xy 151.188681 -74.592684) (xy 151.196801 -74.64786)
			(xy 151.19731 -74.675746) (xy 151.196801 -74.703632) (xy 151.188681 -74.758808) (xy 151.172613 -74.812215)
			(xy 151.148941 -74.862712) (xy 151.118168 -74.909225) (xy 151.080951 -74.950762) (xy 151.038083 -74.986437)
			(xy 150.990477 -75.015491) (xy 150.939148 -75.037303) (xy 150.885191 -75.051409) (xy 150.829754 -75.057509)
			(xy 150.77402 -75.055472) (xy 150.719177 -75.045342) (xy 150.666393 -75.027335) (xy 150.616793 -75.001834)
			(xy 150.571435 -74.969383) (xy 150.531286 -74.930674) (xy 150.4972 -74.886531) (xy 150.469904 -74.837896)
			(xy 150.449981 -74.785805) (xy 150.437855 -74.731368) (xy 150.433784 -74.675746) (xy 150.316004 -74.675746)
			(xy 150.321635 -74.69428) (xy 150.329905 -74.749962) (xy 150.330408 -74.778108) (xy 150.329922 -74.805359)
			(xy 150.322166 -74.859307) (xy 150.306811 -74.911602) (xy 150.284169 -74.961179) (xy 150.254703 -75.007029)
			(xy 150.219012 -75.04822) (xy 150.177821 -75.083911) (xy 150.131971 -75.113377) (xy 150.082394 -75.136019)
			(xy 150.030099 -75.151374) (xy 149.976151 -75.15913) (xy 149.921649 -75.15913) (xy 149.867701 -75.151374)
			(xy 149.815406 -75.136019) (xy 149.765829 -75.113377) (xy 149.719979 -75.083911) (xy 149.678788 -75.04822)
			(xy 149.643097 -75.007029) (xy 149.613631 -74.961179) (xy 149.590989 -74.911602) (xy 149.575634 -74.859307)
			(xy 149.567878 -74.805359) (xy 149.567392 -74.778108) (xy 149.567974 -74.747263) (xy 149.577903 -74.686377)
			(xy 149.59749 -74.627878) (xy 149.611334 -74.600308) (xy 149.617482 -74.587454) (xy 149.623282 -74.559576)
			(xy 149.621166 -74.53118) (xy 149.611297 -74.504469) (xy 149.594441 -74.481519) (xy 149.571908 -74.464109)
			(xy 149.545446 -74.453593) (xy 149.531324 -74.451718) (xy 149.503352 -74.448551) (xy 149.448721 -74.434978)
			(xy 149.396676 -74.413525) (xy 149.348349 -74.384657) (xy 149.304789 -74.349001) (xy 149.266941 -74.307331)
			(xy 149.235627 -74.260551) (xy 149.211527 -74.209678) (xy 149.195165 -74.155816) (xy 149.186894 -74.100134)
			(xy 149.186392 -74.071988) (xy 126.672122 -74.071988) (xy 126.722933 -74.077579) (xy 126.77689 -74.091685)
			(xy 126.828219 -74.113497) (xy 126.875825 -74.142551) (xy 126.918693 -74.178226) (xy 126.95591 -74.219763)
			(xy 126.986683 -74.266276) (xy 127.010355 -74.316773) (xy 127.026423 -74.37018) (xy 127.034543 -74.425356)
			(xy 127.035052 -74.453242) (xy 127.034543 -74.481128) (xy 127.026423 -74.536304) (xy 127.010355 -74.589711)
			(xy 126.986683 -74.640208) (xy 126.95591 -74.686721) (xy 126.918693 -74.728258) (xy 126.875825 -74.763933)
			(xy 126.828219 -74.792987) (xy 126.77689 -74.814799) (xy 126.722933 -74.828905) (xy 126.667496 -74.835005)
			(xy 126.611762 -74.832968) (xy 126.556919 -74.822838) (xy 126.504135 -74.804831) (xy 126.454535 -74.77933)
			(xy 126.409177 -74.746879) (xy 126.369028 -74.70817) (xy 126.334942 -74.664027) (xy 126.307646 -74.615392)
			(xy 126.287723 -74.563301) (xy 126.275597 -74.508864) (xy 126.271526 -74.453242) (xy 124.570836 -74.453242)
			(xy 124.585925 -74.485429) (xy 124.601993 -74.538836) (xy 124.610113 -74.594012) (xy 124.610622 -74.621898)
			(xy 124.610113 -74.649784) (xy 124.601993 -74.70496) (xy 124.585925 -74.758367) (xy 124.562253 -74.808864)
			(xy 124.53148 -74.855377) (xy 124.494263 -74.896914) (xy 124.451395 -74.932589) (xy 124.403789 -74.961643)
			(xy 124.35246 -74.983455) (xy 124.298503 -74.997561) (xy 124.243066 -75.003661) (xy 124.187332 -75.001624)
			(xy 124.132489 -74.991494) (xy 124.079705 -74.973487) (xy 124.030105 -74.947986) (xy 123.984747 -74.915535)
			(xy 123.944598 -74.876826) (xy 123.910512 -74.832683) (xy 123.883216 -74.784048) (xy 123.863293 -74.731957)
			(xy 123.851167 -74.67752) (xy 123.847096 -74.621898) (xy 118.551285 -74.621898) (xy 118.551452 -74.631042)
			(xy 118.550943 -74.658928) (xy 118.542823 -74.714104) (xy 118.526755 -74.767511) (xy 118.503083 -74.818008)
			(xy 118.47231 -74.864521) (xy 118.435093 -74.906058) (xy 118.392225 -74.941733) (xy 118.344619 -74.970787)
			(xy 118.29329 -74.992599) (xy 118.239333 -75.006705) (xy 118.183896 -75.012805) (xy 118.128162 -75.010768)
			(xy 118.073319 -75.000638) (xy 118.020535 -74.982631) (xy 117.970935 -74.95713) (xy 117.925577 -74.924679)
			(xy 117.885428 -74.88597) (xy 117.851342 -74.841827) (xy 117.824046 -74.793192) (xy 117.804123 -74.741101)
			(xy 117.791997 -74.686664) (xy 117.787926 -74.631042) (xy 50.5714 -74.631042) (xy 50.5714 -74.760836)
			(xy 50.570895 -74.86636) (xy 50.562811 -75.077254) (xy 50.546655 -75.287683) (xy 50.522452 -75.49734)
			(xy 50.490235 -75.705915) (xy 50.450053 -75.913103) (xy 50.408532 -76.090538) (xy 119.710154 -76.090538)
			(xy 119.710157 -76.03603) (xy 119.717916 -75.982078) (xy 119.733275 -75.92978) (xy 119.755921 -75.8802)
			(xy 119.785392 -75.834347) (xy 119.821089 -75.793155) (xy 119.862286 -75.757464) (xy 119.908142 -75.727998)
			(xy 119.957725 -75.705358) (xy 120.010025 -75.690006) (xy 120.063978 -75.682253) (xy 120.118486 -75.682258)
			(xy 120.172437 -75.69002) (xy 120.224735 -75.705381) (xy 120.274314 -75.728029) (xy 120.320166 -75.757502)
			(xy 120.361356 -75.793201) (xy 120.397046 -75.834398) (xy 120.42651 -75.880256) (xy 120.449147 -75.92984)
			(xy 120.464497 -75.982141) (xy 120.472248 -76.036094) (xy 120.472708 -76.063348) (xy 120.472306 -76.088885)
			(xy 120.465535 -76.139507) (xy 120.452067 -76.188773) (xy 120.442482 -76.212446) (xy 120.43704 -76.226484)
			(xy 120.433866 -76.256413) (xy 120.439554 -76.285967) (xy 120.453609 -76.31258) (xy 120.474812 -76.33394)
			(xy 120.50132 -76.348192) (xy 120.530831 -76.354099) (xy 120.54586 -76.353162) (xy 120.582944 -76.351384)
			(xy 120.610191 -76.351925) (xy 120.664131 -76.359687) (xy 120.716417 -76.375046) (xy 120.765985 -76.397689)
			(xy 120.811826 -76.427156) (xy 120.853007 -76.462847) (xy 120.88869 -76.504035) (xy 120.918148 -76.549882)
			(xy 120.940781 -76.599454) (xy 120.956129 -76.651743) (xy 120.96388 -76.705684) (xy 120.963876 -76.760179)
			(xy 120.956116 -76.814119) (xy 120.940759 -76.866406) (xy 120.918117 -76.915974) (xy 120.888651 -76.961816)
			(xy 120.852962 -77.002999) (xy 120.811775 -77.038682) (xy 120.765929 -77.068142) (xy 120.716357 -77.090777)
			(xy 120.664068 -77.106127) (xy 120.610128 -77.113879) (xy 120.555632 -77.113876) (xy 120.501693 -77.106118)
			(xy 120.449406 -77.090763) (xy 120.399836 -77.068123) (xy 120.353993 -77.038658) (xy 120.31281 -77.00297)
			(xy 120.277125 -76.961784) (xy 120.247664 -76.915939) (xy 120.225027 -76.866368) (xy 120.209676 -76.81408)
			(xy 120.201922 -76.76014) (xy 120.201436 -76.732892) (xy 120.201823 -76.707354) (xy 120.208601 -76.656732)
			(xy 120.222075 -76.607467) (xy 120.231662 -76.583794) (xy 120.237012 -76.569726) (xy 120.240191 -76.539813)
			(xy 120.234513 -76.510273) (xy 120.220473 -76.48367) (xy 120.199288 -76.462315) (xy 120.172799 -76.448061)
			(xy 120.143305 -76.442147) (xy 120.128284 -76.443078) (xy 120.0912 -76.444856) (xy 120.063946 -76.444345)
			(xy 120.009994 -76.436587) (xy 119.957695 -76.42123) (xy 119.908114 -76.398587) (xy 119.86226 -76.369117)
			(xy 119.821067 -76.333422) (xy 119.785373 -76.292227) (xy 119.755906 -76.246372) (xy 119.733264 -76.19679)
			(xy 119.717909 -76.14449) (xy 119.710154 -76.090538) (xy 50.408532 -76.090538) (xy 50.401965 -76.1186)
			(xy 50.346041 -76.322104) (xy 50.282364 -76.523317) (xy 50.211026 -76.721944) (xy 50.132132 -76.917692)
			(xy 50.045799 -77.110274) (xy 50.035959 -77.130148) (xy 116.534692 -77.130148) (xy 116.535069 -77.103554)
			(xy 116.542443 -77.050881) (xy 116.557068 -76.999745) (xy 116.57866 -76.951138) (xy 116.606799 -76.906005)
			(xy 116.64094 -76.865222) (xy 116.680419 -76.829582) (xy 116.72447 -76.799776) (xy 116.772236 -76.776384)
			(xy 116.822791 -76.759859) (xy 116.84889 -76.754736) (xy 116.863575 -76.75163) (xy 116.890296 -76.737978)
			(xy 116.911906 -76.717159) (xy 116.926545 -76.690965) (xy 116.932953 -76.661651) (xy 116.930579 -76.631738)
			(xy 116.925598 -76.617576) (xy 116.917341 -76.595395) (xy 116.905703 -76.549519) (xy 116.899814 -76.502557)
			(xy 116.899436 -76.478892) (xy 116.899922 -76.451641) (xy 116.907678 -76.397693) (xy 116.923033 -76.345398)
			(xy 116.945675 -76.295821) (xy 116.975141 -76.249971) (xy 117.010832 -76.20878) (xy 117.052023 -76.173089)
			(xy 117.097873 -76.143623) (xy 117.14745 -76.120981) (xy 117.199745 -76.105626) (xy 117.253693 -76.09787)
			(xy 117.308195 -76.09787) (xy 117.362143 -76.105626) (xy 117.414438 -76.120981) (xy 117.464015 -76.143623)
			(xy 117.509865 -76.173089) (xy 117.551056 -76.20878) (xy 117.586747 -76.249971) (xy 117.616213 -76.295821)
			(xy 117.638855 -76.345398) (xy 117.65421 -76.397693) (xy 117.661966 -76.451641) (xy 117.662452 -76.478892)
			(xy 117.661983 -76.505482) (xy 117.654619 -76.55815) (xy 117.640004 -76.609283) (xy 117.618422 -76.657887)
			(xy 117.590293 -76.703018) (xy 117.556162 -76.743801) (xy 117.516693 -76.779443) (xy 117.472653 -76.809252)
			(xy 117.424895 -76.832648) (xy 117.374349 -76.849178) (xy 117.348254 -76.854304) (xy 117.333595 -76.857513)
			(xy 117.306882 -76.871145) (xy 117.285274 -76.891942) (xy 117.270631 -76.918114) (xy 117.264213 -76.94741)
			(xy 117.266574 -76.977307) (xy 117.271546 -76.991464) (xy 117.279817 -77.01364) (xy 117.291449 -77.059519)
			(xy 117.297332 -77.106483) (xy 117.29745 -77.113892) (xy 121.471436 -77.113892) (xy 121.471828 -77.087534)
			(xy 121.479076 -77.035318) (xy 121.493445 -76.984599) (xy 121.514662 -76.936341) (xy 121.542322 -76.891465)
			(xy 121.5759 -76.850826) (xy 121.614754 -76.815198) (xy 121.658144 -76.78526) (xy 121.681494 -76.773024)
			(xy 121.693853 -76.766347) (xy 121.71456 -76.747378) (xy 121.729315 -76.723484) (xy 121.737002 -76.696475)
			(xy 121.737039 -76.668392) (xy 121.729423 -76.641363) (xy 121.714732 -76.61743) (xy 121.694075 -76.598406)
			(xy 121.681748 -76.591668) (xy 121.658454 -76.579457) (xy 121.615224 -76.549499) (xy 121.576521 -76.513884)
			(xy 121.54308 -76.473289) (xy 121.515535 -76.428483) (xy 121.494409 -76.380317) (xy 121.480102 -76.329704)
			(xy 121.472887 -76.277606) (xy 121.472452 -76.251308) (xy 121.472938 -76.224057) (xy 121.480694 -76.170109)
			(xy 121.496049 -76.117814) (xy 121.518691 -76.068237) (xy 121.548157 -76.022387) (xy 121.583848 -75.981196)
			(xy 121.625039 -75.945505) (xy 121.670889 -75.916039) (xy 121.720466 -75.893397) (xy 121.772761 -75.878042)
			(xy 121.826709 -75.870286) (xy 121.881211 -75.870286) (xy 121.935159 -75.878042) (xy 121.987454 -75.893397)
			(xy 122.037031 -75.916039) (xy 122.082881 -75.945505) (xy 122.124072 -75.981196) (xy 122.159763 -76.022387)
			(xy 122.189229 -76.068237) (xy 122.211871 -76.117814) (xy 122.227226 -76.170109) (xy 122.234982 -76.224057)
			(xy 122.235468 -76.251308) (xy 122.235073 -76.277666) (xy 122.231286 -76.304949) (xy 124.605802 -76.304949)
			(xy 124.605802 -76.250451) (xy 124.613558 -76.196507) (xy 124.628912 -76.144216) (xy 124.651551 -76.094642)
			(xy 124.681015 -76.048795) (xy 124.716704 -76.007607) (xy 124.757891 -75.971918) (xy 124.803738 -75.942453)
			(xy 124.853312 -75.919813) (xy 124.905603 -75.904459) (xy 124.959547 -75.896702) (xy 124.986796 -75.896216)
			(xy 125.013137 -75.896663) (xy 125.026366 -75.898502) (xy 128.77749 -75.898502) (xy 128.781561 -75.84288)
			(xy 128.793687 -75.788443) (xy 128.81361 -75.736352) (xy 128.840906 -75.687717) (xy 128.874992 -75.643574)
			(xy 128.915141 -75.604865) (xy 128.960499 -75.572414) (xy 129.010099 -75.546913) (xy 129.062883 -75.528906)
			(xy 129.117726 -75.518776) (xy 129.17346 -75.516739) (xy 129.228897 -75.522839) (xy 129.282854 -75.536945)
			(xy 129.334183 -75.558757) (xy 129.381789 -75.587811) (xy 129.424657 -75.623486) (xy 129.461874 -75.665023)
			(xy 129.492647 -75.711536) (xy 129.516319 -75.762033) (xy 129.532387 -75.81544) (xy 129.540507 -75.870616)
			(xy 129.541016 -75.898502) (xy 129.540507 -75.926388) (xy 129.532387 -75.981564) (xy 129.516319 -76.034971)
			(xy 129.492647 -76.085468) (xy 129.482867 -76.10025) (xy 134.120378 -76.10025) (xy 134.120378 -76.04575)
			(xy 134.128134 -75.991803) (xy 134.143488 -75.93951) (xy 134.166128 -75.889934) (xy 134.195592 -75.844085)
			(xy 134.231282 -75.802895) (xy 134.27247 -75.767203) (xy 134.318318 -75.737736) (xy 134.367893 -75.715094)
			(xy 134.420186 -75.699738) (xy 134.474132 -75.691979) (xy 134.501382 -75.691492) (xy 134.5303 -75.691988)
			(xy 134.587474 -75.700717) (xy 134.642675 -75.717977) (xy 134.694637 -75.743373) (xy 134.74217 -75.776322)
			(xy 134.784184 -75.816069) (xy 134.802372 -75.838558) (xy 134.812269 -75.850363) (xy 134.837593 -75.867882)
			(xy 134.866986 -75.877058) (xy 134.897778 -75.877058) (xy 134.927171 -75.867882) (xy 134.952495 -75.850363)
			(xy 134.962392 -75.838558) (xy 134.980577 -75.81607) (xy 135.022599 -75.776337) (xy 135.070136 -75.743399)
			(xy 135.122098 -75.718012) (xy 135.177296 -75.700757) (xy 135.234466 -75.692027) (xy 135.263382 -75.691492)
			(xy 135.290636 -75.691954) (xy 135.344589 -75.699709) (xy 135.396889 -75.715063) (xy 135.442054 -75.735688)
			(xy 153.508962 -75.735688) (xy 153.513033 -75.680066) (xy 153.525159 -75.625629) (xy 153.545082 -75.573538)
			(xy 153.572378 -75.524903) (xy 153.606464 -75.48076) (xy 153.646613 -75.442051) (xy 153.691971 -75.4096)
			(xy 153.741571 -75.384099) (xy 153.794355 -75.366092) (xy 153.849198 -75.355962) (xy 153.904932 -75.353925)
			(xy 153.960369 -75.360025) (xy 154.014326 -75.374131) (xy 154.024758 -75.378564) (xy 160.435034 -75.378564)
			(xy 160.439105 -75.322942) (xy 160.451231 -75.268505) (xy 160.471154 -75.216414) (xy 160.49845 -75.167779)
			(xy 160.532536 -75.123636) (xy 160.572685 -75.084927) (xy 160.618043 -75.052476) (xy 160.667643 -75.026975)
			(xy 160.720427 -75.008968) (xy 160.77527 -74.998838) (xy 160.831004 -74.996801) (xy 160.886441 -75.002901)
			(xy 160.940398 -75.017007) (xy 160.991727 -75.038819) (xy 161.039333 -75.067873) (xy 161.082201 -75.103548)
			(xy 161.119418 -75.145085) (xy 161.150191 -75.191598) (xy 161.173863 -75.242095) (xy 161.189931 -75.295502)
			(xy 161.198051 -75.350678) (xy 161.19856 -75.378564) (xy 161.198051 -75.40645) (xy 161.189931 -75.461626)
			(xy 161.173863 -75.515033) (xy 161.150191 -75.56553) (xy 161.119418 -75.612043) (xy 161.082201 -75.65358)
			(xy 161.039333 -75.689255) (xy 160.991727 -75.718309) (xy 160.940398 -75.740121) (xy 160.886441 -75.754227)
			(xy 160.831004 -75.760327) (xy 160.77527 -75.75829) (xy 160.720427 -75.74816) (xy 160.667643 -75.730153)
			(xy 160.618043 -75.704652) (xy 160.572685 -75.672201) (xy 160.532536 -75.633492) (xy 160.49845 -75.589349)
			(xy 160.471154 -75.540714) (xy 160.451231 -75.488623) (xy 160.439105 -75.434186) (xy 160.435034 -75.378564)
			(xy 154.024758 -75.378564) (xy 154.065655 -75.395943) (xy 154.113261 -75.424997) (xy 154.156129 -75.460672)
			(xy 154.193346 -75.502209) (xy 154.224119 -75.548722) (xy 154.247791 -75.599219) (xy 154.263859 -75.652626)
			(xy 154.271979 -75.707802) (xy 154.272488 -75.735688) (xy 154.271979 -75.763574) (xy 154.263859 -75.81875)
			(xy 154.247791 -75.872157) (xy 154.225439 -75.919838) (xy 159.117282 -75.919838) (xy 159.121353 -75.864216)
			(xy 159.133479 -75.809779) (xy 159.153402 -75.757688) (xy 159.180698 -75.709053) (xy 159.214784 -75.66491)
			(xy 159.254933 -75.626201) (xy 159.300291 -75.59375) (xy 159.349891 -75.568249) (xy 159.402675 -75.550242)
			(xy 159.457518 -75.540112) (xy 159.513252 -75.538075) (xy 159.568689 -75.544175) (xy 159.622646 -75.558281)
			(xy 159.673975 -75.580093) (xy 159.721581 -75.609147) (xy 159.764449 -75.644822) (xy 159.801666 -75.686359)
			(xy 159.832439 -75.732872) (xy 159.856111 -75.783369) (xy 159.8595 -75.794635) (xy 163.144215 -75.794635)
			(xy 163.144217 -75.740139) (xy 163.151974 -75.686198) (xy 163.167329 -75.633911) (xy 163.189969 -75.58434)
			(xy 163.219432 -75.538496) (xy 163.25512 -75.497311) (xy 163.296306 -75.461625) (xy 163.342151 -75.432162)
			(xy 163.391722 -75.409524) (xy 163.444011 -75.394172) (xy 163.497952 -75.386416) (xy 163.5252 -75.38593)
			(xy 163.561776 -75.387708) (xy 163.576669 -75.388592) (xy 163.605906 -75.382722) (xy 163.632201 -75.368657)
			(xy 163.653312 -75.347596) (xy 163.667439 -75.321335) (xy 163.673379 -75.292112) (xy 163.67252 -75.277218)
			(xy 163.670996 -75.242674) (xy 163.671506 -75.215425) (xy 163.679265 -75.161483) (xy 163.694623 -75.109193)
			(xy 163.717265 -75.059622) (xy 163.746731 -75.013777) (xy 163.782422 -74.972592) (xy 163.823611 -74.936906)
			(xy 163.869459 -74.907445) (xy 163.919033 -74.884808) (xy 163.971324 -74.869456) (xy 164.025267 -74.861703)
			(xy 164.079765 -74.861705) (xy 164.133708 -74.869463) (xy 164.185997 -74.884819) (xy 164.23557 -74.90746)
			(xy 164.281415 -74.936925) (xy 164.322601 -74.972615) (xy 164.358288 -75.013803) (xy 164.387751 -75.05965)
			(xy 164.410389 -75.109223) (xy 164.425741 -75.161514) (xy 164.433496 -75.215457) (xy 164.433495 -75.269955)
			(xy 164.425739 -75.323898) (xy 164.410384 -75.376188) (xy 164.387745 -75.425761) (xy 164.358281 -75.471607)
			(xy 164.322592 -75.512794) (xy 164.281405 -75.548482) (xy 164.235559 -75.577946) (xy 164.185986 -75.600585)
			(xy 164.133696 -75.615939) (xy 164.079753 -75.623696) (xy 164.052504 -75.624182) (xy 164.015928 -75.622404)
			(xy 164.001035 -75.621511) (xy 163.971796 -75.627381) (xy 163.945499 -75.641447) (xy 163.924387 -75.66251)
			(xy 163.910261 -75.688774) (xy 163.904323 -75.717999) (xy 163.905184 -75.732894) (xy 163.906708 -75.767438)
			(xy 163.906181 -75.794686) (xy 163.89842 -75.848626) (xy 163.883062 -75.900913) (xy 163.860419 -75.950482)
			(xy 163.830953 -75.996325) (xy 163.795262 -76.037507) (xy 163.754074 -76.073191) (xy 163.708227 -76.10265)
			(xy 163.658654 -76.125284) (xy 163.606364 -76.140634) (xy 163.552423 -76.148386) (xy 163.497927 -76.148382)
			(xy 163.443986 -76.140623) (xy 163.391699 -76.125267) (xy 163.342129 -76.102625) (xy 163.296286 -76.07316)
			(xy 163.255102 -76.037471) (xy 163.219417 -75.996284) (xy 163.189956 -75.950438) (xy 163.16732 -75.900866)
			(xy 163.151969 -75.848577) (xy 163.144215 -75.794635) (xy 159.8595 -75.794635) (xy 159.872179 -75.836776)
			(xy 159.880299 -75.891952) (xy 159.880808 -75.919838) (xy 159.880299 -75.947724) (xy 159.872179 -76.0029)
			(xy 159.856111 -76.056307) (xy 159.832439 -76.106804) (xy 159.801666 -76.153317) (xy 159.764449 -76.194854)
			(xy 159.721581 -76.230529) (xy 159.673975 -76.259583) (xy 159.622646 -76.281395) (xy 159.568689 -76.295501)
			(xy 159.513252 -76.301601) (xy 159.457518 -76.299564) (xy 159.402675 -76.289434) (xy 159.349891 -76.271427)
			(xy 159.300291 -76.245926) (xy 159.254933 -76.213475) (xy 159.214784 -76.174766) (xy 159.180698 -76.130623)
			(xy 159.153402 -76.081988) (xy 159.133479 -76.029897) (xy 159.121353 -75.97546) (xy 159.117282 -75.919838)
			(xy 154.225439 -75.919838) (xy 154.224119 -75.922654) (xy 154.193346 -75.969167) (xy 154.156129 -76.010704)
			(xy 154.113261 -76.046379) (xy 154.065655 -76.075433) (xy 154.014326 -76.097245) (xy 153.960369 -76.111351)
			(xy 153.904932 -76.117451) (xy 153.849198 -76.115414) (xy 153.794355 -76.105284) (xy 153.741571 -76.087277)
			(xy 153.691971 -76.061776) (xy 153.646613 -76.029325) (xy 153.606464 -75.990616) (xy 153.572378 -75.946473)
			(xy 153.545082 -75.897838) (xy 153.525159 -75.845747) (xy 153.513033 -75.79131) (xy 153.508962 -75.735688)
			(xy 135.442054 -75.735688) (xy 135.446471 -75.737705) (xy 135.492326 -75.767172) (xy 135.533521 -75.802866)
			(xy 135.569217 -75.844059) (xy 135.598686 -75.889913) (xy 135.62133 -75.939495) (xy 135.636687 -75.991794)
			(xy 135.644445 -76.045746) (xy 135.644445 -76.100254) (xy 135.636687 -76.154206) (xy 135.62133 -76.206505)
			(xy 135.598686 -76.256087) (xy 135.569217 -76.301941) (xy 135.533521 -76.343134) (xy 135.492326 -76.378828)
			(xy 135.446471 -76.408295) (xy 135.396889 -76.430937) (xy 135.344589 -76.446291) (xy 135.290636 -76.454046)
			(xy 135.263382 -76.454508) (xy 135.234466 -76.453966) (xy 135.177294 -76.445246) (xy 135.122094 -76.427996)
			(xy 135.070131 -76.402609) (xy 135.022597 -76.369667) (xy 134.980581 -76.329927) (xy 134.962392 -76.307442)
			(xy 134.952495 -76.295637) (xy 134.927171 -76.278118) (xy 134.897778 -76.268942) (xy 134.866986 -76.268942)
			(xy 134.837593 -76.278118) (xy 134.812269 -76.295637) (xy 134.802372 -76.307442) (xy 134.784207 -76.329948)
			(xy 134.742181 -76.36968) (xy 134.69464 -76.402615) (xy 134.642674 -76.427999) (xy 134.587472 -76.445251)
			(xy 134.530299 -76.453975) (xy 134.501382 -76.454508) (xy 134.474132 -76.454021) (xy 134.420186 -76.446262)
			(xy 134.367893 -76.430906) (xy 134.318318 -76.408264) (xy 134.27247 -76.378797) (xy 134.231282 -76.343105)
			(xy 134.195592 -76.301915) (xy 134.166128 -76.256066) (xy 134.143488 -76.20649) (xy 134.128134 -76.154197)
			(xy 134.120378 -76.10025) (xy 129.482867 -76.10025) (xy 129.461874 -76.131981) (xy 129.424657 -76.173518)
			(xy 129.381789 -76.209193) (xy 129.334183 -76.238247) (xy 129.282854 -76.260059) (xy 129.228897 -76.274165)
			(xy 129.17346 -76.280265) (xy 129.117726 -76.278228) (xy 129.062883 -76.268098) (xy 129.010099 -76.250091)
			(xy 128.960499 -76.22459) (xy 128.915141 -76.192139) (xy 128.874992 -76.15343) (xy 128.840906 -76.109287)
			(xy 128.81361 -76.060652) (xy 128.793687 -76.008561) (xy 128.781561 -75.954124) (xy 128.77749 -75.898502)
			(xy 125.026366 -75.898502) (xy 125.065318 -75.903917) (xy 125.116006 -75.918276) (xy 125.164239 -75.939465)
			(xy 125.209101 -75.967084) (xy 125.249742 -76.000607) (xy 125.285389 -76.039398) (xy 125.30074 -76.060808)
			(xy 125.308823 -76.071776) (xy 125.329641 -76.089337) (xy 125.354365 -76.100762) (xy 125.38123 -76.105235)
			(xy 125.408322 -76.10244) (xy 125.433707 -76.092573) (xy 125.455576 -76.07634) (xy 125.464316 -76.065888)
			(xy 125.482489 -76.043509) (xy 125.524441 -76.003969) (xy 125.57187 -75.971199) (xy 125.623693 -75.945946)
			(xy 125.678728 -75.928785) (xy 125.73572 -75.92011) (xy 125.764544 -75.919584) (xy 125.791793 -75.920089)
			(xy 125.845734 -75.92785) (xy 125.898023 -75.943209) (xy 125.947593 -75.965852) (xy 125.993437 -75.995319)
			(xy 126.034622 -76.03101) (xy 126.070308 -76.072198) (xy 126.099769 -76.118045) (xy 126.122407 -76.167618)
			(xy 126.137759 -76.219909) (xy 126.145514 -76.273851) (xy 126.145514 -76.328349) (xy 126.137759 -76.382291)
			(xy 126.122407 -76.434582) (xy 126.099769 -76.484155) (xy 126.094827 -76.491846) (xy 142.194278 -76.491846)
			(xy 142.198349 -76.436224) (xy 142.210475 -76.381787) (xy 142.230398 -76.329696) (xy 142.257694 -76.281061)
			(xy 142.29178 -76.236918) (xy 142.331929 -76.198209) (xy 142.377287 -76.165758) (xy 142.426887 -76.140257)
			(xy 142.479671 -76.12225) (xy 142.534514 -76.11212) (xy 142.590248 -76.110083) (xy 142.645685 -76.116183)
			(xy 142.699642 -76.130289) (xy 142.750971 -76.152101) (xy 142.798577 -76.181155) (xy 142.841445 -76.21683)
			(xy 142.878662 -76.258367) (xy 142.909435 -76.30488) (xy 142.933107 -76.355377) (xy 142.949175 -76.408784)
			(xy 142.95553 -76.451968) (xy 144.367502 -76.451968) (xy 144.371573 -76.396346) (xy 144.383699 -76.341909)
			(xy 144.403622 -76.289818) (xy 144.430918 -76.241183) (xy 144.465004 -76.19704) (xy 144.505153 -76.158331)
			(xy 144.550511 -76.12588) (xy 144.600111 -76.100379) (xy 144.652895 -76.082372) (xy 144.707738 -76.072242)
			(xy 144.763472 -76.070205) (xy 144.818909 -76.076305) (xy 144.872866 -76.090411) (xy 144.924195 -76.112223)
			(xy 144.971801 -76.141277) (xy 145.014669 -76.176952) (xy 145.051886 -76.218489) (xy 145.082659 -76.265002)
			(xy 145.084098 -76.268072) (xy 146.347686 -76.268072) (xy 146.351757 -76.21245) (xy 146.363883 -76.158013)
			(xy 146.383806 -76.105922) (xy 146.411102 -76.057287) (xy 146.445188 -76.013144) (xy 146.485337 -75.974435)
			(xy 146.530695 -75.941984) (xy 146.580295 -75.916483) (xy 146.633079 -75.898476) (xy 146.687922 -75.888346)
			(xy 146.743656 -75.886309) (xy 146.799093 -75.892409) (xy 146.85305 -75.906515) (xy 146.904379 -75.928327)
			(xy 146.951985 -75.957381) (xy 146.994853 -75.993056) (xy 147.03207 -76.034593) (xy 147.062843 -76.081106)
			(xy 147.086515 -76.131603) (xy 147.102583 -76.18501) (xy 147.110703 -76.240186) (xy 147.111212 -76.268072)
			(xy 147.110703 -76.295958) (xy 147.102583 -76.351134) (xy 147.086515 -76.404541) (xy 147.062843 -76.455038)
			(xy 147.03207 -76.501551) (xy 146.994853 -76.543088) (xy 146.951985 -76.578763) (xy 146.904379 -76.607817)
			(xy 146.85305 -76.629629) (xy 146.799093 -76.643735) (xy 146.743656 -76.649835) (xy 146.687922 -76.647798)
			(xy 146.633079 -76.637668) (xy 146.580295 -76.619661) (xy 146.530695 -76.59416) (xy 146.485337 -76.561709)
			(xy 146.445188 -76.523) (xy 146.411102 -76.478857) (xy 146.383806 -76.430222) (xy 146.363883 -76.378131)
			(xy 146.351757 -76.323694) (xy 146.347686 -76.268072) (xy 145.084098 -76.268072) (xy 145.106331 -76.315499)
			(xy 145.122399 -76.368906) (xy 145.130519 -76.424082) (xy 145.131028 -76.451968) (xy 145.130519 -76.479854)
			(xy 145.122399 -76.53503) (xy 145.106331 -76.588437) (xy 145.082659 -76.638934) (xy 145.051886 -76.685447)
			(xy 145.014669 -76.726984) (xy 144.971801 -76.762659) (xy 144.924195 -76.791713) (xy 144.872866 -76.813525)
			(xy 144.818909 -76.827631) (xy 144.763472 -76.833731) (xy 144.707738 -76.831694) (xy 144.652895 -76.821564)
			(xy 144.600111 -76.803557) (xy 144.550511 -76.778056) (xy 144.505153 -76.745605) (xy 144.465004 -76.706896)
			(xy 144.430918 -76.662753) (xy 144.403622 -76.614118) (xy 144.383699 -76.562027) (xy 144.371573 -76.50759)
			(xy 144.367502 -76.451968) (xy 142.95553 -76.451968) (xy 142.957295 -76.46396) (xy 142.957804 -76.491846)
			(xy 142.957295 -76.519732) (xy 142.949175 -76.574908) (xy 142.933107 -76.628315) (xy 142.909435 -76.678812)
			(xy 142.878662 -76.725325) (xy 142.841445 -76.766862) (xy 142.798577 -76.802537) (xy 142.750971 -76.831591)
			(xy 142.699642 -76.853403) (xy 142.645685 -76.867509) (xy 142.590248 -76.873609) (xy 142.534514 -76.871572)
			(xy 142.479671 -76.861442) (xy 142.426887 -76.843435) (xy 142.377287 -76.817934) (xy 142.331929 -76.785483)
			(xy 142.29178 -76.746774) (xy 142.257694 -76.702631) (xy 142.230398 -76.653996) (xy 142.210475 -76.601905)
			(xy 142.198349 -76.547468) (xy 142.194278 -76.491846) (xy 126.094827 -76.491846) (xy 126.070308 -76.530002)
			(xy 126.034622 -76.57119) (xy 125.993437 -76.606881) (xy 125.947593 -76.636348) (xy 125.898023 -76.658991)
			(xy 125.845734 -76.67435) (xy 125.791793 -76.682111) (xy 125.764544 -76.6826) (xy 125.738202 -76.682159)
			(xy 125.68602 -76.674908) (xy 125.63533 -76.660551) (xy 125.587096 -76.639361) (xy 125.542233 -76.611741)
			(xy 125.501594 -76.578215) (xy 125.46595 -76.53942) (xy 125.4506 -76.518008) (xy 125.442469 -76.507077)
			(xy 125.421663 -76.489514) (xy 125.396949 -76.478086) (xy 125.370093 -76.473607) (xy 125.343008 -76.476396)
			(xy 125.317628 -76.486255) (xy 125.295763 -76.50248) (xy 125.287024 -76.512928) (xy 125.268832 -76.535292)
			(xy 125.226883 -76.574831) (xy 125.179459 -76.607603) (xy 125.12764 -76.632859) (xy 125.072608 -76.650023)
			(xy 125.015619 -76.658703) (xy 124.986796 -76.659232) (xy 124.959547 -76.658698) (xy 124.905603 -76.650941)
			(xy 124.853312 -76.635587) (xy 124.803738 -76.612947) (xy 124.757891 -76.583482) (xy 124.716704 -76.547793)
			(xy 124.681015 -76.506605) (xy 124.651551 -76.460758) (xy 124.628912 -76.411184) (xy 124.613558 -76.358893)
			(xy 124.605802 -76.304949) (xy 122.231286 -76.304949) (xy 122.227826 -76.329881) (xy 122.213457 -76.380601)
			(xy 122.192241 -76.428859) (xy 122.16458 -76.473735) (xy 122.131003 -76.514374) (xy 122.09215 -76.550002)
			(xy 122.04876 -76.57994) (xy 122.02541 -76.592176) (xy 122.013051 -76.598852) (xy 121.992343 -76.617822)
			(xy 121.977587 -76.641715) (xy 121.9699 -76.668725) (xy 121.969863 -76.696808) (xy 121.977479 -76.723838)
			(xy 121.992171 -76.74777) (xy 122.012829 -76.766794) (xy 122.025156 -76.773532) (xy 122.048451 -76.785741)
			(xy 122.091681 -76.8157) (xy 122.130383 -76.851315) (xy 122.163824 -76.89191) (xy 122.191369 -76.936717)
			(xy 122.212495 -76.984883) (xy 122.226802 -77.035496) (xy 122.229357 -77.053948) (xy 128.776982 -77.053948)
			(xy 128.781053 -76.998326) (xy 128.793179 -76.943889) (xy 128.813102 -76.891798) (xy 128.840398 -76.843163)
			(xy 128.874484 -76.79902) (xy 128.914633 -76.760311) (xy 128.959991 -76.72786) (xy 129.009591 -76.702359)
			(xy 129.062375 -76.684352) (xy 129.117218 -76.674222) (xy 129.172952 -76.672185) (xy 129.228389 -76.678285)
			(xy 129.282346 -76.692391) (xy 129.333675 -76.714203) (xy 129.381281 -76.743257) (xy 129.424149 -76.778932)
			(xy 129.461366 -76.820469) (xy 129.492139 -76.866982) (xy 129.515811 -76.917479) (xy 129.531879 -76.970886)
			(xy 129.539999 -77.026062) (xy 129.540508 -77.053948) (xy 129.539999 -77.081834) (xy 129.531879 -77.13701)
			(xy 129.515811 -77.190417) (xy 129.51223 -77.198055) (xy 146.298843 -77.198055) (xy 146.298843 -77.143545)
			(xy 146.306601 -77.089591) (xy 146.321958 -77.03729) (xy 146.344603 -76.987707) (xy 146.374074 -76.941851)
			(xy 146.409771 -76.900657) (xy 146.450967 -76.864962) (xy 146.496824 -76.835493) (xy 146.546409 -76.812851)
			(xy 146.59871 -76.797496) (xy 146.652665 -76.789742) (xy 146.67992 -76.78928) (xy 146.707134 -76.789775)
			(xy 146.761009 -76.797517) (xy 146.813235 -76.812841) (xy 146.862752 -76.835436) (xy 146.885914 -76.849732)
			(xy 146.898733 -76.857293) (xy 146.927344 -76.86543) (xy 146.957086 -76.864984) (xy 146.985441 -76.855994)
			(xy 147.010006 -76.839219) (xy 147.0287 -76.816082) (xy 147.039941 -76.788542) (xy 147.04187 -76.773786)
			(xy 147.045098 -76.74581) (xy 147.058629 -76.691148) (xy 147.080049 -76.63907) (xy 147.108894 -76.590708)
			(xy 147.144537 -76.547112) (xy 147.186203 -76.509231) (xy 147.232985 -76.477888) (xy 147.283868 -76.453764)
			(xy 147.337745 -76.437385) (xy 147.393444 -76.429105) (xy 147.4216 -76.4286) (xy 147.448852 -76.42907)
			(xy 147.502801 -76.436826) (xy 147.555097 -76.452182) (xy 147.604675 -76.474824) (xy 147.650526 -76.50429)
			(xy 147.691717 -76.539983) (xy 147.717795 -76.570078) (xy 160.438082 -76.570078) (xy 160.442153 -76.514456)
			(xy 160.454279 -76.460019) (xy 160.474202 -76.407928) (xy 160.501498 -76.359293) (xy 160.535584 -76.31515)
			(xy 160.575733 -76.276441) (xy 160.621091 -76.24399) (xy 160.670691 -76.218489) (xy 160.723475 -76.200482)
			(xy 160.778318 -76.190352) (xy 160.834052 -76.188315) (xy 160.889489 -76.194415) (xy 160.943446 -76.208521)
			(xy 160.994775 -76.230333) (xy 161.042381 -76.259387) (xy 161.085249 -76.295062) (xy 161.122466 -76.336599)
			(xy 161.153239 -76.383112) (xy 161.176911 -76.433609) (xy 161.192979 -76.487016) (xy 161.201099 -76.542192)
			(xy 161.201608 -76.570078) (xy 161.201099 -76.597964) (xy 161.192979 -76.65314) (xy 161.176911 -76.706547)
			(xy 161.153239 -76.757044) (xy 161.126182 -76.797941) (xy 163.144154 -76.797941) (xy 163.144156 -76.743434)
			(xy 163.151915 -76.689482) (xy 163.167274 -76.637184) (xy 163.189919 -76.587604) (xy 163.21939 -76.541751)
			(xy 163.255086 -76.500559) (xy 163.296281 -76.464867) (xy 163.342137 -76.435401) (xy 163.391719 -76.41276)
			(xy 163.444019 -76.397407) (xy 163.497972 -76.389654) (xy 163.552479 -76.389657) (xy 163.60643 -76.397418)
			(xy 163.658728 -76.412778) (xy 163.708308 -76.435425) (xy 163.754159 -76.464897) (xy 163.79535 -76.500595)
			(xy 163.831041 -76.541791) (xy 163.860505 -76.587648) (xy 163.883144 -76.637231) (xy 163.898495 -76.689532)
			(xy 163.906247 -76.743485) (xy 163.906708 -76.770738) (xy 163.905692 -76.799948) (xy 163.905071 -76.814405)
			(xy 163.911059 -76.842704) (xy 163.924732 -76.868194) (xy 163.944995 -76.888835) (xy 163.970228 -76.902976)
			(xy 163.998412 -76.909486) (xy 164.01288 -76.909168) (xy 164.034978 -76.908406) (xy 164.062233 -76.908831)
			(xy 164.116187 -76.916586) (xy 164.168489 -76.93194) (xy 164.218074 -76.954581) (xy 164.263932 -76.984048)
			(xy 164.305129 -77.019742) (xy 164.340827 -77.060935) (xy 164.370299 -77.10679) (xy 164.392946 -77.156372)
			(xy 164.408305 -77.208672) (xy 164.416066 -77.262626) (xy 164.416068 -77.317135) (xy 164.408314 -77.37109)
			(xy 164.392959 -77.423392) (xy 164.370318 -77.472976) (xy 164.34085 -77.518834) (xy 164.305156 -77.560031)
			(xy 164.263963 -77.595729) (xy 164.218108 -77.625201) (xy 164.168526 -77.647847) (xy 164.116225 -77.663206)
			(xy 164.062271 -77.670966) (xy 164.007762 -77.670968) (xy 163.953807 -77.663213) (xy 163.901506 -77.647858)
			(xy 163.851921 -77.625217) (xy 163.806064 -77.595749) (xy 163.764867 -77.560054) (xy 163.72917 -77.51886)
			(xy 163.699698 -77.473006) (xy 163.677052 -77.423423) (xy 163.661693 -77.371123) (xy 163.653934 -77.317169)
			(xy 163.65347 -77.289914) (xy 163.654486 -77.260704) (xy 163.655081 -77.246245) (xy 163.649105 -77.217945)
			(xy 163.63544 -77.192453) (xy 163.61518 -77.17181) (xy 163.589948 -77.157669) (xy 163.561765 -77.151163)
			(xy 163.547298 -77.151484) (xy 163.5252 -77.152246) (xy 163.497947 -77.151745) (xy 163.443995 -77.143987)
			(xy 163.391696 -77.128631) (xy 163.342115 -77.105987) (xy 163.296261 -77.076518) (xy 163.255068 -77.040823)
			(xy 163.219374 -76.999629) (xy 163.189907 -76.953774) (xy 163.167265 -76.904192) (xy 163.15191 -76.851893)
			(xy 163.144154 -76.797941) (xy 161.126182 -76.797941) (xy 161.122466 -76.803557) (xy 161.085249 -76.845094)
			(xy 161.042381 -76.880769) (xy 160.994775 -76.909823) (xy 160.943446 -76.931635) (xy 160.889489 -76.945741)
			(xy 160.834052 -76.951841) (xy 160.778318 -76.949804) (xy 160.723475 -76.939674) (xy 160.670691 -76.921667)
			(xy 160.621091 -76.896166) (xy 160.575733 -76.863715) (xy 160.535584 -76.825006) (xy 160.501498 -76.780863)
			(xy 160.474202 -76.732228) (xy 160.454279 -76.680137) (xy 160.442153 -76.6257) (xy 160.438082 -76.570078)
			(xy 147.717795 -76.570078) (xy 147.72741 -76.581174) (xy 147.756876 -76.627025) (xy 147.779518 -76.676603)
			(xy 147.794874 -76.728899) (xy 147.80263 -76.782848) (xy 147.80263 -76.837352) (xy 147.794874 -76.891301)
			(xy 147.779518 -76.943597) (xy 147.756876 -76.993175) (xy 147.72741 -77.039026) (xy 147.712279 -77.056488)
			(xy 153.430222 -77.056488) (xy 153.434293 -77.000866) (xy 153.446419 -76.946429) (xy 153.466342 -76.894338)
			(xy 153.493638 -76.845703) (xy 153.527724 -76.80156) (xy 153.567873 -76.762851) (xy 153.613231 -76.7304)
			(xy 153.662831 -76.704899) (xy 153.715615 -76.686892) (xy 153.770458 -76.676762) (xy 153.826192 -76.674725)
			(xy 153.881629 -76.680825) (xy 153.935586 -76.694931) (xy 153.986915 -76.716743) (xy 154.034521 -76.745797)
			(xy 154.077389 -76.781472) (xy 154.114606 -76.823009) (xy 154.145379 -76.869522) (xy 154.169051 -76.920019)
			(xy 154.185119 -76.973426) (xy 154.193239 -77.028602) (xy 154.193748 -77.056488) (xy 154.193239 -77.084374)
			(xy 154.185119 -77.13955) (xy 154.169051 -77.192957) (xy 154.145379 -77.243454) (xy 154.114606 -77.289967)
			(xy 154.077389 -77.331504) (xy 154.034521 -77.367179) (xy 153.986915 -77.396233) (xy 153.935586 -77.418045)
			(xy 153.881629 -77.432151) (xy 153.826192 -77.438251) (xy 153.770458 -77.436214) (xy 153.715615 -77.426084)
			(xy 153.662831 -77.408077) (xy 153.613231 -77.382576) (xy 153.567873 -77.350125) (xy 153.527724 -77.311416)
			(xy 153.493638 -77.267273) (xy 153.466342 -77.218638) (xy 153.446419 -77.166547) (xy 153.434293 -77.11211)
			(xy 153.430222 -77.056488) (xy 147.712279 -77.056488) (xy 147.691717 -77.080217) (xy 147.650526 -77.11591)
			(xy 147.604675 -77.145376) (xy 147.555097 -77.168018) (xy 147.502801 -77.183374) (xy 147.448852 -77.19113)
			(xy 147.4216 -77.191616) (xy 147.394386 -77.191113) (xy 147.340512 -77.183373) (xy 147.288285 -77.168051)
			(xy 147.238768 -77.145459) (xy 147.215606 -77.131164) (xy 147.202841 -77.123507) (xy 147.174211 -77.115383)
			(xy 147.144455 -77.115843) (xy 147.116091 -77.12485) (xy 147.09152 -77.14164) (xy 147.072821 -77.164792)
			(xy 147.061579 -77.192347) (xy 147.05965 -77.20711) (xy 147.056497 -77.235096) (xy 147.042963 -77.289765)
			(xy 147.021537 -77.341848) (xy 146.992685 -77.390215) (xy 146.957034 -77.433813) (xy 146.915359 -77.471694)
			(xy 146.868566 -77.503035) (xy 146.817674 -77.527154) (xy 146.763787 -77.543527) (xy 146.708079 -77.551797)
			(xy 146.67992 -77.552296) (xy 146.652665 -77.551858) (xy 146.59871 -77.544104) (xy 146.546409 -77.528749)
			(xy 146.496824 -77.506107) (xy 146.450967 -77.476638) (xy 146.409771 -77.440943) (xy 146.374074 -77.399749)
			(xy 146.344603 -77.353893) (xy 146.321958 -77.30431) (xy 146.306601 -77.252009) (xy 146.298843 -77.198055)
			(xy 129.51223 -77.198055) (xy 129.492139 -77.240914) (xy 129.461366 -77.287427) (xy 129.424149 -77.328964)
			(xy 129.381281 -77.364639) (xy 129.333675 -77.393693) (xy 129.282346 -77.415505) (xy 129.228389 -77.429611)
			(xy 129.172952 -77.435711) (xy 129.117218 -77.433674) (xy 129.062375 -77.423544) (xy 129.009591 -77.405537)
			(xy 128.959991 -77.380036) (xy 128.914633 -77.347585) (xy 128.874484 -77.308876) (xy 128.840398 -77.264733)
			(xy 128.813102 -77.216098) (xy 128.793179 -77.164007) (xy 128.781053 -77.10957) (xy 128.776982 -77.053948)
			(xy 122.229357 -77.053948) (xy 122.234017 -77.087594) (xy 122.234452 -77.113892) (xy 122.233966 -77.141143)
			(xy 122.22621 -77.195091) (xy 122.210855 -77.247386) (xy 122.188213 -77.296963) (xy 122.158747 -77.342813)
			(xy 122.123056 -77.384004) (xy 122.081865 -77.419695) (xy 122.036015 -77.449161) (xy 121.986438 -77.471803)
			(xy 121.934143 -77.487158) (xy 121.880195 -77.494914) (xy 121.825693 -77.494914) (xy 121.771745 -77.487158)
			(xy 121.71945 -77.471803) (xy 121.669873 -77.449161) (xy 121.624023 -77.419695) (xy 121.582832 -77.384004)
			(xy 121.547141 -77.342813) (xy 121.517675 -77.296963) (xy 121.495033 -77.247386) (xy 121.479678 -77.195091)
			(xy 121.471922 -77.141143) (xy 121.471436 -77.113892) (xy 117.29745 -77.113892) (xy 117.297708 -77.130148)
			(xy 117.297116 -77.159319) (xy 117.288194 -77.216975) (xy 117.279928 -77.244956) (xy 117.276081 -77.258639)
			(xy 117.275391 -77.287047) (xy 117.282545 -77.314549) (xy 117.296988 -77.339021) (xy 117.317606 -77.358575)
			(xy 117.342809 -77.371702) (xy 117.356636 -77.375004) (xy 117.385019 -77.381321) (xy 117.4396 -77.401365)
			(xy 117.490506 -77.429461) (xy 117.536559 -77.464956) (xy 117.576691 -77.50703) (xy 117.609973 -77.554707)
			(xy 117.618031 -77.571092) (xy 125.382526 -77.571092) (xy 125.386597 -77.51547) (xy 125.398723 -77.461033)
			(xy 125.418646 -77.408942) (xy 125.445942 -77.360307) (xy 125.480028 -77.316164) (xy 125.520177 -77.277455)
			(xy 125.565535 -77.245004) (xy 125.615135 -77.219503) (xy 125.667919 -77.201496) (xy 125.722762 -77.191366)
			(xy 125.778496 -77.189329) (xy 125.833933 -77.195429) (xy 125.88789 -77.209535) (xy 125.939219 -77.231347)
			(xy 125.986825 -77.260401) (xy 126.029693 -77.296076) (xy 126.06691 -77.337613) (xy 126.097683 -77.384126)
			(xy 126.121355 -77.434623) (xy 126.137423 -77.48803) (xy 126.145543 -77.543206) (xy 126.146052 -77.571092)
			(xy 126.145543 -77.598978) (xy 126.137423 -77.654154) (xy 126.121355 -77.707561) (xy 126.097683 -77.758058)
			(xy 126.06691 -77.804571) (xy 126.029693 -77.846108) (xy 125.992683 -77.876908) (xy 135.668512 -77.876908)
			(xy 135.668998 -77.849657) (xy 135.676754 -77.795709) (xy 135.692109 -77.743414) (xy 135.714751 -77.693837)
			(xy 135.744217 -77.647987) (xy 135.779908 -77.606796) (xy 135.821099 -77.571105) (xy 135.866949 -77.541639)
			(xy 135.916526 -77.518997) (xy 135.968821 -77.503642) (xy 136.022769 -77.495886) (xy 136.077271 -77.495886)
			(xy 136.131219 -77.503642) (xy 136.183514 -77.518997) (xy 136.233091 -77.541639) (xy 136.278941 -77.571105)
			(xy 136.320132 -77.606796) (xy 136.355823 -77.647987) (xy 136.385289 -77.693837) (xy 136.407931 -77.743414)
			(xy 136.423286 -77.795709) (xy 136.431042 -77.849657) (xy 136.431528 -77.876908) (xy 136.431002 -77.905802)
			(xy 136.422296 -77.96293) (xy 136.420042 -77.970147) (xy 138.028726 -77.970147) (xy 138.028726 -77.915653)
			(xy 138.036481 -77.861714) (xy 138.051833 -77.809427) (xy 138.07447 -77.759858) (xy 138.103931 -77.714014)
			(xy 138.139616 -77.67283) (xy 138.180798 -77.637143) (xy 138.22664 -77.60768) (xy 138.276209 -77.58504)
			(xy 138.328494 -77.569685) (xy 138.382433 -77.561928) (xy 138.40968 -77.56144) (xy 138.43705 -77.561908)
			(xy 138.49123 -77.569724) (xy 138.543733 -77.585212) (xy 138.59348 -77.608054) (xy 138.639447 -77.637778)
			(xy 138.660378 -77.65542) (xy 138.671706 -77.664656) (xy 138.698263 -77.676832) (xy 138.72718 -77.681005)
			(xy 138.756097 -77.676832) (xy 138.782654 -77.664656) (xy 138.793982 -77.65542) (xy 138.814913 -77.637779)
			(xy 138.860885 -77.608067) (xy 138.910633 -77.585231) (xy 138.963134 -77.56974) (xy 139.017311 -77.561913)
			(xy 139.04468 -77.56144) (xy 139.071937 -77.561806) (xy 139.125897 -77.569561) (xy 139.178204 -77.584917)
			(xy 139.227793 -77.607562) (xy 139.273654 -77.637033) (xy 139.314855 -77.672731) (xy 139.350555 -77.71393)
			(xy 139.380029 -77.759789) (xy 139.402676 -77.809377) (xy 139.418035 -77.861683) (xy 139.425793 -77.915643)
			(xy 139.425793 -77.970157) (xy 139.418035 -78.024117) (xy 139.402676 -78.076423) (xy 139.398902 -78.084687)
			(xy 140.217008 -78.084687) (xy 140.22476 -78.030729) (xy 140.240112 -77.978423) (xy 140.262751 -77.928835)
			(xy 140.292217 -77.882973) (xy 140.327911 -77.841771) (xy 140.369104 -77.806069) (xy 140.414959 -77.776592)
			(xy 140.464543 -77.753942) (xy 140.516845 -77.738578) (xy 140.570801 -77.730814) (xy 140.625313 -77.730808)
			(xy 140.679272 -77.73856) (xy 140.731577 -77.753912) (xy 140.781166 -77.776551) (xy 140.827028 -77.806018)
			(xy 140.868229 -77.841711) (xy 140.89279 -77.87005) (xy 160.182304 -77.87005) (xy 160.186375 -77.814428)
			(xy 160.198501 -77.759991) (xy 160.218424 -77.7079) (xy 160.24572 -77.659265) (xy 160.279806 -77.615122)
			(xy 160.319955 -77.576413) (xy 160.365313 -77.543962) (xy 160.414913 -77.518461) (xy 160.467697 -77.500454)
			(xy 160.52254 -77.490324) (xy 160.578274 -77.488287) (xy 160.633711 -77.494387) (xy 160.687668 -77.508493)
			(xy 160.738997 -77.530305) (xy 160.786603 -77.559359) (xy 160.829471 -77.595034) (xy 160.866688 -77.636571)
			(xy 160.897461 -77.683084) (xy 160.921133 -77.733581) (xy 160.937201 -77.786988) (xy 160.945321 -77.842164)
			(xy 160.94583 -77.87005) (xy 160.945321 -77.897936) (xy 160.937201 -77.953112) (xy 160.921133 -78.006519)
			(xy 160.897461 -78.057016) (xy 160.866688 -78.103529) (xy 160.829471 -78.145066) (xy 160.786603 -78.180741)
			(xy 160.738997 -78.209795) (xy 160.687668 -78.231607) (xy 160.633711 -78.245713) (xy 160.578274 -78.251813)
			(xy 160.52254 -78.249776) (xy 160.467697 -78.239646) (xy 160.414913 -78.221639) (xy 160.365313 -78.196138)
			(xy 160.319955 -78.163687) (xy 160.279806 -78.124978) (xy 160.24572 -78.080835) (xy 160.218424 -78.0322)
			(xy 160.198501 -77.980109) (xy 160.186375 -77.925672) (xy 160.182304 -77.87005) (xy 140.89279 -77.87005)
			(xy 140.903931 -77.882905) (xy 140.933408 -77.92876) (xy 140.956059 -77.978343) (xy 140.971422 -78.030646)
			(xy 140.979186 -78.084602) (xy 140.979652 -78.111858) (xy 140.979401 -78.13221) (xy 140.97507 -78.172684)
			(xy 140.971016 -78.19263) (xy 140.968513 -78.205831) (xy 140.969932 -78.23266) (xy 140.978299 -78.258189)
			(xy 140.993036 -78.280653) (xy 141.013121 -78.298495) (xy 141.037165 -78.31048) (xy 141.063503 -78.31578)
			(xy 141.076934 -78.315312) (xy 141.10208 -78.31455) (xy 141.129335 -78.315034) (xy 141.183291 -78.322789)
			(xy 141.235594 -78.338144) (xy 141.28518 -78.360786) (xy 141.331038 -78.390255) (xy 141.372235 -78.425951)
			(xy 141.407933 -78.467147) (xy 141.437404 -78.513003) (xy 141.460049 -78.562587) (xy 141.475407 -78.61489)
			(xy 141.483165 -78.668845) (xy 141.483165 -78.723356) (xy 141.475407 -78.777312) (xy 141.460049 -78.829614)
			(xy 141.437404 -78.879198) (xy 141.407932 -78.925054) (xy 141.372234 -78.96625) (xy 141.331037 -79.001945)
			(xy 141.285179 -79.031414) (xy 141.235593 -79.054057) (xy 141.18329 -79.069412) (xy 141.129334 -79.077167)
			(xy 141.074823 -79.077164) (xy 141.020868 -79.069403) (xy 140.968567 -79.054042) (xy 140.918984 -79.031394)
			(xy 140.873129 -79.00192) (xy 140.831936 -78.96622) (xy 140.796242 -78.92502) (xy 140.766776 -78.87916)
			(xy 140.744136 -78.829574) (xy 140.728784 -78.77727) (xy 140.721032 -78.723313) (xy 140.720572 -78.696058)
			(xy 140.720825 -78.675706) (xy 140.725154 -78.635232) (xy 140.729208 -78.615286) (xy 140.731669 -78.602079)
			(xy 140.730253 -78.575257) (xy 140.721892 -78.549732) (xy 140.707162 -78.527272) (xy 140.687084 -78.50943)
			(xy 140.663048 -78.497443) (xy 140.636718 -78.492139) (xy 140.62329 -78.492604) (xy 140.598144 -78.493366)
			(xy 140.570888 -78.492992) (xy 140.51693 -78.485241) (xy 140.464624 -78.469889) (xy 140.415035 -78.447249)
			(xy 140.369174 -78.417783) (xy 140.327972 -78.38209) (xy 140.292269 -78.340896) (xy 140.262793 -78.295041)
			(xy 140.240142 -78.245458) (xy 140.224778 -78.193156) (xy 140.217014 -78.139199) (xy 140.217008 -78.084687)
			(xy 139.398902 -78.084687) (xy 139.380029 -78.126011) (xy 139.350555 -78.17187) (xy 139.314855 -78.213069)
			(xy 139.273654 -78.248767) (xy 139.227793 -78.278238) (xy 139.178204 -78.300883) (xy 139.125897 -78.316239)
			(xy 139.071937 -78.323994) (xy 139.04468 -78.324456) (xy 139.017309 -78.324012) (xy 138.963128 -78.316191)
			(xy 138.910625 -78.300697) (xy 138.860878 -78.27785) (xy 138.814913 -78.24812) (xy 138.793982 -78.230476)
			(xy 138.782654 -78.22124) (xy 138.756097 -78.209064) (xy 138.72718 -78.204891) (xy 138.698263 -78.209064)
			(xy 138.671706 -78.22124) (xy 138.660378 -78.230476) (xy 138.639424 -78.248088) (xy 138.593458 -78.277805)
			(xy 138.543716 -78.300646) (xy 138.49122 -78.316144) (xy 138.437048 -78.323979) (xy 138.40968 -78.324456)
			(xy 138.382433 -78.323872) (xy 138.328494 -78.316115) (xy 138.276209 -78.30076) (xy 138.22664 -78.27812)
			(xy 138.180798 -78.248657) (xy 138.139616 -78.21297) (xy 138.103931 -78.171786) (xy 138.07447 -78.125942)
			(xy 138.051833 -78.076373) (xy 138.036481 -78.024086) (xy 138.028726 -77.970147) (xy 136.420042 -77.970147)
			(xy 136.405071 -78.01809) (xy 136.37972 -78.070019) (xy 136.36371 -78.094078) (xy 136.355713 -78.106659)
			(xy 136.346563 -78.135012) (xy 136.345976 -78.164799) (xy 136.354001 -78.193491) (xy 136.369956 -78.218651)
			(xy 136.392488 -78.238144) (xy 136.405874 -78.2447) (xy 136.430758 -78.25636) (xy 136.477237 -78.285674)
			(xy 136.519027 -78.321354) (xy 136.555265 -78.362663) (xy 136.585198 -78.408745) (xy 136.608209 -78.458645)
			(xy 136.62382 -78.511331) (xy 136.631708 -78.565713) (xy 136.632188 -78.593188) (xy 136.631702 -78.620439)
			(xy 136.623946 -78.674387) (xy 136.608591 -78.726682) (xy 136.585949 -78.776259) (xy 136.556483 -78.822109)
			(xy 136.520792 -78.8633) (xy 136.479601 -78.898991) (xy 136.433751 -78.928457) (xy 136.384174 -78.951099)
			(xy 136.331879 -78.966454) (xy 136.277931 -78.97421) (xy 136.223429 -78.97421) (xy 136.169481 -78.966454)
			(xy 136.117186 -78.951099) (xy 136.067609 -78.928457) (xy 136.021759 -78.898991) (xy 135.980568 -78.8633)
			(xy 135.944877 -78.822109) (xy 135.915411 -78.776259) (xy 135.892769 -78.726682) (xy 135.877414 -78.674387)
			(xy 135.869658 -78.620439) (xy 135.869172 -78.593188) (xy 135.869696 -78.564294) (xy 135.878402 -78.507166)
			(xy 135.895628 -78.452006) (xy 135.92098 -78.400077) (xy 135.93699 -78.376018) (xy 135.944992 -78.36344)
			(xy 135.954141 -78.335086) (xy 135.954728 -78.305298) (xy 135.946702 -78.276605) (xy 135.930745 -78.251445)
			(xy 135.908213 -78.231952) (xy 135.894826 -78.225396) (xy 135.86994 -78.213739) (xy 135.823462 -78.184425)
			(xy 135.781671 -78.148744) (xy 135.745434 -78.107435) (xy 135.7155 -78.061353) (xy 135.69249 -78.011452)
			(xy 135.67688 -77.958765) (xy 135.668992 -77.904383) (xy 135.668512 -77.876908) (xy 125.992683 -77.876908)
			(xy 125.986825 -77.881783) (xy 125.939219 -77.910837) (xy 125.88789 -77.932649) (xy 125.833933 -77.946755)
			(xy 125.778496 -77.952855) (xy 125.722762 -77.950818) (xy 125.667919 -77.940688) (xy 125.615135 -77.922681)
			(xy 125.565535 -77.89718) (xy 125.520177 -77.864729) (xy 125.480028 -77.82602) (xy 125.445942 -77.781877)
			(xy 125.418646 -77.733242) (xy 125.398723 -77.681151) (xy 125.386597 -77.626714) (xy 125.382526 -77.571092)
			(xy 117.618031 -77.571092) (xy 117.635634 -77.606883) (xy 117.65308 -77.662349) (xy 117.661905 -77.71982)
			(xy 117.662452 -77.748892) (xy 117.661966 -77.776143) (xy 117.65421 -77.830091) (xy 117.638855 -77.882386)
			(xy 117.616213 -77.931963) (xy 117.586747 -77.977813) (xy 117.551056 -78.019004) (xy 117.509865 -78.054695)
			(xy 117.464015 -78.084161) (xy 117.414438 -78.106803) (xy 117.362143 -78.122158) (xy 117.308195 -78.129914)
			(xy 117.253693 -78.129914) (xy 117.199745 -78.122158) (xy 117.14745 -78.106803) (xy 117.097873 -78.084161)
			(xy 117.052023 -78.054695) (xy 117.010832 -78.019004) (xy 116.975141 -77.977813) (xy 116.945675 -77.931963)
			(xy 116.923033 -77.882386) (xy 116.907678 -77.830091) (xy 116.899922 -77.776143) (xy 116.899436 -77.748892)
			(xy 116.900013 -77.719721) (xy 116.908945 -77.662064) (xy 116.917216 -77.634084) (xy 116.920985 -77.620383)
			(xy 116.921682 -77.591988) (xy 116.914541 -77.564496) (xy 116.900114 -77.54003) (xy 116.879512 -77.520476)
			(xy 116.854327 -77.507343) (xy 116.840508 -77.504036) (xy 116.812118 -77.497743) (xy 116.757533 -77.477701)
			(xy 116.706623 -77.449605) (xy 116.660568 -77.414108) (xy 116.620434 -77.372031) (xy 116.587153 -77.324349)
			(xy 116.561494 -77.272168) (xy 116.544054 -77.216697) (xy 116.535235 -77.159222) (xy 116.534692 -77.130148)
			(xy 50.035959 -77.130148) (xy 49.952152 -77.299409) (xy 49.85133 -77.484818) (xy 49.74348 -77.666229)
			(xy 49.628761 -77.843376) (xy 49.507341 -78.015998) (xy 49.379398 -78.183844) (xy 49.24512 -78.346666)
			(xy 49.104704 -78.504225) (xy 49.029516 -78.58235) (xy 120.710966 -78.58235) (xy 120.710966 -78.52785)
			(xy 120.718721 -78.473904) (xy 120.734075 -78.421611) (xy 120.756714 -78.372034) (xy 120.786177 -78.326185)
			(xy 120.821866 -78.284994) (xy 120.863052 -78.249301) (xy 120.908899 -78.219833) (xy 120.958473 -78.197189)
			(xy 121.010765 -78.18183) (xy 121.06471 -78.174069) (xy 121.09196 -78.17358) (xy 121.119364 -78.174066)
			(xy 121.173608 -78.18191) (xy 121.22617 -78.197441) (xy 121.275966 -78.22034) (xy 121.321968 -78.250134)
			(xy 121.342912 -78.267814) (xy 121.353519 -78.276435) (xy 121.378115 -78.288325) (xy 121.404985 -78.293259)
			(xy 121.432201 -78.290882) (xy 121.457809 -78.281364) (xy 121.479971 -78.26539) (xy 121.497096 -78.244104)
			(xy 121.502932 -78.231746) (xy 121.514418 -78.206541) (xy 121.543635 -78.159484) (xy 121.579346 -78.117144)
			(xy 121.620802 -78.08041) (xy 121.667132 -78.050053) (xy 121.717363 -78.026711) (xy 121.77044 -78.010874)
			(xy 121.825249 -78.002875) (xy 121.852944 -78.002384) (xy 121.880193 -78.002889) (xy 121.934134 -78.01065)
			(xy 121.986423 -78.026009) (xy 122.035993 -78.048652) (xy 122.081837 -78.078119) (xy 122.103784 -78.097138)
			(xy 122.758154 -78.097138) (xy 122.758157 -78.04263) (xy 122.765916 -77.988678) (xy 122.781275 -77.93638)
			(xy 122.803921 -77.8868) (xy 122.833392 -77.840947) (xy 122.869089 -77.799755) (xy 122.910286 -77.764064)
			(xy 122.956142 -77.734598) (xy 123.005725 -77.711958) (xy 123.058025 -77.696606) (xy 123.111978 -77.688853)
			(xy 123.166486 -77.688858) (xy 123.220437 -77.69662) (xy 123.272735 -77.711981) (xy 123.322314 -77.734629)
			(xy 123.368166 -77.764102) (xy 123.409356 -77.799801) (xy 123.445046 -77.840998) (xy 123.47451 -77.886856)
			(xy 123.497147 -77.93644) (xy 123.512497 -77.988741) (xy 123.520248 -78.042694) (xy 123.520708 -78.069948)
			(xy 123.519692 -78.098142) (xy 123.519083 -78.112837) (xy 123.525279 -78.141575) (xy 123.539403 -78.167358)
			(xy 123.560284 -78.188051) (xy 123.586194 -78.20194) (xy 123.614987 -78.207875) (xy 123.629674 -78.207108)
			(xy 123.662694 -78.205584) (xy 123.689947 -78.206049) (xy 123.7439 -78.213805) (xy 123.796199 -78.229161)
			(xy 123.845781 -78.251803) (xy 123.891635 -78.281272) (xy 123.932829 -78.316966) (xy 123.968524 -78.358159)
			(xy 123.997993 -78.404013) (xy 124.020636 -78.453594) (xy 124.035993 -78.505893) (xy 124.043751 -78.559845)
			(xy 124.043751 -78.614352) (xy 124.035994 -78.668304) (xy 124.020637 -78.720603) (xy 123.997994 -78.770185)
			(xy 123.968526 -78.816039) (xy 123.946817 -78.841092) (xy 125.357126 -78.841092) (xy 125.361197 -78.78547)
			(xy 125.373323 -78.731033) (xy 125.393246 -78.678942) (xy 125.420542 -78.630307) (xy 125.454628 -78.586164)
			(xy 125.494777 -78.547455) (xy 125.540135 -78.515004) (xy 125.589735 -78.489503) (xy 125.642519 -78.471496)
			(xy 125.697362 -78.461366) (xy 125.753096 -78.459329) (xy 125.808533 -78.465429) (xy 125.86249 -78.479535)
			(xy 125.913819 -78.501347) (xy 125.961425 -78.530401) (xy 126.004293 -78.566076) (xy 126.04151 -78.607613)
			(xy 126.072283 -78.654126) (xy 126.095955 -78.704623) (xy 126.112023 -78.75803) (xy 126.120143 -78.813206)
			(xy 126.120652 -78.841092) (xy 126.120143 -78.868978) (xy 126.112023 -78.924154) (xy 126.095955 -78.977561)
			(xy 126.072283 -79.028058) (xy 126.04151 -79.074571) (xy 126.004293 -79.116108) (xy 125.961425 -79.151783)
			(xy 125.913819 -79.180837) (xy 125.86249 -79.202649) (xy 125.808533 -79.216755) (xy 125.753096 -79.222855)
			(xy 125.697362 -79.220818) (xy 125.642519 -79.210688) (xy 125.589735 -79.192681) (xy 125.540135 -79.16718)
			(xy 125.494777 -79.134729) (xy 125.454628 -79.09602) (xy 125.420542 -79.051877) (xy 125.393246 -79.003242)
			(xy 125.373323 -78.951151) (xy 125.361197 -78.896714) (xy 125.357126 -78.841092) (xy 123.946817 -78.841092)
			(xy 123.932831 -78.857232) (xy 123.891637 -78.892927) (xy 123.845783 -78.922395) (xy 123.796202 -78.945038)
			(xy 123.743902 -78.960394) (xy 123.68995 -78.968151) (xy 123.635443 -78.96815) (xy 123.581491 -78.960393)
			(xy 123.529192 -78.945036) (xy 123.479611 -78.922392) (xy 123.433757 -78.892923) (xy 123.392564 -78.857228)
			(xy 123.35687 -78.816034) (xy 123.327402 -78.770179) (xy 123.30476 -78.720597) (xy 123.289405 -78.668298)
			(xy 123.281649 -78.614346) (xy 123.281186 -78.587092) (xy 123.282202 -78.558898) (xy 123.282874 -78.544204)
			(xy 123.276662 -78.515462) (xy 123.262524 -78.489677) (xy 123.241631 -78.468985) (xy 123.215712 -78.455097)
			(xy 123.186911 -78.449164) (xy 123.17222 -78.449932) (xy 123.1392 -78.451456) (xy 123.111946 -78.450945)
			(xy 123.057994 -78.443187) (xy 123.005695 -78.42783) (xy 122.956114 -78.405187) (xy 122.91026 -78.375717)
			(xy 122.869067 -78.340022) (xy 122.833373 -78.298827) (xy 122.803906 -78.252972) (xy 122.781264 -78.20339)
			(xy 122.765909 -78.15109) (xy 122.758154 -78.097138) (xy 122.103784 -78.097138) (xy 122.123022 -78.11381)
			(xy 122.158708 -78.154998) (xy 122.188169 -78.200845) (xy 122.210807 -78.250418) (xy 122.226159 -78.302709)
			(xy 122.233914 -78.356651) (xy 122.233914 -78.411149) (xy 122.226159 -78.465091) (xy 122.210807 -78.517382)
			(xy 122.188169 -78.566955) (xy 122.158708 -78.612802) (xy 122.123022 -78.65399) (xy 122.081837 -78.689681)
			(xy 122.035993 -78.719148) (xy 121.986423 -78.741791) (xy 121.934134 -78.75715) (xy 121.880193 -78.764911)
			(xy 121.852944 -78.7654) (xy 121.82554 -78.764916) (xy 121.771295 -78.757073) (xy 121.718733 -78.741541)
			(xy 121.668938 -78.718642) (xy 121.622935 -78.688847) (xy 121.601992 -78.671166) (xy 121.591376 -78.662557)
			(xy 121.566782 -78.65067) (xy 121.539915 -78.645737) (xy 121.512703 -78.648113) (xy 121.487097 -78.657628)
			(xy 121.464936 -78.673598) (xy 121.447809 -78.694878) (xy 121.441972 -78.707234) (xy 121.430473 -78.732433)
			(xy 121.401259 -78.77949) (xy 121.36555 -78.821831) (xy 121.324096 -78.858567) (xy 121.277768 -78.888924)
			(xy 121.227538 -78.912267) (xy 121.174462 -78.928105) (xy 121.119654 -78.936105) (xy 121.09196 -78.936596)
			(xy 121.06471 -78.936131) (xy 121.010765 -78.92837) (xy 120.958473 -78.913011) (xy 120.908899 -78.890367)
			(xy 120.863052 -78.860899) (xy 120.821866 -78.825206) (xy 120.786177 -78.784015) (xy 120.756714 -78.738166)
			(xy 120.734075 -78.688589) (xy 120.718721 -78.636296) (xy 120.710966 -78.58235) (xy 49.029516 -78.58235)
			(xy 48.958356 -78.65629) (xy 48.806291 -78.802638) (xy 48.648732 -78.943054) (xy 48.48591 -79.077332)
			(xy 48.399633 -79.143098) (xy 117.270274 -79.143098) (xy 117.274345 -79.087476) (xy 117.286471 -79.033039)
			(xy 117.306394 -78.980948) (xy 117.33369 -78.932313) (xy 117.367776 -78.88817) (xy 117.407925 -78.849461)
			(xy 117.453283 -78.81701) (xy 117.502883 -78.791509) (xy 117.555667 -78.773502) (xy 117.61051 -78.763372)
			(xy 117.666244 -78.761335) (xy 117.721681 -78.767435) (xy 117.775638 -78.781541) (xy 117.826967 -78.803353)
			(xy 117.874573 -78.832407) (xy 117.917441 -78.868082) (xy 117.954658 -78.909619) (xy 117.985431 -78.956132)
			(xy 118.009103 -79.006629) (xy 118.025171 -79.060036) (xy 118.033291 -79.115212) (xy 118.0338 -79.143098)
			(xy 118.033291 -79.170984) (xy 118.025171 -79.22616) (xy 118.009103 -79.279567) (xy 117.985431 -79.330064)
			(xy 117.954658 -79.376577) (xy 117.917441 -79.418114) (xy 117.874573 -79.453789) (xy 117.826967 -79.482843)
			(xy 117.818945 -79.486252) (xy 118.422926 -79.486252) (xy 118.426997 -79.43063) (xy 118.439123 -79.376193)
			(xy 118.459046 -79.324102) (xy 118.486342 -79.275467) (xy 118.520428 -79.231324) (xy 118.560577 -79.192615)
			(xy 118.605935 -79.160164) (xy 118.655535 -79.134663) (xy 118.708319 -79.116656) (xy 118.763162 -79.106526)
			(xy 118.818896 -79.104489) (xy 118.874333 -79.110589) (xy 118.92829 -79.124695) (xy 118.979619 -79.146507)
			(xy 119.027225 -79.175561) (xy 119.070093 -79.211236) (xy 119.10731 -79.252773) (xy 119.138083 -79.299286)
			(xy 119.161755 -79.349783) (xy 119.177823 -79.40319) (xy 119.185943 -79.458366) (xy 119.186452 -79.486252)
			(xy 119.185943 -79.514138) (xy 119.177823 -79.569314) (xy 119.161755 -79.622721) (xy 119.149048 -79.649828)
			(xy 123.242322 -79.649828) (xy 123.246393 -79.594206) (xy 123.258519 -79.539769) (xy 123.278442 -79.487678)
			(xy 123.305738 -79.439043) (xy 123.339824 -79.3949) (xy 123.379973 -79.356191) (xy 123.425331 -79.32374)
			(xy 123.474931 -79.298239) (xy 123.527715 -79.280232) (xy 123.582558 -79.270102) (xy 123.638292 -79.268065)
			(xy 123.693729 -79.274165) (xy 123.747686 -79.288271) (xy 123.795177 -79.308452) (xy 126.906526 -79.308452)
			(xy 126.910597 -79.25283) (xy 126.922723 -79.198393) (xy 126.942646 -79.146302) (xy 126.969942 -79.097667)
			(xy 127.004028 -79.053524) (xy 127.044177 -79.014815) (xy 127.089535 -78.982364) (xy 127.139135 -78.956863)
			(xy 127.191919 -78.938856) (xy 127.246762 -78.928726) (xy 127.302496 -78.926689) (xy 127.357933 -78.932789)
			(xy 127.41189 -78.946895) (xy 127.463219 -78.968707) (xy 127.510825 -78.997761) (xy 127.553693 -79.033436)
			(xy 127.59091 -79.074973) (xy 127.621683 -79.121486) (xy 127.64158 -79.163931) (xy 128.117625 -79.163931)
			(xy 128.117627 -79.109437) (xy 128.125385 -79.055498) (xy 128.140739 -79.003212) (xy 128.163378 -78.953643)
			(xy 128.192841 -78.9078) (xy 128.228528 -78.866617) (xy 128.269713 -78.830932) (xy 128.315557 -78.801471)
			(xy 128.365127 -78.778834) (xy 128.417413 -78.763481) (xy 128.471353 -78.755726) (xy 128.4986 -78.75524)
			(xy 128.516619 -78.755466) (xy 128.552494 -78.758897) (xy 128.570228 -78.762098) (xy 128.583991 -78.764213)
			(xy 128.611722 -78.761832) (xy 128.637781 -78.752054) (xy 128.660232 -78.735605) (xy 128.67741 -78.713705)
			(xy 128.688039 -78.687982) (xy 128.691329 -78.660344) (xy 128.689608 -78.646528) (xy 128.687446 -78.631765)
			(xy 128.68516 -78.602012) (xy 128.685036 -78.587092) (xy 128.685486 -78.559842) (xy 128.693243 -78.505897)
			(xy 128.708598 -78.453605) (xy 128.731239 -78.404031) (xy 128.760704 -78.358183) (xy 128.796394 -78.316995)
			(xy 128.837582 -78.281305) (xy 128.88343 -78.251839) (xy 128.933004 -78.229199) (xy 128.985296 -78.213844)
			(xy 129.039241 -78.206086) (xy 129.093741 -78.206085) (xy 129.147686 -78.21384) (xy 129.199978 -78.229192)
			(xy 129.249554 -78.25183) (xy 129.295403 -78.281293) (xy 129.336593 -78.316981) (xy 129.372285 -78.358168)
			(xy 129.401752 -78.404014) (xy 129.424395 -78.453588) (xy 129.439753 -78.505879) (xy 129.447512 -78.559823)
			(xy 129.447516 -78.614323) (xy 129.439764 -78.668269) (xy 129.424414 -78.720562) (xy 129.401778 -78.770139)
			(xy 129.372317 -78.81599) (xy 129.336631 -78.857181) (xy 129.295446 -78.892875) (xy 129.249601 -78.922344)
			(xy 129.200029 -78.944989) (xy 129.147738 -78.960349) (xy 129.093794 -78.968111) (xy 129.066544 -78.9686)
			(xy 129.048525 -78.968383) (xy 129.01265 -78.964946) (xy 128.994916 -78.961742) (xy 128.981151 -78.959626)
			(xy 128.953415 -78.961997) (xy 128.927351 -78.971771) (xy 128.904895 -78.988221) (xy 128.887716 -79.010124)
			(xy 128.877091 -79.035852) (xy 128.873809 -79.063495) (xy 128.875536 -79.077312) (xy 128.877691 -79.092076)
			(xy 128.879982 -79.121828) (xy 128.880108 -79.136748) (xy 128.87957 -79.163995) (xy 128.871809 -79.217933)
			(xy 128.861558 -79.252831) (xy 158.572225 -79.252831) (xy 158.572227 -79.198337) (xy 158.579985 -79.144398)
			(xy 158.595339 -79.092112) (xy 158.617978 -79.042543) (xy 158.647441 -78.9967) (xy 158.683128 -78.955517)
			(xy 158.724313 -78.919832) (xy 158.770157 -78.890371) (xy 158.819727 -78.867734) (xy 158.872013 -78.852381)
			(xy 158.925953 -78.844626) (xy 158.9532 -78.84414) (xy 158.97606 -78.844902) (xy 158.989509 -78.845369)
			(xy 159.015856 -78.83992) (xy 159.039863 -78.827774) (xy 159.059861 -78.809775) (xy 159.074458 -78.787175)
			(xy 159.082641 -78.761544) (xy 159.083839 -78.734666) (xy 159.07797 -78.708409) (xy 159.072072 -78.696312)
			(xy 159.058468 -78.668942) (xy 159.03923 -78.610931) (xy 159.029491 -78.550595) (xy 159.028892 -78.520036)
			(xy 159.029316 -78.49278) (xy 159.037069 -78.438822) (xy 159.052422 -78.386517) (xy 159.075063 -78.336929)
			(xy 159.104531 -78.291068) (xy 159.140225 -78.249868) (xy 159.18142 -78.214167) (xy 159.227276 -78.184692)
			(xy 159.276861 -78.162043) (xy 159.329163 -78.146682) (xy 159.38312 -78.138921) (xy 159.437632 -78.138917)
			(xy 159.49159 -78.146672) (xy 159.543894 -78.162027) (xy 159.593481 -78.184669) (xy 159.639341 -78.214138)
			(xy 159.680541 -78.249834) (xy 159.71624 -78.29103) (xy 159.745714 -78.336887) (xy 159.768361 -78.386472)
			(xy 159.78372 -78.438775) (xy 159.79148 -78.492732) (xy 159.791482 -78.547244) (xy 159.783726 -78.601201)
			(xy 159.768369 -78.653506) (xy 159.745725 -78.703092) (xy 159.716255 -78.748951) (xy 159.680558 -78.790149)
			(xy 159.639361 -78.825847) (xy 159.593503 -78.855319) (xy 159.543917 -78.877965) (xy 159.491613 -78.893323)
			(xy 159.437656 -78.901081) (xy 159.4104 -78.901544) (xy 159.38754 -78.900782) (xy 159.374092 -78.900338)
			(xy 159.347748 -78.905786) (xy 159.323744 -78.91793) (xy 159.303749 -78.935925) (xy 159.289152 -78.958522)
			(xy 159.280968 -78.984148) (xy 159.279767 -79.011022) (xy 159.285632 -79.037276) (xy 159.291528 -79.049372)
			(xy 159.305126 -79.076745) (xy 159.324366 -79.134754) (xy 159.334107 -79.19509) (xy 159.334708 -79.225648)
			(xy 159.33417 -79.252895) (xy 159.326409 -79.306833) (xy 159.31105 -79.359118) (xy 159.288406 -79.408685)
			(xy 159.258939 -79.454526) (xy 159.223249 -79.495706) (xy 159.182061 -79.531387) (xy 159.136215 -79.560845)
			(xy 159.086643 -79.583478) (xy 159.034355 -79.598826) (xy 158.980415 -79.606576) (xy 158.925921 -79.606572)
			(xy 158.871982 -79.598812) (xy 158.819697 -79.583455) (xy 158.770129 -79.560814) (xy 158.724287 -79.531349)
			(xy 158.683106 -79.49566) (xy 158.647422 -79.454474) (xy 158.617963 -79.408629) (xy 158.595328 -79.359058)
			(xy 158.579978 -79.306771) (xy 158.572225 -79.252831) (xy 128.861558 -79.252831) (xy 128.85645 -79.270218)
			(xy 128.833806 -79.319785) (xy 128.804339 -79.365626) (xy 128.768649 -79.406806) (xy 128.727461 -79.442487)
			(xy 128.681615 -79.471945) (xy 128.632043 -79.494578) (xy 128.579755 -79.509926) (xy 128.525815 -79.517676)
			(xy 128.471321 -79.517672) (xy 128.417382 -79.509912) (xy 128.365097 -79.494555) (xy 128.315529 -79.471914)
			(xy 128.269687 -79.442449) (xy 128.228506 -79.40676) (xy 128.192822 -79.365574) (xy 128.163363 -79.319729)
			(xy 128.140728 -79.270158) (xy 128.125378 -79.217871) (xy 128.117625 -79.163931) (xy 127.64158 -79.163931)
			(xy 127.645355 -79.171983) (xy 127.661423 -79.22539) (xy 127.669543 -79.280566) (xy 127.670052 -79.308452)
			(xy 127.669543 -79.336338) (xy 127.661423 -79.391514) (xy 127.645355 -79.444921) (xy 127.621683 -79.495418)
			(xy 127.59091 -79.541931) (xy 127.553693 -79.583468) (xy 127.510825 -79.619143) (xy 127.463219 -79.648197)
			(xy 127.41189 -79.670009) (xy 127.357933 -79.684115) (xy 127.302496 -79.690215) (xy 127.246762 -79.688178)
			(xy 127.191919 -79.678048) (xy 127.139135 -79.660041) (xy 127.089535 -79.63454) (xy 127.044177 -79.602089)
			(xy 127.004028 -79.56338) (xy 126.969942 -79.519237) (xy 126.942646 -79.470602) (xy 126.922723 -79.418511)
			(xy 126.910597 -79.364074) (xy 126.906526 -79.308452) (xy 123.795177 -79.308452) (xy 123.799015 -79.310083)
			(xy 123.846621 -79.339137) (xy 123.889489 -79.374812) (xy 123.926706 -79.416349) (xy 123.957479 -79.462862)
			(xy 123.981151 -79.513359) (xy 123.997219 -79.566766) (xy 124.005339 -79.621942) (xy 124.005848 -79.649828)
			(xy 124.005339 -79.677714) (xy 123.997219 -79.73289) (xy 123.981151 -79.786297) (xy 123.957479 -79.836794)
			(xy 123.926706 -79.883307) (xy 123.889489 -79.924844) (xy 123.857642 -79.951347) (xy 147.909326 -79.951347)
			(xy 147.909326 -79.896853) (xy 147.917081 -79.842914) (xy 147.932433 -79.790627) (xy 147.95507 -79.741058)
			(xy 147.984531 -79.695214) (xy 148.020216 -79.65403) (xy 148.061398 -79.618343) (xy 148.10724 -79.58888)
			(xy 148.156809 -79.56624) (xy 148.209094 -79.550885) (xy 148.263033 -79.543128) (xy 148.29028 -79.54264)
			(xy 148.319197 -79.543158) (xy 148.376369 -79.551885) (xy 148.431569 -79.569142) (xy 148.483531 -79.594533)
			(xy 148.531064 -79.627478) (xy 148.57308 -79.66722) (xy 148.59127 -79.689706) (xy 148.601167 -79.701511)
			(xy 148.626491 -79.71903) (xy 148.655884 -79.728206) (xy 148.686676 -79.728206) (xy 148.716069 -79.71903)
			(xy 148.741393 -79.701511) (xy 148.75129 -79.689706) (xy 148.769488 -79.667229) (xy 148.811506 -79.627493)
			(xy 148.85904 -79.594553) (xy 148.911 -79.569163) (xy 148.966196 -79.551906) (xy 149.023364 -79.543176)
			(xy 149.05228 -79.54264) (xy 149.079537 -79.543006) (xy 149.133497 -79.550761) (xy 149.185804 -79.566117)
			(xy 149.235393 -79.588762) (xy 149.281254 -79.618233) (xy 149.322455 -79.653931) (xy 149.358155 -79.69513)
			(xy 149.387629 -79.740989) (xy 149.410276 -79.790577) (xy 149.425635 -79.842883) (xy 149.433393 -79.896843)
			(xy 149.433393 -79.951357) (xy 149.426094 -80.002123) (xy 150.881073 -80.002123) (xy 150.881077 -79.947619)
			(xy 150.888838 -79.893671) (xy 150.904198 -79.841376) (xy 150.926844 -79.791799) (xy 150.956315 -79.745951)
			(xy 150.992011 -79.704763) (xy 151.033205 -79.669074) (xy 151.079059 -79.639611) (xy 151.12864 -79.616974)
			(xy 151.180937 -79.601624) (xy 151.234887 -79.593873) (xy 151.28939 -79.593878) (xy 151.343339 -79.60164)
			(xy 151.395633 -79.617001) (xy 151.445209 -79.639648) (xy 151.491057 -79.66912) (xy 151.532244 -79.704817)
			(xy 151.567932 -79.746013) (xy 151.597393 -79.791867) (xy 151.620029 -79.841448) (xy 151.635378 -79.893746)
			(xy 151.643128 -79.947696) (xy 151.643588 -79.974948) (xy 151.643401 -79.992447) (xy 151.640223 -80.0273)
			(xy 151.637238 -80.044544) (xy 151.635007 -80.058791) (xy 151.637841 -80.087479) (xy 151.648582 -80.114231)
			(xy 151.666373 -80.136914) (xy 151.689795 -80.153719) (xy 151.716982 -80.163306) (xy 151.745765 -80.164911)
			(xy 151.75992 -80.162146) (xy 151.778286 -80.158145) (xy 151.815563 -80.153306) (xy 151.834342 -80.152494)
			(xy 151.849169 -80.151548) (xy 151.877313 -80.142057) (xy 151.901544 -80.124881) (xy 151.91982 -80.101468)
			(xy 151.930598 -80.073791) (xy 151.932972 -80.044185) (xy 151.930354 -80.029558) (xy 151.926404 -80.009793)
			(xy 151.922205 -79.969703) (xy 151.921972 -79.949548) (xy 151.922458 -79.922297) (xy 151.930214 -79.868349)
			(xy 151.945569 -79.816054) (xy 151.968211 -79.766477) (xy 151.997677 -79.720627) (xy 152.033368 -79.679436)
			(xy 152.074559 -79.643745) (xy 152.120409 -79.614279) (xy 152.169986 -79.591637) (xy 152.222281 -79.576282)
			(xy 152.276229 -79.568526) (xy 152.330731 -79.568526) (xy 152.384679 -79.576282) (xy 152.436974 -79.591637)
			(xy 152.486551 -79.614279) (xy 152.532401 -79.643745) (xy 152.573592 -79.679436) (xy 152.609283 -79.720627)
			(xy 152.638749 -79.766477) (xy 152.661391 -79.816054) (xy 152.676746 -79.868349) (xy 152.684502 -79.922297)
			(xy 152.684852 -79.941928) (xy 153.945842 -79.941928) (xy 153.949913 -79.886306) (xy 153.962039 -79.831869)
			(xy 153.981962 -79.779778) (xy 154.009258 -79.731143) (xy 154.043344 -79.687) (xy 154.083493 -79.648291)
			(xy 154.128851 -79.61584) (xy 154.178451 -79.590339) (xy 154.231235 -79.572332) (xy 154.286078 -79.562202)
			(xy 154.341812 -79.560165) (xy 154.397249 -79.566265) (xy 154.451206 -79.580371) (xy 154.502535 -79.602183)
			(xy 154.550141 -79.631237) (xy 154.593009 -79.666912) (xy 154.630226 -79.708449) (xy 154.660999 -79.754962)
			(xy 154.684671 -79.805459) (xy 154.700739 -79.858866) (xy 154.708859 -79.914042) (xy 154.709368 -79.941928)
			(xy 154.708859 -79.969814) (xy 154.700739 -80.02499) (xy 154.684671 -80.078397) (xy 154.660999 -80.128894)
			(xy 154.630226 -80.175407) (xy 154.593009 -80.216944) (xy 154.550141 -80.252619) (xy 154.502535 -80.281673)
			(xy 154.451206 -80.303485) (xy 154.397249 -80.317591) (xy 154.341812 -80.323691) (xy 154.286078 -80.321654)
			(xy 154.231235 -80.311524) (xy 154.178451 -80.293517) (xy 154.128851 -80.268016) (xy 154.083493 -80.235565)
			(xy 154.043344 -80.196856) (xy 154.009258 -80.152713) (xy 153.981962 -80.104078) (xy 153.962039 -80.051987)
			(xy 153.949913 -79.99755) (xy 153.945842 -79.941928) (xy 152.684852 -79.941928) (xy 152.684988 -79.949548)
			(xy 152.684534 -79.976253) (xy 152.677066 -80.029137) (xy 152.662296 -80.080464) (xy 152.640513 -80.12923)
			(xy 152.612143 -80.174482) (xy 152.57774 -80.215335) (xy 152.537977 -80.250992) (xy 152.493629 -80.280756)
			(xy 152.445565 -80.304045) (xy 152.394722 -80.320405) (xy 152.342095 -80.329514) (xy 152.315418 -80.330802)
			(xy 152.300595 -80.331801) (xy 152.272453 -80.341277) (xy 152.24822 -80.358441) (xy 152.229942 -80.381845)
			(xy 152.219162 -80.409514) (xy 152.216788 -80.439114) (xy 152.219406 -80.453738) (xy 152.223356 -80.473503)
			(xy 152.227554 -80.513593) (xy 152.227788 -80.533748) (xy 152.227302 -80.560999) (xy 152.219546 -80.614947)
			(xy 152.204191 -80.667242) (xy 152.181549 -80.716819) (xy 152.152083 -80.762669) (xy 152.116392 -80.80386)
			(xy 152.075201 -80.839551) (xy 152.029351 -80.869017) (xy 151.979774 -80.891659) (xy 151.927479 -80.907014)
			(xy 151.873531 -80.91477) (xy 151.819029 -80.91477) (xy 151.765081 -80.907014) (xy 151.712786 -80.891659)
			(xy 151.663209 -80.869017) (xy 151.617359 -80.839551) (xy 151.576168 -80.80386) (xy 151.540477 -80.762669)
			(xy 151.511011 -80.716819) (xy 151.488369 -80.667242) (xy 151.473014 -80.614947) (xy 151.465258 -80.560999)
			(xy 151.464772 -80.533748) (xy 151.464959 -80.516249) (xy 151.468137 -80.481396) (xy 151.471122 -80.464152)
			(xy 151.473182 -80.449885) (xy 151.470372 -80.421219) (xy 151.459659 -80.394481) (xy 151.441897 -80.371806)
			(xy 151.418503 -80.355001) (xy 151.391343 -80.345409) (xy 151.362584 -80.343793) (xy 151.34844 -80.34655)
			(xy 151.327151 -80.351183) (xy 151.283865 -80.356146) (xy 151.26208 -80.356456) (xy 151.234828 -80.355923)
			(xy 151.18088 -80.348164) (xy 151.128585 -80.332805) (xy 151.079008 -80.310161) (xy 151.033158 -80.280691)
			(xy 150.991969 -80.244996) (xy 150.95628 -80.203802) (xy 150.926816 -80.157949) (xy 150.904178 -80.108369)
			(xy 150.888826 -80.056072) (xy 150.881073 -80.002123) (xy 149.426094 -80.002123) (xy 149.425635 -80.005317)
			(xy 149.410276 -80.057623) (xy 149.387629 -80.107211) (xy 149.358155 -80.15307) (xy 149.322455 -80.194269)
			(xy 149.281254 -80.229967) (xy 149.235393 -80.259438) (xy 149.185804 -80.282083) (xy 149.133497 -80.297439)
			(xy 149.079537 -80.305194) (xy 149.05228 -80.305656) (xy 149.023364 -80.305097) (xy 148.966194 -80.296378)
			(xy 148.910996 -80.27913) (xy 148.859033 -80.253746) (xy 148.811499 -80.220809) (xy 148.769481 -80.181073)
			(xy 148.75129 -80.15859) (xy 148.741393 -80.146785) (xy 148.716069 -80.129266) (xy 148.686676 -80.12009)
			(xy 148.655884 -80.12009) (xy 148.626491 -80.129266) (xy 148.601167 -80.146785) (xy 148.59127 -80.15859)
			(xy 148.573093 -80.181086) (xy 148.531071 -80.220821) (xy 148.483533 -80.253759) (xy 148.431569 -80.279145)
			(xy 148.376369 -80.296398) (xy 148.319197 -80.305123) (xy 148.29028 -80.305656) (xy 148.263033 -80.305072)
			(xy 148.209094 -80.297315) (xy 148.156809 -80.28196) (xy 148.10724 -80.25932) (xy 148.061398 -80.229857)
			(xy 148.020216 -80.19417) (xy 147.984531 -80.152986) (xy 147.95507 -80.107142) (xy 147.932433 -80.057573)
			(xy 147.917081 -80.005286) (xy 147.909326 -79.951347) (xy 123.857642 -79.951347) (xy 123.846621 -79.960519)
			(xy 123.799015 -79.989573) (xy 123.747686 -80.011385) (xy 123.693729 -80.025491) (xy 123.638292 -80.031591)
			(xy 123.582558 -80.029554) (xy 123.527715 -80.019424) (xy 123.474931 -80.001417) (xy 123.425331 -79.975916)
			(xy 123.379973 -79.943465) (xy 123.339824 -79.904756) (xy 123.305738 -79.860613) (xy 123.278442 -79.811978)
			(xy 123.258519 -79.759887) (xy 123.246393 -79.70545) (xy 123.242322 -79.649828) (xy 119.149048 -79.649828)
			(xy 119.138083 -79.673218) (xy 119.10731 -79.719731) (xy 119.070093 -79.761268) (xy 119.027225 -79.796943)
			(xy 118.979619 -79.825997) (xy 118.92829 -79.847809) (xy 118.874333 -79.861915) (xy 118.818896 -79.868015)
			(xy 118.763162 -79.865978) (xy 118.708319 -79.855848) (xy 118.655535 -79.837841) (xy 118.605935 -79.81234)
			(xy 118.560577 -79.779889) (xy 118.520428 -79.74118) (xy 118.486342 -79.697037) (xy 118.459046 -79.648402)
			(xy 118.439123 -79.596311) (xy 118.426997 -79.541874) (xy 118.422926 -79.486252) (xy 117.818945 -79.486252)
			(xy 117.775638 -79.504655) (xy 117.721681 -79.518761) (xy 117.666244 -79.524861) (xy 117.61051 -79.522824)
			(xy 117.555667 -79.512694) (xy 117.502883 -79.494687) (xy 117.453283 -79.469186) (xy 117.407925 -79.436735)
			(xy 117.367776 -79.398026) (xy 117.33369 -79.353883) (xy 117.306394 -79.305248) (xy 117.286471 -79.253157)
			(xy 117.274345 -79.19872) (xy 117.270274 -79.143098) (xy 48.399633 -79.143098) (xy 48.318064 -79.205275)
			(xy 48.145442 -79.326695) (xy 47.968295 -79.441414) (xy 47.786884 -79.549264) (xy 47.601475 -79.650086)
			(xy 47.41234 -79.743733) (xy 47.252393 -79.815436) (xy 87.289638 -79.815436) (xy 87.293709 -79.759814)
			(xy 87.305835 -79.705377) (xy 87.325758 -79.653286) (xy 87.353054 -79.604651) (xy 87.38714 -79.560508)
			(xy 87.427289 -79.521799) (xy 87.472647 -79.489348) (xy 87.522247 -79.463847) (xy 87.575031 -79.44584)
			(xy 87.629874 -79.43571) (xy 87.685608 -79.433673) (xy 87.741045 -79.439773) (xy 87.795002 -79.453879)
			(xy 87.846331 -79.475691) (xy 87.893937 -79.504745) (xy 87.936805 -79.54042) (xy 87.974022 -79.581957)
			(xy 88.004795 -79.62847) (xy 88.028467 -79.678967) (xy 88.044535 -79.732374) (xy 88.052655 -79.78755)
			(xy 88.053164 -79.815436) (xy 90.490038 -79.815436) (xy 90.494109 -79.759814) (xy 90.506235 -79.705377)
			(xy 90.526158 -79.653286) (xy 90.553454 -79.604651) (xy 90.58754 -79.560508) (xy 90.627689 -79.521799)
			(xy 90.673047 -79.489348) (xy 90.722647 -79.463847) (xy 90.775431 -79.44584) (xy 90.830274 -79.43571)
			(xy 90.886008 -79.433673) (xy 90.941445 -79.439773) (xy 90.995402 -79.453879) (xy 91.046731 -79.475691)
			(xy 91.094337 -79.504745) (xy 91.137205 -79.54042) (xy 91.174422 -79.581957) (xy 91.205195 -79.62847)
			(xy 91.228867 -79.678967) (xy 91.244935 -79.732374) (xy 91.253055 -79.78755) (xy 91.253564 -79.815436)
			(xy 91.253055 -79.843322) (xy 91.244935 -79.898498) (xy 91.24486 -79.898748) (xy 111.154462 -79.898748)
			(xy 111.158533 -79.843126) (xy 111.170659 -79.788689) (xy 111.190582 -79.736598) (xy 111.217878 -79.687963)
			(xy 111.251964 -79.64382) (xy 111.292113 -79.605111) (xy 111.337471 -79.57266) (xy 111.387071 -79.547159)
			(xy 111.439855 -79.529152) (xy 111.494698 -79.519022) (xy 111.550432 -79.516985) (xy 111.605869 -79.523085)
			(xy 111.659826 -79.537191) (xy 111.711155 -79.559003) (xy 111.758761 -79.588057) (xy 111.801629 -79.623732)
			(xy 111.838846 -79.665269) (xy 111.869619 -79.711782) (xy 111.893291 -79.762279) (xy 111.909284 -79.815436)
			(xy 112.892838 -79.815436) (xy 112.896909 -79.759814) (xy 112.909035 -79.705377) (xy 112.928958 -79.653286)
			(xy 112.956254 -79.604651) (xy 112.99034 -79.560508) (xy 113.030489 -79.521799) (xy 113.075847 -79.489348)
			(xy 113.125447 -79.463847) (xy 113.178231 -79.44584) (xy 113.233074 -79.43571) (xy 113.288808 -79.433673)
			(xy 113.344245 -79.439773) (xy 113.398202 -79.453879) (xy 113.449531 -79.475691) (xy 113.497137 -79.504745)
			(xy 113.540005 -79.54042) (xy 113.577222 -79.581957) (xy 113.607995 -79.62847) (xy 113.631667 -79.678967)
			(xy 113.647735 -79.732374) (xy 113.655855 -79.78755) (xy 113.656364 -79.815436) (xy 113.655855 -79.843322)
			(xy 113.647735 -79.898498) (xy 113.631667 -79.951905) (xy 113.607995 -80.002402) (xy 113.577222 -80.048915)
			(xy 113.540005 -80.090452) (xy 113.497137 -80.126127) (xy 113.449531 -80.155181) (xy 113.398202 -80.176993)
			(xy 113.344245 -80.191099) (xy 113.288808 -80.197199) (xy 113.233074 -80.195162) (xy 113.178231 -80.185032)
			(xy 113.125447 -80.167025) (xy 113.075847 -80.141524) (xy 113.030489 -80.109073) (xy 112.99034 -80.070364)
			(xy 112.956254 -80.026221) (xy 112.928958 -79.977586) (xy 112.909035 -79.925495) (xy 112.896909 -79.871058)
			(xy 112.892838 -79.815436) (xy 111.909284 -79.815436) (xy 111.909359 -79.815686) (xy 111.917479 -79.870862)
			(xy 111.917988 -79.898748) (xy 111.917479 -79.926634) (xy 111.909359 -79.98181) (xy 111.893291 -80.035217)
			(xy 111.869619 -80.085714) (xy 111.838846 -80.132227) (xy 111.801629 -80.173764) (xy 111.758761 -80.209439)
			(xy 111.711155 -80.238493) (xy 111.659826 -80.260305) (xy 111.605869 -80.274411) (xy 111.550432 -80.280511)
			(xy 111.494698 -80.278474) (xy 111.439855 -80.268344) (xy 111.387071 -80.250337) (xy 111.337471 -80.224836)
			(xy 111.292113 -80.192385) (xy 111.251964 -80.153676) (xy 111.217878 -80.109533) (xy 111.190582 -80.060898)
			(xy 111.170659 -80.008807) (xy 111.158533 -79.95437) (xy 111.154462 -79.898748) (xy 91.24486 -79.898748)
			(xy 91.228867 -79.951905) (xy 91.205195 -80.002402) (xy 91.174422 -80.048915) (xy 91.137205 -80.090452)
			(xy 91.094337 -80.126127) (xy 91.046731 -80.155181) (xy 90.995402 -80.176993) (xy 90.941445 -80.191099)
			(xy 90.886008 -80.197199) (xy 90.830274 -80.195162) (xy 90.775431 -80.185032) (xy 90.722647 -80.167025)
			(xy 90.673047 -80.141524) (xy 90.627689 -80.109073) (xy 90.58754 -80.070364) (xy 90.553454 -80.026221)
			(xy 90.526158 -79.977586) (xy 90.506235 -79.925495) (xy 90.494109 -79.871058) (xy 90.490038 -79.815436)
			(xy 88.053164 -79.815436) (xy 88.052655 -79.843322) (xy 88.044535 -79.898498) (xy 88.028467 -79.951905)
			(xy 88.004795 -80.002402) (xy 87.974022 -80.048915) (xy 87.936805 -80.090452) (xy 87.893937 -80.126127)
			(xy 87.846331 -80.155181) (xy 87.795002 -80.176993) (xy 87.741045 -80.191099) (xy 87.685608 -80.197199)
			(xy 87.629874 -80.195162) (xy 87.575031 -80.185032) (xy 87.522247 -80.167025) (xy 87.472647 -80.141524)
			(xy 87.427289 -80.109073) (xy 87.38714 -80.070364) (xy 87.353054 -80.026221) (xy 87.325758 -79.977586)
			(xy 87.305835 -79.925495) (xy 87.293709 -79.871058) (xy 87.289638 -79.815436) (xy 47.252393 -79.815436)
			(xy 47.219758 -79.830066) (xy 47.02401 -79.90896) (xy 46.825383 -79.980298) (xy 46.62417 -80.043975)
			(xy 46.420666 -80.099899) (xy 46.215169 -80.147987) (xy 46.007981 -80.188169) (xy 45.799406 -80.220386)
			(xy 45.589749 -80.244589) (xy 45.37932 -80.260745) (xy 45.168426 -80.268829) (xy 44.957378 -80.268829)
			(xy 44.746484 -80.260745) (xy 44.536055 -80.244589) (xy 44.326398 -80.220386) (xy 44.117823 -80.188169)
			(xy 43.910635 -80.147987) (xy 43.705138 -80.099899) (xy 43.501634 -80.043975) (xy 43.300421 -79.980298)
			(xy 43.101794 -79.90896) (xy 42.906046 -79.830066) (xy 42.713464 -79.743733) (xy 42.524329 -79.650086)
			(xy 42.33892 -79.549264) (xy 42.157509 -79.441414) (xy 41.980362 -79.326695) (xy 41.80774 -79.205275)
			(xy 41.639894 -79.077332) (xy 41.477072 -78.943054) (xy 41.319513 -78.802638) (xy 41.167448 -78.65629)
			(xy 41.0211 -78.504225) (xy 40.880684 -78.346666) (xy 40.746406 -78.183844) (xy 40.618463 -78.015998)
			(xy 40.497043 -77.843376) (xy 40.382324 -77.666229) (xy 40.274474 -77.484818) (xy 40.173652 -77.299409)
			(xy 40.080005 -77.110274) (xy 39.993672 -76.917692) (xy 39.914778 -76.721944) (xy 39.84344 -76.523317)
			(xy 39.779763 -76.322104) (xy 39.723839 -76.1186) (xy 39.675751 -75.913103) (xy 39.635569 -75.705915)
			(xy 39.603352 -75.49734) (xy 39.579149 -75.287683) (xy 39.562993 -75.077254) (xy 39.554909 -74.86636)
			(xy 39.554404 -74.760836) (xy 22.396581 -74.760836) (xy 22.435976 -74.771135) (xy 22.487305 -74.792947)
			(xy 22.534911 -74.822001) (xy 22.577779 -74.857676) (xy 22.614996 -74.899213) (xy 22.645769 -74.945726)
			(xy 22.669441 -74.996223) (xy 22.685509 -75.04963) (xy 22.693629 -75.104806) (xy 22.694138 -75.132692)
			(xy 22.693629 -75.160578) (xy 22.685509 -75.215754) (xy 22.669441 -75.269161) (xy 22.645769 -75.319658)
			(xy 22.614996 -75.366171) (xy 22.577779 -75.407708) (xy 22.534911 -75.443383) (xy 22.487305 -75.472437)
			(xy 22.435976 -75.494249) (xy 22.382019 -75.508355) (xy 22.326582 -75.514455) (xy 22.270848 -75.512418)
			(xy 22.216005 -75.502288) (xy 22.163221 -75.484281) (xy 22.113621 -75.45878) (xy 22.068263 -75.426329)
			(xy 22.028114 -75.38762) (xy 21.994028 -75.343477) (xy 21.966732 -75.294842) (xy 21.946809 -75.242751)
			(xy 21.934683 -75.188314) (xy 21.930612 -75.132692) (xy 16.132426 -75.132692) (xy 16.134079 -75.143922)
			(xy 16.134588 -75.171808) (xy 16.134079 -75.199694) (xy 16.125959 -75.25487) (xy 16.109891 -75.308277)
			(xy 16.086219 -75.358774) (xy 16.055446 -75.405287) (xy 16.018229 -75.446824) (xy 15.975361 -75.482499)
			(xy 15.927755 -75.511553) (xy 15.876426 -75.533365) (xy 15.822469 -75.547471) (xy 15.767032 -75.553571)
			(xy 15.711298 -75.551534) (xy 15.656455 -75.541404) (xy 15.603671 -75.523397) (xy 15.554071 -75.497896)
			(xy 15.508713 -75.465445) (xy 15.468564 -75.426736) (xy 15.434478 -75.382593) (xy 15.407182 -75.333958)
			(xy 15.387259 -75.281867) (xy 15.375133 -75.22743) (xy 15.371062 -75.171808) (xy 9.525508 -75.171808)
			(xy 9.524999 -75.199694) (xy 9.516879 -75.25487) (xy 9.500811 -75.308277) (xy 9.477139 -75.358774)
			(xy 9.446366 -75.405287) (xy 9.409149 -75.446824) (xy 9.366281 -75.482499) (xy 9.318675 -75.511553)
			(xy 9.267346 -75.533365) (xy 9.213389 -75.547471) (xy 9.157952 -75.553571) (xy 9.102218 -75.551534)
			(xy 9.047375 -75.541404) (xy 8.994591 -75.523397) (xy 8.944991 -75.497896) (xy 8.899633 -75.465445)
			(xy 8.859484 -75.426736) (xy 8.825398 -75.382593) (xy 8.798102 -75.333958) (xy 8.778179 -75.281867)
			(xy 8.766053 -75.22743) (xy 8.761982 -75.171808) (xy 6.055868 -75.171808) (xy 6.055868 -75.871578)
			(xy 9.777982 -75.871578) (xy 9.782053 -75.815956) (xy 9.794179 -75.761519) (xy 9.814102 -75.709428)
			(xy 9.841398 -75.660793) (xy 9.875484 -75.61665) (xy 9.915633 -75.577941) (xy 9.960991 -75.54549)
			(xy 10.010591 -75.519989) (xy 10.063375 -75.501982) (xy 10.118218 -75.491852) (xy 10.173952 -75.489815)
			(xy 10.229389 -75.495915) (xy 10.283346 -75.510021) (xy 10.334675 -75.531833) (xy 10.382281 -75.560887)
			(xy 10.425149 -75.596562) (xy 10.462366 -75.638099) (xy 10.493139 -75.684612) (xy 10.516811 -75.735109)
			(xy 10.532879 -75.788516) (xy 10.540999 -75.843692) (xy 10.541508 -75.871578) (xy 10.540999 -75.899464)
			(xy 10.532879 -75.95464) (xy 10.516811 -76.008047) (xy 10.493139 -76.058544) (xy 10.462366 -76.105057)
			(xy 10.425149 -76.146594) (xy 10.382281 -76.182269) (xy 10.334675 -76.211323) (xy 10.283346 -76.233135)
			(xy 10.229389 -76.247241) (xy 10.173952 -76.253341) (xy 10.118218 -76.251304) (xy 10.063375 -76.241174)
			(xy 10.010591 -76.223167) (xy 9.960991 -76.197666) (xy 9.915633 -76.165215) (xy 9.875484 -76.126506)
			(xy 9.841398 -76.082363) (xy 9.814102 -76.033728) (xy 9.794179 -75.981637) (xy 9.782053 -75.9272)
			(xy 9.777982 -75.871578) (xy 6.055868 -75.871578) (xy 6.055868 -76.266548) (xy 22.655782 -76.266548)
			(xy 22.659853 -76.210926) (xy 22.671979 -76.156489) (xy 22.691902 -76.104398) (xy 22.719198 -76.055763)
			(xy 22.753284 -76.01162) (xy 22.793433 -75.972911) (xy 22.838791 -75.94046) (xy 22.888391 -75.914959)
			(xy 22.941175 -75.896952) (xy 22.996018 -75.886822) (xy 23.051752 -75.884785) (xy 23.107189 -75.890885)
			(xy 23.161146 -75.904991) (xy 23.212475 -75.926803) (xy 23.260081 -75.955857) (xy 23.302949 -75.991532)
			(xy 23.340166 -76.033069) (xy 23.370939 -76.079582) (xy 23.394611 -76.130079) (xy 23.410679 -76.183486)
			(xy 23.418799 -76.238662) (xy 23.419308 -76.266548) (xy 23.418799 -76.294434) (xy 23.410679 -76.34961)
			(xy 23.394611 -76.403017) (xy 23.370939 -76.453514) (xy 23.340166 -76.500027) (xy 23.302949 -76.541564)
			(xy 23.260081 -76.577239) (xy 23.212475 -76.606293) (xy 23.161146 -76.628105) (xy 23.107189 -76.642211)
			(xy 23.051752 -76.648311) (xy 22.996018 -76.646274) (xy 22.941175 -76.636144) (xy 22.888391 -76.618137)
			(xy 22.838791 -76.592636) (xy 22.793433 -76.560185) (xy 22.753284 -76.521476) (xy 22.719198 -76.477333)
			(xy 22.691902 -76.428698) (xy 22.671979 -76.376607) (xy 22.659853 -76.32217) (xy 22.655782 -76.266548)
			(xy 6.055868 -76.266548) (xy 6.055868 -76.916534) (xy 21.924262 -76.916534) (xy 21.928333 -76.860912)
			(xy 21.940459 -76.806475) (xy 21.960382 -76.754384) (xy 21.987678 -76.705749) (xy 22.021764 -76.661606)
			(xy 22.061913 -76.622897) (xy 22.107271 -76.590446) (xy 22.156871 -76.564945) (xy 22.209655 -76.546938)
			(xy 22.264498 -76.536808) (xy 22.320232 -76.534771) (xy 22.375669 -76.540871) (xy 22.429626 -76.554977)
			(xy 22.480955 -76.576789) (xy 22.528561 -76.605843) (xy 22.571429 -76.641518) (xy 22.608646 -76.683055)
			(xy 22.639419 -76.729568) (xy 22.663091 -76.780065) (xy 22.679159 -76.833472) (xy 22.687279 -76.888648)
			(xy 22.687788 -76.916534) (xy 22.687635 -76.924916) (xy 28.59608 -76.924916) (xy 28.600151 -76.869294)
			(xy 28.612277 -76.814857) (xy 28.6322 -76.762766) (xy 28.659496 -76.714131) (xy 28.693582 -76.669988)
			(xy 28.733731 -76.631279) (xy 28.779089 -76.598828) (xy 28.828689 -76.573327) (xy 28.881473 -76.55532)
			(xy 28.936316 -76.54519) (xy 28.99205 -76.543153) (xy 29.047487 -76.549253) (xy 29.101444 -76.563359)
			(xy 29.152773 -76.585171) (xy 29.200379 -76.614225) (xy 29.243247 -76.6499) (xy 29.280464 -76.691437)
			(xy 29.311237 -76.73795) (xy 29.334909 -76.788447) (xy 29.350977 -76.841854) (xy 29.359097 -76.89703)
			(xy 29.359606 -76.924916) (xy 29.359097 -76.952802) (xy 29.350977 -77.007978) (xy 29.334909 -77.061385)
			(xy 29.311237 -77.111882) (xy 29.280464 -77.158395) (xy 29.243247 -77.199932) (xy 29.200379 -77.235607)
			(xy 29.152773 -77.264661) (xy 29.101444 -77.286473) (xy 29.047487 -77.300579) (xy 28.99205 -77.306679)
			(xy 28.936316 -77.304642) (xy 28.881473 -77.294512) (xy 28.828689 -77.276505) (xy 28.779089 -77.251004)
			(xy 28.733731 -77.218553) (xy 28.693582 -77.179844) (xy 28.659496 -77.135701) (xy 28.6322 -77.087066)
			(xy 28.612277 -77.034975) (xy 28.600151 -76.980538) (xy 28.59608 -76.924916) (xy 22.687635 -76.924916)
			(xy 22.687279 -76.94442) (xy 22.679159 -76.999596) (xy 22.663091 -77.053003) (xy 22.639419 -77.1035)
			(xy 22.608646 -77.150013) (xy 22.571429 -77.19155) (xy 22.528561 -77.227225) (xy 22.480955 -77.256279)
			(xy 22.429626 -77.278091) (xy 22.375669 -77.292197) (xy 22.320232 -77.298297) (xy 22.264498 -77.29626)
			(xy 22.209655 -77.28613) (xy 22.156871 -77.268123) (xy 22.107271 -77.242622) (xy 22.061913 -77.210171)
			(xy 22.021764 -77.171462) (xy 21.987678 -77.127319) (xy 21.960382 -77.078684) (xy 21.940459 -77.026593)
			(xy 21.928333 -76.972156) (xy 21.924262 -76.916534) (xy 6.055868 -76.916534) (xy 6.055868 -77.462888)
			(xy 8.826752 -77.462888) (xy 8.830823 -77.407266) (xy 8.842949 -77.352829) (xy 8.862872 -77.300738)
			(xy 8.890168 -77.252103) (xy 8.924254 -77.20796) (xy 8.964403 -77.169251) (xy 9.009761 -77.1368)
			(xy 9.059361 -77.111299) (xy 9.112145 -77.093292) (xy 9.166988 -77.083162) (xy 9.222722 -77.081125)
			(xy 9.278159 -77.087225) (xy 9.332116 -77.101331) (xy 9.383445 -77.123143) (xy 9.431051 -77.152197)
			(xy 9.473919 -77.187872) (xy 9.511136 -77.229409) (xy 9.541909 -77.275922) (xy 9.565581 -77.326419)
			(xy 9.581649 -77.379826) (xy 9.589769 -77.435002) (xy 9.590278 -77.462888) (xy 9.589769 -77.490774)
			(xy 9.581649 -77.54595) (xy 9.571945 -77.578204) (xy 16.351756 -77.578204) (xy 16.355827 -77.522582)
			(xy 16.367953 -77.468145) (xy 16.387876 -77.416054) (xy 16.415172 -77.367419) (xy 16.449258 -77.323276)
			(xy 16.489407 -77.284567) (xy 16.534765 -77.252116) (xy 16.584365 -77.226615) (xy 16.637149 -77.208608)
			(xy 16.691992 -77.198478) (xy 16.747726 -77.196441) (xy 16.803163 -77.202541) (xy 16.85712 -77.216647)
			(xy 16.908449 -77.238459) (xy 16.956055 -77.267513) (xy 16.998923 -77.303188) (xy 17.03614 -77.344725)
			(xy 17.066913 -77.391238) (xy 17.090585 -77.441735) (xy 17.106653 -77.495142) (xy 17.114773 -77.550318)
			(xy 17.115282 -77.578204) (xy 17.114773 -77.60609) (xy 17.106653 -77.661266) (xy 17.090585 -77.714673)
			(xy 17.066913 -77.76517) (xy 17.054492 -77.783944) (xy 29.899862 -77.783944) (xy 29.903933 -77.728322)
			(xy 29.916059 -77.673885) (xy 29.935982 -77.621794) (xy 29.963278 -77.573159) (xy 29.997364 -77.529016)
			(xy 30.037513 -77.490307) (xy 30.082871 -77.457856) (xy 30.132471 -77.432355) (xy 30.185255 -77.414348)
			(xy 30.240098 -77.404218) (xy 30.295832 -77.402181) (xy 30.351269 -77.408281) (xy 30.405226 -77.422387)
			(xy 30.456555 -77.444199) (xy 30.504161 -77.473253) (xy 30.547029 -77.508928) (xy 30.584246 -77.550465)
			(xy 30.615019 -77.596978) (xy 30.638691 -77.647475) (xy 30.654759 -77.700882) (xy 30.662879 -77.756058)
			(xy 30.663388 -77.783944) (xy 30.662879 -77.81183) (xy 30.654759 -77.867006) (xy 30.638691 -77.920413)
			(xy 30.615019 -77.97091) (xy 30.584246 -78.017423) (xy 30.547029 -78.05896) (xy 30.504161 -78.094635)
			(xy 30.456555 -78.123689) (xy 30.405226 -78.145501) (xy 30.351269 -78.159607) (xy 30.295832 -78.165707)
			(xy 30.240098 -78.16367) (xy 30.185255 -78.15354) (xy 30.132471 -78.135533) (xy 30.082871 -78.110032)
			(xy 30.037513 -78.077581) (xy 29.997364 -78.038872) (xy 29.963278 -77.994729) (xy 29.935982 -77.946094)
			(xy 29.916059 -77.894003) (xy 29.903933 -77.839566) (xy 29.899862 -77.783944) (xy 17.054492 -77.783944)
			(xy 17.03614 -77.811683) (xy 16.998923 -77.85322) (xy 16.956055 -77.888895) (xy 16.908449 -77.917949)
			(xy 16.85712 -77.939761) (xy 16.803163 -77.953867) (xy 16.747726 -77.959967) (xy 16.691992 -77.95793)
			(xy 16.637149 -77.9478) (xy 16.584365 -77.929793) (xy 16.534765 -77.904292) (xy 16.489407 -77.871841)
			(xy 16.449258 -77.833132) (xy 16.415172 -77.788989) (xy 16.387876 -77.740354) (xy 16.367953 -77.688263)
			(xy 16.355827 -77.633826) (xy 16.351756 -77.578204) (xy 9.571945 -77.578204) (xy 9.565581 -77.599357)
			(xy 9.541909 -77.649854) (xy 9.511136 -77.696367) (xy 9.473919 -77.737904) (xy 9.431051 -77.773579)
			(xy 9.383445 -77.802633) (xy 9.332116 -77.824445) (xy 9.278159 -77.838551) (xy 9.222722 -77.844651)
			(xy 9.166988 -77.842614) (xy 9.112145 -77.832484) (xy 9.059361 -77.814477) (xy 9.009761 -77.788976)
			(xy 8.964403 -77.756525) (xy 8.924254 -77.717816) (xy 8.890168 -77.673673) (xy 8.862872 -77.625038)
			(xy 8.842949 -77.572947) (xy 8.830823 -77.51851) (xy 8.826752 -77.462888) (xy 6.055868 -77.462888)
			(xy 6.055868 -80.9879) (xy 90.463622 -80.9879) (xy 90.467693 -80.932278) (xy 90.479819 -80.877841)
			(xy 90.499742 -80.82575) (xy 90.527038 -80.777115) (xy 90.561124 -80.732972) (xy 90.601273 -80.694263)
			(xy 90.646631 -80.661812) (xy 90.696231 -80.636311) (xy 90.749015 -80.618304) (xy 90.803858 -80.608174)
			(xy 90.859592 -80.606137) (xy 90.915029 -80.612237) (xy 90.968986 -80.626343) (xy 91.020315 -80.648155)
			(xy 91.067921 -80.677209) (xy 91.110789 -80.712884) (xy 91.148006 -80.754421) (xy 91.178779 -80.800934)
			(xy 91.202451 -80.851431) (xy 91.218519 -80.904838) (xy 91.226639 -80.960014) (xy 91.227148 -80.9879)
			(xy 91.226639 -81.015786) (xy 91.218519 -81.070962) (xy 91.202451 -81.124369) (xy 91.178779 -81.174866)
			(xy 91.148006 -81.221379) (xy 91.110789 -81.262916) (xy 91.067921 -81.298591) (xy 91.020315 -81.327645)
			(xy 90.968986 -81.349457) (xy 90.915029 -81.363563) (xy 90.859592 -81.369663) (xy 90.803858 -81.367626)
			(xy 90.749015 -81.357496) (xy 90.696231 -81.339489) (xy 90.646631 -81.313988) (xy 90.601273 -81.281537)
			(xy 90.561124 -81.242828) (xy 90.527038 -81.198685) (xy 90.499742 -81.15005) (xy 90.479819 -81.097959)
			(xy 90.467693 -81.043522) (xy 90.463622 -80.9879) (xy 6.055868 -80.9879) (xy 6.055868 -82.235294)
			(xy 97.591372 -82.235294) (xy 97.591852 -82.208246) (xy 97.5995 -82.154692) (xy 97.614629 -82.102754)
			(xy 97.636935 -82.05347) (xy 97.665972 -82.007827) (xy 97.701159 -81.966737) (xy 97.721166 -81.948528)
			(xy 97.731692 -81.938648) (xy 97.747216 -81.914326) (xy 97.755302 -81.886628) (xy 97.755302 -81.857773)
			(xy 97.747216 -81.830075) (xy 97.731693 -81.805753) (xy 97.721166 -81.795874) (xy 97.701169 -81.777652)
			(xy 97.665969 -81.736573) (xy 97.636922 -81.690935) (xy 97.614612 -81.641652) (xy 97.599484 -81.589712)
			(xy 97.591844 -81.536157) (xy 97.591372 -81.509108) (xy 97.591858 -81.481857) (xy 97.599614 -81.427909)
			(xy 97.614969 -81.375614) (xy 97.637611 -81.326037) (xy 97.667077 -81.280187) (xy 97.702768 -81.238996)
			(xy 97.743959 -81.203305) (xy 97.789809 -81.173839) (xy 97.839386 -81.151197) (xy 97.891681 -81.135842)
			(xy 97.945629 -81.128086) (xy 98.000131 -81.128086) (xy 98.054079 -81.135842) (xy 98.106374 -81.151197)
			(xy 98.155951 -81.173839) (xy 98.201801 -81.203305) (xy 98.242992 -81.238996) (xy 98.278683 -81.280187)
			(xy 98.308149 -81.326037) (xy 98.330791 -81.375614) (xy 98.346146 -81.427909) (xy 98.353902 -81.481857)
			(xy 98.354388 -81.509108) (xy 98.353923 -81.536157) (xy 98.346274 -81.589712) (xy 98.331143 -81.641651)
			(xy 98.308834 -81.690935) (xy 98.279794 -81.736578) (xy 98.244602 -81.777666) (xy 98.224594 -81.795874)
			(xy 98.214113 -81.805777) (xy 98.198672 -81.830113) (xy 98.190632 -81.85779) (xy 98.190633 -81.886611)
			(xy 98.198673 -81.914288) (xy 98.214114 -81.938624) (xy 98.224594 -81.948528) (xy 98.244584 -81.966757)
			(xy 98.279786 -82.007834) (xy 98.308835 -82.05347) (xy 98.331147 -82.102752) (xy 98.346275 -82.154691)
			(xy 98.353916 -82.208245) (xy 98.354388 -82.235294) (xy 100.878386 -82.235294) (xy 100.878937 -82.206236)
			(xy 100.88777 -82.148794) (xy 100.905215 -82.093357) (xy 100.930868 -82.041208) (xy 100.964135 -81.993554)
			(xy 100.983796 -81.97215) (xy 100.993696 -81.96085) (xy 101.00714 -81.934005) (xy 101.012214 -81.904413)
			(xy 101.008482 -81.874623) (xy 100.996266 -81.847197) (xy 100.986844 -81.835498) (xy 100.969291 -81.814585)
			(xy 100.939736 -81.768678) (xy 100.917024 -81.719028) (xy 100.90162 -81.666648) (xy 100.893838 -81.612607)
			(xy 100.893372 -81.585308) (xy 100.893883 -81.55715) (xy 100.902182 -81.501449) (xy 100.918584 -81.447575)
			(xy 100.942733 -81.3967) (xy 100.974105 -81.349931) (xy 100.992686 -81.328768) (xy 101.002428 -81.317276)
			(xy 101.015374 -81.290091) (xy 101.019821 -81.260311) (xy 101.015381 -81.23053) (xy 101.002441 -81.203342)
			(xy 100.992686 -81.191862) (xy 100.974116 -81.170692) (xy 100.942765 -81.123915) (xy 100.918623 -81.07304)
			(xy 100.902216 -81.019172) (xy 100.893898 -80.963477) (xy 100.893372 -80.935322) (xy 100.893858 -80.908071)
			(xy 100.901614 -80.854123) (xy 100.916969 -80.801828) (xy 100.939611 -80.752251) (xy 100.969077 -80.706401)
			(xy 101.004768 -80.66521) (xy 101.045959 -80.629519) (xy 101.091809 -80.600053) (xy 101.141386 -80.577411)
			(xy 101.193681 -80.562056) (xy 101.247629 -80.5543) (xy 101.302131 -80.5543) (xy 101.356079 -80.562056)
			(xy 101.408374 -80.577411) (xy 101.457951 -80.600053) (xy 101.503801 -80.629519) (xy 101.544992 -80.66521)
			(xy 101.580683 -80.706401) (xy 101.610149 -80.752251) (xy 101.632791 -80.801828) (xy 101.648146 -80.854123)
			(xy 101.655902 -80.908071) (xy 101.656388 -80.935322) (xy 101.655879 -80.96348) (xy 101.647578 -81.01918)
			(xy 101.631174 -81.073054) (xy 101.607025 -81.123929) (xy 101.588889 -81.150968) (xy 107.750862 -81.150968)
			(xy 107.754933 -81.095346) (xy 107.767059 -81.040909) (xy 107.786982 -80.988818) (xy 107.814278 -80.940183)
			(xy 107.848364 -80.89604) (xy 107.888513 -80.857331) (xy 107.933871 -80.82488) (xy 107.983471 -80.799379)
			(xy 108.036255 -80.781372) (xy 108.091098 -80.771242) (xy 108.146832 -80.769205) (xy 108.202269 -80.775305)
			(xy 108.256226 -80.789411) (xy 108.307555 -80.811223) (xy 108.355161 -80.840277) (xy 108.398029 -80.875952)
			(xy 108.435246 -80.917489) (xy 108.466019 -80.964002) (xy 108.489691 -81.014499) (xy 108.505759 -81.067906)
			(xy 108.513879 -81.123082) (xy 108.514388 -81.150968) (xy 108.513879 -81.178854) (xy 108.505759 -81.23403)
			(xy 108.502474 -81.244948) (xy 113.465862 -81.244948) (xy 113.469933 -81.189326) (xy 113.482059 -81.134889)
			(xy 113.501982 -81.082798) (xy 113.529278 -81.034163) (xy 113.563364 -80.99002) (xy 113.603513 -80.951311)
			(xy 113.648871 -80.91886) (xy 113.698471 -80.893359) (xy 113.751255 -80.875352) (xy 113.806098 -80.865222)
			(xy 113.861832 -80.863185) (xy 113.917269 -80.869285) (xy 113.971226 -80.883391) (xy 114.022555 -80.905203)
			(xy 114.070161 -80.934257) (xy 114.113029 -80.969932) (xy 114.150246 -81.011469) (xy 114.181019 -81.057982)
			(xy 114.188888 -81.074768) (xy 149.597362 -81.074768) (xy 149.601433 -81.019146) (xy 149.613559 -80.964709)
			(xy 149.633482 -80.912618) (xy 149.660778 -80.863983) (xy 149.694864 -80.81984) (xy 149.735013 -80.781131)
			(xy 149.780371 -80.74868) (xy 149.829971 -80.723179) (xy 149.882755 -80.705172) (xy 149.937598 -80.695042)
			(xy 149.993332 -80.693005) (xy 150.048769 -80.699105) (xy 150.102726 -80.713211) (xy 150.154055 -80.735023)
			(xy 150.201661 -80.764077) (xy 150.244529 -80.799752) (xy 150.281746 -80.841289) (xy 150.312519 -80.887802)
			(xy 150.336191 -80.938299) (xy 150.352259 -80.991706) (xy 150.360379 -81.046882) (xy 150.360888 -81.074768)
			(xy 150.360379 -81.102654) (xy 150.352259 -81.15783) (xy 150.336191 -81.211237) (xy 150.312519 -81.261734)
			(xy 150.281746 -81.308247) (xy 150.244529 -81.349784) (xy 150.201661 -81.385459) (xy 150.154055 -81.414513)
			(xy 150.102726 -81.436325) (xy 150.048769 -81.450431) (xy 149.993332 -81.456531) (xy 149.937598 -81.454494)
			(xy 149.882755 -81.444364) (xy 149.829971 -81.426357) (xy 149.780371 -81.400856) (xy 149.735013 -81.368405)
			(xy 149.694864 -81.329696) (xy 149.660778 -81.285553) (xy 149.633482 -81.236918) (xy 149.613559 -81.184827)
			(xy 149.601433 -81.13039) (xy 149.597362 -81.074768) (xy 114.188888 -81.074768) (xy 114.204691 -81.108479)
			(xy 114.220759 -81.161886) (xy 114.228879 -81.217062) (xy 114.229388 -81.244948) (xy 114.228879 -81.272834)
			(xy 114.220759 -81.32801) (xy 114.204691 -81.381417) (xy 114.181019 -81.431914) (xy 114.150246 -81.478427)
			(xy 114.113029 -81.519964) (xy 114.070161 -81.555639) (xy 114.022555 -81.584693) (xy 113.971226 -81.606505)
			(xy 113.917269 -81.620611) (xy 113.861832 -81.626711) (xy 113.806098 -81.624674) (xy 113.751255 -81.614544)
			(xy 113.698471 -81.596537) (xy 113.648871 -81.571036) (xy 113.603513 -81.538585) (xy 113.563364 -81.499876)
			(xy 113.529278 -81.455733) (xy 113.501982 -81.407098) (xy 113.482059 -81.355007) (xy 113.469933 -81.30057)
			(xy 113.465862 -81.244948) (xy 108.502474 -81.244948) (xy 108.489691 -81.287437) (xy 108.466019 -81.337934)
			(xy 108.435246 -81.384447) (xy 108.398029 -81.425984) (xy 108.355161 -81.461659) (xy 108.307555 -81.490713)
			(xy 108.256226 -81.512525) (xy 108.202269 -81.526631) (xy 108.146832 -81.532731) (xy 108.091098 -81.530694)
			(xy 108.036255 -81.520564) (xy 107.983471 -81.502557) (xy 107.933871 -81.477056) (xy 107.888513 -81.444605)
			(xy 107.848364 -81.405896) (xy 107.814278 -81.361753) (xy 107.786982 -81.313118) (xy 107.767059 -81.261027)
			(xy 107.754933 -81.20659) (xy 107.750862 -81.150968) (xy 101.588889 -81.150968) (xy 101.575654 -81.170699)
			(xy 101.557074 -81.191862) (xy 101.547354 -81.203354) (xy 101.534494 -81.230552) (xy 101.530083 -81.260311)
			(xy 101.534501 -81.29007) (xy 101.547367 -81.317265) (xy 101.557074 -81.328768) (xy 101.575651 -81.349932)
			(xy 101.607003 -81.39671) (xy 101.631144 -81.447586) (xy 101.647549 -81.501456) (xy 101.655864 -81.557152)
			(xy 101.656388 -81.585308) (xy 101.655845 -81.614367) (xy 101.647011 -81.671809) (xy 101.629565 -81.727247)
			(xy 101.60391 -81.779395) (xy 101.57064 -81.827048) (xy 101.550978 -81.848452) (xy 101.541077 -81.85975)
			(xy 101.527637 -81.886597) (xy 101.522565 -81.916188) (xy 101.526296 -81.945978) (xy 101.538509 -81.973405)
			(xy 101.54793 -81.985104) (xy 101.56548 -82.006019) (xy 101.595037 -82.051925) (xy 101.617749 -82.101575)
			(xy 101.62727 -82.133948) (xy 111.941862 -82.133948) (xy 111.945933 -82.078326) (xy 111.958059 -82.023889)
			(xy 111.977982 -81.971798) (xy 112.005278 -81.923163) (xy 112.039364 -81.87902) (xy 112.079513 -81.840311)
			(xy 112.124871 -81.80786) (xy 112.174471 -81.782359) (xy 112.227255 -81.764352) (xy 112.282098 -81.754222)
			(xy 112.337832 -81.752185) (xy 112.393269 -81.758285) (xy 112.447226 -81.772391) (xy 112.498555 -81.794203)
			(xy 112.546161 -81.823257) (xy 112.589029 -81.858932) (xy 112.626246 -81.900469) (xy 112.657019 -81.946982)
			(xy 112.680691 -81.997479) (xy 112.696759 -82.050886) (xy 112.704879 -82.106062) (xy 112.705388 -82.133948)
			(xy 112.704879 -82.161834) (xy 112.700759 -82.189828) (xy 113.465862 -82.189828) (xy 113.469933 -82.134206)
			(xy 113.482059 -82.079769) (xy 113.501982 -82.027678) (xy 113.529278 -81.979043) (xy 113.563364 -81.9349)
			(xy 113.603513 -81.896191) (xy 113.648871 -81.86374) (xy 113.698471 -81.838239) (xy 113.751255 -81.820232)
			(xy 113.806098 -81.810102) (xy 113.861832 -81.808065) (xy 113.917269 -81.814165) (xy 113.971226 -81.828271)
			(xy 114.022555 -81.850083) (xy 114.070161 -81.879137) (xy 114.113029 -81.914812) (xy 114.150246 -81.956349)
			(xy 114.181019 -82.002862) (xy 114.204691 -82.053359) (xy 114.220759 -82.106766) (xy 114.223539 -82.125656)
			(xy 132.628543 -82.125656) (xy 132.628543 -82.071144) (xy 132.636301 -82.017188) (xy 132.65166 -81.964885)
			(xy 132.674306 -81.915301) (xy 132.703779 -81.869445) (xy 132.739478 -81.828249) (xy 132.780677 -81.792555)
			(xy 132.826536 -81.763087) (xy 132.876123 -81.740446) (xy 132.928427 -81.725093) (xy 132.982384 -81.71734)
			(xy 133.00964 -81.71688) (xy 133.038421 -81.717385) (xy 133.095329 -81.726038) (xy 133.150291 -81.743141)
			(xy 133.20206 -81.768306) (xy 133.249462 -81.800962) (xy 133.291421 -81.840369) (xy 133.309614 -81.862676)
			(xy 133.318584 -81.873333) (xy 133.341096 -81.88972) (xy 133.367197 -81.899419) (xy 133.394947 -81.90171)
			(xy 133.422286 -81.896423) (xy 133.447181 -81.883951) (xy 133.467784 -81.865219) (xy 133.482563 -81.841621)
			(xy 133.486906 -81.828386) (xy 133.495041 -81.802371) (xy 133.517667 -81.752783) (xy 133.547122 -81.706922)
			(xy 133.582806 -81.66572) (xy 133.623992 -81.630019) (xy 133.669841 -81.600544) (xy 133.719419 -81.577897)
			(xy 133.771716 -81.562539) (xy 133.825667 -81.554782) (xy 133.85292 -81.55432) (xy 133.880172 -81.554751)
			(xy 133.934122 -81.562511) (xy 133.986418 -81.577869) (xy 134.035996 -81.600513) (xy 134.081848 -81.629982)
			(xy 134.123038 -81.665676) (xy 134.15873 -81.706868) (xy 134.188197 -81.752721) (xy 134.210838 -81.802301)
			(xy 134.226194 -81.854598) (xy 134.23349 -81.905348) (xy 145.617182 -81.905348) (xy 145.621253 -81.849726)
			(xy 145.633379 -81.795289) (xy 145.653302 -81.743198) (xy 145.680598 -81.694563) (xy 145.714684 -81.65042)
			(xy 145.754833 -81.611711) (xy 145.800191 -81.57926) (xy 145.849791 -81.553759) (xy 145.902575 -81.535752)
			(xy 145.957418 -81.525622) (xy 146.013152 -81.523585) (xy 146.068589 -81.529685) (xy 146.122546 -81.543791)
			(xy 146.173875 -81.565603) (xy 146.221481 -81.594657) (xy 146.264349 -81.630332) (xy 146.301566 -81.671869)
			(xy 146.332339 -81.718382) (xy 146.356011 -81.768879) (xy 146.372079 -81.822286) (xy 146.380199 -81.877462)
			(xy 146.380708 -81.905348) (xy 146.380199 -81.933234) (xy 146.372079 -81.98841) (xy 146.356011 -82.041817)
			(xy 146.332339 -82.092314) (xy 146.301566 -82.138827) (xy 146.264349 -82.180364) (xy 146.221481 -82.216039)
			(xy 146.173875 -82.245093) (xy 146.122546 -82.266905) (xy 146.068589 -82.281011) (xy 146.013152 -82.287111)
			(xy 145.957418 -82.285074) (xy 145.902575 -82.274944) (xy 145.849791 -82.256937) (xy 145.800191 -82.231436)
			(xy 145.754833 -82.198985) (xy 145.714684 -82.160276) (xy 145.680598 -82.116133) (xy 145.653302 -82.067498)
			(xy 145.633379 -82.015407) (xy 145.621253 -81.96097) (xy 145.617182 -81.905348) (xy 134.23349 -81.905348)
			(xy 134.23395 -81.908548) (xy 134.23395 -81.963052) (xy 134.226194 -82.017002) (xy 134.210838 -82.069299)
			(xy 134.188197 -82.118879) (xy 134.15873 -82.164732) (xy 134.123038 -82.205924) (xy 134.081848 -82.241618)
			(xy 134.035996 -82.271087) (xy 133.986418 -82.293731) (xy 133.934122 -82.309089) (xy 133.880172 -82.316849)
			(xy 133.85292 -82.317336) (xy 133.824141 -82.316782) (xy 133.767236 -82.308139) (xy 133.712275 -82.291045)
			(xy 133.660505 -82.265889) (xy 133.613102 -82.233241) (xy 133.571141 -82.193843) (xy 133.552946 -82.17154)
			(xy 133.544031 -82.160833) (xy 133.521507 -82.144443) (xy 133.495394 -82.134744) (xy 133.467632 -82.132457)
			(xy 133.440284 -82.137751) (xy 133.415381 -82.150234) (xy 133.394775 -82.168977) (xy 133.379995 -82.192589)
			(xy 133.375654 -82.20583) (xy 133.367565 -82.23186) (xy 133.344934 -82.28145) (xy 133.315473 -82.327312)
			(xy 133.279783 -82.368513) (xy 133.238591 -82.404214) (xy 133.192736 -82.433686) (xy 133.143153 -82.45633)
			(xy 133.09085 -82.471685) (xy 133.036895 -82.479437) (xy 133.00964 -82.479896) (xy 132.982384 -82.47946)
			(xy 132.928427 -82.471707) (xy 132.876123 -82.456354) (xy 132.826536 -82.433713) (xy 132.780677 -82.404245)
			(xy 132.739478 -82.368551) (xy 132.703779 -82.327355) (xy 132.674306 -82.281499) (xy 132.65166 -82.231915)
			(xy 132.636301 -82.179612) (xy 132.628543 -82.125656) (xy 114.223539 -82.125656) (xy 114.228879 -82.161942)
			(xy 114.229388 -82.189828) (xy 114.228879 -82.217714) (xy 114.220759 -82.27289) (xy 114.204691 -82.326297)
			(xy 114.181019 -82.376794) (xy 114.150246 -82.423307) (xy 114.113029 -82.464844) (xy 114.070161 -82.500519)
			(xy 114.022555 -82.529573) (xy 113.971226 -82.551385) (xy 113.917269 -82.565491) (xy 113.861832 -82.571591)
			(xy 113.806098 -82.569554) (xy 113.751255 -82.559424) (xy 113.698471 -82.541417) (xy 113.648871 -82.515916)
			(xy 113.603513 -82.483465) (xy 113.563364 -82.444756) (xy 113.529278 -82.400613) (xy 113.501982 -82.351978)
			(xy 113.482059 -82.299887) (xy 113.469933 -82.24545) (xy 113.465862 -82.189828) (xy 112.700759 -82.189828)
			(xy 112.696759 -82.21701) (xy 112.680691 -82.270417) (xy 112.657019 -82.320914) (xy 112.626246 -82.367427)
			(xy 112.589029 -82.408964) (xy 112.546161 -82.444639) (xy 112.498555 -82.473693) (xy 112.447226 -82.495505)
			(xy 112.393269 -82.509611) (xy 112.337832 -82.515711) (xy 112.282098 -82.513674) (xy 112.227255 -82.503544)
			(xy 112.174471 -82.485537) (xy 112.124871 -82.460036) (xy 112.079513 -82.427585) (xy 112.039364 -82.388876)
			(xy 112.005278 -82.344733) (xy 111.977982 -82.296098) (xy 111.958059 -82.244007) (xy 111.945933 -82.18957)
			(xy 111.941862 -82.133948) (xy 101.62727 -82.133948) (xy 101.633154 -82.153954) (xy 101.640936 -82.207995)
			(xy 101.641402 -82.235294) (xy 101.640916 -82.262545) (xy 101.63316 -82.316493) (xy 101.617805 -82.368788)
			(xy 101.595163 -82.418365) (xy 101.565697 -82.464215) (xy 101.530006 -82.505406) (xy 101.488815 -82.541097)
			(xy 101.442965 -82.570563) (xy 101.393388 -82.593205) (xy 101.341093 -82.60856) (xy 101.287145 -82.616316)
			(xy 101.232643 -82.616316) (xy 101.178695 -82.60856) (xy 101.1264 -82.593205) (xy 101.076823 -82.570563)
			(xy 101.030973 -82.541097) (xy 100.989782 -82.505406) (xy 100.954091 -82.464215) (xy 100.924625 -82.418365)
			(xy 100.901983 -82.368788) (xy 100.886628 -82.316493) (xy 100.878872 -82.262545) (xy 100.878386 -82.235294)
			(xy 98.354388 -82.235294) (xy 98.353902 -82.262545) (xy 98.346146 -82.316493) (xy 98.330791 -82.368788)
			(xy 98.308149 -82.418365) (xy 98.278683 -82.464215) (xy 98.242992 -82.505406) (xy 98.201801 -82.541097)
			(xy 98.155951 -82.570563) (xy 98.106374 -82.593205) (xy 98.054079 -82.60856) (xy 98.000131 -82.616316)
			(xy 97.945629 -82.616316) (xy 97.891681 -82.60856) (xy 97.839386 -82.593205) (xy 97.789809 -82.570563)
			(xy 97.743959 -82.541097) (xy 97.702768 -82.505406) (xy 97.667077 -82.464215) (xy 97.637611 -82.418365)
			(xy 97.614969 -82.368788) (xy 97.599614 -82.316493) (xy 97.591858 -82.262545) (xy 97.591372 -82.235294)
			(xy 6.055868 -82.235294) (xy 6.055868 -83.276948) (xy 149.661372 -83.276948) (xy 149.661876 -83.248606)
			(xy 149.670258 -83.192544) (xy 149.686844 -83.13834) (xy 149.711269 -83.087188) (xy 149.742995 -83.040213)
			(xy 149.781324 -82.998451) (xy 149.825411 -82.962821) (xy 149.849586 -82.948018) (xy 149.862378 -82.939912)
			(xy 149.882871 -82.917635) (xy 149.895934 -82.890329) (xy 149.900418 -82.860394) (xy 149.89593 -82.830459)
			(xy 149.882865 -82.803155) (xy 149.862369 -82.78088) (xy 149.849586 -82.772758) (xy 149.825428 -82.757931)
			(xy 149.781347 -82.7223) (xy 149.743023 -82.68054) (xy 149.711298 -82.633569) (xy 149.686872 -82.582422)
			(xy 149.670281 -82.528224) (xy 149.661892 -82.472168) (xy 149.661372 -82.443828) (xy 149.661881 -82.416577)
			(xy 149.669634 -82.362629) (xy 149.684985 -82.310333) (xy 149.707623 -82.260754) (xy 149.737086 -82.214902)
			(xy 149.772775 -82.173709) (xy 149.813963 -82.138015) (xy 149.859812 -82.108546) (xy 149.909388 -82.085902)
			(xy 149.961682 -82.070544) (xy 150.015629 -82.062785) (xy 150.04288 -82.06232) (xy 150.07188 -82.062859)
			(xy 150.129213 -82.071636) (xy 150.184556 -82.088991) (xy 150.236634 -82.114523) (xy 150.284247 -82.147645)
			(xy 150.326297 -82.187593) (xy 150.361815 -82.233446) (xy 150.389983 -82.284147) (xy 150.410152 -82.338528)
			(xy 150.421855 -82.395336) (xy 150.42388 -82.42427) (xy 150.425134 -82.438463) (xy 150.43437 -82.465398)
			(xy 150.450699 -82.488726) (xy 150.472845 -82.506626) (xy 150.499079 -82.517699) (xy 150.527352 -82.521081)
			(xy 150.541482 -82.519266) (xy 150.55643 -82.517015) (xy 150.586564 -82.514598) (xy 150.60168 -82.51444)
			(xy 150.628937 -82.514806) (xy 150.682897 -82.522561) (xy 150.735204 -82.537917) (xy 150.784793 -82.560562)
			(xy 150.830654 -82.590033) (xy 150.871855 -82.625731) (xy 150.907555 -82.66693) (xy 150.937029 -82.712789)
			(xy 150.959676 -82.762377) (xy 150.975035 -82.814683) (xy 150.982793 -82.868643) (xy 150.982793 -82.923157)
			(xy 150.975035 -82.977117) (xy 150.959676 -83.029423) (xy 150.937029 -83.079011) (xy 150.907555 -83.12487)
			(xy 150.871855 -83.166069) (xy 150.830654 -83.201767) (xy 150.784793 -83.231238) (xy 150.735204 -83.253883)
			(xy 150.682897 -83.269239) (xy 150.628937 -83.276994) (xy 150.60168 -83.277456) (xy 150.584827 -83.277308)
			(xy 150.551249 -83.274379) (xy 150.534624 -83.271614) (xy 150.521614 -83.269586) (xy 150.49537 -83.271673)
			(xy 150.470538 -83.280419) (xy 150.448778 -83.295237) (xy 150.431543 -83.315138) (xy 150.419985 -83.338792)
			(xy 150.417022 -83.351624) (xy 150.411123 -83.378625) (xy 150.392621 -83.430702) (xy 150.366794 -83.479561)
			(xy 150.3478 -83.505548) (xy 155.607002 -83.505548) (xy 155.611073 -83.449926) (xy 155.623199 -83.395489)
			(xy 155.643122 -83.343398) (xy 155.670418 -83.294763) (xy 155.704504 -83.25062) (xy 155.744653 -83.211911)
			(xy 155.790011 -83.17946) (xy 155.839611 -83.153959) (xy 155.892395 -83.135952) (xy 155.947238 -83.125822)
			(xy 156.002972 -83.123785) (xy 156.058409 -83.129885) (xy 156.112366 -83.143991) (xy 156.163695 -83.165803)
			(xy 156.211301 -83.194857) (xy 156.254169 -83.230532) (xy 156.291386 -83.272069) (xy 156.322159 -83.318582)
			(xy 156.345831 -83.369079) (xy 156.361899 -83.422486) (xy 156.370019 -83.477662) (xy 156.370528 -83.505548)
			(xy 156.370019 -83.533434) (xy 156.361899 -83.58861) (xy 156.345831 -83.642017) (xy 156.322159 -83.692514)
			(xy 156.291386 -83.739027) (xy 156.254169 -83.780564) (xy 156.211301 -83.816239) (xy 156.163695 -83.845293)
			(xy 156.112366 -83.867105) (xy 156.058409 -83.881211) (xy 156.002972 -83.887311) (xy 155.947238 -83.885274)
			(xy 155.892395 -83.875144) (xy 155.839611 -83.857137) (xy 155.790011 -83.831636) (xy 155.744653 -83.799185)
			(xy 155.704504 -83.760476) (xy 155.670418 -83.716333) (xy 155.643122 -83.667698) (xy 155.623199 -83.615607)
			(xy 155.611073 -83.56117) (xy 155.607002 -83.505548) (xy 150.3478 -83.505548) (xy 150.334182 -83.52418)
			(xy 150.29547 -83.563621) (xy 150.273766 -83.580732) (xy 150.263003 -83.589464) (xy 150.2463 -83.611572)
			(xy 150.236145 -83.637352) (xy 150.233282 -83.664912) (xy 150.237923 -83.692229) (xy 150.249725 -83.717297)
			(xy 150.267824 -83.738278) (xy 150.2791 -83.74634) (xy 150.301235 -83.76157) (xy 150.3414 -83.797257)
			(xy 150.376163 -83.838225) (xy 150.404837 -83.883663) (xy 150.426856 -83.932673) (xy 150.441784 -83.984286)
			(xy 150.449326 -84.037484) (xy 150.449788 -84.064348) (xy 150.449302 -84.091599) (xy 150.445916 -84.115148)
			(xy 153.365452 -84.115148) (xy 153.369523 -84.059526) (xy 153.381649 -84.005089) (xy 153.401572 -83.952998)
			(xy 153.428868 -83.904363) (xy 153.462954 -83.86022) (xy 153.503103 -83.821511) (xy 153.548461 -83.78906)
			(xy 153.598061 -83.763559) (xy 153.650845 -83.745552) (xy 153.705688 -83.735422) (xy 153.761422 -83.733385)
			(xy 153.816859 -83.739485) (xy 153.870816 -83.753591) (xy 153.922145 -83.775403) (xy 153.969751 -83.804457)
			(xy 154.012619 -83.840132) (xy 154.049836 -83.881669) (xy 154.077431 -83.923378) (xy 154.518358 -83.923378)
			(xy 154.522429 -83.867756) (xy 154.534555 -83.813319) (xy 154.554478 -83.761228) (xy 154.581774 -83.712593)
			(xy 154.61586 -83.66845) (xy 154.656009 -83.629741) (xy 154.701367 -83.59729) (xy 154.750967 -83.571789)
			(xy 154.803751 -83.553782) (xy 154.858594 -83.543652) (xy 154.914328 -83.541615) (xy 154.969765 -83.547715)
			(xy 155.023722 -83.561821) (xy 155.075051 -83.583633) (xy 155.122657 -83.612687) (xy 155.165525 -83.648362)
			(xy 155.202742 -83.689899) (xy 155.233515 -83.736412) (xy 155.257187 -83.786909) (xy 155.273255 -83.840316)
			(xy 155.281375 -83.895492) (xy 155.281884 -83.923378) (xy 155.281375 -83.951264) (xy 155.273255 -84.00644)
			(xy 155.257187 -84.059847) (xy 155.233515 -84.110344) (xy 155.230337 -84.115148) (xy 156.964378 -84.115148)
			(xy 156.968449 -84.059526) (xy 156.980575 -84.005089) (xy 157.000498 -83.952998) (xy 157.027794 -83.904363)
			(xy 157.06188 -83.86022) (xy 157.102029 -83.821511) (xy 157.147387 -83.78906) (xy 157.196987 -83.763559)
			(xy 157.249771 -83.745552) (xy 157.304614 -83.735422) (xy 157.360348 -83.733385) (xy 157.415785 -83.739485)
			(xy 157.469742 -83.753591) (xy 157.521071 -83.775403) (xy 157.568677 -83.804457) (xy 157.611545 -83.840132)
			(xy 157.648762 -83.881669) (xy 157.679535 -83.928182) (xy 157.703207 -83.978679) (xy 157.719275 -84.032086)
			(xy 157.727395 -84.087262) (xy 157.727904 -84.115148) (xy 157.727395 -84.143034) (xy 157.719275 -84.19821)
			(xy 157.703207 -84.251617) (xy 157.679535 -84.302114) (xy 157.648762 -84.348627) (xy 157.611545 -84.390164)
			(xy 157.568677 -84.425839) (xy 157.521071 -84.454893) (xy 157.469742 -84.476705) (xy 157.415785 -84.490811)
			(xy 157.360348 -84.496911) (xy 157.304614 -84.494874) (xy 157.249771 -84.484744) (xy 157.196987 -84.466737)
			(xy 157.147387 -84.441236) (xy 157.102029 -84.408785) (xy 157.06188 -84.370076) (xy 157.027794 -84.325933)
			(xy 157.000498 -84.277298) (xy 156.980575 -84.225207) (xy 156.968449 -84.17077) (xy 156.964378 -84.115148)
			(xy 155.230337 -84.115148) (xy 155.202742 -84.156857) (xy 155.165525 -84.198394) (xy 155.122657 -84.234069)
			(xy 155.075051 -84.263123) (xy 155.023722 -84.284935) (xy 154.969765 -84.299041) (xy 154.914328 -84.305141)
			(xy 154.858594 -84.303104) (xy 154.803751 -84.292974) (xy 154.750967 -84.274967) (xy 154.701367 -84.249466)
			(xy 154.656009 -84.217015) (xy 154.61586 -84.178306) (xy 154.581774 -84.134163) (xy 154.554478 -84.085528)
			(xy 154.534555 -84.033437) (xy 154.522429 -83.979) (xy 154.518358 -83.923378) (xy 154.077431 -83.923378)
			(xy 154.080609 -83.928182) (xy 154.104281 -83.978679) (xy 154.120349 -84.032086) (xy 154.128469 -84.087262)
			(xy 154.128978 -84.115148) (xy 154.128469 -84.143034) (xy 154.120349 -84.19821) (xy 154.104281 -84.251617)
			(xy 154.080609 -84.302114) (xy 154.049836 -84.348627) (xy 154.012619 -84.390164) (xy 153.969751 -84.425839)
			(xy 153.922145 -84.454893) (xy 153.870816 -84.476705) (xy 153.816859 -84.490811) (xy 153.761422 -84.496911)
			(xy 153.705688 -84.494874) (xy 153.650845 -84.484744) (xy 153.598061 -84.466737) (xy 153.548461 -84.441236)
			(xy 153.503103 -84.408785) (xy 153.462954 -84.370076) (xy 153.428868 -84.325933) (xy 153.401572 -84.277298)
			(xy 153.381649 -84.225207) (xy 153.369523 -84.17077) (xy 153.365452 -84.115148) (xy 150.445916 -84.115148)
			(xy 150.441546 -84.145547) (xy 150.426191 -84.197842) (xy 150.403549 -84.247419) (xy 150.374083 -84.293269)
			(xy 150.338392 -84.33446) (xy 150.297201 -84.370151) (xy 150.251351 -84.399617) (xy 150.201774 -84.422259)
			(xy 150.149479 -84.437614) (xy 150.095531 -84.44537) (xy 150.041029 -84.44537) (xy 149.987081 -84.437614)
			(xy 149.934786 -84.422259) (xy 149.885209 -84.399617) (xy 149.839359 -84.370151) (xy 149.798168 -84.33446)
			(xy 149.762477 -84.293269) (xy 149.733011 -84.247419) (xy 149.710369 -84.197842) (xy 149.695014 -84.145547)
			(xy 149.687258 -84.091599) (xy 149.686772 -84.064348) (xy 149.687303 -84.035054) (xy 149.696273 -83.977155)
			(xy 149.71398 -83.921305) (xy 149.740008 -83.868815) (xy 149.773747 -83.820915) (xy 149.814405 -83.778729)
			(xy 149.837394 -83.760564) (xy 149.848167 -83.75184) (xy 149.864876 -83.729732) (xy 149.875036 -83.70395)
			(xy 149.877899 -83.676386) (xy 149.873256 -83.649065) (xy 149.861447 -83.623995) (xy 149.84334 -83.603016)
			(xy 149.83206 -83.594956) (xy 149.809936 -83.57971) (xy 149.769769 -83.544027) (xy 149.735003 -83.503063)
			(xy 149.706326 -83.457628) (xy 149.684305 -83.40862) (xy 149.669376 -83.357008) (xy 149.661833 -83.303812)
			(xy 149.661372 -83.276948) (xy 6.055868 -83.276948) (xy 6.055868 -85.764678) (xy 10.421355 -85.764678)
			(xy 10.421355 -85.635538) (xy 10.429305 -85.506643) (xy 10.445175 -85.378483) (xy 10.468904 -85.251542)
			(xy 10.500403 -85.126303) (xy 10.539552 -85.00324) (xy 10.586203 -84.882821) (xy 10.640178 -84.765502)
			(xy 10.701273 -84.651728) (xy 10.769256 -84.541931) (xy 10.84387 -84.436528) (xy 10.924831 -84.335918)
			(xy 11.011831 -84.240483) (xy 11.104542 -84.150584) (xy 11.202612 -84.066563) (xy 11.305667 -83.988739)
			(xy 11.413318 -83.917407) (xy 11.525157 -83.852837) (xy 11.640758 -83.795275) (xy 11.759683 -83.744938)
			(xy 11.881482 -83.702018) (xy 12.005692 -83.666677) (xy 12.131841 -83.63905) (xy 12.259453 -83.619241)
			(xy 12.388042 -83.607325) (xy 12.51712 -83.603349) (xy 12.646198 -83.607325) (xy 12.774787 -83.619241)
			(xy 12.902399 -83.63905) (xy 13.028548 -83.666677) (xy 13.152758 -83.702018) (xy 13.274557 -83.744938)
			(xy 13.393482 -83.795275) (xy 13.509083 -83.852837) (xy 13.620922 -83.917407) (xy 13.728573 -83.988739)
			(xy 13.831628 -84.066563) (xy 13.929698 -84.150584) (xy 14.022409 -84.240483) (xy 14.109409 -84.335918)
			(xy 14.19037 -84.436528) (xy 14.194816 -84.442808) (xy 128.436622 -84.442808) (xy 128.440693 -84.387186)
			(xy 128.452819 -84.332749) (xy 128.472742 -84.280658) (xy 128.500038 -84.232023) (xy 128.534124 -84.18788)
			(xy 128.574273 -84.149171) (xy 128.619631 -84.11672) (xy 128.669231 -84.091219) (xy 128.722015 -84.073212)
			(xy 128.776858 -84.063082) (xy 128.832592 -84.061045) (xy 128.888029 -84.067145) (xy 128.941986 -84.081251)
			(xy 128.993315 -84.103063) (xy 129.040921 -84.132117) (xy 129.083789 -84.167792) (xy 129.121006 -84.209329)
			(xy 129.151779 -84.255842) (xy 129.175451 -84.306339) (xy 129.191519 -84.359746) (xy 129.199639 -84.414922)
			(xy 129.200148 -84.442808) (xy 129.199639 -84.470694) (xy 129.19851 -84.478368) (xy 129.345942 -84.478368)
			(xy 129.350013 -84.422746) (xy 129.362139 -84.368309) (xy 129.382062 -84.316218) (xy 129.409358 -84.267583)
			(xy 129.443444 -84.22344) (xy 129.483593 -84.184731) (xy 129.528951 -84.15228) (xy 129.578551 -84.126779)
			(xy 129.631335 -84.108772) (xy 129.686178 -84.098642) (xy 129.741912 -84.096605) (xy 129.797349 -84.102705)
			(xy 129.851306 -84.116811) (xy 129.902635 -84.138623) (xy 129.950241 -84.167677) (xy 129.993109 -84.203352)
			(xy 130.030326 -84.244889) (xy 130.061099 -84.291402) (xy 130.072701 -84.316151) (xy 141.551662 -84.316151)
			(xy 141.551662 -84.261649) (xy 141.559417 -84.207703) (xy 141.574771 -84.155409) (xy 141.59741 -84.105833)
			(xy 141.626874 -84.059982) (xy 141.662563 -84.018791) (xy 141.70375 -83.983098) (xy 141.749597 -83.95363)
			(xy 141.799172 -83.930985) (xy 141.851464 -83.915626) (xy 141.905409 -83.907865) (xy 141.93266 -83.907376)
			(xy 141.96003 -83.907847) (xy 142.01421 -83.915661) (xy 142.066714 -83.931148) (xy 142.116461 -83.953989)
			(xy 142.162427 -83.983714) (xy 142.183358 -84.001356) (xy 142.194686 -84.010592) (xy 142.221243 -84.022768)
			(xy 142.25016 -84.026941) (xy 142.279077 -84.022768) (xy 142.305634 -84.010592) (xy 142.316962 -84.001356)
			(xy 142.337895 -83.983715) (xy 142.383863 -83.953991) (xy 142.433609 -83.931145) (xy 142.486111 -83.915649)
			(xy 142.540289 -83.90782) (xy 142.595031 -83.90782) (xy 142.649209 -83.915649) (xy 142.701711 -83.931145)
			(xy 142.751457 -83.953991) (xy 142.797425 -83.983715) (xy 142.818358 -84.001356) (xy 142.829686 -84.010592)
			(xy 142.856243 -84.022768) (xy 142.88516 -84.026941) (xy 142.914077 -84.022768) (xy 142.940634 -84.010592)
			(xy 142.951962 -84.001356) (xy 142.972892 -83.983714) (xy 143.018866 -83.954004) (xy 143.068614 -83.931169)
			(xy 143.121115 -83.915679) (xy 143.175291 -83.90785) (xy 143.20266 -83.907376) (xy 143.229914 -83.907869)
			(xy 143.283867 -83.915621) (xy 143.336167 -83.930973) (xy 143.38575 -83.953612) (xy 143.431606 -83.983077)
			(xy 143.472802 -84.01877) (xy 143.508499 -84.059962) (xy 143.537969 -84.105815) (xy 143.560613 -84.155395)
			(xy 143.575971 -84.207694) (xy 143.583729 -84.261646) (xy 143.583729 -84.316154) (xy 143.579646 -84.344551)
			(xy 143.796987 -84.344551) (xy 143.796987 -84.290049) (xy 143.804744 -84.2361) (xy 143.8201 -84.183805)
			(xy 143.842742 -84.134228) (xy 143.872209 -84.088378) (xy 143.907902 -84.047188) (xy 143.949094 -84.011497)
			(xy 143.994946 -83.982032) (xy 144.044524 -83.959393) (xy 144.09682 -83.94404) (xy 144.150768 -83.936286)
			(xy 144.17802 -83.935824) (xy 144.204136 -83.936241) (xy 144.255876 -83.943386) (xy 144.306157 -83.957528)
			(xy 144.354037 -83.9784) (xy 144.398619 -84.005612) (xy 144.439071 -84.038654) (xy 144.457166 -84.05749)
			(xy 144.467097 -84.067505) (xy 144.491244 -84.082065) (xy 144.518448 -84.089481) (xy 144.546643 -84.08919)
			(xy 144.573689 -84.081215) (xy 144.59753 -84.066159) (xy 144.60728 -84.055966) (xy 144.625459 -84.036318)
			(xy 144.666366 -84.001794) (xy 144.711695 -83.973324) (xy 144.760557 -83.951466) (xy 144.811994 -83.93665)
			(xy 144.864996 -83.929166) (xy 144.89176 -83.928712) (xy 144.919016 -83.929132) (xy 144.972974 -83.936885)
			(xy 145.02528 -83.952238) (xy 145.074868 -83.97488) (xy 145.120728 -84.004348) (xy 145.161928 -84.040044)
			(xy 145.197628 -84.08124) (xy 145.227101 -84.127097) (xy 145.249748 -84.176683) (xy 145.265107 -84.228987)
			(xy 145.272865 -84.282944) (xy 145.272865 -84.337456) (xy 145.265107 -84.391413) (xy 145.249748 -84.443717)
			(xy 145.227101 -84.493303) (xy 145.197628 -84.53916) (xy 145.161928 -84.580356) (xy 145.120728 -84.616052)
			(xy 145.074868 -84.64552) (xy 145.02528 -84.668162) (xy 144.972974 -84.683515) (xy 144.919016 -84.691268)
			(xy 144.89176 -84.691728) (xy 144.865645 -84.691308) (xy 144.813905 -84.684161) (xy 144.763625 -84.670019)
			(xy 144.715746 -84.649148) (xy 144.671162 -84.621937) (xy 144.63071 -84.588896) (xy 144.612614 -84.570062)
			(xy 144.602704 -84.560021) (xy 144.578553 -84.545455) (xy 144.551342 -84.538037) (xy 144.523139 -84.538332)
			(xy 144.496089 -84.546317) (xy 144.472248 -84.561385) (xy 144.4625 -84.571586) (xy 144.444341 -84.591253)
			(xy 144.403429 -84.625774) (xy 144.358095 -84.65424) (xy 144.30923 -84.676094) (xy 144.25779 -84.690907)
			(xy 144.204785 -84.698388) (xy 144.17802 -84.69884) (xy 144.150768 -84.698314) (xy 144.09682 -84.69056)
			(xy 144.044524 -84.675207) (xy 143.994946 -84.652568) (xy 143.949094 -84.623103) (xy 143.907902 -84.587412)
			(xy 143.872209 -84.546222) (xy 143.842742 -84.500372) (xy 143.8201 -84.450795) (xy 143.804744 -84.3985)
			(xy 143.796987 -84.344551) (xy 143.579646 -84.344551) (xy 143.575971 -84.370106) (xy 143.560613 -84.422405)
			(xy 143.537969 -84.471985) (xy 143.508499 -84.517838) (xy 143.472802 -84.55903) (xy 143.431606 -84.594723)
			(xy 143.38575 -84.624188) (xy 143.336167 -84.646827) (xy 143.283867 -84.662179) (xy 143.229914 -84.669931)
			(xy 143.20266 -84.670392) (xy 143.175291 -84.669893) (xy 143.121113 -84.662083) (xy 143.06861 -84.646602)
			(xy 143.018863 -84.623768) (xy 142.972895 -84.59405) (xy 142.951962 -84.576412) (xy 142.940634 -84.567176)
			(xy 142.914077 -84.555) (xy 142.88516 -84.550827) (xy 142.856243 -84.555) (xy 142.829686 -84.567176)
			(xy 142.818358 -84.576412) (xy 142.797425 -84.594053) (xy 142.751457 -84.623777) (xy 142.701711 -84.646623)
			(xy 142.649209 -84.662119) (xy 142.595031 -84.669948) (xy 142.540289 -84.669948) (xy 142.486111 -84.662119)
			(xy 142.433609 -84.646623) (xy 142.383863 -84.623777) (xy 142.337895 -84.594053) (xy 142.316962 -84.576412)
			(xy 142.305634 -84.567176) (xy 142.279077 -84.555) (xy 142.25016 -84.550827) (xy 142.221243 -84.555)
			(xy 142.194686 -84.567176) (xy 142.183358 -84.576412) (xy 142.162416 -84.594039) (xy 142.116446 -84.623752)
			(xy 142.066701 -84.64659) (xy 142.014202 -84.662084) (xy 141.960028 -84.669916) (xy 141.93266 -84.670392)
			(xy 141.905409 -84.669935) (xy 141.851464 -84.662174) (xy 141.799172 -84.646815) (xy 141.749597 -84.62417)
			(xy 141.70375 -84.594702) (xy 141.662563 -84.559009) (xy 141.626874 -84.517818) (xy 141.59741 -84.471967)
			(xy 141.574771 -84.422391) (xy 141.559417 -84.370097) (xy 141.551662 -84.316151) (xy 130.072701 -84.316151)
			(xy 130.084771 -84.341899) (xy 130.100839 -84.395306) (xy 130.108959 -84.450482) (xy 130.109468 -84.478368)
			(xy 130.108959 -84.506254) (xy 130.100839 -84.56143) (xy 130.084771 -84.614837) (xy 130.061099 -84.665334)
			(xy 130.030326 -84.711847) (xy 129.993109 -84.753384) (xy 129.950241 -84.789059) (xy 129.902635 -84.818113)
			(xy 129.851306 -84.839925) (xy 129.797349 -84.854031) (xy 129.741912 -84.860131) (xy 129.686178 -84.858094)
			(xy 129.631335 -84.847964) (xy 129.578551 -84.829957) (xy 129.528951 -84.804456) (xy 129.483593 -84.772005)
			(xy 129.443444 -84.733296) (xy 129.409358 -84.689153) (xy 129.382062 -84.640518) (xy 129.362139 -84.588427)
			(xy 129.350013 -84.53399) (xy 129.345942 -84.478368) (xy 129.19851 -84.478368) (xy 129.191519 -84.52587)
			(xy 129.175451 -84.579277) (xy 129.151779 -84.629774) (xy 129.121006 -84.676287) (xy 129.083789 -84.717824)
			(xy 129.040921 -84.753499) (xy 128.993315 -84.782553) (xy 128.941986 -84.804365) (xy 128.888029 -84.818471)
			(xy 128.832592 -84.824571) (xy 128.776858 -84.822534) (xy 128.722015 -84.812404) (xy 128.669231 -84.794397)
			(xy 128.619631 -84.768896) (xy 128.574273 -84.736445) (xy 128.534124 -84.697736) (xy 128.500038 -84.653593)
			(xy 128.472742 -84.604958) (xy 128.452819 -84.552867) (xy 128.440693 -84.49843) (xy 128.436622 -84.442808)
			(xy 14.194816 -84.442808) (xy 14.264984 -84.541931) (xy 14.332967 -84.651728) (xy 14.394062 -84.765502)
			(xy 14.448037 -84.882821) (xy 14.494688 -85.00324) (xy 14.533837 -85.126303) (xy 14.565336 -85.251542)
			(xy 14.589065 -85.378483) (xy 14.604935 -85.506643) (xy 14.612885 -85.635538) (xy 14.613382 -85.700108)
			(xy 14.612885 -85.764678) (xy 14.604935 -85.893573) (xy 14.60162 -85.920347) (xy 106.278726 -85.920347)
			(xy 106.278726 -85.865853) (xy 106.286481 -85.811914) (xy 106.301833 -85.759627) (xy 106.32447 -85.710058)
			(xy 106.353931 -85.664214) (xy 106.389616 -85.62303) (xy 106.430798 -85.587343) (xy 106.47664 -85.55788)
			(xy 106.526209 -85.53524) (xy 106.578494 -85.519885) (xy 106.632433 -85.512128) (xy 106.65968 -85.51164)
			(xy 106.68705 -85.512108) (xy 106.74123 -85.519924) (xy 106.793733 -85.535412) (xy 106.84348 -85.558254)
			(xy 106.889447 -85.587978) (xy 106.910378 -85.60562) (xy 106.921706 -85.614856) (xy 106.948263 -85.627032)
			(xy 106.97718 -85.631205) (xy 107.006097 -85.627032) (xy 107.032654 -85.614856) (xy 107.043982 -85.60562)
			(xy 107.064913 -85.587979) (xy 107.110885 -85.558267) (xy 107.160633 -85.535431) (xy 107.213134 -85.51994)
			(xy 107.267311 -85.512113) (xy 107.29468 -85.51164) (xy 107.320231 -85.512049) (xy 107.370877 -85.518857)
			(xy 107.420159 -85.532368) (xy 107.467197 -85.552339) (xy 107.511146 -85.578413) (xy 107.551219 -85.610123)
			(xy 107.569254 -85.628226) (xy 107.57944 -85.638198) (xy 107.604099 -85.652477) (xy 107.631746 -85.65938)
			(xy 107.660223 -85.658369) (xy 107.687311 -85.649523) (xy 107.710896 -85.633531) (xy 107.720384 -85.622892)
			(xy 107.738612 -85.601855) (xy 107.780133 -85.564782) (xy 107.8266 -85.534134) (xy 107.877025 -85.510563)
			(xy 107.930341 -85.494567) (xy 107.985414 -85.486487) (xy 108.013246 -85.485986) (xy 108.040495 -85.486487)
			(xy 108.094437 -85.494249) (xy 108.146725 -85.509607) (xy 108.196296 -85.532251) (xy 108.223505 -85.54974)
			(xy 124.624082 -85.54974) (xy 124.628153 -85.494118) (xy 124.640279 -85.439681) (xy 124.660202 -85.38759)
			(xy 124.687498 -85.338955) (xy 124.721584 -85.294812) (xy 124.761733 -85.256103) (xy 124.807091 -85.223652)
			(xy 124.856691 -85.198151) (xy 124.909475 -85.180144) (xy 124.964318 -85.170014) (xy 125.020052 -85.167977)
			(xy 125.075489 -85.174077) (xy 125.129446 -85.188183) (xy 125.180775 -85.209995) (xy 125.228381 -85.239049)
			(xy 125.271249 -85.274724) (xy 125.308466 -85.316261) (xy 125.339239 -85.362774) (xy 125.362911 -85.413271)
			(xy 125.378979 -85.466678) (xy 125.387099 -85.521854) (xy 125.387385 -85.537548) (xy 132.160262 -85.537548)
			(xy 132.164333 -85.481926) (xy 132.176459 -85.427489) (xy 132.196382 -85.375398) (xy 132.223678 -85.326763)
			(xy 132.257764 -85.28262) (xy 132.297913 -85.243911) (xy 132.343271 -85.21146) (xy 132.392871 -85.185959)
			(xy 132.445655 -85.167952) (xy 132.500498 -85.157822) (xy 132.556232 -85.155785) (xy 132.611669 -85.161885)
			(xy 132.665626 -85.175991) (xy 132.716955 -85.197803) (xy 132.764561 -85.226857) (xy 132.807429 -85.262532)
			(xy 132.844646 -85.304069) (xy 132.875419 -85.350582) (xy 132.899091 -85.401079) (xy 132.915159 -85.454486)
			(xy 132.923279 -85.509662) (xy 132.923788 -85.537548) (xy 132.923556 -85.550248) (xy 155.873702 -85.550248)
			(xy 155.877773 -85.494626) (xy 155.889899 -85.440189) (xy 155.909822 -85.388098) (xy 155.937118 -85.339463)
			(xy 155.971204 -85.29532) (xy 156.011353 -85.256611) (xy 156.056711 -85.22416) (xy 156.106311 -85.198659)
			(xy 156.159095 -85.180652) (xy 156.213938 -85.170522) (xy 156.269672 -85.168485) (xy 156.325109 -85.174585)
			(xy 156.379066 -85.188691) (xy 156.430395 -85.210503) (xy 156.478001 -85.239557) (xy 156.520869 -85.275232)
			(xy 156.558086 -85.316769) (xy 156.588859 -85.363282) (xy 156.612531 -85.413779) (xy 156.624321 -85.452966)
			(xy 158.007302 -85.452966) (xy 158.011373 -85.397344) (xy 158.023499 -85.342907) (xy 158.043422 -85.290816)
			(xy 158.070718 -85.242181) (xy 158.104804 -85.198038) (xy 158.144953 -85.159329) (xy 158.190311 -85.126878)
			(xy 158.239911 -85.101377) (xy 158.292695 -85.08337) (xy 158.347538 -85.07324) (xy 158.403272 -85.071203)
			(xy 158.458709 -85.077303) (xy 158.512666 -85.091409) (xy 158.563995 -85.113221) (xy 158.611601 -85.142275)
			(xy 158.654469 -85.17795) (xy 158.691686 -85.219487) (xy 158.722459 -85.266) (xy 158.746131 -85.316497)
			(xy 158.762199 -85.369904) (xy 158.770319 -85.42508) (xy 158.770828 -85.452966) (xy 158.770319 -85.480852)
			(xy 158.762199 -85.536028) (xy 158.746131 -85.589435) (xy 158.722459 -85.639932) (xy 158.691686 -85.686445)
			(xy 158.654469 -85.727982) (xy 158.611601 -85.763657) (xy 158.563995 -85.792711) (xy 158.512666 -85.814523)
			(xy 158.458709 -85.828629) (xy 158.403272 -85.834729) (xy 158.347538 -85.832692) (xy 158.292695 -85.822562)
			(xy 158.239911 -85.804555) (xy 158.190311 -85.779054) (xy 158.144953 -85.746603) (xy 158.104804 -85.707894)
			(xy 158.070718 -85.663751) (xy 158.043422 -85.615116) (xy 158.023499 -85.563025) (xy 158.011373 -85.508588)
			(xy 158.007302 -85.452966) (xy 156.624321 -85.452966) (xy 156.628599 -85.467186) (xy 156.636719 -85.522362)
			(xy 156.637228 -85.550248) (xy 156.636719 -85.578134) (xy 156.628599 -85.63331) (xy 156.612531 -85.686717)
			(xy 156.588859 -85.737214) (xy 156.558086 -85.783727) (xy 156.520869 -85.825264) (xy 156.478001 -85.860939)
			(xy 156.430395 -85.889993) (xy 156.379066 -85.911805) (xy 156.325109 -85.925911) (xy 156.269672 -85.932011)
			(xy 156.213938 -85.929974) (xy 156.159095 -85.919844) (xy 156.106311 -85.901837) (xy 156.056711 -85.876336)
			(xy 156.011353 -85.843885) (xy 155.971204 -85.805176) (xy 155.937118 -85.761033) (xy 155.909822 -85.712398)
			(xy 155.889899 -85.660307) (xy 155.877773 -85.60587) (xy 155.873702 -85.550248) (xy 132.923556 -85.550248)
			(xy 132.923279 -85.565434) (xy 132.915159 -85.62061) (xy 132.899091 -85.674017) (xy 132.875419 -85.724514)
			(xy 132.844646 -85.771027) (xy 132.807429 -85.812564) (xy 132.764561 -85.848239) (xy 132.716955 -85.877293)
			(xy 132.665626 -85.899105) (xy 132.611669 -85.913211) (xy 132.556232 -85.919311) (xy 132.500498 -85.917274)
			(xy 132.445655 -85.907144) (xy 132.392871 -85.889137) (xy 132.343271 -85.863636) (xy 132.297913 -85.831185)
			(xy 132.257764 -85.792476) (xy 132.223678 -85.748333) (xy 132.196382 -85.699698) (xy 132.176459 -85.647607)
			(xy 132.164333 -85.59317) (xy 132.160262 -85.537548) (xy 125.387385 -85.537548) (xy 125.387608 -85.54974)
			(xy 125.387099 -85.577626) (xy 125.378979 -85.632802) (xy 125.362911 -85.686209) (xy 125.339239 -85.736706)
			(xy 125.308466 -85.783219) (xy 125.271249 -85.824756) (xy 125.228381 -85.860431) (xy 125.180775 -85.889485)
			(xy 125.129446 -85.911297) (xy 125.075489 -85.925403) (xy 125.020052 -85.931503) (xy 124.964318 -85.929466)
			(xy 124.909475 -85.919336) (xy 124.856691 -85.901329) (xy 124.807091 -85.875828) (xy 124.761733 -85.843377)
			(xy 124.721584 -85.804668) (xy 124.687498 -85.760525) (xy 124.660202 -85.71189) (xy 124.640279 -85.659799)
			(xy 124.628153 -85.605362) (xy 124.624082 -85.54974) (xy 108.223505 -85.54974) (xy 108.24214 -85.561718)
			(xy 108.283324 -85.597409) (xy 108.31901 -85.638597) (xy 108.348471 -85.684445) (xy 108.371109 -85.734018)
			(xy 108.386461 -85.786308) (xy 108.394216 -85.840251) (xy 108.394216 -85.894749) (xy 108.386461 -85.948692)
			(xy 108.371109 -86.000982) (xy 108.348471 -86.050555) (xy 108.31901 -86.096403) (xy 108.283324 -86.137591)
			(xy 108.24214 -86.173282) (xy 108.203765 -86.197948) (xy 112.901982 -86.197948) (xy 112.906053 -86.142326)
			(xy 112.918179 -86.087889) (xy 112.938102 -86.035798) (xy 112.965398 -85.987163) (xy 112.999484 -85.94302)
			(xy 113.039633 -85.904311) (xy 113.084991 -85.87186) (xy 113.134591 -85.846359) (xy 113.187375 -85.828352)
			(xy 113.242218 -85.818222) (xy 113.297952 -85.816185) (xy 113.353389 -85.822285) (xy 113.407346 -85.836391)
			(xy 113.458675 -85.858203) (xy 113.506281 -85.887257) (xy 113.549149 -85.922932) (xy 113.586366 -85.964469)
			(xy 113.617139 -86.010982) (xy 113.639296 -86.058248) (xy 114.019582 -86.058248) (xy 114.023653 -86.002626)
			(xy 114.035779 -85.948189) (xy 114.055702 -85.896098) (xy 114.082998 -85.847463) (xy 114.117084 -85.80332)
			(xy 114.157233 -85.764611) (xy 114.202591 -85.73216) (xy 114.252191 -85.706659) (xy 114.304975 -85.688652)
			(xy 114.359818 -85.678522) (xy 114.415552 -85.676485) (xy 114.470989 -85.682585) (xy 114.524946 -85.696691)
			(xy 114.576275 -85.718503) (xy 114.623881 -85.747557) (xy 114.666749 -85.783232) (xy 114.703966 -85.824769)
			(xy 114.734739 -85.871282) (xy 114.758411 -85.921779) (xy 114.774479 -85.975186) (xy 114.782599 -86.030362)
			(xy 114.783108 -86.058248) (xy 114.782599 -86.086134) (xy 114.774479 -86.14131) (xy 114.758411 -86.194717)
			(xy 114.734739 -86.245214) (xy 114.703966 -86.291727) (xy 114.666749 -86.333264) (xy 114.623881 -86.368939)
			(xy 114.576275 -86.397993) (xy 114.524946 -86.419805) (xy 114.470989 -86.433911) (xy 114.415552 -86.440011)
			(xy 114.359818 -86.437974) (xy 114.304975 -86.427844) (xy 114.252191 -86.409837) (xy 114.202591 -86.384336)
			(xy 114.157233 -86.351885) (xy 114.117084 -86.313176) (xy 114.082998 -86.269033) (xy 114.055702 -86.220398)
			(xy 114.035779 -86.168307) (xy 114.023653 -86.11387) (xy 114.019582 -86.058248) (xy 113.639296 -86.058248)
			(xy 113.640811 -86.061479) (xy 113.656879 -86.114886) (xy 113.664999 -86.170062) (xy 113.665508 -86.197948)
			(xy 113.664999 -86.225834) (xy 113.656879 -86.28101) (xy 113.640811 -86.334417) (xy 113.617139 -86.384914)
			(xy 113.586366 -86.431427) (xy 113.567979 -86.451948) (xy 115.187982 -86.451948) (xy 115.192053 -86.396326)
			(xy 115.204179 -86.341889) (xy 115.224102 -86.289798) (xy 115.251398 -86.241163) (xy 115.285484 -86.19702)
			(xy 115.325633 -86.158311) (xy 115.370991 -86.12586) (xy 115.420591 -86.100359) (xy 115.473375 -86.082352)
			(xy 115.528218 -86.072222) (xy 115.583952 -86.070185) (xy 115.639389 -86.076285) (xy 115.693346 -86.090391)
			(xy 115.744675 -86.112203) (xy 115.792281 -86.141257) (xy 115.835149 -86.176932) (xy 115.872366 -86.218469)
			(xy 115.903139 -86.264982) (xy 115.926811 -86.315479) (xy 115.942879 -86.368886) (xy 115.950999 -86.424062)
			(xy 115.951508 -86.451948) (xy 117.727982 -86.451948) (xy 117.732053 -86.396326) (xy 117.744179 -86.341889)
			(xy 117.764102 -86.289798) (xy 117.791398 -86.241163) (xy 117.825484 -86.19702) (xy 117.865633 -86.158311)
			(xy 117.910991 -86.12586) (xy 117.960591 -86.100359) (xy 118.013375 -86.082352) (xy 118.068218 -86.072222)
			(xy 118.123952 -86.070185) (xy 118.179389 -86.076285) (xy 118.233346 -86.090391) (xy 118.284675 -86.112203)
			(xy 118.332281 -86.141257) (xy 118.375149 -86.176932) (xy 118.412366 -86.218469) (xy 118.443139 -86.264982)
			(xy 118.466811 -86.315479) (xy 118.482879 -86.368886) (xy 118.490999 -86.424062) (xy 118.491508 -86.451948)
			(xy 118.490999 -86.479834) (xy 118.487253 -86.505288) (xy 118.614442 -86.505288) (xy 118.618513 -86.449666)
			(xy 118.630639 -86.395229) (xy 118.650562 -86.343138) (xy 118.677858 -86.294503) (xy 118.711944 -86.25036)
			(xy 118.752093 -86.211651) (xy 118.797451 -86.1792) (xy 118.847051 -86.153699) (xy 118.899835 -86.135692)
			(xy 118.954678 -86.125562) (xy 119.010412 -86.123525) (xy 119.065849 -86.129625) (xy 119.119806 -86.143731)
			(xy 119.171135 -86.165543) (xy 119.218741 -86.194597) (xy 119.261609 -86.230272) (xy 119.298826 -86.271809)
			(xy 119.304575 -86.280498) (xy 139.119862 -86.280498) (xy 139.123933 -86.224876) (xy 139.136059 -86.170439)
			(xy 139.155982 -86.118348) (xy 139.183278 -86.069713) (xy 139.217364 -86.02557) (xy 139.257513 -85.986861)
			(xy 139.302871 -85.95441) (xy 139.352471 -85.928909) (xy 139.405255 -85.910902) (xy 139.460098 -85.900772)
			(xy 139.515832 -85.898735) (xy 139.571269 -85.904835) (xy 139.625226 -85.918941) (xy 139.676555 -85.940753)
			(xy 139.724161 -85.969807) (xy 139.767029 -86.005482) (xy 139.804246 -86.047019) (xy 139.835019 -86.093532)
			(xy 139.858691 -86.144029) (xy 139.874759 -86.197436) (xy 139.882879 -86.252612) (xy 139.883388 -86.280498)
			(xy 139.882879 -86.308384) (xy 139.874759 -86.36356) (xy 139.858691 -86.416967) (xy 139.835019 -86.467464)
			(xy 139.804246 -86.513977) (xy 139.767029 -86.555514) (xy 139.724161 -86.591189) (xy 139.676555 -86.620243)
			(xy 139.625226 -86.642055) (xy 139.571269 -86.656161) (xy 139.515832 -86.662261) (xy 139.460098 -86.660224)
			(xy 139.405255 -86.650094) (xy 139.352471 -86.632087) (xy 139.302871 -86.606586) (xy 139.257513 -86.574135)
			(xy 139.217364 -86.535426) (xy 139.183278 -86.491283) (xy 139.155982 -86.442648) (xy 139.136059 -86.390557)
			(xy 139.123933 -86.33612) (xy 139.119862 -86.280498) (xy 119.304575 -86.280498) (xy 119.329599 -86.318322)
			(xy 119.353271 -86.368819) (xy 119.369339 -86.422226) (xy 119.377459 -86.477402) (xy 119.377968 -86.505288)
			(xy 119.377459 -86.533174) (xy 119.369339 -86.58835) (xy 119.353271 -86.641757) (xy 119.329599 -86.692254)
			(xy 119.298826 -86.738767) (xy 119.261609 -86.780304) (xy 119.218741 -86.815979) (xy 119.171135 -86.845033)
			(xy 119.119806 -86.866845) (xy 119.065849 -86.880951) (xy 119.010412 -86.887051) (xy 118.954678 -86.885014)
			(xy 118.899835 -86.874884) (xy 118.847051 -86.856877) (xy 118.797451 -86.831376) (xy 118.752093 -86.798925)
			(xy 118.711944 -86.760216) (xy 118.677858 -86.716073) (xy 118.650562 -86.667438) (xy 118.630639 -86.615347)
			(xy 118.618513 -86.56091) (xy 118.614442 -86.505288) (xy 118.487253 -86.505288) (xy 118.482879 -86.53501)
			(xy 118.466811 -86.588417) (xy 118.443139 -86.638914) (xy 118.412366 -86.685427) (xy 118.375149 -86.726964)
			(xy 118.332281 -86.762639) (xy 118.284675 -86.791693) (xy 118.233346 -86.813505) (xy 118.179389 -86.827611)
			(xy 118.123952 -86.833711) (xy 118.068218 -86.831674) (xy 118.013375 -86.821544) (xy 117.960591 -86.803537)
			(xy 117.910991 -86.778036) (xy 117.865633 -86.745585) (xy 117.825484 -86.706876) (xy 117.791398 -86.662733)
			(xy 117.764102 -86.614098) (xy 117.744179 -86.562007) (xy 117.732053 -86.50757) (xy 117.727982 -86.451948)
			(xy 115.951508 -86.451948) (xy 115.950999 -86.479834) (xy 115.942879 -86.53501) (xy 115.926811 -86.588417)
			(xy 115.903139 -86.638914) (xy 115.872366 -86.685427) (xy 115.835149 -86.726964) (xy 115.792281 -86.762639)
			(xy 115.744675 -86.791693) (xy 115.693346 -86.813505) (xy 115.639389 -86.827611) (xy 115.583952 -86.833711)
			(xy 115.528218 -86.831674) (xy 115.473375 -86.821544) (xy 115.420591 -86.803537) (xy 115.370991 -86.778036)
			(xy 115.325633 -86.745585) (xy 115.285484 -86.706876) (xy 115.251398 -86.662733) (xy 115.224102 -86.614098)
			(xy 115.204179 -86.562007) (xy 115.192053 -86.50757) (xy 115.187982 -86.451948) (xy 113.567979 -86.451948)
			(xy 113.549149 -86.472964) (xy 113.506281 -86.508639) (xy 113.458675 -86.537693) (xy 113.407346 -86.559505)
			(xy 113.353389 -86.573611) (xy 113.297952 -86.579711) (xy 113.242218 -86.577674) (xy 113.187375 -86.567544)
			(xy 113.134591 -86.549537) (xy 113.084991 -86.524036) (xy 113.039633 -86.491585) (xy 112.999484 -86.452876)
			(xy 112.965398 -86.408733) (xy 112.938102 -86.360098) (xy 112.918179 -86.308007) (xy 112.906053 -86.25357)
			(xy 112.901982 -86.197948) (xy 108.203765 -86.197948) (xy 108.196296 -86.202749) (xy 108.146725 -86.225393)
			(xy 108.094437 -86.240751) (xy 108.040495 -86.248513) (xy 108.013246 -86.249002) (xy 107.987695 -86.248593)
			(xy 107.937049 -86.241787) (xy 107.887765 -86.228278) (xy 107.840727 -86.208307) (xy 107.796779 -86.182232)
			(xy 107.756706 -86.150521) (xy 107.738672 -86.132416) (xy 107.728465 -86.122466) (xy 107.703813 -86.108179)
			(xy 107.676171 -86.101269) (xy 107.647696 -86.102276) (xy 107.620611 -86.111119) (xy 107.597029 -86.127111)
			(xy 107.587542 -86.13775) (xy 107.56931 -86.158783) (xy 107.527788 -86.195855) (xy 107.481323 -86.226502)
			(xy 107.430898 -86.250073) (xy 107.377584 -86.26607) (xy 107.322511 -86.274153) (xy 107.29468 -86.274656)
			(xy 107.267309 -86.274212) (xy 107.213128 -86.266391) (xy 107.160625 -86.250897) (xy 107.110878 -86.22805)
			(xy 107.064913 -86.19832) (xy 107.043982 -86.180676) (xy 107.032654 -86.17144) (xy 107.006097 -86.159264)
			(xy 106.97718 -86.155091) (xy 106.948263 -86.159264) (xy 106.921706 -86.17144) (xy 106.910378 -86.180676)
			(xy 106.889424 -86.198288) (xy 106.843458 -86.228005) (xy 106.793716 -86.250846) (xy 106.74122 -86.266344)
			(xy 106.687048 -86.274179) (xy 106.65968 -86.274656) (xy 106.632433 -86.274072) (xy 106.578494 -86.266315)
			(xy 106.526209 -86.25096) (xy 106.47664 -86.22832) (xy 106.430798 -86.198857) (xy 106.389616 -86.16317)
			(xy 106.353931 -86.121986) (xy 106.32447 -86.076142) (xy 106.301833 -86.026573) (xy 106.286481 -85.974286)
			(xy 106.278726 -85.920347) (xy 14.60162 -85.920347) (xy 14.589065 -86.021733) (xy 14.565336 -86.148674)
			(xy 14.533837 -86.273913) (xy 14.494688 -86.396976) (xy 14.448037 -86.517395) (xy 14.394062 -86.634714)
			(xy 14.332967 -86.748488) (xy 14.264984 -86.858285) (xy 14.19037 -86.963688) (xy 14.109409 -87.064298)
			(xy 14.107285 -87.066628) (xy 150.270462 -87.066628) (xy 150.274533 -87.011006) (xy 150.286659 -86.956569)
			(xy 150.306582 -86.904478) (xy 150.333878 -86.855843) (xy 150.367964 -86.8117) (xy 150.408113 -86.772991)
			(xy 150.453471 -86.74054) (xy 150.503071 -86.715039) (xy 150.555855 -86.697032) (xy 150.610698 -86.686902)
			(xy 150.666432 -86.684865) (xy 150.721869 -86.690965) (xy 150.775826 -86.705071) (xy 150.827155 -86.726883)
			(xy 150.874761 -86.755937) (xy 150.917629 -86.791612) (xy 150.954846 -86.833149) (xy 150.985619 -86.879662)
			(xy 151.009291 -86.930159) (xy 151.025359 -86.983566) (xy 151.033479 -87.038742) (xy 151.033988 -87.066628)
			(xy 151.033479 -87.094514) (xy 151.025359 -87.14969) (xy 151.009291 -87.203097) (xy 150.985619 -87.253594)
			(xy 150.954846 -87.300107) (xy 150.917629 -87.341644) (xy 150.874761 -87.377319) (xy 150.827155 -87.406373)
			(xy 150.775826 -87.428185) (xy 150.721869 -87.442291) (xy 150.666432 -87.448391) (xy 150.610698 -87.446354)
			(xy 150.555855 -87.436224) (xy 150.503071 -87.418217) (xy 150.453471 -87.392716) (xy 150.408113 -87.360265)
			(xy 150.367964 -87.321556) (xy 150.333878 -87.277413) (xy 150.306582 -87.228778) (xy 150.286659 -87.176687)
			(xy 150.274533 -87.12225) (xy 150.270462 -87.066628) (xy 14.107285 -87.066628) (xy 14.022409 -87.159733)
			(xy 13.929698 -87.249632) (xy 13.831628 -87.333653) (xy 13.728573 -87.411477) (xy 13.620922 -87.482809)
			(xy 13.520213 -87.540953) (xy 39.413146 -87.540953) (xy 39.413146 -87.486447) (xy 39.420902 -87.432497)
			(xy 39.436258 -87.380199) (xy 39.458899 -87.330619) (xy 39.488366 -87.284766) (xy 39.524059 -87.243573)
			(xy 39.56525 -87.207878) (xy 39.611102 -87.178409) (xy 39.660681 -87.155765) (xy 39.712977 -87.140407)
			(xy 39.766927 -87.132647) (xy 39.79418 -87.13216) (xy 39.821551 -87.132623) (xy 39.87573 -87.140439)
			(xy 39.928234 -87.155928) (xy 39.977981 -87.178771) (xy 40.023947 -87.208498) (xy 40.044878 -87.22614)
			(xy 40.056206 -87.235376) (xy 40.082763 -87.247552) (xy 40.11168 -87.251725) (xy 40.140597 -87.247552)
			(xy 40.167154 -87.235376) (xy 40.178482 -87.22614) (xy 40.199415 -87.208499) (xy 40.245383 -87.178775)
			(xy 40.295129 -87.155929) (xy 40.347631 -87.140433) (xy 40.401809 -87.132604) (xy 40.456551 -87.132604)
			(xy 40.510729 -87.140433) (xy 40.563231 -87.155929) (xy 40.612977 -87.178775) (xy 40.658945 -87.208499)
			(xy 40.679878 -87.22614) (xy 40.691206 -87.235376) (xy 40.717763 -87.247552) (xy 40.74668 -87.251725)
			(xy 40.775597 -87.247552) (xy 40.802154 -87.235376) (xy 40.813482 -87.22614) (xy 40.834415 -87.208502)
			(xy 40.880387 -87.178789) (xy 40.930134 -87.155952) (xy 40.982635 -87.140461) (xy 41.036811 -87.132633)
			(xy 41.06418 -87.13216) (xy 41.090914 -87.132638) (xy 41.143861 -87.140089) (xy 41.195248 -87.154861)
			(xy 41.244068 -87.176666) (xy 41.289364 -87.205076) (xy 41.330248 -87.239534) (xy 41.365919 -87.279364)
			(xy 41.381172 -87.301324) (xy 41.389506 -87.312879) (xy 41.411295 -87.331214) (xy 41.437301 -87.342818)
			(xy 41.4655 -87.34679) (xy 41.493699 -87.342818) (xy 41.519705 -87.331214) (xy 41.541494 -87.312879)
			(xy 41.549828 -87.301324) (xy 41.565117 -87.27939) (xy 41.600787 -87.239564) (xy 41.641668 -87.205106)
			(xy 41.686957 -87.176692) (xy 41.735769 -87.154877) (xy 41.787148 -87.140088) (xy 41.840088 -87.132614)
			(xy 41.86682 -87.13216) (xy 41.894068 -87.132712) (xy 41.948009 -87.14047) (xy 42.000297 -87.155825)
			(xy 42.049867 -87.178466) (xy 42.095711 -87.20793) (xy 42.136896 -87.243618) (xy 42.172582 -87.284805)
			(xy 42.202044 -87.33065) (xy 42.224682 -87.380222) (xy 42.240035 -87.432511) (xy 42.24779 -87.486452)
			(xy 42.24779 -87.540948) (xy 42.240035 -87.594889) (xy 42.224682 -87.647178) (xy 42.202044 -87.69675)
			(xy 42.172582 -87.742595) (xy 42.136896 -87.783782) (xy 42.095711 -87.81947) (xy 42.049867 -87.848934)
			(xy 42.000297 -87.871575) (xy 41.948009 -87.88693) (xy 41.894068 -87.894688) (xy 41.86682 -87.895176)
			(xy 41.840084 -87.894727) (xy 41.787136 -87.887274) (xy 41.735747 -87.872499) (xy 41.686926 -87.85069)
			(xy 41.64163 -87.822275) (xy 41.600747 -87.787812) (xy 41.565079 -87.747976) (xy 41.549828 -87.726012)
			(xy 41.541494 -87.714457) (xy 41.519705 -87.696122) (xy 41.493699 -87.684518) (xy 41.4655 -87.680546)
			(xy 41.437301 -87.684518) (xy 41.411295 -87.696122) (xy 41.389506 -87.714457) (xy 41.381172 -87.726012)
			(xy 41.365895 -87.747955) (xy 41.330221 -87.787779) (xy 41.289338 -87.822234) (xy 41.244047 -87.850647)
			(xy 41.195234 -87.872461) (xy 41.143854 -87.887249) (xy 41.090913 -87.894722) (xy 41.06418 -87.895176)
			(xy 41.036809 -87.894728) (xy 40.982629 -87.886906) (xy 40.930125 -87.871413) (xy 40.880379 -87.848568)
			(xy 40.834413 -87.818839) (xy 40.813482 -87.801196) (xy 40.802154 -87.79196) (xy 40.775597 -87.779784)
			(xy 40.74668 -87.775611) (xy 40.717763 -87.779784) (xy 40.691206 -87.79196) (xy 40.679878 -87.801196)
			(xy 40.658945 -87.818837) (xy 40.612977 -87.848561) (xy 40.563231 -87.871407) (xy 40.510729 -87.886903)
			(xy 40.456551 -87.894732) (xy 40.401809 -87.894732) (xy 40.347631 -87.886903) (xy 40.295129 -87.871407)
			(xy 40.245383 -87.848561) (xy 40.199415 -87.818837) (xy 40.178482 -87.801196) (xy 40.167154 -87.79196)
			(xy 40.140597 -87.779784) (xy 40.11168 -87.775611) (xy 40.082763 -87.779784) (xy 40.056206 -87.79196)
			(xy 40.044878 -87.801196) (xy 40.023927 -87.818811) (xy 39.977959 -87.848527) (xy 39.928217 -87.871367)
			(xy 39.87572 -87.886864) (xy 39.821548 -87.894699) (xy 39.79418 -87.895176) (xy 39.766927 -87.894753)
			(xy 39.712977 -87.886993) (xy 39.660681 -87.871635) (xy 39.611102 -87.848991) (xy 39.56525 -87.819522)
			(xy 39.524059 -87.783827) (xy 39.488366 -87.742634) (xy 39.458899 -87.696781) (xy 39.436258 -87.647201)
			(xy 39.420902 -87.594903) (xy 39.413146 -87.540953) (xy 13.520213 -87.540953) (xy 13.509083 -87.547379)
			(xy 13.393482 -87.604941) (xy 13.274557 -87.655278) (xy 13.152758 -87.698198) (xy 13.028548 -87.733539)
			(xy 12.902399 -87.761166) (xy 12.774787 -87.780975) (xy 12.646198 -87.792891) (xy 12.51712 -87.796868)
			(xy 12.388042 -87.792891) (xy 12.259453 -87.780975) (xy 12.131841 -87.761166) (xy 12.005692 -87.733539)
			(xy 11.881482 -87.698198) (xy 11.759683 -87.655278) (xy 11.640758 -87.604941) (xy 11.525157 -87.547379)
			(xy 11.413318 -87.482809) (xy 11.305667 -87.411477) (xy 11.202612 -87.333653) (xy 11.104542 -87.249632)
			(xy 11.011831 -87.159733) (xy 10.924831 -87.064298) (xy 10.84387 -86.963688) (xy 10.769256 -86.858285)
			(xy 10.701273 -86.748488) (xy 10.640178 -86.634714) (xy 10.586203 -86.517395) (xy 10.539552 -86.396976)
			(xy 10.500403 -86.273913) (xy 10.468904 -86.148674) (xy 10.445175 -86.021733) (xy 10.429305 -85.893573)
			(xy 10.421355 -85.764678) (xy 6.055868 -85.764678) (xy 6.055868 -88.016588) (xy 109.442502 -88.016588)
			(xy 109.446573 -87.960966) (xy 109.458699 -87.906529) (xy 109.478622 -87.854438) (xy 109.505918 -87.805803)
			(xy 109.540004 -87.76166) (xy 109.580153 -87.722951) (xy 109.625511 -87.6905) (xy 109.675111 -87.664999)
			(xy 109.727895 -87.646992) (xy 109.782738 -87.636862) (xy 109.838472 -87.634825) (xy 109.893909 -87.640925)
			(xy 109.947866 -87.655031) (xy 109.999195 -87.676843) (xy 110.046801 -87.705897) (xy 110.089669 -87.741572)
			(xy 110.126886 -87.783109) (xy 110.157659 -87.829622) (xy 110.181331 -87.880119) (xy 110.197399 -87.933526)
			(xy 110.205519 -87.988702) (xy 110.206028 -88.016588) (xy 110.205519 -88.044474) (xy 110.197399 -88.09965)
			(xy 110.181331 -88.153057) (xy 110.157659 -88.203554) (xy 110.126886 -88.250067) (xy 110.089669 -88.291604)
			(xy 110.046801 -88.327279) (xy 109.999195 -88.356333) (xy 109.947866 -88.378145) (xy 109.893909 -88.392251)
			(xy 109.838472 -88.398351) (xy 109.782738 -88.396314) (xy 109.727895 -88.386184) (xy 109.675111 -88.368177)
			(xy 109.625511 -88.342676) (xy 109.580153 -88.310225) (xy 109.540004 -88.271516) (xy 109.505918 -88.227373)
			(xy 109.478622 -88.178738) (xy 109.458699 -88.126647) (xy 109.446573 -88.07221) (xy 109.442502 -88.016588)
			(xy 6.055868 -88.016588) (xy 6.055868 -88.588088) (xy 144.863312 -88.588088) (xy 144.863798 -88.560837)
			(xy 144.871554 -88.506889) (xy 144.886909 -88.454594) (xy 144.909551 -88.405017) (xy 144.939017 -88.359167)
			(xy 144.974708 -88.317976) (xy 145.015899 -88.282285) (xy 145.061749 -88.252819) (xy 145.111326 -88.230177)
			(xy 145.163621 -88.214822) (xy 145.217569 -88.207066) (xy 145.272071 -88.207066) (xy 145.326019 -88.214822)
			(xy 145.378314 -88.230177) (xy 145.427891 -88.252819) (xy 145.473741 -88.282285) (xy 145.514932 -88.317976)
			(xy 145.550623 -88.359167) (xy 145.580089 -88.405017) (xy 145.602731 -88.454594) (xy 145.618086 -88.506889)
			(xy 145.625842 -88.560837) (xy 145.626328 -88.588088) (xy 145.625856 -88.615168) (xy 145.618202 -88.668785)
			(xy 145.603047 -88.720782) (xy 145.580695 -88.770114) (xy 145.551594 -88.815792) (xy 145.516329 -88.856898)
			(xy 145.49628 -88.875108) (xy 145.485442 -88.885185) (xy 145.469659 -88.910204) (xy 145.46171 -88.938698)
			(xy 145.462262 -88.968275) (xy 145.47127 -88.996452) (xy 145.487977 -89.020865) (xy 145.51098 -89.039464)
			(xy 145.524474 -89.045542) (xy 145.550338 -89.056711) (xy 145.598734 -89.085547) (xy 145.642361 -89.121188)
			(xy 145.68027 -89.162861) (xy 145.711636 -89.209657) (xy 145.735776 -89.260558) (xy 145.752165 -89.314457)
			(xy 145.760446 -89.37018) (xy 145.760948 -89.398348) (xy 145.760462 -89.425599) (xy 145.752706 -89.479547)
			(xy 145.751191 -89.484708) (xy 148.479762 -89.484708) (xy 148.483833 -89.429086) (xy 148.495959 -89.374649)
			(xy 148.515882 -89.322558) (xy 148.543178 -89.273923) (xy 148.577264 -89.22978) (xy 148.617413 -89.191071)
			(xy 148.662771 -89.15862) (xy 148.712371 -89.133119) (xy 148.765155 -89.115112) (xy 148.819998 -89.104982)
			(xy 148.875732 -89.102945) (xy 148.931169 -89.109045) (xy 148.985126 -89.123151) (xy 149.036455 -89.144963)
			(xy 149.084061 -89.174017) (xy 149.126929 -89.209692) (xy 149.164146 -89.251229) (xy 149.194919 -89.297742)
			(xy 149.218591 -89.348239) (xy 149.234659 -89.401646) (xy 149.242779 -89.456822) (xy 149.243288 -89.484708)
			(xy 149.242779 -89.512594) (xy 149.234659 -89.56777) (xy 149.218591 -89.621177) (xy 149.194919 -89.671674)
			(xy 149.164146 -89.718187) (xy 149.126929 -89.759724) (xy 149.084061 -89.795399) (xy 149.036455 -89.824453)
			(xy 148.985126 -89.846265) (xy 148.931169 -89.860371) (xy 148.875732 -89.866471) (xy 148.819998 -89.864434)
			(xy 148.765155 -89.854304) (xy 148.712371 -89.836297) (xy 148.662771 -89.810796) (xy 148.617413 -89.778345)
			(xy 148.577264 -89.739636) (xy 148.543178 -89.695493) (xy 148.515882 -89.646858) (xy 148.495959 -89.594767)
			(xy 148.483833 -89.54033) (xy 148.479762 -89.484708) (xy 145.751191 -89.484708) (xy 145.737351 -89.531842)
			(xy 145.714709 -89.581419) (xy 145.685243 -89.627269) (xy 145.649552 -89.66846) (xy 145.608361 -89.704151)
			(xy 145.562511 -89.733617) (xy 145.512934 -89.756259) (xy 145.460639 -89.771614) (xy 145.406691 -89.77937)
			(xy 145.352189 -89.77937) (xy 145.298241 -89.771614) (xy 145.245946 -89.756259) (xy 145.196369 -89.733617)
			(xy 145.150519 -89.704151) (xy 145.109328 -89.66846) (xy 145.073637 -89.627269) (xy 145.044171 -89.581419)
			(xy 145.021529 -89.531842) (xy 145.006174 -89.479547) (xy 144.998418 -89.425599) (xy 144.997932 -89.398348)
			(xy 144.998374 -89.371267) (xy 145.006036 -89.317649) (xy 145.021198 -89.265653) (xy 145.043556 -89.216321)
			(xy 145.072661 -89.170643) (xy 145.10793 -89.129538) (xy 145.12798 -89.111328) (xy 145.138759 -89.101197)
			(xy 145.154532 -89.07619) (xy 145.162478 -89.047711) (xy 145.161931 -89.01815) (xy 145.152937 -88.989986)
			(xy 145.13625 -88.965579) (xy 145.113269 -88.946977) (xy 145.099786 -88.940894) (xy 145.073927 -88.929716)
			(xy 145.025533 -88.900879) (xy 144.981908 -88.865237) (xy 144.944 -88.823566) (xy 144.912634 -88.776772)
			(xy 144.888493 -88.725873) (xy 144.872102 -88.671976) (xy 144.863817 -88.616255) (xy 144.863312 -88.588088)
			(xy 6.055868 -88.588088) (xy 6.055868 -91.658948) (xy 10.491468 -91.658948) (xy 10.495539 -91.603326)
			(xy 10.507665 -91.548889) (xy 10.527588 -91.496798) (xy 10.554884 -91.448163) (xy 10.58897 -91.40402)
			(xy 10.629119 -91.365311) (xy 10.674477 -91.33286) (xy 10.724077 -91.307359) (xy 10.776861 -91.289352)
			(xy 10.831704 -91.279222) (xy 10.887438 -91.277185) (xy 10.942875 -91.283285) (xy 10.996832 -91.297391)
			(xy 11.048161 -91.319203) (xy 11.095767 -91.348257) (xy 11.138635 -91.383932) (xy 11.175852 -91.425469)
			(xy 11.206625 -91.471982) (xy 11.230297 -91.522479) (xy 11.246365 -91.575886) (xy 11.254485 -91.631062)
			(xy 11.254994 -91.658948) (xy 11.513818 -91.658948) (xy 11.517889 -91.603326) (xy 11.530015 -91.548889)
			(xy 11.549938 -91.496798) (xy 11.577234 -91.448163) (xy 11.61132 -91.40402) (xy 11.651469 -91.365311)
			(xy 11.696827 -91.33286) (xy 11.746427 -91.307359) (xy 11.799211 -91.289352) (xy 11.854054 -91.279222)
			(xy 11.909788 -91.277185) (xy 11.965225 -91.283285) (xy 12.019182 -91.297391) (xy 12.070511 -91.319203)
			(xy 12.118117 -91.348257) (xy 12.160985 -91.383932) (xy 12.198202 -91.425469) (xy 12.228975 -91.471982)
			(xy 12.252647 -91.522479) (xy 12.268715 -91.575886) (xy 12.276835 -91.631062) (xy 12.277344 -91.658948)
			(xy 13.636242 -91.658948) (xy 13.640313 -91.603326) (xy 13.652439 -91.548889) (xy 13.672362 -91.496798)
			(xy 13.699658 -91.448163) (xy 13.733744 -91.40402) (xy 13.773893 -91.365311) (xy 13.819251 -91.33286)
			(xy 13.868851 -91.307359) (xy 13.921635 -91.289352) (xy 13.976478 -91.279222) (xy 14.032212 -91.277185)
			(xy 14.087649 -91.283285) (xy 14.141606 -91.297391) (xy 14.192935 -91.319203) (xy 14.240541 -91.348257)
			(xy 14.283409 -91.383932) (xy 14.320626 -91.425469) (xy 14.351399 -91.471982) (xy 14.375071 -91.522479)
			(xy 14.391139 -91.575886) (xy 14.397382 -91.618308) (xy 16.808956 -91.618308) (xy 16.813027 -91.562686)
			(xy 16.825153 -91.508249) (xy 16.845076 -91.456158) (xy 16.872372 -91.407523) (xy 16.906458 -91.36338)
			(xy 16.946607 -91.324671) (xy 16.991965 -91.29222) (xy 17.041565 -91.266719) (xy 17.094349 -91.248712)
			(xy 17.149192 -91.238582) (xy 17.204926 -91.236545) (xy 17.260363 -91.242645) (xy 17.31432 -91.256751)
			(xy 17.365649 -91.278563) (xy 17.407092 -91.303856) (xy 57.225182 -91.303856) (xy 57.229253 -91.248234)
			(xy 57.241379 -91.193797) (xy 57.261302 -91.141706) (xy 57.288598 -91.093071) (xy 57.322684 -91.048928)
			(xy 57.362833 -91.010219) (xy 57.408191 -90.977768) (xy 57.457791 -90.952267) (xy 57.510575 -90.93426)
			(xy 57.565418 -90.92413) (xy 57.621152 -90.922093) (xy 57.676589 -90.928193) (xy 57.730546 -90.942299)
			(xy 57.781875 -90.964111) (xy 57.829481 -90.993165) (xy 57.872349 -91.02884) (xy 57.909566 -91.070377)
			(xy 57.940339 -91.11689) (xy 57.964011 -91.167387) (xy 57.973661 -91.199462) (xy 112.887758 -91.199462)
			(xy 112.891829 -91.14384) (xy 112.903955 -91.089403) (xy 112.923878 -91.037312) (xy 112.951174 -90.988677)
			(xy 112.98526 -90.944534) (xy 113.025409 -90.905825) (xy 113.070767 -90.873374) (xy 113.120367 -90.847873)
			(xy 113.173151 -90.829866) (xy 113.227994 -90.819736) (xy 113.283728 -90.817699) (xy 113.339165 -90.823799)
			(xy 113.393122 -90.837905) (xy 113.444451 -90.859717) (xy 113.492057 -90.888771) (xy 113.534925 -90.924446)
			(xy 113.572142 -90.965983) (xy 113.602915 -91.012496) (xy 113.626587 -91.062993) (xy 113.642655 -91.1164)
			(xy 113.650775 -91.171576) (xy 113.650895 -91.178148) (xy 114.046026 -91.178148) (xy 114.046026 -91.123652)
			(xy 114.053782 -91.069711) (xy 114.069135 -91.017423) (xy 114.091773 -90.967852) (xy 114.121236 -90.922008)
			(xy 114.156923 -90.880823) (xy 114.198108 -90.845136) (xy 114.243952 -90.815673) (xy 114.293523 -90.793035)
			(xy 114.345811 -90.777682) (xy 114.399752 -90.769926) (xy 114.427 -90.76944) (xy 114.454987 -90.769896)
			(xy 114.510363 -90.778064) (xy 114.56395 -90.794237) (xy 114.614598 -90.818069) (xy 114.661218 -90.849048)
			(xy 114.702809 -90.886509) (xy 114.738478 -90.929647) (xy 114.75339 -90.953336) (xy 114.761011 -90.965111)
			(xy 114.781552 -90.984201) (xy 114.806507 -90.996989) (xy 114.833999 -91.002514) (xy 114.861957 -91.00036)
			(xy 114.888278 -90.990688) (xy 114.910979 -90.974227) (xy 114.920014 -90.963496) (xy 114.938218 -90.941238)
			(xy 114.980148 -90.901893) (xy 115.02751 -90.869292) (xy 115.079231 -90.844172) (xy 115.134138 -90.827104)
			(xy 115.190985 -90.818474) (xy 115.219734 -90.817954) (xy 115.246059 -90.818425) (xy 115.298209 -90.825674)
			(xy 115.348865 -90.840028) (xy 115.397065 -90.861214) (xy 115.441891 -90.88883) (xy 115.482492 -90.922351)
			(xy 115.518095 -90.961139) (xy 115.533424 -90.982546) (xy 115.541474 -90.993343) (xy 115.56206 -91.010689)
			(xy 115.586463 -91.022054) (xy 115.612988 -91.026648) (xy 115.639792 -91.024151) (xy 115.665012 -91.014737)
			(xy 115.686896 -90.99906) (xy 115.69573 -90.988896) (xy 115.713918 -90.96729) (xy 115.755636 -90.929222)
			(xy 115.802511 -90.897719) (xy 115.853517 -90.873471) (xy 115.907541 -90.857007) (xy 115.963402 -90.848687)
			(xy 115.99164 -90.84818) (xy 116.018888 -90.848693) (xy 116.07283 -90.856454) (xy 116.125118 -90.871812)
			(xy 116.174689 -90.894455) (xy 116.220533 -90.923921) (xy 116.261717 -90.959611) (xy 116.297403 -91.000799)
			(xy 116.326865 -91.046646) (xy 116.349502 -91.096219) (xy 116.364855 -91.148509) (xy 116.368857 -91.176348)
			(xy 116.661182 -91.176348) (xy 116.665253 -91.120726) (xy 116.677379 -91.066289) (xy 116.697302 -91.014198)
			(xy 116.724598 -90.965563) (xy 116.758684 -90.92142) (xy 116.798833 -90.882711) (xy 116.844191 -90.85026)
			(xy 116.893791 -90.824759) (xy 116.946575 -90.806752) (xy 117.001418 -90.796622) (xy 117.057152 -90.794585)
			(xy 117.112589 -90.800685) (xy 117.166546 -90.814791) (xy 117.217875 -90.836603) (xy 117.265481 -90.865657)
			(xy 117.308349 -90.901332) (xy 117.345566 -90.942869) (xy 117.376339 -90.989382) (xy 117.400011 -91.039879)
			(xy 117.416079 -91.093286) (xy 117.424199 -91.148462) (xy 117.424708 -91.176348) (xy 117.424199 -91.204234)
			(xy 117.416939 -91.253564) (xy 120.397014 -91.253564) (xy 120.401085 -91.197942) (xy 120.413211 -91.143505)
			(xy 120.433134 -91.091414) (xy 120.46043 -91.042779) (xy 120.494516 -90.998636) (xy 120.534665 -90.959927)
			(xy 120.580023 -90.927476) (xy 120.629623 -90.901975) (xy 120.682407 -90.883968) (xy 120.73725 -90.873838)
			(xy 120.792984 -90.871801) (xy 120.848421 -90.877901) (xy 120.902378 -90.892007) (xy 120.953707 -90.913819)
			(xy 121.001313 -90.942873) (xy 121.044181 -90.978548) (xy 121.081398 -91.020085) (xy 121.112171 -91.066598)
			(xy 121.135843 -91.117095) (xy 121.151911 -91.170502) (xy 121.160031 -91.225678) (xy 121.16054 -91.253564)
			(xy 121.160031 -91.28145) (xy 121.151911 -91.336626) (xy 121.135843 -91.390033) (xy 121.112171 -91.44053)
			(xy 121.081398 -91.487043) (xy 121.044181 -91.52858) (xy 121.001313 -91.564255) (xy 120.953707 -91.593309)
			(xy 120.902378 -91.615121) (xy 120.848421 -91.629227) (xy 120.792984 -91.635327) (xy 120.73725 -91.63329)
			(xy 120.682407 -91.62316) (xy 120.629623 -91.605153) (xy 120.580023 -91.579652) (xy 120.534665 -91.547201)
			(xy 120.494516 -91.508492) (xy 120.46043 -91.464349) (xy 120.433134 -91.415714) (xy 120.413211 -91.363623)
			(xy 120.401085 -91.309186) (xy 120.397014 -91.253564) (xy 117.416939 -91.253564) (xy 117.416079 -91.25941)
			(xy 117.400011 -91.312817) (xy 117.376339 -91.363314) (xy 117.345566 -91.409827) (xy 117.308349 -91.451364)
			(xy 117.265481 -91.487039) (xy 117.217875 -91.516093) (xy 117.166546 -91.537905) (xy 117.112589 -91.552011)
			(xy 117.057152 -91.558111) (xy 117.001418 -91.556074) (xy 116.946575 -91.545944) (xy 116.893791 -91.527937)
			(xy 116.844191 -91.502436) (xy 116.798833 -91.469985) (xy 116.758684 -91.431276) (xy 116.724598 -91.387133)
			(xy 116.697302 -91.338498) (xy 116.677379 -91.286407) (xy 116.665253 -91.23197) (xy 116.661182 -91.176348)
			(xy 116.368857 -91.176348) (xy 116.37261 -91.202451) (xy 116.37261 -91.256949) (xy 116.364855 -91.310891)
			(xy 116.349502 -91.363181) (xy 116.326865 -91.412754) (xy 116.297403 -91.458601) (xy 116.261717 -91.499789)
			(xy 116.220533 -91.535479) (xy 116.174689 -91.564945) (xy 116.125118 -91.587588) (xy 116.07283 -91.602946)
			(xy 116.018888 -91.610707) (xy 115.99164 -91.611196) (xy 115.965313 -91.610766) (xy 115.913161 -91.603513)
			(xy 115.862503 -91.589153) (xy 115.814302 -91.567961) (xy 115.769476 -91.540337) (xy 115.728877 -91.506809)
			(xy 115.693277 -91.468014) (xy 115.67795 -91.446604) (xy 115.66993 -91.435785) (xy 115.649335 -91.418446)
			(xy 115.624925 -91.407088) (xy 115.598397 -91.4025) (xy 115.571591 -91.405) (xy 115.546368 -91.414415)
			(xy 115.52448 -91.430091) (xy 115.515644 -91.440254) (xy 115.497403 -91.461814) (xy 115.455698 -91.499888)
			(xy 115.408835 -91.531397) (xy 115.357838 -91.555654) (xy 115.303823 -91.572127) (xy 115.24797 -91.580458)
			(xy 115.219734 -91.58097) (xy 115.191748 -91.580482) (xy 115.136374 -91.57232) (xy 115.082788 -91.556152)
			(xy 115.03214 -91.532325) (xy 114.98552 -91.501351) (xy 114.943927 -91.463894) (xy 114.908257 -91.420761)
			(xy 114.893344 -91.397074) (xy 114.88568 -91.385333) (xy 114.865143 -91.36626) (xy 114.840197 -91.353481)
			(xy 114.812719 -91.347957) (xy 114.784774 -91.350103) (xy 114.758461 -91.359758) (xy 114.735759 -91.376196)
			(xy 114.72672 -91.386914) (xy 114.708555 -91.409206) (xy 114.666617 -91.448548) (xy 114.619247 -91.481145)
			(xy 114.567518 -91.506259) (xy 114.512604 -91.52332) (xy 114.455752 -91.53194) (xy 114.427 -91.532456)
			(xy 114.399752 -91.531874) (xy 114.345811 -91.524118) (xy 114.293523 -91.508765) (xy 114.243952 -91.486127)
			(xy 114.198108 -91.456664) (xy 114.156923 -91.420977) (xy 114.121236 -91.379792) (xy 114.091773 -91.333948)
			(xy 114.069135 -91.284377) (xy 114.053782 -91.232089) (xy 114.046026 -91.178148) (xy 113.650895 -91.178148)
			(xy 113.651284 -91.199462) (xy 113.650775 -91.227348) (xy 113.642655 -91.282524) (xy 113.626587 -91.335931)
			(xy 113.602915 -91.386428) (xy 113.572142 -91.432941) (xy 113.534925 -91.474478) (xy 113.492057 -91.510153)
			(xy 113.444451 -91.539207) (xy 113.393122 -91.561019) (xy 113.339165 -91.575125) (xy 113.283728 -91.581225)
			(xy 113.227994 -91.579188) (xy 113.173151 -91.569058) (xy 113.120367 -91.551051) (xy 113.070767 -91.52555)
			(xy 113.025409 -91.493099) (xy 112.98526 -91.45439) (xy 112.951174 -91.410247) (xy 112.923878 -91.361612)
			(xy 112.903955 -91.309521) (xy 112.891829 -91.255084) (xy 112.887758 -91.199462) (xy 57.973661 -91.199462)
			(xy 57.980079 -91.220794) (xy 57.988199 -91.27597) (xy 57.988708 -91.303856) (xy 57.988199 -91.331742)
			(xy 57.980079 -91.386918) (xy 57.964011 -91.440325) (xy 57.940339 -91.490822) (xy 57.909566 -91.537335)
			(xy 57.872349 -91.578872) (xy 57.829481 -91.614547) (xy 57.781875 -91.643601) (xy 57.74576 -91.658948)
			(xy 122.228862 -91.658948) (xy 122.232933 -91.603326) (xy 122.245059 -91.548889) (xy 122.264982 -91.496798)
			(xy 122.292278 -91.448163) (xy 122.326364 -91.40402) (xy 122.366513 -91.365311) (xy 122.411871 -91.33286)
			(xy 122.461471 -91.307359) (xy 122.514255 -91.289352) (xy 122.569098 -91.279222) (xy 122.624832 -91.277185)
			(xy 122.680269 -91.283285) (xy 122.734226 -91.297391) (xy 122.785555 -91.319203) (xy 122.833161 -91.348257)
			(xy 122.876029 -91.383932) (xy 122.913246 -91.425469) (xy 122.944019 -91.471982) (xy 122.967691 -91.522479)
			(xy 122.983759 -91.575886) (xy 122.991879 -91.631062) (xy 122.992388 -91.658948) (xy 123.244862 -91.658948)
			(xy 123.248933 -91.603326) (xy 123.261059 -91.548889) (xy 123.280982 -91.496798) (xy 123.308278 -91.448163)
			(xy 123.342364 -91.40402) (xy 123.382513 -91.365311) (xy 123.427871 -91.33286) (xy 123.477471 -91.307359)
			(xy 123.530255 -91.289352) (xy 123.585098 -91.279222) (xy 123.640832 -91.277185) (xy 123.696269 -91.283285)
			(xy 123.750226 -91.297391) (xy 123.801555 -91.319203) (xy 123.849161 -91.348257) (xy 123.892029 -91.383932)
			(xy 123.929246 -91.425469) (xy 123.960019 -91.471982) (xy 123.983691 -91.522479) (xy 123.999759 -91.575886)
			(xy 124.007879 -91.631062) (xy 124.008388 -91.658948) (xy 124.260862 -91.658948) (xy 124.264933 -91.603326)
			(xy 124.277059 -91.548889) (xy 124.296982 -91.496798) (xy 124.324278 -91.448163) (xy 124.358364 -91.40402)
			(xy 124.398513 -91.365311) (xy 124.443871 -91.33286) (xy 124.493471 -91.307359) (xy 124.546255 -91.289352)
			(xy 124.601098 -91.279222) (xy 124.656832 -91.277185) (xy 124.712269 -91.283285) (xy 124.766226 -91.297391)
			(xy 124.817555 -91.319203) (xy 124.865161 -91.348257) (xy 124.908029 -91.383932) (xy 124.945246 -91.425469)
			(xy 124.976019 -91.471982) (xy 124.999691 -91.522479) (xy 125.015759 -91.575886) (xy 125.023879 -91.631062)
			(xy 125.024388 -91.658948) (xy 126.292862 -91.658948) (xy 126.296933 -91.603326) (xy 126.309059 -91.548889)
			(xy 126.328982 -91.496798) (xy 126.356278 -91.448163) (xy 126.390364 -91.40402) (xy 126.430513 -91.365311)
			(xy 126.475871 -91.33286) (xy 126.525471 -91.307359) (xy 126.578255 -91.289352) (xy 126.633098 -91.279222)
			(xy 126.688832 -91.277185) (xy 126.744269 -91.283285) (xy 126.798226 -91.297391) (xy 126.849555 -91.319203)
			(xy 126.897161 -91.348257) (xy 126.940029 -91.383932) (xy 126.977246 -91.425469) (xy 127.008019 -91.471982)
			(xy 127.031691 -91.522479) (xy 127.047759 -91.575886) (xy 127.055879 -91.631062) (xy 127.056388 -91.658948)
			(xy 127.308862 -91.658948) (xy 127.312933 -91.603326) (xy 127.325059 -91.548889) (xy 127.344982 -91.496798)
			(xy 127.372278 -91.448163) (xy 127.406364 -91.40402) (xy 127.446513 -91.365311) (xy 127.491871 -91.33286)
			(xy 127.541471 -91.307359) (xy 127.594255 -91.289352) (xy 127.649098 -91.279222) (xy 127.704832 -91.277185)
			(xy 127.760269 -91.283285) (xy 127.814226 -91.297391) (xy 127.865555 -91.319203) (xy 127.913161 -91.348257)
			(xy 127.956029 -91.383932) (xy 127.993246 -91.425469) (xy 128.024019 -91.471982) (xy 128.047691 -91.522479)
			(xy 128.063759 -91.575886) (xy 128.071879 -91.631062) (xy 128.072388 -91.658948) (xy 129.340862 -91.658948)
			(xy 129.344933 -91.603326) (xy 129.357059 -91.548889) (xy 129.376982 -91.496798) (xy 129.404278 -91.448163)
			(xy 129.438364 -91.40402) (xy 129.478513 -91.365311) (xy 129.523871 -91.33286) (xy 129.573471 -91.307359)
			(xy 129.626255 -91.289352) (xy 129.681098 -91.279222) (xy 129.736832 -91.277185) (xy 129.792269 -91.283285)
			(xy 129.846226 -91.297391) (xy 129.897555 -91.319203) (xy 129.945161 -91.348257) (xy 129.988029 -91.383932)
			(xy 130.025246 -91.425469) (xy 130.056019 -91.471982) (xy 130.079691 -91.522479) (xy 130.095759 -91.575886)
			(xy 130.103879 -91.631062) (xy 130.104388 -91.658948) (xy 130.356862 -91.658948) (xy 130.360933 -91.603326)
			(xy 130.373059 -91.548889) (xy 130.392982 -91.496798) (xy 130.420278 -91.448163) (xy 130.454364 -91.40402)
			(xy 130.494513 -91.365311) (xy 130.539871 -91.33286) (xy 130.589471 -91.307359) (xy 130.642255 -91.289352)
			(xy 130.697098 -91.279222) (xy 130.752832 -91.277185) (xy 130.808269 -91.283285) (xy 130.862226 -91.297391)
			(xy 130.913555 -91.319203) (xy 130.961161 -91.348257) (xy 131.004029 -91.383932) (xy 131.041246 -91.425469)
			(xy 131.072019 -91.471982) (xy 131.095691 -91.522479) (xy 131.111759 -91.575886) (xy 131.119879 -91.631062)
			(xy 131.120388 -91.658948) (xy 133.658862 -91.658948) (xy 133.662933 -91.603326) (xy 133.675059 -91.548889)
			(xy 133.694982 -91.496798) (xy 133.722278 -91.448163) (xy 133.756364 -91.40402) (xy 133.796513 -91.365311)
			(xy 133.841871 -91.33286) (xy 133.891471 -91.307359) (xy 133.944255 -91.289352) (xy 133.999098 -91.279222)
			(xy 134.054832 -91.277185) (xy 134.110269 -91.283285) (xy 134.164226 -91.297391) (xy 134.215555 -91.319203)
			(xy 134.263161 -91.348257) (xy 134.306029 -91.383932) (xy 134.343246 -91.425469) (xy 134.374019 -91.471982)
			(xy 134.397691 -91.522479) (xy 134.413759 -91.575886) (xy 134.421879 -91.631062) (xy 134.422388 -91.658948)
			(xy 134.674862 -91.658948) (xy 134.678933 -91.603326) (xy 134.691059 -91.548889) (xy 134.710982 -91.496798)
			(xy 134.738278 -91.448163) (xy 134.772364 -91.40402) (xy 134.812513 -91.365311) (xy 134.857871 -91.33286)
			(xy 134.907471 -91.307359) (xy 134.960255 -91.289352) (xy 135.015098 -91.279222) (xy 135.070832 -91.277185)
			(xy 135.126269 -91.283285) (xy 135.180226 -91.297391) (xy 135.231555 -91.319203) (xy 135.279161 -91.348257)
			(xy 135.322029 -91.383932) (xy 135.359246 -91.425469) (xy 135.390019 -91.471982) (xy 135.413691 -91.522479)
			(xy 135.429759 -91.575886) (xy 135.437879 -91.631062) (xy 135.438388 -91.658948) (xy 135.690862 -91.658948)
			(xy 135.694933 -91.603326) (xy 135.707059 -91.548889) (xy 135.726982 -91.496798) (xy 135.754278 -91.448163)
			(xy 135.788364 -91.40402) (xy 135.828513 -91.365311) (xy 135.873871 -91.33286) (xy 135.923471 -91.307359)
			(xy 135.976255 -91.289352) (xy 136.031098 -91.279222) (xy 136.086832 -91.277185) (xy 136.142269 -91.283285)
			(xy 136.196226 -91.297391) (xy 136.247555 -91.319203) (xy 136.295161 -91.348257) (xy 136.338029 -91.383932)
			(xy 136.375246 -91.425469) (xy 136.406019 -91.471982) (xy 136.429691 -91.522479) (xy 136.443238 -91.567508)
			(xy 138.494514 -91.567508) (xy 138.498585 -91.511886) (xy 138.510711 -91.457449) (xy 138.530634 -91.405358)
			(xy 138.55793 -91.356723) (xy 138.592016 -91.31258) (xy 138.632165 -91.273871) (xy 138.677523 -91.24142)
			(xy 138.727123 -91.215919) (xy 138.779907 -91.197912) (xy 138.83475 -91.187782) (xy 138.890484 -91.185745)
			(xy 138.945921 -91.191845) (xy 138.999878 -91.205951) (xy 139.051207 -91.227763) (xy 139.098813 -91.256817)
			(xy 139.141681 -91.292492) (xy 139.178898 -91.334029) (xy 139.209671 -91.380542) (xy 139.233343 -91.431039)
			(xy 139.249411 -91.484446) (xy 139.257531 -91.539622) (xy 139.25804 -91.567508) (xy 139.257531 -91.595394)
			(xy 139.249411 -91.65057) (xy 139.233899 -91.702128) (xy 147.557236 -91.702128) (xy 147.557722 -91.674877)
			(xy 147.565478 -91.620929) (xy 147.580833 -91.568634) (xy 147.603475 -91.519057) (xy 147.632941 -91.473207)
			(xy 147.668632 -91.432016) (xy 147.709823 -91.396325) (xy 147.755673 -91.366859) (xy 147.80525 -91.344217)
			(xy 147.857545 -91.328862) (xy 147.911493 -91.321106) (xy 147.965995 -91.321106) (xy 148.019943 -91.328862)
			(xy 148.072238 -91.344217) (xy 148.121815 -91.366859) (xy 148.167665 -91.396325) (xy 148.208856 -91.432016)
			(xy 148.244547 -91.473207) (xy 148.274013 -91.519057) (xy 148.296655 -91.568634) (xy 148.31201 -91.620929)
			(xy 148.319766 -91.674877) (xy 148.320252 -91.702128) (xy 148.319924 -91.724174) (xy 148.314833 -91.767972)
			(xy 148.310092 -91.789504) (xy 148.307203 -91.804276) (xy 148.309195 -91.834292) (xy 148.319854 -91.862423)
			(xy 148.338252 -91.886224) (xy 148.362791 -91.903625) (xy 148.376894 -91.908884) (xy 148.400578 -91.917232)
			(xy 148.445689 -91.939295) (xy 148.487516 -91.967087) (xy 148.506688 -91.983306) (xy 148.518016 -91.992542)
			(xy 148.544573 -92.004718) (xy 148.57349 -92.008891) (xy 148.602407 -92.004718) (xy 148.628964 -91.992542)
			(xy 148.640292 -91.983306) (xy 148.661217 -91.965658) (xy 148.707192 -91.935947) (xy 148.756941 -91.913113)
			(xy 148.809443 -91.897624) (xy 148.86362 -91.889799) (xy 148.89099 -91.889326) (xy 148.918246 -91.88972)
			(xy 148.972203 -91.897477) (xy 149.024506 -91.912833) (xy 149.074092 -91.935477) (xy 149.119951 -91.964948)
			(xy 149.161148 -92.000645) (xy 149.196846 -92.041841) (xy 149.226318 -92.087699) (xy 149.248963 -92.137284)
			(xy 149.264321 -92.189588) (xy 149.272079 -92.243544) (xy 149.272079 -92.298056) (xy 149.264321 -92.352012)
			(xy 149.248963 -92.404316) (xy 149.226318 -92.453901) (xy 149.196846 -92.499759) (xy 149.161148 -92.540955)
			(xy 149.119951 -92.576652) (xy 149.074092 -92.606123) (xy 149.024506 -92.628767) (xy 148.972203 -92.644123)
			(xy 148.918246 -92.65188) (xy 148.89099 -92.652342) (xy 148.863619 -92.651896) (xy 148.809438 -92.644075)
			(xy 148.756934 -92.628582) (xy 148.707188 -92.605736) (xy 148.661222 -92.576006) (xy 148.640292 -92.558362)
			(xy 148.628964 -92.549126) (xy 148.602407 -92.53695) (xy 148.57349 -92.532777) (xy 148.544573 -92.53695)
			(xy 148.518016 -92.549126) (xy 148.506688 -92.558362) (xy 148.485729 -92.575967) (xy 148.439764 -92.605686)
			(xy 148.390023 -92.628529) (xy 148.337529 -92.644027) (xy 148.283357 -92.651864) (xy 148.25599 -92.652342)
			(xy 148.22874 -92.651832) (xy 148.174795 -92.644075) (xy 148.122503 -92.62872) (xy 148.072928 -92.60608)
			(xy 148.027079 -92.576616) (xy 147.98589 -92.540927) (xy 147.950198 -92.49974) (xy 147.920731 -92.453893)
			(xy 147.898088 -92.40432) (xy 147.88273 -92.352029) (xy 147.87497 -92.298084) (xy 147.874482 -92.270834)
			(xy 147.874803 -92.248788) (xy 147.879898 -92.20499) (xy 147.884642 -92.183458) (xy 147.887547 -92.16869)
			(xy 147.885546 -92.138673) (xy 147.874881 -92.110543) (xy 147.856481 -92.086742) (xy 147.831942 -92.069339)
			(xy 147.81784 -92.064078) (xy 147.792873 -92.055261) (xy 147.745457 -92.031693) (xy 147.701756 -92.001795)
			(xy 147.662609 -91.966142) (xy 147.628767 -91.925419) (xy 147.600881 -91.880408) (xy 147.579487 -91.831973)
			(xy 147.564995 -91.781045) (xy 147.557683 -91.728603) (xy 147.557236 -91.702128) (xy 139.233899 -91.702128)
			(xy 139.233343 -91.703977) (xy 139.209671 -91.754474) (xy 139.178898 -91.800987) (xy 139.141681 -91.842524)
			(xy 139.098813 -91.878199) (xy 139.051207 -91.907253) (xy 138.999878 -91.929065) (xy 138.945921 -91.943171)
			(xy 138.890484 -91.949271) (xy 138.83475 -91.947234) (xy 138.779907 -91.937104) (xy 138.727123 -91.919097)
			(xy 138.677523 -91.893596) (xy 138.632165 -91.861145) (xy 138.592016 -91.822436) (xy 138.55793 -91.778293)
			(xy 138.530634 -91.729658) (xy 138.510711 -91.677567) (xy 138.498585 -91.62313) (xy 138.494514 -91.567508)
			(xy 136.443238 -91.567508) (xy 136.445759 -91.575886) (xy 136.453879 -91.631062) (xy 136.454388 -91.658948)
			(xy 136.453879 -91.686834) (xy 136.445759 -91.74201) (xy 136.429691 -91.795417) (xy 136.406019 -91.845914)
			(xy 136.375246 -91.892427) (xy 136.338029 -91.933964) (xy 136.295161 -91.969639) (xy 136.247555 -91.998693)
			(xy 136.196226 -92.020505) (xy 136.142269 -92.034611) (xy 136.086832 -92.040711) (xy 136.031098 -92.038674)
			(xy 135.976255 -92.028544) (xy 135.923471 -92.010537) (xy 135.873871 -91.985036) (xy 135.828513 -91.952585)
			(xy 135.788364 -91.913876) (xy 135.754278 -91.869733) (xy 135.726982 -91.821098) (xy 135.707059 -91.769007)
			(xy 135.694933 -91.71457) (xy 135.690862 -91.658948) (xy 135.438388 -91.658948) (xy 135.437879 -91.686834)
			(xy 135.429759 -91.74201) (xy 135.413691 -91.795417) (xy 135.390019 -91.845914) (xy 135.359246 -91.892427)
			(xy 135.322029 -91.933964) (xy 135.279161 -91.969639) (xy 135.231555 -91.998693) (xy 135.180226 -92.020505)
			(xy 135.126269 -92.034611) (xy 135.070832 -92.040711) (xy 135.015098 -92.038674) (xy 134.960255 -92.028544)
			(xy 134.907471 -92.010537) (xy 134.857871 -91.985036) (xy 134.812513 -91.952585) (xy 134.772364 -91.913876)
			(xy 134.738278 -91.869733) (xy 134.710982 -91.821098) (xy 134.691059 -91.769007) (xy 134.678933 -91.71457)
			(xy 134.674862 -91.658948) (xy 134.422388 -91.658948) (xy 134.421879 -91.686834) (xy 134.413759 -91.74201)
			(xy 134.397691 -91.795417) (xy 134.374019 -91.845914) (xy 134.343246 -91.892427) (xy 134.306029 -91.933964)
			(xy 134.263161 -91.969639) (xy 134.215555 -91.998693) (xy 134.164226 -92.020505) (xy 134.110269 -92.034611)
			(xy 134.054832 -92.040711) (xy 133.999098 -92.038674) (xy 133.944255 -92.028544) (xy 133.891471 -92.010537)
			(xy 133.841871 -91.985036) (xy 133.796513 -91.952585) (xy 133.756364 -91.913876) (xy 133.722278 -91.869733)
			(xy 133.694982 -91.821098) (xy 133.675059 -91.769007) (xy 133.662933 -91.71457) (xy 133.658862 -91.658948)
			(xy 131.120388 -91.658948) (xy 131.119879 -91.686834) (xy 131.111759 -91.74201) (xy 131.095691 -91.795417)
			(xy 131.072019 -91.845914) (xy 131.041246 -91.892427) (xy 131.004029 -91.933964) (xy 130.961161 -91.969639)
			(xy 130.913555 -91.998693) (xy 130.862226 -92.020505) (xy 130.808269 -92.034611) (xy 130.752832 -92.040711)
			(xy 130.697098 -92.038674) (xy 130.642255 -92.028544) (xy 130.589471 -92.010537) (xy 130.539871 -91.985036)
			(xy 130.494513 -91.952585) (xy 130.454364 -91.913876) (xy 130.420278 -91.869733) (xy 130.392982 -91.821098)
			(xy 130.373059 -91.769007) (xy 130.360933 -91.71457) (xy 130.356862 -91.658948) (xy 130.104388 -91.658948)
			(xy 130.103879 -91.686834) (xy 130.095759 -91.74201) (xy 130.079691 -91.795417) (xy 130.056019 -91.845914)
			(xy 130.025246 -91.892427) (xy 129.988029 -91.933964) (xy 129.945161 -91.969639) (xy 129.897555 -91.998693)
			(xy 129.846226 -92.020505) (xy 129.792269 -92.034611) (xy 129.736832 -92.040711) (xy 129.681098 -92.038674)
			(xy 129.626255 -92.028544) (xy 129.573471 -92.010537) (xy 129.523871 -91.985036) (xy 129.478513 -91.952585)
			(xy 129.438364 -91.913876) (xy 129.404278 -91.869733) (xy 129.376982 -91.821098) (xy 129.357059 -91.769007)
			(xy 129.344933 -91.71457) (xy 129.340862 -91.658948) (xy 128.072388 -91.658948) (xy 128.071879 -91.686834)
			(xy 128.063759 -91.74201) (xy 128.047691 -91.795417) (xy 128.024019 -91.845914) (xy 127.993246 -91.892427)
			(xy 127.956029 -91.933964) (xy 127.913161 -91.969639) (xy 127.865555 -91.998693) (xy 127.814226 -92.020505)
			(xy 127.760269 -92.034611) (xy 127.704832 -92.040711) (xy 127.649098 -92.038674) (xy 127.594255 -92.028544)
			(xy 127.541471 -92.010537) (xy 127.491871 -91.985036) (xy 127.446513 -91.952585) (xy 127.406364 -91.913876)
			(xy 127.372278 -91.869733) (xy 127.344982 -91.821098) (xy 127.325059 -91.769007) (xy 127.312933 -91.71457)
			(xy 127.308862 -91.658948) (xy 127.056388 -91.658948) (xy 127.055879 -91.686834) (xy 127.047759 -91.74201)
			(xy 127.031691 -91.795417) (xy 127.008019 -91.845914) (xy 126.977246 -91.892427) (xy 126.940029 -91.933964)
			(xy 126.897161 -91.969639) (xy 126.849555 -91.998693) (xy 126.798226 -92.020505) (xy 126.744269 -92.034611)
			(xy 126.688832 -92.040711) (xy 126.633098 -92.038674) (xy 126.578255 -92.028544) (xy 126.525471 -92.010537)
			(xy 126.475871 -91.985036) (xy 126.430513 -91.952585) (xy 126.390364 -91.913876) (xy 126.356278 -91.869733)
			(xy 126.328982 -91.821098) (xy 126.309059 -91.769007) (xy 126.296933 -91.71457) (xy 126.292862 -91.658948)
			(xy 125.024388 -91.658948) (xy 125.023879 -91.686834) (xy 125.015759 -91.74201) (xy 124.999691 -91.795417)
			(xy 124.976019 -91.845914) (xy 124.945246 -91.892427) (xy 124.908029 -91.933964) (xy 124.865161 -91.969639)
			(xy 124.817555 -91.998693) (xy 124.766226 -92.020505) (xy 124.712269 -92.034611) (xy 124.656832 -92.040711)
			(xy 124.601098 -92.038674) (xy 124.546255 -92.028544) (xy 124.493471 -92.010537) (xy 124.443871 -91.985036)
			(xy 124.398513 -91.952585) (xy 124.358364 -91.913876) (xy 124.324278 -91.869733) (xy 124.296982 -91.821098)
			(xy 124.277059 -91.769007) (xy 124.264933 -91.71457) (xy 124.260862 -91.658948) (xy 124.008388 -91.658948)
			(xy 124.007879 -91.686834) (xy 123.999759 -91.74201) (xy 123.983691 -91.795417) (xy 123.960019 -91.845914)
			(xy 123.929246 -91.892427) (xy 123.892029 -91.933964) (xy 123.849161 -91.969639) (xy 123.801555 -91.998693)
			(xy 123.750226 -92.020505) (xy 123.696269 -92.034611) (xy 123.640832 -92.040711) (xy 123.585098 -92.038674)
			(xy 123.530255 -92.028544) (xy 123.477471 -92.010537) (xy 123.427871 -91.985036) (xy 123.382513 -91.952585)
			(xy 123.342364 -91.913876) (xy 123.308278 -91.869733) (xy 123.280982 -91.821098) (xy 123.261059 -91.769007)
			(xy 123.248933 -91.71457) (xy 123.244862 -91.658948) (xy 122.992388 -91.658948) (xy 122.991879 -91.686834)
			(xy 122.983759 -91.74201) (xy 122.967691 -91.795417) (xy 122.944019 -91.845914) (xy 122.913246 -91.892427)
			(xy 122.876029 -91.933964) (xy 122.833161 -91.969639) (xy 122.785555 -91.998693) (xy 122.734226 -92.020505)
			(xy 122.680269 -92.034611) (xy 122.624832 -92.040711) (xy 122.569098 -92.038674) (xy 122.514255 -92.028544)
			(xy 122.461471 -92.010537) (xy 122.411871 -91.985036) (xy 122.366513 -91.952585) (xy 122.326364 -91.913876)
			(xy 122.292278 -91.869733) (xy 122.264982 -91.821098) (xy 122.245059 -91.769007) (xy 122.232933 -91.71457)
			(xy 122.228862 -91.658948) (xy 57.74576 -91.658948) (xy 57.730546 -91.665413) (xy 57.676589 -91.679519)
			(xy 57.621152 -91.685619) (xy 57.565418 -91.683582) (xy 57.510575 -91.673452) (xy 57.457791 -91.655445)
			(xy 57.408191 -91.629944) (xy 57.362833 -91.597493) (xy 57.322684 -91.558784) (xy 57.288598 -91.514641)
			(xy 57.261302 -91.466006) (xy 57.241379 -91.413915) (xy 57.229253 -91.359478) (xy 57.225182 -91.303856)
			(xy 17.407092 -91.303856) (xy 17.413255 -91.307617) (xy 17.456123 -91.343292) (xy 17.49334 -91.384829)
			(xy 17.524113 -91.431342) (xy 17.547785 -91.481839) (xy 17.563853 -91.535246) (xy 17.571973 -91.590422)
			(xy 17.572482 -91.618308) (xy 17.571973 -91.646194) (xy 17.563853 -91.70137) (xy 17.547785 -91.754777)
			(xy 17.524113 -91.805274) (xy 17.49334 -91.851787) (xy 17.456123 -91.893324) (xy 17.413255 -91.928999)
			(xy 17.365649 -91.958053) (xy 17.31432 -91.979865) (xy 17.260363 -91.993971) (xy 17.204926 -92.000071)
			(xy 17.149192 -91.998034) (xy 17.094349 -91.987904) (xy 17.041565 -91.969897) (xy 16.991965 -91.944396)
			(xy 16.946607 -91.911945) (xy 16.906458 -91.873236) (xy 16.872372 -91.829093) (xy 16.845076 -91.780458)
			(xy 16.825153 -91.728367) (xy 16.813027 -91.67393) (xy 16.808956 -91.618308) (xy 14.397382 -91.618308)
			(xy 14.399259 -91.631062) (xy 14.399768 -91.658948) (xy 14.399259 -91.686834) (xy 14.391139 -91.74201)
			(xy 14.375071 -91.795417) (xy 14.351399 -91.845914) (xy 14.320626 -91.892427) (xy 14.283409 -91.933964)
			(xy 14.240541 -91.969639) (xy 14.192935 -91.998693) (xy 14.141606 -92.020505) (xy 14.087649 -92.034611)
			(xy 14.032212 -92.040711) (xy 13.976478 -92.038674) (xy 13.921635 -92.028544) (xy 13.868851 -92.010537)
			(xy 13.819251 -91.985036) (xy 13.773893 -91.952585) (xy 13.733744 -91.913876) (xy 13.699658 -91.869733)
			(xy 13.672362 -91.821098) (xy 13.652439 -91.769007) (xy 13.640313 -91.71457) (xy 13.636242 -91.658948)
			(xy 12.277344 -91.658948) (xy 12.276835 -91.686834) (xy 12.268715 -91.74201) (xy 12.252647 -91.795417)
			(xy 12.228975 -91.845914) (xy 12.198202 -91.892427) (xy 12.160985 -91.933964) (xy 12.118117 -91.969639)
			(xy 12.070511 -91.998693) (xy 12.019182 -92.020505) (xy 11.965225 -92.034611) (xy 11.909788 -92.040711)
			(xy 11.854054 -92.038674) (xy 11.799211 -92.028544) (xy 11.746427 -92.010537) (xy 11.696827 -91.985036)
			(xy 11.651469 -91.952585) (xy 11.61132 -91.913876) (xy 11.577234 -91.869733) (xy 11.549938 -91.821098)
			(xy 11.530015 -91.769007) (xy 11.517889 -91.71457) (xy 11.513818 -91.658948) (xy 11.254994 -91.658948)
			(xy 11.254485 -91.686834) (xy 11.246365 -91.74201) (xy 11.230297 -91.795417) (xy 11.206625 -91.845914)
			(xy 11.175852 -91.892427) (xy 11.138635 -91.933964) (xy 11.095767 -91.969639) (xy 11.048161 -91.998693)
			(xy 10.996832 -92.020505) (xy 10.942875 -92.034611) (xy 10.887438 -92.040711) (xy 10.831704 -92.038674)
			(xy 10.776861 -92.028544) (xy 10.724077 -92.010537) (xy 10.674477 -91.985036) (xy 10.629119 -91.952585)
			(xy 10.58897 -91.913876) (xy 10.554884 -91.869733) (xy 10.527588 -91.821098) (xy 10.507665 -91.769007)
			(xy 10.495539 -91.71457) (xy 10.491468 -91.658948) (xy 6.055868 -91.658948) (xy 6.055868 -92.287598)
			(xy 8.695942 -92.287598) (xy 8.700013 -92.231976) (xy 8.712139 -92.177539) (xy 8.732062 -92.125448)
			(xy 8.759358 -92.076813) (xy 8.793444 -92.03267) (xy 8.833593 -91.993961) (xy 8.878951 -91.96151)
			(xy 8.928551 -91.936009) (xy 8.981335 -91.918002) (xy 9.036178 -91.907872) (xy 9.091912 -91.905835)
			(xy 9.147349 -91.911935) (xy 9.201306 -91.926041) (xy 9.252635 -91.947853) (xy 9.300241 -91.976907)
			(xy 9.343109 -92.012582) (xy 9.380326 -92.054119) (xy 9.411099 -92.100632) (xy 9.434771 -92.151129)
			(xy 9.450839 -92.204536) (xy 9.458959 -92.259712) (xy 9.459066 -92.265549) (xy 86.8454 -92.265549)
			(xy 86.8454 -92.211051) (xy 86.853156 -92.157107) (xy 86.86851 -92.104815) (xy 86.891149 -92.055242)
			(xy 86.920613 -92.009394) (xy 86.956302 -91.968206) (xy 86.997489 -91.932517) (xy 87.043336 -91.903052)
			(xy 87.09291 -91.880412) (xy 87.145201 -91.865057) (xy 87.199145 -91.857301) (xy 87.226394 -91.856814)
			(xy 87.252959 -91.85728) (xy 87.305574 -91.864652) (xy 87.356657 -91.879253) (xy 87.40522 -91.900802)
			(xy 87.450323 -91.928881) (xy 87.491094 -91.962947) (xy 87.526742 -92.002342) (xy 87.556579 -92.046301)
			(xy 87.580027 -92.093976) (xy 87.593507 -92.134944) (xy 95.248982 -92.134944) (xy 95.253053 -92.079322)
			(xy 95.265179 -92.024885) (xy 95.285102 -91.972794) (xy 95.312398 -91.924159) (xy 95.346484 -91.880016)
			(xy 95.386633 -91.841307) (xy 95.431991 -91.808856) (xy 95.481591 -91.783355) (xy 95.534375 -91.765348)
			(xy 95.589218 -91.755218) (xy 95.644952 -91.753181) (xy 95.700389 -91.759281) (xy 95.754346 -91.773387)
			(xy 95.805675 -91.795199) (xy 95.853281 -91.824253) (xy 95.896149 -91.859928) (xy 95.933366 -91.901465)
			(xy 95.964139 -91.947978) (xy 95.987811 -91.998475) (xy 96.003879 -92.051882) (xy 96.011999 -92.107058)
			(xy 96.012508 -92.134944) (xy 96.011999 -92.16283) (xy 96.003879 -92.218006) (xy 96.002505 -92.222574)
			(xy 102.151942 -92.222574) (xy 102.152428 -92.195323) (xy 102.160184 -92.141375) (xy 102.175539 -92.08908)
			(xy 102.198181 -92.039503) (xy 102.227647 -91.993653) (xy 102.263338 -91.952462) (xy 102.304529 -91.916771)
			(xy 102.350379 -91.887305) (xy 102.399956 -91.864663) (xy 102.452251 -91.849308) (xy 102.506199 -91.841552)
			(xy 102.560701 -91.841552) (xy 102.614649 -91.849308) (xy 102.666944 -91.864663) (xy 102.716521 -91.887305)
			(xy 102.762371 -91.916771) (xy 102.803562 -91.952462) (xy 102.839253 -91.993653) (xy 102.868719 -92.039503)
			(xy 102.891361 -92.08908) (xy 102.906716 -92.141375) (xy 102.914472 -92.195323) (xy 102.914958 -92.222574)
			(xy 102.91454 -92.247865) (xy 102.907864 -92.298005) (xy 102.894613 -92.346821) (xy 102.875271 -92.392856)
			(xy 109.348431 -92.392856) (xy 109.348431 -92.338344) (xy 109.356189 -92.284388) (xy 109.371547 -92.232085)
			(xy 109.394193 -92.1825) (xy 109.423665 -92.136643) (xy 109.459364 -92.095447) (xy 109.500562 -92.059751)
			(xy 109.546421 -92.030281) (xy 109.596007 -92.007639) (xy 109.648311 -91.992284) (xy 109.702268 -91.984529)
			(xy 109.729524 -91.984068) (xy 109.756088 -91.984544) (xy 109.808701 -91.991919) (xy 109.859782 -92.006522)
			(xy 109.908343 -92.028071) (xy 109.953444 -92.05615) (xy 109.994214 -92.090214) (xy 110.029862 -92.129606)
			(xy 110.0597 -92.173563) (xy 110.083151 -92.221235) (xy 110.099761 -92.271699) (xy 110.104936 -92.297758)
			(xy 110.108105 -92.312282) (xy 110.121603 -92.338751) (xy 110.14216 -92.360204) (xy 110.16803 -92.374818)
			(xy 110.197015 -92.381352) (xy 110.21187 -92.380816) (xy 110.237524 -92.380054) (xy 110.264771 -92.380618)
			(xy 110.318711 -92.388376) (xy 110.370998 -92.403732) (xy 110.420567 -92.426372) (xy 110.46641 -92.455836)
			(xy 110.507593 -92.491524) (xy 110.543278 -92.53271) (xy 110.572739 -92.578554) (xy 110.595376 -92.628125)
			(xy 110.610729 -92.680412) (xy 110.618484 -92.734353) (xy 110.618484 -92.788847) (xy 110.610729 -92.842788)
			(xy 110.595376 -92.895075) (xy 110.572739 -92.944646) (xy 110.543278 -92.99049) (xy 110.531458 -93.004132)
			(xy 118.954802 -93.004132) (xy 118.958873 -92.94851) (xy 118.970999 -92.894073) (xy 118.990922 -92.841982)
			(xy 119.018218 -92.793347) (xy 119.052304 -92.749204) (xy 119.092453 -92.710495) (xy 119.137811 -92.678044)
			(xy 119.187411 -92.652543) (xy 119.240195 -92.634536) (xy 119.295038 -92.624406) (xy 119.350772 -92.622369)
			(xy 119.406209 -92.628469) (xy 119.460166 -92.642575) (xy 119.511495 -92.664387) (xy 119.559101 -92.693441)
			(xy 119.601969 -92.729116) (xy 119.639186 -92.770653) (xy 119.669959 -92.817166) (xy 119.693631 -92.867663)
			(xy 119.709699 -92.92107) (xy 119.717819 -92.976246) (xy 119.718328 -93.004132) (xy 119.717819 -93.032018)
			(xy 119.709699 -93.087194) (xy 119.693631 -93.140601) (xy 119.669959 -93.191098) (xy 119.639186 -93.237611)
			(xy 119.601969 -93.279148) (xy 119.559101 -93.314823) (xy 119.511495 -93.343877) (xy 119.460166 -93.365689)
			(xy 119.406209 -93.379795) (xy 119.350772 -93.385895) (xy 119.295038 -93.383858) (xy 119.240195 -93.373728)
			(xy 119.187411 -93.355721) (xy 119.137811 -93.33022) (xy 119.092453 -93.297769) (xy 119.052304 -93.25906)
			(xy 119.018218 -93.214917) (xy 118.990922 -93.166282) (xy 118.970999 -93.114191) (xy 118.958873 -93.059754)
			(xy 118.954802 -93.004132) (xy 110.531458 -93.004132) (xy 110.507593 -93.031676) (xy 110.46641 -93.067364)
			(xy 110.420567 -93.096828) (xy 110.370998 -93.119468) (xy 110.318711 -93.134824) (xy 110.264771 -93.142582)
			(xy 110.237524 -93.14307) (xy 110.21096 -93.14261) (xy 110.158348 -93.13523) (xy 110.107268 -93.120622)
			(xy 110.058709 -93.099069) (xy 110.013609 -93.070988) (xy 109.972841 -93.036922) (xy 109.937192 -92.99753)
			(xy 109.907354 -92.953573) (xy 109.883901 -92.905902) (xy 109.867289 -92.855438) (xy 109.862112 -92.82938)
			(xy 109.858969 -92.814848) (xy 109.845471 -92.788371) (xy 109.824909 -92.766914) (xy 109.79903 -92.752303)
			(xy 109.770036 -92.745778) (xy 109.755178 -92.746322) (xy 109.729524 -92.747084) (xy 109.702268 -92.746671)
			(xy 109.648311 -92.738916) (xy 109.596007 -92.723561) (xy 109.546421 -92.700919) (xy 109.500562 -92.671449)
			(xy 109.459364 -92.635753) (xy 109.423665 -92.594557) (xy 109.394193 -92.5487) (xy 109.371547 -92.499115)
			(xy 109.356189 -92.446812) (xy 109.348431 -92.392856) (xy 102.875271 -92.392856) (xy 102.87502 -92.393454)
			(xy 102.84943 -92.437085) (xy 102.834186 -92.45727) (xy 102.825371 -92.46951) (xy 102.814555 -92.497649)
			(xy 102.812431 -92.52772) (xy 102.819182 -92.557099) (xy 102.83422 -92.583226) (xy 102.844854 -92.593922)
			(xy 102.863557 -92.612049) (xy 102.896402 -92.652471) (xy 102.923444 -92.696985) (xy 102.944179 -92.744764)
			(xy 102.958222 -92.794919) (xy 102.965313 -92.846518) (xy 102.965758 -92.87256) (xy 102.965272 -92.899811)
			(xy 102.957516 -92.953759) (xy 102.942161 -93.006054) (xy 102.919519 -93.055631) (xy 102.890053 -93.101481)
			(xy 102.854362 -93.142672) (xy 102.813171 -93.178363) (xy 102.767321 -93.207829) (xy 102.717744 -93.230471)
			(xy 102.665449 -93.245826) (xy 102.611501 -93.253582) (xy 102.556999 -93.253582) (xy 102.503051 -93.245826)
			(xy 102.450756 -93.230471) (xy 102.401179 -93.207829) (xy 102.355329 -93.178363) (xy 102.314138 -93.142672)
			(xy 102.278447 -93.101481) (xy 102.248981 -93.055631) (xy 102.226339 -93.006054) (xy 102.210984 -92.953759)
			(xy 102.203228 -92.899811) (xy 102.202742 -92.87256) (xy 102.203124 -92.847268) (xy 102.209808 -92.797126)
			(xy 102.223068 -92.74831) (xy 102.242668 -92.701678) (xy 102.268267 -92.658048) (xy 102.283514 -92.637864)
			(xy 102.292397 -92.625668) (xy 102.303202 -92.597512) (xy 102.305313 -92.567428) (xy 102.298546 -92.538039)
			(xy 102.283489 -92.511908) (xy 102.272846 -92.501212) (xy 102.254111 -92.483116) (xy 102.221269 -92.442688)
			(xy 102.194231 -92.398167) (xy 102.173502 -92.350382) (xy 102.159465 -92.300222) (xy 102.152383 -92.248618)
			(xy 102.151942 -92.222574) (xy 96.002505 -92.222574) (xy 95.987811 -92.271413) (xy 95.964139 -92.32191)
			(xy 95.933366 -92.368423) (xy 95.896149 -92.40996) (xy 95.853281 -92.445635) (xy 95.805675 -92.474689)
			(xy 95.754346 -92.496501) (xy 95.700389 -92.510607) (xy 95.644952 -92.516707) (xy 95.589218 -92.51467)
			(xy 95.534375 -92.50454) (xy 95.481591 -92.486533) (xy 95.431991 -92.461032) (xy 95.386633 -92.428581)
			(xy 95.346484 -92.389872) (xy 95.312398 -92.345729) (xy 95.285102 -92.297094) (xy 95.265179 -92.245003)
			(xy 95.253053 -92.190566) (xy 95.248982 -92.134944) (xy 87.593507 -92.134944) (xy 87.596633 -92.144444)
			(xy 87.601806 -92.170504) (xy 87.604974 -92.185027) (xy 87.618477 -92.211492) (xy 87.639035 -92.232941)
			(xy 87.664903 -92.247555) (xy 87.693885 -92.254094) (xy 87.70874 -92.253562) (xy 87.734394 -92.2528)
			(xy 87.761648 -92.253247) (xy 87.8156 -92.261003) (xy 87.8679 -92.276359) (xy 87.917482 -92.299002)
			(xy 87.963337 -92.32847) (xy 88.004531 -92.364165) (xy 88.040226 -92.405358) (xy 88.069695 -92.451213)
			(xy 88.092339 -92.500794) (xy 88.107695 -92.553094) (xy 88.115453 -92.607046) (xy 88.115453 -92.661554)
			(xy 88.107695 -92.715506) (xy 88.092339 -92.767806) (xy 88.069695 -92.817387) (xy 88.040226 -92.863242)
			(xy 88.004531 -92.904435) (xy 87.963337 -92.94013) (xy 87.917482 -92.969598) (xy 87.8679 -92.992241)
			(xy 87.8156 -93.007597) (xy 87.761648 -93.015353) (xy 87.734394 -93.015816) (xy 87.70783 -93.015337)
			(xy 87.655216 -93.007964) (xy 87.604135 -92.993362) (xy 87.555573 -92.971814) (xy 87.510471 -92.943736)
			(xy 87.469702 -92.909672) (xy 87.434053 -92.87028) (xy 87.404215 -92.826322) (xy 87.380765 -92.77865)
			(xy 87.364156 -92.728185) (xy 87.358982 -92.702126) (xy 87.355806 -92.687604) (xy 87.342308 -92.661138)
			(xy 87.321752 -92.639686) (xy 87.295885 -92.625071) (xy 87.266903 -92.618534) (xy 87.252048 -92.619068)
			(xy 87.226394 -92.61983) (xy 87.199145 -92.619299) (xy 87.145201 -92.611543) (xy 87.09291 -92.596188)
			(xy 87.043336 -92.573548) (xy 86.997489 -92.544083) (xy 86.956302 -92.508394) (xy 86.920613 -92.467206)
			(xy 86.891149 -92.421358) (xy 86.86851 -92.371785) (xy 86.853156 -92.319493) (xy 86.8454 -92.265549)
			(xy 9.459066 -92.265549) (xy 9.459468 -92.287598) (xy 9.458959 -92.315484) (xy 9.450839 -92.37066)
			(xy 9.434771 -92.424067) (xy 9.411099 -92.474564) (xy 9.380326 -92.521077) (xy 9.343109 -92.562614)
			(xy 9.300241 -92.598289) (xy 9.252635 -92.627343) (xy 9.201306 -92.649155) (xy 9.147349 -92.663261)
			(xy 9.091912 -92.669361) (xy 9.036178 -92.667324) (xy 8.981335 -92.657194) (xy 8.928551 -92.639187)
			(xy 8.878951 -92.613686) (xy 8.833593 -92.581235) (xy 8.793444 -92.542526) (xy 8.759358 -92.498383)
			(xy 8.732062 -92.449748) (xy 8.712139 -92.397657) (xy 8.700013 -92.34322) (xy 8.695942 -92.287598)
			(xy 6.055868 -92.287598) (xy 6.055868 -93.538294) (xy 83.609688 -93.538294) (xy 83.610212 -93.510137)
			(xy 83.618511 -93.454437) (xy 83.634911 -93.400564) (xy 83.659057 -93.349689) (xy 83.690423 -93.302918)
			(xy 83.709002 -93.281754) (xy 83.718757 -93.270272) (xy 83.731699 -93.243083) (xy 83.736142 -93.213301)
			(xy 83.731699 -93.183518) (xy 83.718758 -93.156329) (xy 83.709002 -93.144848) (xy 83.690428 -93.123681)
			(xy 83.659077 -93.076903) (xy 83.634936 -93.026028) (xy 83.618529 -92.972159) (xy 83.610213 -92.916464)
			(xy 83.609688 -92.888308) (xy 83.610174 -92.861057) (xy 83.61793 -92.807109) (xy 83.633285 -92.754814)
			(xy 83.655927 -92.705237) (xy 83.685393 -92.659387) (xy 83.721084 -92.618196) (xy 83.762275 -92.582505)
			(xy 83.808125 -92.553039) (xy 83.857702 -92.530397) (xy 83.909997 -92.515042) (xy 83.963945 -92.507286)
			(xy 84.018447 -92.507286) (xy 84.072395 -92.515042) (xy 84.12469 -92.530397) (xy 84.174267 -92.553039)
			(xy 84.220117 -92.582505) (xy 84.261308 -92.618196) (xy 84.296999 -92.659387) (xy 84.326465 -92.705237)
			(xy 84.349107 -92.754814) (xy 84.364462 -92.807109) (xy 84.372218 -92.861057) (xy 84.372704 -92.888308)
			(xy 84.372183 -92.916465) (xy 84.363884 -92.972165) (xy 84.347483 -93.026039) (xy 84.323336 -93.076914)
			(xy 84.291969 -93.123684) (xy 84.27339 -93.144848) (xy 84.263682 -93.15635) (xy 84.250819 -93.183544)
			(xy 84.246404 -93.213301) (xy 84.250819 -93.243058) (xy 84.263683 -93.270251) (xy 84.27339 -93.281754)
			(xy 84.291963 -93.302921) (xy 84.323315 -93.349699) (xy 84.347456 -93.400574) (xy 84.363863 -93.454443)
			(xy 84.372179 -93.510138) (xy 84.372704 -93.538294) (xy 84.372218 -93.565545) (xy 84.364462 -93.619493)
			(xy 84.349107 -93.671788) (xy 84.326465 -93.721365) (xy 84.296999 -93.767215) (xy 84.261308 -93.808406)
			(xy 84.250296 -93.817948) (xy 92.010992 -93.817948) (xy 92.011486 -93.790952) (xy 92.01908 -93.737497)
			(xy 92.034137 -93.685647) (xy 92.056357 -93.636439) (xy 92.085295 -93.590857) (xy 92.120373 -93.549811)
			(xy 92.160889 -93.514124) (xy 92.183204 -93.498924) (xy 92.19564 -93.490054) (xy 92.215015 -93.46646)
			(xy 92.22656 -93.438197) (xy 92.229245 -93.407785) (xy 92.222831 -93.377936) (xy 92.207889 -93.351312)
			(xy 92.197174 -93.340428) (xy 92.178678 -93.322358) (xy 92.146275 -93.28206) (xy 92.11962 -93.23775)
			(xy 92.099201 -93.190243) (xy 92.085395 -93.140411) (xy 92.078454 -93.089169) (xy 92.078048 -93.063314)
			(xy 92.078534 -93.036063) (xy 92.08629 -92.982115) (xy 92.101645 -92.92982) (xy 92.124287 -92.880243)
			(xy 92.153753 -92.834393) (xy 92.189444 -92.793202) (xy 92.230635 -92.757511) (xy 92.276485 -92.728045)
			(xy 92.326062 -92.705403) (xy 92.378357 -92.690048) (xy 92.432305 -92.682292) (xy 92.486807 -92.682292)
			(xy 92.540755 -92.690048) (xy 92.59305 -92.705403) (xy 92.642627 -92.728045) (xy 92.688477 -92.757511)
			(xy 92.729668 -92.793202) (xy 92.765359 -92.834393) (xy 92.794825 -92.880243) (xy 92.817467 -92.92982)
			(xy 92.832822 -92.982115) (xy 92.840578 -93.036063) (xy 92.841064 -93.063314) (xy 95.248982 -93.063314)
			(xy 95.253053 -93.007692) (xy 95.265179 -92.953255) (xy 95.285102 -92.901164) (xy 95.312398 -92.852529)
			(xy 95.346484 -92.808386) (xy 95.386633 -92.769677) (xy 95.431991 -92.737226) (xy 95.481591 -92.711725)
			(xy 95.534375 -92.693718) (xy 95.589218 -92.683588) (xy 95.644952 -92.681551) (xy 95.700389 -92.687651)
			(xy 95.754346 -92.701757) (xy 95.805675 -92.723569) (xy 95.853281 -92.752623) (xy 95.896149 -92.788298)
			(xy 95.933366 -92.829835) (xy 95.961633 -92.87256) (xy 98.900996 -92.87256) (xy 98.901482 -92.845309)
			(xy 98.909238 -92.791361) (xy 98.924593 -92.739066) (xy 98.947235 -92.689489) (xy 98.976701 -92.643639)
			(xy 99.012392 -92.602448) (xy 99.053583 -92.566757) (xy 99.099433 -92.537291) (xy 99.14901 -92.514649)
			(xy 99.201305 -92.499294) (xy 99.255253 -92.491538) (xy 99.309755 -92.491538) (xy 99.363703 -92.499294)
			(xy 99.415998 -92.514649) (xy 99.465575 -92.537291) (xy 99.511425 -92.566757) (xy 99.552616 -92.602448)
			(xy 99.588307 -92.643639) (xy 99.617773 -92.689489) (xy 99.640415 -92.739066) (xy 99.65577 -92.791361)
			(xy 99.663526 -92.845309) (xy 99.664012 -92.87256) (xy 99.663437 -92.902186) (xy 99.654294 -92.960729)
			(xy 99.636221 -93.017158) (xy 99.609652 -93.07012) (xy 99.592892 -93.094556) (xy 99.58449 -93.107187)
			(xy 99.574884 -93.135951) (xy 99.574137 -93.166267) (xy 99.582314 -93.195468) (xy 99.598696 -93.220987)
			(xy 99.60991 -93.231208) (xy 99.630686 -93.249436) (xy 99.667285 -93.290852) (xy 99.696119 -93.334958)
			(xy 105.476417 -93.334958) (xy 105.476417 -93.280442) (xy 105.484176 -93.226482) (xy 105.499536 -93.174175)
			(xy 105.522184 -93.124586) (xy 105.55166 -93.078726) (xy 105.587362 -93.037528) (xy 105.628565 -93.001831)
			(xy 105.674429 -92.972361) (xy 105.72402 -92.949719) (xy 105.776329 -92.934366) (xy 105.83029 -92.926614)
			(xy 105.857548 -92.926154) (xy 105.885797 -92.926636) (xy 105.941678 -92.934953) (xy 105.995719 -92.951428)
			(xy 106.046737 -92.975699) (xy 106.093614 -93.007234) (xy 106.135321 -93.045344) (xy 106.170947 -93.089193)
			(xy 106.19971 -93.13782) (xy 106.22098 -93.19016) (xy 106.228134 -93.217492) (xy 106.232482 -93.232632)
			(xy 106.248923 -93.259477) (xy 106.272742 -93.28006) (xy 106.301687 -93.292436) (xy 106.333023 -93.295436)
			(xy 106.34853 -93.292676) (xy 106.368417 -93.288655) (xy 106.408761 -93.284325) (xy 106.429048 -93.28404)
			(xy 106.4563 -93.284433) (xy 106.51025 -93.292196) (xy 106.562545 -93.307557) (xy 106.612123 -93.330204)
			(xy 106.657973 -93.359675) (xy 106.699163 -93.395371) (xy 106.734853 -93.436566) (xy 106.764319 -93.482419)
			(xy 106.786959 -93.532) (xy 106.802314 -93.584297) (xy 106.81007 -93.638248) (xy 106.81007 -93.690948)
			(xy 124.260862 -93.690948) (xy 124.264933 -93.635326) (xy 124.277059 -93.580889) (xy 124.296982 -93.528798)
			(xy 124.324278 -93.480163) (xy 124.358364 -93.43602) (xy 124.398513 -93.397311) (xy 124.443871 -93.36486)
			(xy 124.493471 -93.339359) (xy 124.546255 -93.321352) (xy 124.601098 -93.311222) (xy 124.656832 -93.309185)
			(xy 124.712269 -93.315285) (xy 124.766226 -93.329391) (xy 124.817555 -93.351203) (xy 124.865161 -93.380257)
			(xy 124.908029 -93.415932) (xy 124.945246 -93.457469) (xy 124.976019 -93.503982) (xy 124.999691 -93.554479)
			(xy 125.015759 -93.607886) (xy 125.023879 -93.663062) (xy 125.024388 -93.690948) (xy 128.324862 -93.690948)
			(xy 128.328933 -93.635326) (xy 128.341059 -93.580889) (xy 128.360982 -93.528798) (xy 128.388278 -93.480163)
			(xy 128.422364 -93.43602) (xy 128.462513 -93.397311) (xy 128.507871 -93.36486) (xy 128.557471 -93.339359)
			(xy 128.610255 -93.321352) (xy 128.665098 -93.311222) (xy 128.720832 -93.309185) (xy 128.776269 -93.315285)
			(xy 128.830226 -93.329391) (xy 128.881555 -93.351203) (xy 128.929161 -93.380257) (xy 128.972029 -93.415932)
			(xy 129.009246 -93.457469) (xy 129.040019 -93.503982) (xy 129.063691 -93.554479) (xy 129.079759 -93.607886)
			(xy 129.087879 -93.663062) (xy 129.088388 -93.690948) (xy 129.088249 -93.698568) (xy 132.630162 -93.698568)
			(xy 132.634233 -93.642946) (xy 132.646359 -93.588509) (xy 132.666282 -93.536418) (xy 132.693578 -93.487783)
			(xy 132.727664 -93.44364) (xy 132.767813 -93.404931) (xy 132.813171 -93.37248) (xy 132.862771 -93.346979)
			(xy 132.915555 -93.328972) (xy 132.970398 -93.318842) (xy 133.026132 -93.316805) (xy 133.081569 -93.322905)
			(xy 133.135526 -93.337011) (xy 133.186855 -93.358823) (xy 133.234461 -93.387877) (xy 133.277329 -93.423552)
			(xy 133.314546 -93.465089) (xy 133.345319 -93.511602) (xy 133.368991 -93.562099) (xy 133.385059 -93.615506)
			(xy 133.393179 -93.670682) (xy 133.393688 -93.698568) (xy 133.393179 -93.726454) (xy 133.388648 -93.757242)
			(xy 139.324078 -93.757242) (xy 139.328149 -93.70162) (xy 139.340275 -93.647183) (xy 139.360198 -93.595092)
			(xy 139.387494 -93.546457) (xy 139.42158 -93.502314) (xy 139.461729 -93.463605) (xy 139.507087 -93.431154)
			(xy 139.556687 -93.405653) (xy 139.609471 -93.387646) (xy 139.664314 -93.377516) (xy 139.720048 -93.375479)
			(xy 139.775485 -93.381579) (xy 139.829442 -93.395685) (xy 139.880771 -93.417497) (xy 139.928377 -93.446551)
			(xy 139.971245 -93.482226) (xy 140.008462 -93.523763) (xy 140.039235 -93.570276) (xy 140.062907 -93.620773)
			(xy 140.078975 -93.67418) (xy 140.087095 -93.729356) (xy 140.087604 -93.757242) (xy 141.274036 -93.757242)
			(xy 141.278107 -93.70162) (xy 141.290233 -93.647183) (xy 141.310156 -93.595092) (xy 141.337452 -93.546457)
			(xy 141.371538 -93.502314) (xy 141.411687 -93.463605) (xy 141.457045 -93.431154) (xy 141.506645 -93.405653)
			(xy 141.559429 -93.387646) (xy 141.614272 -93.377516) (xy 141.670006 -93.375479) (xy 141.725443 -93.381579)
			(xy 141.7794 -93.395685) (xy 141.830729 -93.417497) (xy 141.878335 -93.446551) (xy 141.921203 -93.482226)
			(xy 141.95842 -93.523763) (xy 141.989193 -93.570276) (xy 142.012865 -93.620773) (xy 142.028933 -93.67418)
			(xy 142.037053 -93.729356) (xy 142.037562 -93.757242) (xy 142.037053 -93.785128) (xy 142.028933 -93.840304)
			(xy 142.012865 -93.893711) (xy 141.989193 -93.944208) (xy 141.95842 -93.990721) (xy 141.921203 -94.032258)
			(xy 141.878335 -94.067933) (xy 141.830729 -94.096987) (xy 141.7794 -94.118799) (xy 141.725443 -94.132905)
			(xy 141.670006 -94.139005) (xy 141.614272 -94.136968) (xy 141.559429 -94.126838) (xy 141.506645 -94.108831)
			(xy 141.457045 -94.08333) (xy 141.411687 -94.050879) (xy 141.371538 -94.01217) (xy 141.337452 -93.968027)
			(xy 141.310156 -93.919392) (xy 141.290233 -93.867301) (xy 141.278107 -93.812864) (xy 141.274036 -93.757242)
			(xy 140.087604 -93.757242) (xy 140.087095 -93.785128) (xy 140.078975 -93.840304) (xy 140.062907 -93.893711)
			(xy 140.039235 -93.944208) (xy 140.008462 -93.990721) (xy 139.971245 -94.032258) (xy 139.928377 -94.067933)
			(xy 139.880771 -94.096987) (xy 139.829442 -94.118799) (xy 139.775485 -94.132905) (xy 139.720048 -94.139005)
			(xy 139.664314 -94.136968) (xy 139.609471 -94.126838) (xy 139.556687 -94.108831) (xy 139.507087 -94.08333)
			(xy 139.461729 -94.050879) (xy 139.42158 -94.01217) (xy 139.387494 -93.968027) (xy 139.360198 -93.919392)
			(xy 139.340275 -93.867301) (xy 139.328149 -93.812864) (xy 139.324078 -93.757242) (xy 133.388648 -93.757242)
			(xy 133.385059 -93.78163) (xy 133.368991 -93.835037) (xy 133.345319 -93.885534) (xy 133.314546 -93.932047)
			(xy 133.277329 -93.973584) (xy 133.234461 -94.009259) (xy 133.186855 -94.038313) (xy 133.135526 -94.060125)
			(xy 133.081569 -94.074231) (xy 133.026132 -94.080331) (xy 132.970398 -94.078294) (xy 132.915555 -94.068164)
			(xy 132.862771 -94.050157) (xy 132.813171 -94.024656) (xy 132.767813 -93.992205) (xy 132.727664 -93.953496)
			(xy 132.693578 -93.909353) (xy 132.666282 -93.860718) (xy 132.646359 -93.808627) (xy 132.634233 -93.75419)
			(xy 132.630162 -93.698568) (xy 129.088249 -93.698568) (xy 129.087879 -93.718834) (xy 129.079759 -93.77401)
			(xy 129.063691 -93.827417) (xy 129.040019 -93.877914) (xy 129.009246 -93.924427) (xy 128.972029 -93.965964)
			(xy 128.929161 -94.001639) (xy 128.881555 -94.030693) (xy 128.830226 -94.052505) (xy 128.776269 -94.066611)
			(xy 128.720832 -94.072711) (xy 128.665098 -94.070674) (xy 128.610255 -94.060544) (xy 128.557471 -94.042537)
			(xy 128.507871 -94.017036) (xy 128.462513 -93.984585) (xy 128.422364 -93.945876) (xy 128.388278 -93.901733)
			(xy 128.360982 -93.853098) (xy 128.341059 -93.801007) (xy 128.328933 -93.74657) (xy 128.324862 -93.690948)
			(xy 125.024388 -93.690948) (xy 125.023879 -93.718834) (xy 125.015759 -93.77401) (xy 124.999691 -93.827417)
			(xy 124.976019 -93.877914) (xy 124.945246 -93.924427) (xy 124.908029 -93.965964) (xy 124.865161 -94.001639)
			(xy 124.817555 -94.030693) (xy 124.766226 -94.052505) (xy 124.712269 -94.066611) (xy 124.656832 -94.072711)
			(xy 124.601098 -94.070674) (xy 124.546255 -94.060544) (xy 124.493471 -94.042537) (xy 124.443871 -94.017036)
			(xy 124.398513 -93.984585) (xy 124.358364 -93.945876) (xy 124.324278 -93.901733) (xy 124.296982 -93.853098)
			(xy 124.277059 -93.801007) (xy 124.264933 -93.74657) (xy 124.260862 -93.690948) (xy 106.81007 -93.690948)
			(xy 106.81007 -93.692752) (xy 106.802314 -93.746703) (xy 106.786959 -93.799) (xy 106.764319 -93.848581)
			(xy 106.734853 -93.894434) (xy 106.699163 -93.935629) (xy 106.657973 -93.971325) (xy 106.612123 -94.000796)
			(xy 106.562545 -94.023443) (xy 106.51025 -94.038804) (xy 106.4563 -94.046567) (xy 106.429048 -94.047056)
			(xy 106.4008 -94.04657) (xy 106.344919 -94.038253) (xy 106.290878 -94.021778) (xy 106.239861 -93.997507)
			(xy 106.192985 -93.965972) (xy 106.151277 -93.927863) (xy 106.115651 -93.884015) (xy 106.086887 -93.835389)
			(xy 106.065616 -93.78305) (xy 106.058462 -93.755718) (xy 106.054113 -93.740578) (xy 106.037673 -93.713732)
			(xy 106.013855 -93.693149) (xy 105.98491 -93.680772) (xy 105.953573 -93.677773) (xy 105.938066 -93.680534)
			(xy 105.918179 -93.684555) (xy 105.877835 -93.688885) (xy 105.857548 -93.68917) (xy 105.83029 -93.688786)
			(xy 105.776329 -93.681034) (xy 105.72402 -93.665681) (xy 105.674429 -93.643039) (xy 105.628565 -93.613569)
			(xy 105.587362 -93.577872) (xy 105.55166 -93.536674) (xy 105.522184 -93.490814) (xy 105.499536 -93.441225)
			(xy 105.484176 -93.388918) (xy 105.476417 -93.334958) (xy 99.696119 -93.334958) (xy 99.697528 -93.337113)
			(xy 99.720784 -93.387252) (xy 99.736566 -93.44022) (xy 99.744544 -93.494911) (xy 99.745038 -93.522546)
			(xy 99.744552 -93.549797) (xy 99.736796 -93.603745) (xy 99.721441 -93.65604) (xy 99.698799 -93.705617)
			(xy 99.669333 -93.751467) (xy 99.633642 -93.792658) (xy 99.592451 -93.828349) (xy 99.546601 -93.857815)
			(xy 99.497024 -93.880457) (xy 99.444729 -93.895812) (xy 99.390781 -93.903568) (xy 99.336279 -93.903568)
			(xy 99.282331 -93.895812) (xy 99.230036 -93.880457) (xy 99.180459 -93.857815) (xy 99.134609 -93.828349)
			(xy 99.093418 -93.792658) (xy 99.057727 -93.751467) (xy 99.028261 -93.705617) (xy 99.005619 -93.65604)
			(xy 98.990264 -93.603745) (xy 98.982508 -93.549797) (xy 98.982022 -93.522546) (xy 98.982593 -93.492919)
			(xy 98.991736 -93.434376) (xy 99.00981 -93.377947) (xy 99.036381 -93.324986) (xy 99.053142 -93.30055)
			(xy 99.061531 -93.287911) (xy 99.071134 -93.259151) (xy 99.071882 -93.228839) (xy 99.063709 -93.19964)
			(xy 99.047334 -93.17412) (xy 99.036124 -93.163898) (xy 99.015357 -93.145659) (xy 98.978757 -93.104246)
			(xy 98.948511 -93.057988) (xy 98.925253 -93.007851) (xy 98.90947 -92.954884) (xy 98.90149 -92.900194)
			(xy 98.900996 -92.87256) (xy 95.961633 -92.87256) (xy 95.964139 -92.876348) (xy 95.987811 -92.926845)
			(xy 96.003879 -92.980252) (xy 96.011999 -93.035428) (xy 96.012508 -93.063314) (xy 96.011999 -93.0912)
			(xy 96.003879 -93.146376) (xy 95.987811 -93.199783) (xy 95.964139 -93.25028) (xy 95.933366 -93.296793)
			(xy 95.896149 -93.33833) (xy 95.853281 -93.374005) (xy 95.805675 -93.403059) (xy 95.754346 -93.424871)
			(xy 95.700389 -93.438977) (xy 95.644952 -93.445077) (xy 95.589218 -93.44304) (xy 95.534375 -93.43291)
			(xy 95.481591 -93.414903) (xy 95.431991 -93.389402) (xy 95.386633 -93.356951) (xy 95.346484 -93.318242)
			(xy 95.312398 -93.274099) (xy 95.285102 -93.225464) (xy 95.265179 -93.173373) (xy 95.253053 -93.118936)
			(xy 95.248982 -93.063314) (xy 92.841064 -93.063314) (xy 92.840638 -93.090313) (xy 92.833034 -93.143772)
			(xy 92.817966 -93.195624) (xy 92.795735 -93.244833) (xy 92.766787 -93.290414) (xy 92.731698 -93.331457)
			(xy 92.691172 -93.367141) (xy 92.668852 -93.382338) (xy 92.656359 -93.391138) (xy 92.636973 -93.414747)
			(xy 92.625427 -93.443028) (xy 92.622751 -93.473459) (xy 92.629184 -93.503322) (xy 92.644152 -93.529951)
			(xy 92.654882 -93.540834) (xy 92.67337 -93.558912) (xy 92.705772 -93.599209) (xy 92.732427 -93.643518)
			(xy 92.752847 -93.691023) (xy 92.766656 -93.740854) (xy 92.7736 -93.792093) (xy 92.774008 -93.817948)
			(xy 92.773522 -93.845199) (xy 92.765766 -93.899147) (xy 92.750411 -93.951442) (xy 92.727769 -94.001019)
			(xy 92.698303 -94.046869) (xy 92.662612 -94.08806) (xy 92.621421 -94.123751) (xy 92.575571 -94.153217)
			(xy 92.525994 -94.175859) (xy 92.473699 -94.191214) (xy 92.419751 -94.19897) (xy 92.365249 -94.19897)
			(xy 92.311301 -94.191214) (xy 92.259006 -94.175859) (xy 92.209429 -94.153217) (xy 92.163579 -94.123751)
			(xy 92.122388 -94.08806) (xy 92.086697 -94.046869) (xy 92.057231 -94.001019) (xy 92.034589 -93.951442)
			(xy 92.019234 -93.899147) (xy 92.011478 -93.845199) (xy 92.010992 -93.817948) (xy 84.250296 -93.817948)
			(xy 84.220117 -93.844097) (xy 84.174267 -93.873563) (xy 84.12469 -93.896205) (xy 84.072395 -93.91156)
			(xy 84.018447 -93.919316) (xy 83.963945 -93.919316) (xy 83.909997 -93.91156) (xy 83.857702 -93.896205)
			(xy 83.808125 -93.873563) (xy 83.762275 -93.844097) (xy 83.721084 -93.808406) (xy 83.685393 -93.767215)
			(xy 83.655927 -93.721365) (xy 83.633285 -93.671788) (xy 83.61793 -93.619493) (xy 83.610174 -93.565545)
			(xy 83.609688 -93.538294) (xy 6.055868 -93.538294) (xy 6.055868 -94.244668) (xy 112.335562 -94.244668)
			(xy 112.339633 -94.189046) (xy 112.351759 -94.134609) (xy 112.371682 -94.082518) (xy 112.398978 -94.033883)
			(xy 112.433064 -93.98974) (xy 112.473213 -93.951031) (xy 112.518571 -93.91858) (xy 112.568171 -93.893079)
			(xy 112.620955 -93.875072) (xy 112.675798 -93.864942) (xy 112.731532 -93.862905) (xy 112.786969 -93.869005)
			(xy 112.840926 -93.883111) (xy 112.892255 -93.904923) (xy 112.939861 -93.933977) (xy 112.982729 -93.969652)
			(xy 113.019946 -94.011189) (xy 113.050719 -94.057702) (xy 113.074391 -94.108199) (xy 113.090459 -94.161606)
			(xy 113.098579 -94.216782) (xy 113.099088 -94.244668) (xy 113.098579 -94.272554) (xy 113.090459 -94.32773)
			(xy 113.074391 -94.381137) (xy 113.050719 -94.431634) (xy 113.029896 -94.463108) (xy 118.289576 -94.463108)
			(xy 118.293647 -94.407486) (xy 118.305773 -94.353049) (xy 118.325696 -94.300958) (xy 118.352992 -94.252323)
			(xy 118.387078 -94.20818) (xy 118.427227 -94.169471) (xy 118.472585 -94.13702) (xy 118.522185 -94.111519)
			(xy 118.574969 -94.093512) (xy 118.629812 -94.083382) (xy 118.685546 -94.081345) (xy 118.740983 -94.087445)
			(xy 118.79494 -94.101551) (xy 118.846269 -94.123363) (xy 118.893875 -94.152417) (xy 118.908584 -94.164658)
			(xy 120.670572 -94.164658) (xy 120.674643 -94.109036) (xy 120.686769 -94.054599) (xy 120.706692 -94.002508)
			(xy 120.733988 -93.953873) (xy 120.768074 -93.90973) (xy 120.808223 -93.871021) (xy 120.853581 -93.83857)
			(xy 120.903181 -93.813069) (xy 120.955965 -93.795062) (xy 121.010808 -93.784932) (xy 121.066542 -93.782895)
			(xy 121.121979 -93.788995) (xy 121.175936 -93.803101) (xy 121.227265 -93.824913) (xy 121.274871 -93.853967)
			(xy 121.317739 -93.889642) (xy 121.354956 -93.931179) (xy 121.385729 -93.977692) (xy 121.409401 -94.028189)
			(xy 121.425469 -94.081596) (xy 121.433589 -94.136772) (xy 121.434098 -94.164658) (xy 121.433589 -94.192544)
			(xy 121.425469 -94.24772) (xy 121.409401 -94.301127) (xy 121.385729 -94.351624) (xy 121.354956 -94.398137)
			(xy 121.317739 -94.439674) (xy 121.274871 -94.475349) (xy 121.227265 -94.504403) (xy 121.175936 -94.526215)
			(xy 121.121979 -94.540321) (xy 121.068859 -94.546166) (xy 144.448782 -94.546166) (xy 144.452853 -94.490544)
			(xy 144.464979 -94.436107) (xy 144.484902 -94.384016) (xy 144.512198 -94.335381) (xy 144.546284 -94.291238)
			(xy 144.586433 -94.252529) (xy 144.631791 -94.220078) (xy 144.681391 -94.194577) (xy 144.734175 -94.17657)
			(xy 144.789018 -94.16644) (xy 144.844752 -94.164403) (xy 144.900189 -94.170503) (xy 144.954146 -94.184609)
			(xy 145.005475 -94.206421) (xy 145.053081 -94.235475) (xy 145.095949 -94.27115) (xy 145.133166 -94.312687)
			(xy 145.163939 -94.3592) (xy 145.187611 -94.409697) (xy 145.203679 -94.463104) (xy 145.211799 -94.51828)
			(xy 145.212308 -94.546166) (xy 145.211799 -94.574052) (xy 145.203679 -94.629228) (xy 145.187611 -94.682635)
			(xy 145.163939 -94.733132) (xy 145.142757 -94.765148) (xy 153.517114 -94.765148) (xy 153.517114 -94.710652)
			(xy 153.52487 -94.65671) (xy 153.540223 -94.604421) (xy 153.562861 -94.554849) (xy 153.592324 -94.509003)
			(xy 153.628011 -94.467817) (xy 153.669197 -94.432129) (xy 153.715042 -94.402665) (xy 153.764613 -94.380026)
			(xy 153.816902 -94.364671) (xy 153.870844 -94.356915) (xy 153.898092 -94.356428) (xy 153.925369 -94.35686)
			(xy 153.979368 -94.36463) (xy 154.031709 -94.380012) (xy 154.081325 -94.402693) (xy 154.127205 -94.432211)
			(xy 154.168412 -94.467962) (xy 154.204106 -94.509219) (xy 154.23356 -94.555139) (xy 154.256172 -94.604787)
			(xy 154.271482 -94.657149) (xy 154.27579 -94.684088) (xy 154.278393 -94.698514) (xy 154.290578 -94.725158)
			(xy 154.309826 -94.747245) (xy 154.334553 -94.76296) (xy 154.362724 -94.771007) (xy 154.392021 -94.770725)
			(xy 154.420031 -94.762137) (xy 154.432508 -94.754446) (xy 154.456021 -94.739495) (xy 154.506476 -94.715856)
			(xy 154.559835 -94.699813) (xy 154.614961 -94.691706) (xy 154.64282 -94.6912) (xy 154.670071 -94.691671)
			(xy 154.724018 -94.69943) (xy 154.776311 -94.714787) (xy 154.825887 -94.73743) (xy 154.871736 -94.766898)
			(xy 154.912924 -94.80259) (xy 154.948614 -94.84378) (xy 154.97808 -94.889631) (xy 155.00072 -94.939208)
			(xy 155.016074 -94.991502) (xy 155.02383 -95.045449) (xy 155.02383 -95.099951) (xy 155.016074 -95.153898)
			(xy 155.006838 -95.185355) (xy 156.87033 -95.185355) (xy 156.87033 -95.130845) (xy 156.878087 -95.076891)
			(xy 156.893444 -95.024589) (xy 156.916088 -94.975006) (xy 156.945558 -94.92915) (xy 156.981254 -94.887954)
			(xy 157.02245 -94.852258) (xy 157.068306 -94.822788) (xy 157.117889 -94.800144) (xy 157.170191 -94.784787)
			(xy 157.224145 -94.77703) (xy 157.2514 -94.776544) (xy 157.278093 -94.776991) (xy 157.330961 -94.78441)
			(xy 157.382281 -94.799116) (xy 157.406848 -94.809564) (xy 157.420568 -94.815161) (xy 157.449939 -94.818986)
			(xy 157.479172 -94.814219) (xy 157.505807 -94.801263) (xy 157.527602 -94.781206) (xy 157.542724 -94.755738)
			(xy 157.546802 -94.741492) (xy 157.554075 -94.714326) (xy 157.575553 -94.662353) (xy 157.604432 -94.614097)
			(xy 157.640083 -94.570606) (xy 157.681736 -94.532821) (xy 157.728485 -94.501564) (xy 157.779318 -94.47751)
			(xy 157.833133 -94.461183) (xy 157.888762 -94.452936) (xy 157.91688 -94.45244) (xy 157.944137 -94.452806)
			(xy 157.998097 -94.460561) (xy 158.050404 -94.475917) (xy 158.099993 -94.498562) (xy 158.145854 -94.528033)
			(xy 158.187055 -94.563731) (xy 158.222755 -94.60493) (xy 158.252229 -94.650789) (xy 158.274876 -94.700377)
			(xy 158.290235 -94.752683) (xy 158.297993 -94.806643) (xy 158.297993 -94.861157) (xy 158.290235 -94.915117)
			(xy 158.274876 -94.967423) (xy 158.252229 -95.017011) (xy 158.222755 -95.06287) (xy 158.187055 -95.104069)
			(xy 158.145854 -95.139767) (xy 158.099993 -95.169238) (xy 158.050404 -95.191883) (xy 157.998097 -95.207239)
			(xy 157.944137 -95.214994) (xy 157.91688 -95.215456) (xy 157.890187 -95.215015) (xy 157.837319 -95.207594)
			(xy 157.785999 -95.192885) (xy 157.761432 -95.182436) (xy 157.74772 -95.176816) (xy 157.718345 -95.172995)
			(xy 157.68911 -95.177766) (xy 157.662473 -95.190727) (xy 157.640677 -95.210788) (xy 157.625556 -95.23626)
			(xy 157.621478 -95.250508) (xy 157.614132 -95.277652) (xy 157.59266 -95.329621) (xy 157.563789 -95.377873)
			(xy 157.528146 -95.421363) (xy 157.486503 -95.459148) (xy 157.439764 -95.490408) (xy 157.388941 -95.514467)
			(xy 157.335135 -95.530801) (xy 157.279515 -95.539058) (xy 157.2514 -95.53956) (xy 157.224145 -95.53917)
			(xy 157.170191 -95.531413) (xy 157.117889 -95.516056) (xy 157.068306 -95.493412) (xy 157.02245 -95.463942)
			(xy 156.981254 -95.428246) (xy 156.945558 -95.38705) (xy 156.916088 -95.341194) (xy 156.893444 -95.291611)
			(xy 156.878087 -95.239309) (xy 156.87033 -95.185355) (xy 155.006838 -95.185355) (xy 155.00072 -95.206192)
			(xy 154.978079 -95.255769) (xy 154.948614 -95.30162) (xy 154.912924 -95.34281) (xy 154.871736 -95.378502)
			(xy 154.825887 -95.40797) (xy 154.776311 -95.430613) (xy 154.724018 -95.44597) (xy 154.670071 -95.453729)
			(xy 154.64282 -95.454216) (xy 154.615545 -95.453735) (xy 154.56155 -95.445968) (xy 154.509212 -95.430589)
			(xy 154.459598 -95.407913) (xy 154.41372 -95.378401) (xy 154.372514 -95.342655) (xy 154.336819 -95.301405)
			(xy 154.307363 -95.255491) (xy 154.284747 -95.205849) (xy 154.269433 -95.153492) (xy 154.265122 -95.126556)
			(xy 154.262533 -95.112129) (xy 154.250338 -95.085492) (xy 154.231085 -95.063411) (xy 154.206357 -95.047701)
			(xy 154.178188 -95.039654) (xy 154.148894 -95.039932) (xy 154.120882 -95.048511) (xy 154.108404 -95.056198)
			(xy 154.084891 -95.071149) (xy 154.034435 -95.094786) (xy 153.981077 -95.11083) (xy 153.925951 -95.118937)
			(xy 153.898092 -95.119444) (xy 153.870844 -95.118885) (xy 153.816902 -95.111129) (xy 153.764613 -95.095774)
			(xy 153.715042 -95.073135) (xy 153.669197 -95.043671) (xy 153.628011 -95.007983) (xy 153.592324 -94.966797)
			(xy 153.562861 -94.920951) (xy 153.540223 -94.871379) (xy 153.52487 -94.81909) (xy 153.517114 -94.765148)
			(xy 145.142757 -94.765148) (xy 145.133166 -94.779645) (xy 145.095949 -94.821182) (xy 145.053081 -94.856857)
			(xy 145.005475 -94.885911) (xy 144.954146 -94.907723) (xy 144.900189 -94.921829) (xy 144.844752 -94.927929)
			(xy 144.789018 -94.925892) (xy 144.734175 -94.915762) (xy 144.681391 -94.897755) (xy 144.631791 -94.872254)
			(xy 144.586433 -94.839803) (xy 144.546284 -94.801094) (xy 144.512198 -94.756951) (xy 144.484902 -94.708316)
			(xy 144.464979 -94.656225) (xy 144.452853 -94.601788) (xy 144.448782 -94.546166) (xy 121.068859 -94.546166)
			(xy 121.066542 -94.546421) (xy 121.010808 -94.544384) (xy 120.955965 -94.534254) (xy 120.903181 -94.516247)
			(xy 120.853581 -94.490746) (xy 120.808223 -94.458295) (xy 120.768074 -94.419586) (xy 120.733988 -94.375443)
			(xy 120.706692 -94.326808) (xy 120.686769 -94.274717) (xy 120.674643 -94.22028) (xy 120.670572 -94.164658)
			(xy 118.908584 -94.164658) (xy 118.936743 -94.188092) (xy 118.97396 -94.229629) (xy 119.004733 -94.276142)
			(xy 119.028405 -94.326639) (xy 119.044473 -94.380046) (xy 119.052593 -94.435222) (xy 119.053102 -94.463108)
			(xy 119.052593 -94.490994) (xy 119.044473 -94.54617) (xy 119.028405 -94.599577) (xy 119.004733 -94.650074)
			(xy 118.97396 -94.696587) (xy 118.936743 -94.738124) (xy 118.893875 -94.773799) (xy 118.846269 -94.802853)
			(xy 118.79494 -94.824665) (xy 118.740983 -94.838771) (xy 118.685546 -94.844871) (xy 118.629812 -94.842834)
			(xy 118.574969 -94.832704) (xy 118.522185 -94.814697) (xy 118.472585 -94.789196) (xy 118.427227 -94.756745)
			(xy 118.387078 -94.718036) (xy 118.352992 -94.673893) (xy 118.325696 -94.625258) (xy 118.305773 -94.573167)
			(xy 118.293647 -94.51873) (xy 118.289576 -94.463108) (xy 113.029896 -94.463108) (xy 113.019946 -94.478147)
			(xy 112.982729 -94.519684) (xy 112.939861 -94.555359) (xy 112.892255 -94.584413) (xy 112.840926 -94.606225)
			(xy 112.786969 -94.620331) (xy 112.731532 -94.626431) (xy 112.675798 -94.624394) (xy 112.620955 -94.614264)
			(xy 112.568171 -94.596257) (xy 112.518571 -94.570756) (xy 112.473213 -94.538305) (xy 112.433064 -94.499596)
			(xy 112.398978 -94.455453) (xy 112.371682 -94.406818) (xy 112.351759 -94.354727) (xy 112.339633 -94.30029)
			(xy 112.335562 -94.244668) (xy 6.055868 -94.244668) (xy 6.055868 -94.899988) (xy 93.945962 -94.899988)
			(xy 93.950033 -94.844366) (xy 93.962159 -94.789929) (xy 93.982082 -94.737838) (xy 94.009378 -94.689203)
			(xy 94.043464 -94.64506) (xy 94.083613 -94.606351) (xy 94.128971 -94.5739) (xy 94.178571 -94.548399)
			(xy 94.231355 -94.530392) (xy 94.286198 -94.520262) (xy 94.341932 -94.518225) (xy 94.397369 -94.524325)
			(xy 94.451326 -94.538431) (xy 94.502655 -94.560243) (xy 94.550261 -94.589297) (xy 94.593129 -94.624972)
			(xy 94.630346 -94.666509) (xy 94.661119 -94.713022) (xy 94.684791 -94.763519) (xy 94.700859 -94.816926)
			(xy 94.708979 -94.872102) (xy 94.709488 -94.899988) (xy 94.708979 -94.927874) (xy 94.700859 -94.98305)
			(xy 94.684791 -95.036457) (xy 94.661119 -95.086954) (xy 94.630346 -95.133467) (xy 94.593129 -95.175004)
			(xy 94.550261 -95.210679) (xy 94.502655 -95.239733) (xy 94.451326 -95.261545) (xy 94.397369 -95.275651)
			(xy 94.341932 -95.281751) (xy 94.286198 -95.279714) (xy 94.231355 -95.269584) (xy 94.178571 -95.251577)
			(xy 94.128971 -95.226076) (xy 94.083613 -95.193625) (xy 94.043464 -95.154916) (xy 94.009378 -95.110773)
			(xy 93.982082 -95.062138) (xy 93.962159 -95.010047) (xy 93.950033 -94.95561) (xy 93.945962 -94.899988)
			(xy 6.055868 -94.899988) (xy 6.055868 -95.510604) (xy 21.882098 -95.510604) (xy 21.886169 -95.454982)
			(xy 21.898295 -95.400545) (xy 21.918218 -95.348454) (xy 21.945514 -95.299819) (xy 21.9796 -95.255676)
			(xy 22.019749 -95.216967) (xy 22.065107 -95.184516) (xy 22.114707 -95.159015) (xy 22.167491 -95.141008)
			(xy 22.222334 -95.130878) (xy 22.278068 -95.128841) (xy 22.333505 -95.134941) (xy 22.387462 -95.149047)
			(xy 22.438791 -95.170859) (xy 22.486397 -95.199913) (xy 22.529265 -95.235588) (xy 22.566482 -95.277125)
			(xy 22.597255 -95.323638) (xy 22.620927 -95.374135) (xy 22.635697 -95.423228) (xy 38.789862 -95.423228)
			(xy 38.793933 -95.367606) (xy 38.806059 -95.313169) (xy 38.825982 -95.261078) (xy 38.853278 -95.212443)
			(xy 38.887364 -95.1683) (xy 38.927513 -95.129591) (xy 38.972871 -95.09714) (xy 39.022471 -95.071639)
			(xy 39.075255 -95.053632) (xy 39.130098 -95.043502) (xy 39.185832 -95.041465) (xy 39.241269 -95.047565)
			(xy 39.295226 -95.061671) (xy 39.346555 -95.083483) (xy 39.394161 -95.112537) (xy 39.437029 -95.148212)
			(xy 39.474246 -95.189749) (xy 39.505019 -95.236262) (xy 39.528691 -95.286759) (xy 39.544759 -95.340166)
			(xy 39.552879 -95.395342) (xy 39.553388 -95.423228) (xy 39.552879 -95.451114) (xy 39.544759 -95.50629)
			(xy 39.532304 -95.547688) (xy 39.777922 -95.547688) (xy 39.781993 -95.492066) (xy 39.794119 -95.437629)
			(xy 39.814042 -95.385538) (xy 39.841338 -95.336903) (xy 39.875424 -95.29276) (xy 39.915573 -95.254051)
			(xy 39.960931 -95.2216) (xy 40.010531 -95.196099) (xy 40.063315 -95.178092) (xy 40.118158 -95.167962)
			(xy 40.173892 -95.165925) (xy 40.229329 -95.172025) (xy 40.283286 -95.186131) (xy 40.334615 -95.207943)
			(xy 40.382221 -95.236997) (xy 40.425089 -95.272672) (xy 40.462306 -95.314209) (xy 40.493079 -95.360722)
			(xy 40.497313 -95.369754) (xy 86.845334 -95.369754) (xy 86.845334 -95.315246) (xy 86.853091 -95.261292)
			(xy 86.868448 -95.208992) (xy 86.891091 -95.15941) (xy 86.92056 -95.113554) (xy 86.956255 -95.072359)
			(xy 86.997449 -95.036664) (xy 87.043304 -95.007194) (xy 87.092887 -94.98455) (xy 87.145187 -94.969192)
			(xy 87.19914 -94.961434) (xy 87.226394 -94.960948) (xy 87.252956 -94.961468) (xy 87.305567 -94.968838)
			(xy 87.356646 -94.983436) (xy 87.405206 -95.004981) (xy 87.450307 -95.033054) (xy 87.491076 -95.067114)
			(xy 87.526725 -95.106501) (xy 87.556565 -95.150453) (xy 87.580017 -95.198121) (xy 87.59663 -95.248581)
			(xy 87.601806 -95.274638) (xy 87.605017 -95.289151) (xy 87.618505 -95.315617) (xy 87.639052 -95.33707)
			(xy 87.664912 -95.351688) (xy 87.693888 -95.358228) (xy 87.70874 -95.357696) (xy 87.734394 -95.356934)
			(xy 87.76165 -95.357313) (xy 87.815608 -95.36507) (xy 87.867912 -95.380427) (xy 87.917499 -95.403072)
			(xy 87.963357 -95.432543) (xy 88.004555 -95.46824) (xy 88.00913 -95.47352) (xy 102.128066 -95.47352)
			(xy 102.128552 -95.446269) (xy 102.136308 -95.392321) (xy 102.151663 -95.340026) (xy 102.174305 -95.290449)
			(xy 102.203771 -95.244599) (xy 102.239462 -95.203408) (xy 102.280653 -95.167717) (xy 102.326503 -95.138251)
			(xy 102.37608 -95.115609) (xy 102.428375 -95.100254) (xy 102.482323 -95.092498) (xy 102.536825 -95.092498)
			(xy 102.590773 -95.100254) (xy 102.643068 -95.115609) (xy 102.692645 -95.138251) (xy 102.738495 -95.167717)
			(xy 102.779686 -95.203408) (xy 102.815377 -95.244599) (xy 102.844843 -95.290449) (xy 102.867485 -95.340026)
			(xy 102.88284 -95.392321) (xy 102.890596 -95.446269) (xy 102.891082 -95.47352) (xy 102.890656 -95.499794)
			(xy 102.88345 -95.551847) (xy 102.869165 -95.602417) (xy 102.848071 -95.650546) (xy 102.838299 -95.667068)
			(xy 109.220254 -95.667068) (xy 109.22074 -95.639817) (xy 109.228496 -95.585869) (xy 109.243851 -95.533574)
			(xy 109.266493 -95.483997) (xy 109.295959 -95.438147) (xy 109.33165 -95.396956) (xy 109.372841 -95.361265)
			(xy 109.418691 -95.331799) (xy 109.468268 -95.309157) (xy 109.520563 -95.293802) (xy 109.574511 -95.286046)
			(xy 109.629013 -95.286046) (xy 109.682961 -95.293802) (xy 109.735256 -95.309157) (xy 109.784833 -95.331799)
			(xy 109.830683 -95.361265) (xy 109.871874 -95.396956) (xy 109.907565 -95.438147) (xy 109.937031 -95.483997)
			(xy 109.959673 -95.533574) (xy 109.975028 -95.585869) (xy 109.982784 -95.639817) (xy 109.982849 -95.643446)
			(xy 145.538696 -95.643446) (xy 145.542767 -95.587824) (xy 145.554893 -95.533387) (xy 145.574816 -95.481296)
			(xy 145.602112 -95.432661) (xy 145.636198 -95.388518) (xy 145.676347 -95.349809) (xy 145.721705 -95.317358)
			(xy 145.771305 -95.291857) (xy 145.824089 -95.27385) (xy 145.878932 -95.26372) (xy 145.934666 -95.261683)
			(xy 145.990103 -95.267783) (xy 146.04406 -95.281889) (xy 146.095389 -95.303701) (xy 146.142995 -95.332755)
			(xy 146.185863 -95.36843) (xy 146.22308 -95.409967) (xy 146.253853 -95.45648) (xy 146.277525 -95.506977)
			(xy 146.293593 -95.560384) (xy 146.301713 -95.61556) (xy 146.302222 -95.643446) (xy 146.301713 -95.671332)
			(xy 146.293593 -95.726508) (xy 146.277525 -95.779915) (xy 146.253853 -95.830412) (xy 146.22308 -95.876925)
			(xy 146.185863 -95.918462) (xy 146.142995 -95.954137) (xy 146.095389 -95.983191) (xy 146.04406 -96.005003)
			(xy 145.990103 -96.019109) (xy 145.934666 -96.025209) (xy 145.878932 -96.023172) (xy 145.824089 -96.013042)
			(xy 145.771305 -95.995035) (xy 145.721705 -95.969534) (xy 145.676347 -95.937083) (xy 145.636198 -95.898374)
			(xy 145.602112 -95.854231) (xy 145.574816 -95.805596) (xy 145.554893 -95.753505) (xy 145.542767 -95.699068)
			(xy 145.538696 -95.643446) (xy 109.982849 -95.643446) (xy 109.98327 -95.667068) (xy 109.982698 -95.697373)
			(xy 109.973111 -95.757219) (xy 109.954176 -95.814794) (xy 109.926367 -95.868648) (xy 109.908848 -95.893382)
			(xy 109.900381 -95.905929) (xy 109.890379 -95.934475) (xy 109.889177 -95.964699) (xy 109.896881 -95.993949)
			(xy 109.912815 -96.01966) (xy 109.923834 -96.030034) (xy 109.943865 -96.048262) (xy 109.979129 -96.089366)
			(xy 110.008231 -96.13504) (xy 110.030586 -96.184369) (xy 110.045746 -96.236362) (xy 110.053406 -96.289975)
			(xy 110.053882 -96.317054) (xy 110.053396 -96.344305) (xy 110.04564 -96.398253) (xy 110.030285 -96.450548)
			(xy 110.007643 -96.500125) (xy 109.978177 -96.545975) (xy 109.942486 -96.587166) (xy 109.901295 -96.622857)
			(xy 109.855445 -96.652323) (xy 109.805868 -96.674965) (xy 109.753573 -96.69032) (xy 109.699625 -96.698076)
			(xy 109.645123 -96.698076) (xy 109.591175 -96.69032) (xy 109.53888 -96.674965) (xy 109.489303 -96.652323)
			(xy 109.443453 -96.622857) (xy 109.402262 -96.587166) (xy 109.366571 -96.545975) (xy 109.337105 -96.500125)
			(xy 109.314463 -96.450548) (xy 109.299108 -96.398253) (xy 109.291352 -96.344305) (xy 109.290866 -96.317054)
			(xy 109.291443 -96.286749) (xy 109.301026 -96.226903) (xy 109.319961 -96.169327) (xy 109.347768 -96.115474)
			(xy 109.365288 -96.09074) (xy 109.373849 -96.07825) (xy 109.383846 -96.049681) (xy 109.385032 -96.019437)
			(xy 109.377303 -95.990173) (xy 109.361338 -95.964459) (xy 109.350302 -95.954088) (xy 109.33024 -95.935892)
			(xy 109.294977 -95.894782) (xy 109.265878 -95.849102) (xy 109.243528 -95.799766) (xy 109.228376 -95.747767)
			(xy 109.220725 -95.694149) (xy 109.220254 -95.667068) (xy 102.838299 -95.667068) (xy 102.834694 -95.673164)
			(xy 102.827116 -95.686623) (xy 102.819601 -95.716565) (xy 102.821365 -95.747386) (xy 102.832247 -95.776276)
			(xy 102.851255 -95.800601) (xy 102.86365 -95.809816) (xy 102.885043 -95.825147) (xy 102.923782 -95.860775)
			(xy 102.957257 -95.90139) (xy 102.984833 -95.94622) (xy 103.005986 -95.994414) (xy 103.020314 -96.045058)
			(xy 103.027547 -96.09719) (xy 103.027988 -96.123506) (xy 103.027502 -96.150757) (xy 103.019746 -96.204705)
			(xy 103.004391 -96.257) (xy 102.981749 -96.306577) (xy 102.975016 -96.317054) (xy 105.969308 -96.317054)
			(xy 105.969794 -96.289803) (xy 105.97755 -96.235855) (xy 105.992905 -96.18356) (xy 106.015547 -96.133983)
			(xy 106.045013 -96.088133) (xy 106.080704 -96.046942) (xy 106.121895 -96.011251) (xy 106.167745 -95.981785)
			(xy 106.217322 -95.959143) (xy 106.269617 -95.943788) (xy 106.323565 -95.936032) (xy 106.378067 -95.936032)
			(xy 106.432015 -95.943788) (xy 106.48431 -95.959143) (xy 106.533887 -95.981785) (xy 106.579737 -96.011251)
			(xy 106.620928 -96.046942) (xy 106.656619 -96.088133) (xy 106.686085 -96.133983) (xy 106.708727 -96.18356)
			(xy 106.724082 -96.235855) (xy 106.731838 -96.289803) (xy 106.732324 -96.317054) (xy 106.731744 -96.34668)
			(xy 106.722602 -96.405223) (xy 106.704531 -96.461652) (xy 106.677963 -96.514613) (xy 106.661204 -96.53905)
			(xy 106.652805 -96.551684) (xy 106.643197 -96.580446) (xy 106.642449 -96.610762) (xy 106.650625 -96.639963)
			(xy 106.667008 -96.665482) (xy 106.678222 -96.675702) (xy 106.698998 -96.693931) (xy 106.735596 -96.735347)
			(xy 106.765839 -96.781608) (xy 106.789095 -96.831746) (xy 106.804877 -96.884715) (xy 106.812856 -96.939405)
			(xy 106.81335 -96.96704) (xy 106.812864 -96.994291) (xy 106.805108 -97.048239) (xy 106.789753 -97.100534)
			(xy 106.772766 -97.137728) (xy 113.087402 -97.137728) (xy 113.091473 -97.082106) (xy 113.103599 -97.027669)
			(xy 113.123522 -96.975578) (xy 113.150818 -96.926943) (xy 113.184904 -96.8828) (xy 113.225053 -96.844091)
			(xy 113.270411 -96.81164) (xy 113.320011 -96.786139) (xy 113.372795 -96.768132) (xy 113.427638 -96.758002)
			(xy 113.483372 -96.755965) (xy 113.538809 -96.762065) (xy 113.592766 -96.776171) (xy 113.644095 -96.797983)
			(xy 113.691701 -96.827037) (xy 113.734569 -96.862712) (xy 113.771786 -96.904249) (xy 113.802559 -96.950762)
			(xy 113.822335 -96.992948) (xy 144.834862 -96.992948) (xy 144.838933 -96.937326) (xy 144.851059 -96.882889)
			(xy 144.870982 -96.830798) (xy 144.898278 -96.782163) (xy 144.932364 -96.73802) (xy 144.972513 -96.699311)
			(xy 145.017871 -96.66686) (xy 145.067471 -96.641359) (xy 145.120255 -96.623352) (xy 145.175098 -96.613222)
			(xy 145.230832 -96.611185) (xy 145.286269 -96.617285) (xy 145.340226 -96.631391) (xy 145.391555 -96.653203)
			(xy 145.439161 -96.682257) (xy 145.482029 -96.717932) (xy 145.519246 -96.759469) (xy 145.550019 -96.805982)
			(xy 145.573691 -96.856479) (xy 145.589759 -96.909886) (xy 145.597879 -96.965062) (xy 145.598388 -96.992948)
			(xy 145.597879 -97.020834) (xy 145.589759 -97.07601) (xy 145.573691 -97.129417) (xy 145.550019 -97.179914)
			(xy 145.519246 -97.226427) (xy 145.482029 -97.267964) (xy 145.439161 -97.303639) (xy 145.391555 -97.332693)
			(xy 145.340226 -97.354505) (xy 145.286269 -97.368611) (xy 145.230832 -97.374711) (xy 145.175098 -97.372674)
			(xy 145.120255 -97.362544) (xy 145.067471 -97.344537) (xy 145.017871 -97.319036) (xy 144.972513 -97.286585)
			(xy 144.932364 -97.247876) (xy 144.898278 -97.203733) (xy 144.870982 -97.155098) (xy 144.851059 -97.103007)
			(xy 144.838933 -97.04857) (xy 144.834862 -96.992948) (xy 113.822335 -96.992948) (xy 113.826231 -97.001259)
			(xy 113.842299 -97.054666) (xy 113.850419 -97.109842) (xy 113.850928 -97.137728) (xy 113.850419 -97.165614)
			(xy 113.842299 -97.22079) (xy 113.826231 -97.274197) (xy 113.802559 -97.324694) (xy 113.771786 -97.371207)
			(xy 113.734569 -97.412744) (xy 113.720145 -97.424748) (xy 117.346982 -97.424748) (xy 117.351053 -97.369126)
			(xy 117.363179 -97.314689) (xy 117.383102 -97.262598) (xy 117.410398 -97.213963) (xy 117.444484 -97.16982)
			(xy 117.484633 -97.131111) (xy 117.529991 -97.09866) (xy 117.579591 -97.073159) (xy 117.632375 -97.055152)
			(xy 117.687218 -97.045022) (xy 117.742952 -97.042985) (xy 117.798389 -97.049085) (xy 117.852346 -97.063191)
			(xy 117.903675 -97.085003) (xy 117.951281 -97.114057) (xy 117.994149 -97.149732) (xy 118.031366 -97.191269)
			(xy 118.062139 -97.237782) (xy 118.085811 -97.288279) (xy 118.101879 -97.341686) (xy 118.109999 -97.396862)
			(xy 118.110462 -97.422208) (xy 135.563862 -97.422208) (xy 135.567933 -97.366586) (xy 135.580059 -97.312149)
			(xy 135.599982 -97.260058) (xy 135.627278 -97.211423) (xy 135.661364 -97.16728) (xy 135.701513 -97.128571)
			(xy 135.746871 -97.09612) (xy 135.796471 -97.070619) (xy 135.849255 -97.052612) (xy 135.904098 -97.042482)
			(xy 135.959832 -97.040445) (xy 136.015269 -97.046545) (xy 136.069226 -97.060651) (xy 136.120555 -97.082463)
			(xy 136.168161 -97.111517) (xy 136.211029 -97.147192) (xy 136.248246 -97.188729) (xy 136.279019 -97.235242)
			(xy 136.302691 -97.285739) (xy 136.318759 -97.339146) (xy 136.326879 -97.394322) (xy 136.327388 -97.422208)
			(xy 136.326879 -97.450094) (xy 136.325105 -97.462148) (xy 145.681686 -97.462148) (xy 145.681686 -97.407647)
			(xy 145.689443 -97.3537) (xy 145.704798 -97.301407) (xy 145.727438 -97.251831) (xy 145.756904 -97.205982)
			(xy 145.792595 -97.164793) (xy 145.833784 -97.129103) (xy 145.879634 -97.099637) (xy 145.92921 -97.076997)
			(xy 145.981503 -97.061642) (xy 146.035449 -97.053886) (xy 146.0627 -97.0534) (xy 146.089163 -97.053832)
			(xy 146.141583 -97.061146) (xy 146.192488 -97.075634) (xy 146.216878 -97.085912) (xy 146.230273 -97.091313)
			(xy 146.258896 -97.095088) (xy 146.287432 -97.090699) (xy 146.313598 -97.078497) (xy 146.335301 -97.059458)
			(xy 146.350807 -97.035105) (xy 146.358876 -97.007384) (xy 146.359372 -96.992948) (xy 146.359858 -96.965697)
			(xy 146.367614 -96.911749) (xy 146.382969 -96.859454) (xy 146.405611 -96.809877) (xy 146.435077 -96.764027)
			(xy 146.470768 -96.722836) (xy 146.511959 -96.687145) (xy 146.557809 -96.657679) (xy 146.607386 -96.635037)
			(xy 146.659681 -96.619682) (xy 146.713629 -96.611926) (xy 146.768131 -96.611926) (xy 146.822079 -96.619682)
			(xy 146.874374 -96.635037) (xy 146.923951 -96.657679) (xy 146.969801 -96.687145) (xy 147.010992 -96.722836)
			(xy 147.046683 -96.764027) (xy 147.076149 -96.809877) (xy 147.098791 -96.859454) (xy 147.114146 -96.911749)
			(xy 147.121902 -96.965697) (xy 147.122388 -96.992948) (xy 147.122134 -97.004886) (xy 147.122238 -97.019496)
			(xy 147.129633 -97.047743) (xy 147.144713 -97.072747) (xy 147.166248 -97.092467) (xy 147.192479 -97.105293)
			(xy 147.221267 -97.110179) (xy 147.250262 -97.106726) (xy 147.263866 -97.101406) (xy 147.287689 -97.091695)
			(xy 147.33728 -97.078011) (xy 147.388258 -97.071098) (xy 147.41398 -97.070672) (xy 147.441235 -97.071134)
			(xy 147.49519 -97.078888) (xy 147.547493 -97.094243) (xy 147.597078 -97.116885) (xy 147.642935 -97.146354)
			(xy 147.684133 -97.182049) (xy 147.71983 -97.223243) (xy 147.749302 -97.269099) (xy 147.771947 -97.318682)
			(xy 147.787306 -97.370984) (xy 147.795065 -97.424938) (xy 147.795066 -97.479448) (xy 147.787309 -97.533403)
			(xy 147.771952 -97.585705) (xy 147.749308 -97.635289) (xy 147.719838 -97.681146) (xy 147.684142 -97.722342)
			(xy 147.642946 -97.758038) (xy 147.597089 -97.787508) (xy 147.547505 -97.810152) (xy 147.495203 -97.825509)
			(xy 147.441248 -97.833266) (xy 147.386738 -97.833265) (xy 147.332784 -97.825506) (xy 147.280482 -97.810147)
			(xy 147.230899 -97.787502) (xy 147.185043 -97.75803) (xy 147.143849 -97.722333) (xy 147.108154 -97.681135)
			(xy 147.078685 -97.635278) (xy 147.056043 -97.585693) (xy 147.040688 -97.53339) (xy 147.032934 -97.479435)
			(xy 147.032472 -97.45218) (xy 147.032726 -97.440242) (xy 147.032655 -97.425629) (xy 147.025263 -97.397372)
			(xy 147.01018 -97.37236) (xy 146.988639 -97.352636) (xy 146.962398 -97.33981) (xy 146.933601 -97.33493)
			(xy 146.9046 -97.338395) (xy 146.890994 -97.343722) (xy 146.867177 -97.353447) (xy 146.817583 -97.367125)
			(xy 146.766603 -97.374033) (xy 146.74088 -97.374456) (xy 146.714418 -97.373992) (xy 146.662 -97.366691)
			(xy 146.611093 -97.352216) (xy 146.586702 -97.341944) (xy 146.573303 -97.336559) (xy 146.544685 -97.332792)
			(xy 146.516155 -97.337183) (xy 146.489995 -97.349383) (xy 146.468293 -97.368417) (xy 146.452785 -97.392762)
			(xy 146.444709 -97.420475) (xy 146.444208 -97.434908) (xy 146.443714 -97.462159) (xy 146.435956 -97.516105)
			(xy 146.4206 -97.568398) (xy 146.397959 -97.617973) (xy 146.368493 -97.663822) (xy 146.332801 -97.705011)
			(xy 146.291611 -97.740701) (xy 146.245762 -97.770165) (xy 146.196185 -97.792805) (xy 146.143892 -97.808159)
			(xy 146.089945 -97.815915) (xy 146.035444 -97.815914) (xy 145.981498 -97.808157) (xy 145.929205 -97.792801)
			(xy 145.879629 -97.77016) (xy 145.83378 -97.740694) (xy 145.792591 -97.705003) (xy 145.756901 -97.663814)
			(xy 145.727436 -97.617964) (xy 145.704796 -97.568388) (xy 145.689441 -97.516094) (xy 145.681686 -97.462148)
			(xy 136.325105 -97.462148) (xy 136.318759 -97.50527) (xy 136.302691 -97.558677) (xy 136.279019 -97.609174)
			(xy 136.248246 -97.655687) (xy 136.211029 -97.697224) (xy 136.168161 -97.732899) (xy 136.120555 -97.761953)
			(xy 136.069226 -97.783765) (xy 136.015269 -97.797871) (xy 135.959832 -97.803971) (xy 135.904098 -97.801934)
			(xy 135.849255 -97.791804) (xy 135.796471 -97.773797) (xy 135.746871 -97.748296) (xy 135.701513 -97.715845)
			(xy 135.661364 -97.677136) (xy 135.627278 -97.632993) (xy 135.599982 -97.584358) (xy 135.580059 -97.532267)
			(xy 135.567933 -97.47783) (xy 135.563862 -97.422208) (xy 118.110462 -97.422208) (xy 118.110508 -97.424748)
			(xy 118.109999 -97.452634) (xy 118.101879 -97.50781) (xy 118.085811 -97.561217) (xy 118.062139 -97.611714)
			(xy 118.031366 -97.658227) (xy 117.994149 -97.699764) (xy 117.951281 -97.735439) (xy 117.903675 -97.764493)
			(xy 117.852346 -97.786305) (xy 117.798389 -97.800411) (xy 117.742952 -97.806511) (xy 117.687218 -97.804474)
			(xy 117.632375 -97.794344) (xy 117.579591 -97.776337) (xy 117.529991 -97.750836) (xy 117.484633 -97.718385)
			(xy 117.444484 -97.679676) (xy 117.410398 -97.635533) (xy 117.383102 -97.586898) (xy 117.363179 -97.534807)
			(xy 117.351053 -97.48037) (xy 117.346982 -97.424748) (xy 113.720145 -97.424748) (xy 113.691701 -97.448419)
			(xy 113.644095 -97.477473) (xy 113.592766 -97.499285) (xy 113.538809 -97.513391) (xy 113.483372 -97.519491)
			(xy 113.427638 -97.517454) (xy 113.372795 -97.507324) (xy 113.320011 -97.489317) (xy 113.270411 -97.463816)
			(xy 113.225053 -97.431365) (xy 113.184904 -97.392656) (xy 113.150818 -97.348513) (xy 113.123522 -97.299878)
			(xy 113.103599 -97.247787) (xy 113.091473 -97.19335) (xy 113.087402 -97.137728) (xy 106.772766 -97.137728)
			(xy 106.767111 -97.150111) (xy 106.737645 -97.195961) (xy 106.701954 -97.237152) (xy 106.660763 -97.272843)
			(xy 106.614913 -97.302309) (xy 106.565336 -97.324951) (xy 106.513041 -97.340306) (xy 106.459093 -97.348062)
			(xy 106.404591 -97.348062) (xy 106.350643 -97.340306) (xy 106.298348 -97.324951) (xy 106.248771 -97.302309)
			(xy 106.202921 -97.272843) (xy 106.16173 -97.237152) (xy 106.126039 -97.195961) (xy 106.096573 -97.150111)
			(xy 106.073931 -97.100534) (xy 106.058576 -97.048239) (xy 106.05082 -96.994291) (xy 106.050334 -96.96704)
			(xy 106.0509 -96.937413) (xy 106.060044 -96.87887) (xy 106.07812 -96.822441) (xy 106.104692 -96.76948)
			(xy 106.121454 -96.745044) (xy 106.129847 -96.732408) (xy 106.139447 -96.703646) (xy 106.140194 -96.673334)
			(xy 106.13202 -96.644135) (xy 106.115646 -96.618615) (xy 106.104436 -96.608392) (xy 106.083669 -96.590153)
			(xy 106.047068 -96.548741) (xy 106.016822 -96.502483) (xy 105.993564 -96.452345) (xy 105.977781 -96.399378)
			(xy 105.969802 -96.344688) (xy 105.969308 -96.317054) (xy 102.975016 -96.317054) (xy 102.952283 -96.352427)
			(xy 102.916592 -96.393618) (xy 102.875401 -96.429309) (xy 102.829551 -96.458775) (xy 102.779974 -96.481417)
			(xy 102.727679 -96.496772) (xy 102.673731 -96.504528) (xy 102.619229 -96.504528) (xy 102.565281 -96.496772)
			(xy 102.512986 -96.481417) (xy 102.463409 -96.458775) (xy 102.417559 -96.429309) (xy 102.376368 -96.393618)
			(xy 102.340677 -96.352427) (xy 102.311211 -96.306577) (xy 102.288569 -96.257) (xy 102.273214 -96.204705)
			(xy 102.265458 -96.150757) (xy 102.264972 -96.123506) (xy 102.265417 -96.097232) (xy 102.272618 -96.045181)
			(xy 102.286898 -95.994611) (xy 102.307986 -95.946481) (xy 102.32136 -95.923862) (xy 102.328893 -95.910381)
			(xy 102.336407 -95.880449) (xy 102.33465 -95.849638) (xy 102.323781 -95.820754) (xy 102.30479 -95.796428)
			(xy 102.292404 -95.78721) (xy 102.271013 -95.771877) (xy 102.232276 -95.736247) (xy 102.198802 -95.695632)
			(xy 102.171227 -95.650803) (xy 102.150074 -95.60261) (xy 102.135744 -95.551967) (xy 102.128509 -95.499836)
			(xy 102.128066 -95.47352) (xy 88.00913 -95.47352) (xy 88.040254 -95.509438) (xy 88.069726 -95.555296)
			(xy 88.092371 -95.604882) (xy 88.107729 -95.657186) (xy 88.115487 -95.711144) (xy 88.115487 -95.765656)
			(xy 88.107729 -95.819614) (xy 88.092371 -95.871918) (xy 88.069726 -95.921504) (xy 88.040254 -95.967362)
			(xy 88.004555 -96.00856) (xy 87.963357 -96.044257) (xy 87.917499 -96.073728) (xy 87.867912 -96.096373)
			(xy 87.815608 -96.11173) (xy 87.76165 -96.119487) (xy 87.734394 -96.11995) (xy 87.707831 -96.119443)
			(xy 87.65522 -96.112071) (xy 87.604141 -96.097471) (xy 87.555581 -96.075925) (xy 87.51048 -96.04785)
			(xy 87.469711 -96.013789) (xy 87.434062 -95.974401) (xy 87.404222 -95.930447) (xy 87.38077 -95.882779)
			(xy 87.364158 -95.832317) (xy 87.358982 -95.80626) (xy 87.355784 -95.791744) (xy 87.342293 -95.765276)
			(xy 87.321743 -95.743822) (xy 87.29588 -95.729206) (xy 87.266901 -95.722668) (xy 87.252048 -95.723202)
			(xy 87.226394 -95.723964) (xy 87.19914 -95.723566) (xy 87.145187 -95.715808) (xy 87.092887 -95.70045)
			(xy 87.043304 -95.677806) (xy 86.997449 -95.648336) (xy 86.956255 -95.612641) (xy 86.92056 -95.571446)
			(xy 86.891091 -95.52559) (xy 86.868448 -95.476008) (xy 86.853091 -95.423708) (xy 86.845334 -95.369754)
			(xy 40.497313 -95.369754) (xy 40.516751 -95.411219) (xy 40.532819 -95.464626) (xy 40.540939 -95.519802)
			(xy 40.541448 -95.547688) (xy 40.540939 -95.575574) (xy 40.532819 -95.63075) (xy 40.516751 -95.684157)
			(xy 40.493079 -95.734654) (xy 40.462306 -95.781167) (xy 40.425089 -95.822704) (xy 40.382221 -95.858379)
			(xy 40.334615 -95.887433) (xy 40.283286 -95.909245) (xy 40.229329 -95.923351) (xy 40.173892 -95.929451)
			(xy 40.118158 -95.927414) (xy 40.063315 -95.917284) (xy 40.010531 -95.899277) (xy 39.960931 -95.873776)
			(xy 39.915573 -95.841325) (xy 39.875424 -95.802616) (xy 39.841338 -95.758473) (xy 39.814042 -95.709838)
			(xy 39.794119 -95.657747) (xy 39.781993 -95.60331) (xy 39.777922 -95.547688) (xy 39.532304 -95.547688)
			(xy 39.528691 -95.559697) (xy 39.505019 -95.610194) (xy 39.474246 -95.656707) (xy 39.437029 -95.698244)
			(xy 39.394161 -95.733919) (xy 39.346555 -95.762973) (xy 39.295226 -95.784785) (xy 39.241269 -95.798891)
			(xy 39.185832 -95.804991) (xy 39.130098 -95.802954) (xy 39.075255 -95.792824) (xy 39.022471 -95.774817)
			(xy 38.972871 -95.749316) (xy 38.927513 -95.716865) (xy 38.887364 -95.678156) (xy 38.853278 -95.634013)
			(xy 38.825982 -95.585378) (xy 38.806059 -95.533287) (xy 38.793933 -95.47885) (xy 38.789862 -95.423228)
			(xy 22.635697 -95.423228) (xy 22.636995 -95.427542) (xy 22.645115 -95.482718) (xy 22.645624 -95.510604)
			(xy 22.645115 -95.53849) (xy 22.636995 -95.593666) (xy 22.620927 -95.647073) (xy 22.597255 -95.69757)
			(xy 22.566482 -95.744083) (xy 22.529265 -95.78562) (xy 22.486397 -95.821295) (xy 22.438791 -95.850349)
			(xy 22.387462 -95.872161) (xy 22.333505 -95.886267) (xy 22.278068 -95.892367) (xy 22.222334 -95.89033)
			(xy 22.167491 -95.8802) (xy 22.114707 -95.862193) (xy 22.065107 -95.836692) (xy 22.019749 -95.804241)
			(xy 21.9796 -95.765532) (xy 21.945514 -95.721389) (xy 21.918218 -95.672754) (xy 21.898295 -95.620663)
			(xy 21.886169 -95.566226) (xy 21.882098 -95.510604) (xy 6.055868 -95.510604) (xy 6.055868 -96.357948)
			(xy 30.077662 -96.357948) (xy 30.081733 -96.302326) (xy 30.093859 -96.247889) (xy 30.113782 -96.195798)
			(xy 30.141078 -96.147163) (xy 30.175164 -96.10302) (xy 30.215313 -96.064311) (xy 30.260671 -96.03186)
			(xy 30.310271 -96.006359) (xy 30.363055 -95.988352) (xy 30.417898 -95.978222) (xy 30.473632 -95.976185)
			(xy 30.529069 -95.982285) (xy 30.583026 -95.996391) (xy 30.634355 -96.018203) (xy 30.681961 -96.047257)
			(xy 30.724829 -96.082932) (xy 30.762046 -96.124469) (xy 30.792819 -96.170982) (xy 30.816491 -96.221479)
			(xy 30.832559 -96.274886) (xy 30.837984 -96.311751) (xy 82.973397 -96.311751) (xy 82.973397 -96.257249)
			(xy 82.981154 -96.203303) (xy 82.996509 -96.151009) (xy 83.01915 -96.101433) (xy 83.048617 -96.055584)
			(xy 83.084309 -96.014396) (xy 83.125499 -95.978706) (xy 83.171349 -95.949242) (xy 83.220926 -95.926603)
			(xy 83.27322 -95.91125) (xy 83.327167 -95.903496) (xy 83.354418 -95.903034) (xy 83.382665 -95.903558)
			(xy 83.438544 -95.91187) (xy 83.492584 -95.92834) (xy 83.5436 -95.952606) (xy 83.590476 -95.984136)
			(xy 83.632184 -96.022241) (xy 83.667811 -96.066084) (xy 83.696576 -96.114706) (xy 83.717849 -96.167042)
			(xy 83.720416 -96.176846) (xy 92.077538 -96.176846) (xy 92.081609 -96.121224) (xy 92.093735 -96.066787)
			(xy 92.113658 -96.014696) (xy 92.140954 -95.966061) (xy 92.17504 -95.921918) (xy 92.215189 -95.883209)
			(xy 92.260547 -95.850758) (xy 92.310147 -95.825257) (xy 92.362931 -95.80725) (xy 92.417774 -95.79712)
			(xy 92.473508 -95.795083) (xy 92.528945 -95.801183) (xy 92.582902 -95.815289) (xy 92.634231 -95.837101)
			(xy 92.681837 -95.866155) (xy 92.724705 -95.90183) (xy 92.761922 -95.943367) (xy 92.792695 -95.98988)
			(xy 92.816367 -96.040377) (xy 92.832435 -96.093784) (xy 92.840555 -96.14896) (xy 92.841064 -96.176846)
			(xy 95.248982 -96.176846) (xy 95.253053 -96.121224) (xy 95.265179 -96.066787) (xy 95.285102 -96.014696)
			(xy 95.312398 -95.966061) (xy 95.346484 -95.921918) (xy 95.386633 -95.883209) (xy 95.431991 -95.850758)
			(xy 95.481591 -95.825257) (xy 95.534375 -95.80725) (xy 95.589218 -95.79712) (xy 95.644952 -95.795083)
			(xy 95.700389 -95.801183) (xy 95.754346 -95.815289) (xy 95.805675 -95.837101) (xy 95.853281 -95.866155)
			(xy 95.896149 -95.90183) (xy 95.933366 -95.943367) (xy 95.964139 -95.98988) (xy 95.987811 -96.040377)
			(xy 96.003879 -96.093784) (xy 96.008253 -96.123506) (xy 98.892614 -96.123506) (xy 98.8931 -96.096255)
			(xy 98.900856 -96.042307) (xy 98.916211 -95.990012) (xy 98.938853 -95.940435) (xy 98.968319 -95.894585)
			(xy 99.00401 -95.853394) (xy 99.045201 -95.817703) (xy 99.091051 -95.788237) (xy 99.140628 -95.765595)
			(xy 99.192923 -95.75024) (xy 99.246871 -95.742484) (xy 99.301373 -95.742484) (xy 99.355321 -95.75024)
			(xy 99.407616 -95.765595) (xy 99.457193 -95.788237) (xy 99.503043 -95.817703) (xy 99.544234 -95.853394)
			(xy 99.579925 -95.894585) (xy 99.609391 -95.940435) (xy 99.632033 -95.990012) (xy 99.647388 -96.042307)
			(xy 99.655144 -96.096255) (xy 99.65563 -96.123506) (xy 99.655057 -96.153029) (xy 99.645926 -96.211364)
			(xy 99.627915 -96.267596) (xy 99.601454 -96.320381) (xy 99.584764 -96.34474) (xy 99.576651 -96.357014)
			(xy 99.567158 -96.38485) (xy 99.56598 -96.414236) (xy 99.573212 -96.442743) (xy 99.588258 -96.468013)
			(xy 99.598734 -96.478344) (xy 99.617685 -96.496478) (xy 99.650936 -96.537042) (xy 99.67832 -96.581776)
			(xy 99.699323 -96.629839) (xy 99.713548 -96.680324) (xy 99.720728 -96.732281) (xy 99.721162 -96.758506)
			(xy 99.720676 -96.785757) (xy 99.71292 -96.839705) (xy 99.697565 -96.892) (xy 99.674923 -96.941577)
			(xy 99.645457 -96.987427) (xy 99.609766 -97.028618) (xy 99.568575 -97.064309) (xy 99.522725 -97.093775)
			(xy 99.473148 -97.116417) (xy 99.420853 -97.131772) (xy 99.366905 -97.139528) (xy 99.312403 -97.139528)
			(xy 99.258455 -97.131772) (xy 99.20616 -97.116417) (xy 99.156583 -97.093775) (xy 99.110733 -97.064309)
			(xy 99.069542 -97.028618) (xy 99.033851 -96.987427) (xy 99.004385 -96.941577) (xy 98.981743 -96.892)
			(xy 98.966388 -96.839705) (xy 98.958632 -96.785757) (xy 98.958146 -96.758506) (xy 98.95873 -96.728984)
			(xy 98.967858 -96.670649) (xy 98.985866 -96.614417) (xy 99.012324 -96.561632) (xy 99.029012 -96.537272)
			(xy 99.037117 -96.524992) (xy 99.046614 -96.497159) (xy 99.047796 -96.467773) (xy 99.040564 -96.439267)
			(xy 99.025519 -96.413998) (xy 99.015042 -96.403668) (xy 98.996092 -96.385533) (xy 98.962842 -96.344969)
			(xy 98.935458 -96.300234) (xy 98.914456 -96.252172) (xy 98.90023 -96.201688) (xy 98.893049 -96.149731)
			(xy 98.892614 -96.123506) (xy 96.008253 -96.123506) (xy 96.011999 -96.14896) (xy 96.012508 -96.176846)
			(xy 96.011999 -96.204732) (xy 96.003879 -96.259908) (xy 95.987811 -96.313315) (xy 95.964139 -96.363812)
			(xy 95.933366 -96.410325) (xy 95.896149 -96.451862) (xy 95.853281 -96.487537) (xy 95.805675 -96.516591)
			(xy 95.754346 -96.538403) (xy 95.700389 -96.552509) (xy 95.644952 -96.558609) (xy 95.589218 -96.556572)
			(xy 95.534375 -96.546442) (xy 95.481591 -96.528435) (xy 95.431991 -96.502934) (xy 95.386633 -96.470483)
			(xy 95.346484 -96.431774) (xy 95.312398 -96.387631) (xy 95.285102 -96.338996) (xy 95.265179 -96.286905)
			(xy 95.253053 -96.232468) (xy 95.248982 -96.176846) (xy 92.841064 -96.176846) (xy 92.840555 -96.204732)
			(xy 92.832435 -96.259908) (xy 92.816367 -96.313315) (xy 92.792695 -96.363812) (xy 92.761922 -96.410325)
			(xy 92.724705 -96.451862) (xy 92.681837 -96.487537) (xy 92.634231 -96.516591) (xy 92.582902 -96.538403)
			(xy 92.528945 -96.552509) (xy 92.473508 -96.558609) (xy 92.417774 -96.556572) (xy 92.362931 -96.546442)
			(xy 92.310147 -96.528435) (xy 92.260547 -96.502934) (xy 92.215189 -96.470483) (xy 92.17504 -96.431774)
			(xy 92.140954 -96.387631) (xy 92.113658 -96.338996) (xy 92.093735 -96.286905) (xy 92.081609 -96.232468)
			(xy 92.077538 -96.176846) (xy 83.720416 -96.176846) (xy 83.725004 -96.194372) (xy 83.728487 -96.207019)
			(xy 83.741019 -96.230058) (xy 83.759001 -96.249149) (xy 83.781249 -96.263035) (xy 83.806298 -96.270804)
			(xy 83.8325 -96.271943) (xy 83.8454 -96.269556) (xy 83.865285 -96.265524) (xy 83.90563 -96.261201)
			(xy 83.925918 -96.26092) (xy 83.95317 -96.261351) (xy 84.00712 -96.26911) (xy 84.059417 -96.284468)
			(xy 84.108995 -96.307112) (xy 84.154847 -96.336581) (xy 84.196038 -96.372275) (xy 84.23173 -96.413468)
			(xy 84.261197 -96.459321) (xy 84.283838 -96.5089) (xy 84.299194 -96.561197) (xy 84.30695 -96.615148)
			(xy 84.30695 -96.669652) (xy 84.299194 -96.723603) (xy 84.283838 -96.7759) (xy 84.261197 -96.825479)
			(xy 84.23173 -96.871332) (xy 84.196038 -96.912525) (xy 84.154847 -96.948219) (xy 84.108995 -96.977688)
			(xy 84.059417 -97.000332) (xy 84.00712 -97.01569) (xy 83.95317 -97.023449) (xy 83.925918 -97.023936)
			(xy 83.897671 -97.023402) (xy 83.841791 -97.015094) (xy 83.787751 -96.998628) (xy 83.736733 -96.974365)
			(xy 83.689856 -96.942836) (xy 83.648147 -96.904732) (xy 83.61252 -96.860888) (xy 83.583756 -96.812265)
			(xy 83.562486 -96.759929) (xy 83.555332 -96.732598) (xy 83.551828 -96.719958) (xy 83.539296 -96.696926)
			(xy 83.521317 -96.677838) (xy 83.499075 -96.663951) (xy 83.474031 -96.656179) (xy 83.447835 -96.655033)
			(xy 83.434936 -96.657414) (xy 83.41505 -96.66144) (xy 83.374706 -96.665767) (xy 83.354418 -96.66605)
			(xy 83.327167 -96.665504) (xy 83.27322 -96.65775) (xy 83.220926 -96.642397) (xy 83.171349 -96.619758)
			(xy 83.125499 -96.590294) (xy 83.084309 -96.554604) (xy 83.048617 -96.513416) (xy 83.01915 -96.467567)
			(xy 82.996509 -96.417991) (xy 82.981154 -96.365697) (xy 82.973397 -96.311751) (xy 30.837984 -96.311751)
			(xy 30.840679 -96.330062) (xy 30.841188 -96.357948) (xy 30.840679 -96.385834) (xy 30.832559 -96.44101)
			(xy 30.816491 -96.494417) (xy 30.792819 -96.544914) (xy 30.762046 -96.591427) (xy 30.724829 -96.632964)
			(xy 30.681961 -96.668639) (xy 30.634355 -96.697693) (xy 30.583026 -96.719505) (xy 30.529069 -96.733611)
			(xy 30.473632 -96.739711) (xy 30.417898 -96.737674) (xy 30.363055 -96.727544) (xy 30.310271 -96.709537)
			(xy 30.260671 -96.684036) (xy 30.215313 -96.651585) (xy 30.175164 -96.612876) (xy 30.141078 -96.568733)
			(xy 30.113782 -96.520098) (xy 30.093859 -96.468007) (xy 30.081733 -96.41357) (xy 30.077662 -96.357948)
			(xy 6.055868 -96.357948) (xy 6.055868 -96.82734) (xy 9.83107 -96.82734) (xy 10.373106 -97.36963)
			(xy 10.383086 -97.379004) (xy 10.406872 -97.392543) (xy 10.433401 -97.399274) (xy 10.460764 -97.39871)
			(xy 10.486994 -97.390893) (xy 10.510202 -97.376385) (xy 10.528718 -97.35623) (xy 10.541211 -97.331879)
			(xy 10.546782 -97.305082) (xy 10.546334 -97.291398) (xy 10.545572 -97.267268) (xy 10.54606 -97.240016)
			(xy 10.553821 -97.186066) (xy 10.569182 -97.13377) (xy 10.591828 -97.084192) (xy 10.621299 -97.038342)
			(xy 10.656995 -96.997153) (xy 10.69819 -96.961463) (xy 10.744045 -96.931999) (xy 10.793626 -96.909361)
			(xy 10.845925 -96.894009) (xy 10.899875 -96.886256) (xy 10.95438 -96.88626) (xy 11.00833 -96.894021)
			(xy 11.060626 -96.90938) (xy 11.110204 -96.932026) (xy 11.156054 -96.961497) (xy 11.197244 -96.997193)
			(xy 11.232935 -97.038387) (xy 11.262399 -97.084242) (xy 11.285038 -97.133823) (xy 11.30039 -97.186121)
			(xy 11.308144 -97.240071) (xy 11.30814 -97.294576) (xy 11.30038 -97.348526) (xy 11.285021 -97.400822)
			(xy 11.262376 -97.450401) (xy 11.232906 -97.496251) (xy 11.19721 -97.537441) (xy 11.156016 -97.573132)
			(xy 11.110162 -97.602597) (xy 11.060581 -97.625237) (xy 11.02539 -97.635568) (xy 12.165582 -97.635568)
			(xy 12.169653 -97.579946) (xy 12.181779 -97.525509) (xy 12.201702 -97.473418) (xy 12.228998 -97.424783)
			(xy 12.263084 -97.38064) (xy 12.303233 -97.341931) (xy 12.348591 -97.30948) (xy 12.398191 -97.283979)
			(xy 12.450975 -97.265972) (xy 12.505818 -97.255842) (xy 12.561552 -97.253805) (xy 12.616989 -97.259905)
			(xy 12.670946 -97.274011) (xy 12.722275 -97.295823) (xy 12.769881 -97.324877) (xy 12.812749 -97.360552)
			(xy 12.849966 -97.402089) (xy 12.880739 -97.448602) (xy 12.904411 -97.499099) (xy 12.920479 -97.552506)
			(xy 12.928599 -97.607682) (xy 12.928969 -97.627948) (xy 15.198342 -97.627948) (xy 15.202413 -97.572326)
			(xy 15.214539 -97.517889) (xy 15.234462 -97.465798) (xy 15.261758 -97.417163) (xy 15.295844 -97.37302)
			(xy 15.335993 -97.334311) (xy 15.381351 -97.30186) (xy 15.430951 -97.276359) (xy 15.483735 -97.258352)
			(xy 15.538578 -97.248222) (xy 15.594312 -97.246185) (xy 15.649749 -97.252285) (xy 15.703706 -97.266391)
			(xy 15.755035 -97.288203) (xy 15.802641 -97.317257) (xy 15.845509 -97.352932) (xy 15.882726 -97.394469)
			(xy 15.913499 -97.440982) (xy 15.937171 -97.491479) (xy 15.953239 -97.544886) (xy 15.954585 -97.554034)
			(xy 31.36976 -97.554034) (xy 31.373831 -97.498412) (xy 31.385957 -97.443975) (xy 31.40588 -97.391884)
			(xy 31.433176 -97.343249) (xy 31.467262 -97.299106) (xy 31.507411 -97.260397) (xy 31.552769 -97.227946)
			(xy 31.602369 -97.202445) (xy 31.655153 -97.184438) (xy 31.709996 -97.174308) (xy 31.76573 -97.172271)
			(xy 31.821167 -97.178371) (xy 31.875124 -97.192477) (xy 31.926453 -97.214289) (xy 31.974059 -97.243343)
			(xy 32.016927 -97.279018) (xy 32.02233 -97.285048) (xy 48.101502 -97.285048) (xy 48.105573 -97.229426)
			(xy 48.117699 -97.174989) (xy 48.137622 -97.122898) (xy 48.164918 -97.074263) (xy 48.199004 -97.03012)
			(xy 48.239153 -96.991411) (xy 48.284511 -96.95896) (xy 48.334111 -96.933459) (xy 48.386895 -96.915452)
			(xy 48.441738 -96.905322) (xy 48.497472 -96.903285) (xy 48.552909 -96.909385) (xy 48.606866 -96.923491)
			(xy 48.658195 -96.945303) (xy 48.705801 -96.974357) (xy 48.748669 -97.010032) (xy 48.785886 -97.051569)
			(xy 48.816659 -97.098082) (xy 48.820003 -97.105216) (xy 92.077538 -97.105216) (xy 92.081609 -97.049594)
			(xy 92.093735 -96.995157) (xy 92.113658 -96.943066) (xy 92.140954 -96.894431) (xy 92.17504 -96.850288)
			(xy 92.215189 -96.811579) (xy 92.260547 -96.779128) (xy 92.310147 -96.753627) (xy 92.362931 -96.73562)
			(xy 92.417774 -96.72549) (xy 92.473508 -96.723453) (xy 92.528945 -96.729553) (xy 92.582902 -96.743659)
			(xy 92.634231 -96.765471) (xy 92.681837 -96.794525) (xy 92.724705 -96.8302) (xy 92.761922 -96.871737)
			(xy 92.792695 -96.91825) (xy 92.816367 -96.968747) (xy 92.832435 -97.022154) (xy 92.840555 -97.07733)
			(xy 92.841064 -97.105216) (xy 92.840555 -97.133102) (xy 92.832435 -97.188278) (xy 92.816367 -97.241685)
			(xy 92.792695 -97.292182) (xy 92.761922 -97.338695) (xy 92.724705 -97.380232) (xy 92.681837 -97.415907)
			(xy 92.634231 -97.444961) (xy 92.582902 -97.466773) (xy 92.528945 -97.480879) (xy 92.473508 -97.486979)
			(xy 92.417774 -97.484942) (xy 92.362931 -97.474812) (xy 92.310147 -97.456805) (xy 92.260547 -97.431304)
			(xy 92.215189 -97.398853) (xy 92.17504 -97.360144) (xy 92.140954 -97.316001) (xy 92.113658 -97.267366)
			(xy 92.093735 -97.215275) (xy 92.081609 -97.160838) (xy 92.077538 -97.105216) (xy 48.820003 -97.105216)
			(xy 48.840331 -97.148579) (xy 48.856399 -97.201986) (xy 48.864519 -97.257162) (xy 48.865028 -97.285048)
			(xy 48.864519 -97.312934) (xy 48.856399 -97.36811) (xy 48.840331 -97.421517) (xy 48.816659 -97.472014)
			(xy 48.785886 -97.518527) (xy 48.748669 -97.560064) (xy 48.705801 -97.595739) (xy 48.658195 -97.624793)
			(xy 48.606866 -97.646605) (xy 48.552909 -97.660711) (xy 48.497472 -97.666811) (xy 48.441738 -97.664774)
			(xy 48.386895 -97.654644) (xy 48.334111 -97.636637) (xy 48.284511 -97.611136) (xy 48.239153 -97.578685)
			(xy 48.199004 -97.539976) (xy 48.164918 -97.495833) (xy 48.137622 -97.447198) (xy 48.117699 -97.395107)
			(xy 48.105573 -97.34067) (xy 48.101502 -97.285048) (xy 32.02233 -97.285048) (xy 32.054144 -97.320555)
			(xy 32.084917 -97.367068) (xy 32.108589 -97.417565) (xy 32.124657 -97.470972) (xy 32.132777 -97.526148)
			(xy 32.133286 -97.554034) (xy 32.132777 -97.58192) (xy 32.124657 -97.637096) (xy 32.108589 -97.690503)
			(xy 32.084917 -97.741) (xy 32.054144 -97.787513) (xy 32.035757 -97.808034) (xy 46.97806 -97.808034)
			(xy 46.982131 -97.752412) (xy 46.994257 -97.697975) (xy 47.01418 -97.645884) (xy 47.041476 -97.597249)
			(xy 47.075562 -97.553106) (xy 47.115711 -97.514397) (xy 47.161069 -97.481946) (xy 47.210669 -97.456445)
			(xy 47.263453 -97.438438) (xy 47.318296 -97.428308) (xy 47.37403 -97.426271) (xy 47.429467 -97.432371)
			(xy 47.483424 -97.446477) (xy 47.534753 -97.468289) (xy 47.582359 -97.497343) (xy 47.625227 -97.533018)
			(xy 47.662444 -97.574555) (xy 47.693217 -97.621068) (xy 47.716889 -97.671565) (xy 47.732957 -97.724972)
			(xy 47.741077 -97.780148) (xy 47.741586 -97.808034) (xy 47.741077 -97.83592) (xy 47.732957 -97.891096)
			(xy 47.716889 -97.944503) (xy 47.693217 -97.995) (xy 47.662444 -98.041513) (xy 47.625227 -98.08305)
			(xy 47.582359 -98.118725) (xy 47.534753 -98.147779) (xy 47.483424 -98.169591) (xy 47.429467 -98.183697)
			(xy 47.37403 -98.189797) (xy 47.318296 -98.18776) (xy 47.263453 -98.17763) (xy 47.210669 -98.159623)
			(xy 47.161069 -98.134122) (xy 47.115711 -98.101671) (xy 47.075562 -98.062962) (xy 47.041476 -98.018819)
			(xy 47.01418 -97.970184) (xy 46.994257 -97.918093) (xy 46.982131 -97.863656) (xy 46.97806 -97.808034)
			(xy 32.035757 -97.808034) (xy 32.016927 -97.82905) (xy 31.974059 -97.864725) (xy 31.926453 -97.893779)
			(xy 31.875124 -97.915591) (xy 31.821167 -97.929697) (xy 31.76573 -97.935797) (xy 31.709996 -97.93376)
			(xy 31.655153 -97.92363) (xy 31.602369 -97.905623) (xy 31.552769 -97.880122) (xy 31.507411 -97.847671)
			(xy 31.467262 -97.808962) (xy 31.433176 -97.764819) (xy 31.40588 -97.716184) (xy 31.385957 -97.664093)
			(xy 31.373831 -97.609656) (xy 31.36976 -97.554034) (xy 15.954585 -97.554034) (xy 15.961359 -97.600062)
			(xy 15.961868 -97.627948) (xy 15.961359 -97.655834) (xy 15.953239 -97.71101) (xy 15.937171 -97.764417)
			(xy 15.913499 -97.814914) (xy 15.882726 -97.861427) (xy 15.845509 -97.902964) (xy 15.802641 -97.938639)
			(xy 15.755035 -97.967693) (xy 15.703706 -97.989505) (xy 15.649749 -98.003611) (xy 15.594312 -98.009711)
			(xy 15.538578 -98.007674) (xy 15.483735 -97.997544) (xy 15.430951 -97.979537) (xy 15.381351 -97.954036)
			(xy 15.335993 -97.921585) (xy 15.295844 -97.882876) (xy 15.261758 -97.838733) (xy 15.234462 -97.790098)
			(xy 15.214539 -97.738007) (xy 15.202413 -97.68357) (xy 15.198342 -97.627948) (xy 12.928969 -97.627948)
			(xy 12.929108 -97.635568) (xy 12.928599 -97.663454) (xy 12.920479 -97.71863) (xy 12.904411 -97.772037)
			(xy 12.880739 -97.822534) (xy 12.849966 -97.869047) (xy 12.812749 -97.910584) (xy 12.769881 -97.946259)
			(xy 12.722275 -97.975313) (xy 12.670946 -97.997125) (xy 12.616989 -98.011231) (xy 12.561552 -98.017331)
			(xy 12.505818 -98.015294) (xy 12.450975 -98.005164) (xy 12.398191 -97.987157) (xy 12.348591 -97.961656)
			(xy 12.303233 -97.929205) (xy 12.263084 -97.890496) (xy 12.228998 -97.846353) (xy 12.201702 -97.797718)
			(xy 12.181779 -97.745627) (xy 12.169653 -97.69119) (xy 12.165582 -97.635568) (xy 11.02539 -97.635568)
			(xy 11.008283 -97.64059) (xy 10.954333 -97.648344) (xy 10.92708 -97.648776) (xy 10.897662 -97.648211)
			(xy 10.839527 -97.63915) (xy 10.783467 -97.62129) (xy 10.7569 -97.608644) (xy 10.743449 -97.602518)
			(xy 10.714337 -97.597493) (xy 10.685005 -97.601009) (xy 10.657905 -97.612773) (xy 10.635306 -97.6318)
			(xy 10.619097 -97.6565) (xy 10.610636 -97.684805) (xy 10.610088 -97.699576) (xy 10.610088 -98.056954)
			(xy 10.632164 -98.072201) (xy 10.672216 -98.107897) (xy 10.706877 -98.14885) (xy 10.721142 -98.171508)
			(xy 21.848062 -98.171508) (xy 21.852133 -98.115886) (xy 21.864259 -98.061449) (xy 21.884182 -98.009358)
			(xy 21.911478 -97.960723) (xy 21.945564 -97.91658) (xy 21.985713 -97.877871) (xy 22.031071 -97.84542)
			(xy 22.080671 -97.819919) (xy 22.133455 -97.801912) (xy 22.188298 -97.791782) (xy 22.244032 -97.789745)
			(xy 22.299469 -97.795845) (xy 22.353426 -97.809951) (xy 22.404755 -97.831763) (xy 22.452361 -97.860817)
			(xy 22.495229 -97.896492) (xy 22.532446 -97.938029) (xy 22.563219 -97.984542) (xy 22.586891 -98.035039)
			(xy 22.602959 -98.088446) (xy 22.611079 -98.143622) (xy 22.611588 -98.171508) (xy 22.611079 -98.199394)
			(xy 22.602959 -98.25457) (xy 22.586891 -98.307977) (xy 22.563219 -98.358474) (xy 22.532446 -98.404987)
			(xy 22.495229 -98.446524) (xy 22.452361 -98.482199) (xy 22.404755 -98.511253) (xy 22.353426 -98.533065)
			(xy 22.299469 -98.547171) (xy 22.244032 -98.553271) (xy 22.188298 -98.551234) (xy 22.133455 -98.541104)
			(xy 22.080671 -98.523097) (xy 22.031071 -98.497596) (xy 21.985713 -98.465145) (xy 21.945564 -98.426436)
			(xy 21.911478 -98.382293) (xy 21.884182 -98.333658) (xy 21.864259 -98.281567) (xy 21.852133 -98.22713)
			(xy 21.848062 -98.171508) (xy 10.721142 -98.171508) (xy 10.735461 -98.194252) (xy 10.757407 -98.243209)
			(xy 10.772283 -98.294756) (xy 10.779794 -98.347879) (xy 10.779793 -98.40153) (xy 10.772281 -98.454652)
			(xy 10.757404 -98.5062) (xy 10.735457 -98.555156) (xy 10.726089 -98.570034) (xy 26.872436 -98.570034)
			(xy 26.876507 -98.514412) (xy 26.888633 -98.459975) (xy 26.908556 -98.407884) (xy 26.935852 -98.359249)
			(xy 26.969938 -98.315106) (xy 27.010087 -98.276397) (xy 27.055445 -98.243946) (xy 27.105045 -98.218445)
			(xy 27.157829 -98.200438) (xy 27.212672 -98.190308) (xy 27.268406 -98.188271) (xy 27.323843 -98.194371)
			(xy 27.3778 -98.208477) (xy 27.429129 -98.230289) (xy 27.476735 -98.259343) (xy 27.519603 -98.295018)
			(xy 27.55682 -98.336555) (xy 27.587593 -98.383068) (xy 27.611265 -98.433565) (xy 27.627333 -98.486972)
			(xy 27.635453 -98.542148) (xy 27.635962 -98.570034) (xy 29.96006 -98.570034) (xy 29.964131 -98.514412)
			(xy 29.976257 -98.459975) (xy 29.99618 -98.407884) (xy 30.023476 -98.359249) (xy 30.057562 -98.315106)
			(xy 30.097711 -98.276397) (xy 30.143069 -98.243946) (xy 30.192669 -98.218445) (xy 30.245453 -98.200438)
			(xy 30.300296 -98.190308) (xy 30.35603 -98.188271) (xy 30.411467 -98.194371) (xy 30.465424 -98.208477)
			(xy 30.516753 -98.230289) (xy 30.564359 -98.259343) (xy 30.607227 -98.295018) (xy 30.644444 -98.336555)
			(xy 30.675217 -98.383068) (xy 30.698889 -98.433565) (xy 30.714957 -98.486972) (xy 30.723077 -98.542148)
			(xy 30.723586 -98.570034) (xy 31.36976 -98.570034) (xy 31.373831 -98.514412) (xy 31.385957 -98.459975)
			(xy 31.40588 -98.407884) (xy 31.433176 -98.359249) (xy 31.467262 -98.315106) (xy 31.507411 -98.276397)
			(xy 31.552769 -98.243946) (xy 31.602369 -98.218445) (xy 31.655153 -98.200438) (xy 31.709996 -98.190308)
			(xy 31.76573 -98.188271) (xy 31.821167 -98.194371) (xy 31.875124 -98.208477) (xy 31.926453 -98.230289)
			(xy 31.974059 -98.259343) (xy 32.016927 -98.295018) (xy 32.054144 -98.336555) (xy 32.05586 -98.339148)
			(xy 48.101502 -98.339148) (xy 48.105573 -98.283526) (xy 48.117699 -98.229089) (xy 48.137622 -98.176998)
			(xy 48.164918 -98.128363) (xy 48.199004 -98.08422) (xy 48.239153 -98.045511) (xy 48.284511 -98.01306)
			(xy 48.334111 -97.987559) (xy 48.386895 -97.969552) (xy 48.441738 -97.959422) (xy 48.497472 -97.957385)
			(xy 48.552909 -97.963485) (xy 48.606866 -97.977591) (xy 48.658195 -97.999403) (xy 48.705801 -98.028457)
			(xy 48.748669 -98.064132) (xy 48.785886 -98.105669) (xy 48.816659 -98.152182) (xy 48.840331 -98.202679)
			(xy 48.856399 -98.256086) (xy 48.864519 -98.311262) (xy 48.865028 -98.339148) (xy 48.864519 -98.367034)
			(xy 48.856399 -98.42221) (xy 48.840331 -98.475617) (xy 48.816659 -98.526114) (xy 48.801549 -98.548952)
			(xy 86.829898 -98.548952) (xy 86.833969 -98.49333) (xy 86.846095 -98.438893) (xy 86.866018 -98.386802)
			(xy 86.893314 -98.338167) (xy 86.9274 -98.294024) (xy 86.967549 -98.255315) (xy 87.012907 -98.222864)
			(xy 87.062507 -98.197363) (xy 87.115291 -98.179356) (xy 87.170134 -98.169226) (xy 87.225868 -98.167189)
			(xy 87.281305 -98.173289) (xy 87.335262 -98.187395) (xy 87.386591 -98.209207) (xy 87.434197 -98.238261)
			(xy 87.477065 -98.273936) (xy 87.514282 -98.315473) (xy 87.545055 -98.361986) (xy 87.547447 -98.367088)
			(xy 95.318072 -98.367088) (xy 95.318558 -98.339837) (xy 95.326314 -98.285889) (xy 95.341669 -98.233594)
			(xy 95.364311 -98.184017) (xy 95.393777 -98.138167) (xy 95.429468 -98.096976) (xy 95.470659 -98.061285)
			(xy 95.516509 -98.031819) (xy 95.566086 -98.009177) (xy 95.618381 -97.993822) (xy 95.672329 -97.986066)
			(xy 95.726831 -97.986066) (xy 95.780779 -97.993822) (xy 95.833074 -98.009177) (xy 95.882651 -98.031819)
			(xy 95.928501 -98.061285) (xy 95.969692 -98.096976) (xy 96.005383 -98.138167) (xy 96.034849 -98.184017)
			(xy 96.057491 -98.233594) (xy 96.072846 -98.285889) (xy 96.080602 -98.339837) (xy 96.081088 -98.367088)
			(xy 96.080623 -98.392949) (xy 96.073644 -98.444199) (xy 96.059798 -98.494033) (xy 96.03934 -98.541538)
			(xy 96.012646 -98.58584) (xy 95.980206 -98.626124) (xy 95.961708 -98.644202) (xy 95.95212 -98.653836)
			(xy 95.937995 -98.67705) (xy 95.930487 -98.703164) (xy 95.930124 -98.730335) (xy 95.936934 -98.75664)
			(xy 95.946871 -98.773996) (xy 102.125272 -98.773996) (xy 102.125758 -98.746745) (xy 102.133514 -98.692797)
			(xy 102.148869 -98.640502) (xy 102.171511 -98.590925) (xy 102.200977 -98.545075) (xy 102.236668 -98.503884)
			(xy 102.277859 -98.468193) (xy 102.323709 -98.438727) (xy 102.373286 -98.416085) (xy 102.425581 -98.40073)
			(xy 102.479529 -98.392974) (xy 102.534031 -98.392974) (xy 102.587979 -98.40073) (xy 102.640274 -98.416085)
			(xy 102.689851 -98.438727) (xy 102.735701 -98.468193) (xy 102.776892 -98.503884) (xy 102.812583 -98.545075)
			(xy 102.842049 -98.590925) (xy 102.864691 -98.640502) (xy 102.880046 -98.692797) (xy 102.887802 -98.746745)
			(xy 102.888288 -98.773996) (xy 102.887664 -98.805754) (xy 102.877186 -98.8684) (xy 102.856453 -98.928436)
			(xy 102.841806 -98.956622) (xy 102.835926 -98.968347) (xy 102.831416 -98.986649) (xy 109.244394 -98.986649)
			(xy 109.244394 -98.932151) (xy 109.25215 -98.878207) (xy 109.267504 -98.825915) (xy 109.290143 -98.776341)
			(xy 109.319606 -98.730494) (xy 109.355294 -98.689306) (xy 109.396481 -98.653616) (xy 109.442327 -98.62415)
			(xy 109.4919 -98.601509) (xy 109.544191 -98.586153) (xy 109.598135 -98.578395) (xy 109.625384 -98.577908)
			(xy 109.651951 -98.578296) (xy 109.704569 -98.58568) (xy 109.755654 -98.600293) (xy 109.804217 -98.621852)
			(xy 109.84932 -98.64994) (xy 109.890089 -98.684015) (xy 109.925736 -98.723416) (xy 109.955572 -98.767382)
			(xy 109.979019 -98.815063) (xy 109.995624 -98.865535) (xy 110.000796 -98.891598) (xy 110.003879 -98.906145)
			(xy 110.017397 -98.93262) (xy 110.037975 -98.954073) (xy 110.063865 -98.96868) (xy 110.092868 -98.975201)
			(xy 110.10773 -98.974656) (xy 110.133384 -98.973894) (xy 110.160638 -98.974352) (xy 110.214591 -98.982107)
			(xy 110.266891 -98.997462) (xy 110.316473 -99.020104) (xy 110.362328 -99.049572) (xy 110.403523 -99.085265)
			(xy 110.439219 -99.126459) (xy 110.468688 -99.172313) (xy 110.491332 -99.221894) (xy 110.506689 -99.274194)
			(xy 110.514447 -99.328146) (xy 110.514447 -99.382654) (xy 110.511097 -99.405948) (xy 119.688862 -99.405948)
			(xy 119.692933 -99.350326) (xy 119.705059 -99.295889) (xy 119.724982 -99.243798) (xy 119.752278 -99.195163)
			(xy 119.786364 -99.15102) (xy 119.826513 -99.112311) (xy 119.871871 -99.07986) (xy 119.921471 -99.054359)
			(xy 119.974255 -99.036352) (xy 120.029098 -99.026222) (xy 120.084832 -99.024185) (xy 120.140269 -99.030285)
			(xy 120.194226 -99.044391) (xy 120.245555 -99.066203) (xy 120.293161 -99.095257) (xy 120.336029 -99.130932)
			(xy 120.354859 -99.151948) (xy 129.086862 -99.151948) (xy 129.090933 -99.096326) (xy 129.103059 -99.041889)
			(xy 129.122982 -98.989798) (xy 129.150278 -98.941163) (xy 129.184364 -98.89702) (xy 129.224513 -98.858311)
			(xy 129.269871 -98.82586) (xy 129.319471 -98.800359) (xy 129.372255 -98.782352) (xy 129.427098 -98.772222)
			(xy 129.482832 -98.770185) (xy 129.538269 -98.776285) (xy 129.592226 -98.790391) (xy 129.643555 -98.812203)
			(xy 129.691161 -98.841257) (xy 129.734029 -98.876932) (xy 129.771246 -98.918469) (xy 129.802019 -98.964982)
			(xy 129.825691 -99.015479) (xy 129.841759 -99.068886) (xy 129.849879 -99.124062) (xy 129.850388 -99.151948)
			(xy 130.102862 -99.151948) (xy 130.106933 -99.096326) (xy 130.119059 -99.041889) (xy 130.138982 -98.989798)
			(xy 130.166278 -98.941163) (xy 130.200364 -98.89702) (xy 130.240513 -98.858311) (xy 130.285871 -98.82586)
			(xy 130.335471 -98.800359) (xy 130.388255 -98.782352) (xy 130.443098 -98.772222) (xy 130.498832 -98.770185)
			(xy 130.554269 -98.776285) (xy 130.608226 -98.790391) (xy 130.659555 -98.812203) (xy 130.707161 -98.841257)
			(xy 130.750029 -98.876932) (xy 130.787246 -98.918469) (xy 130.818019 -98.964982) (xy 130.841691 -99.015479)
			(xy 130.857759 -99.068886) (xy 130.865879 -99.124062) (xy 130.866388 -99.151948) (xy 133.150862 -99.151948)
			(xy 133.154933 -99.096326) (xy 133.167059 -99.041889) (xy 133.186982 -98.989798) (xy 133.214278 -98.941163)
			(xy 133.248364 -98.89702) (xy 133.288513 -98.858311) (xy 133.333871 -98.82586) (xy 133.383471 -98.800359)
			(xy 133.436255 -98.782352) (xy 133.491098 -98.772222) (xy 133.546832 -98.770185) (xy 133.602269 -98.776285)
			(xy 133.656226 -98.790391) (xy 133.707555 -98.812203) (xy 133.755161 -98.841257) (xy 133.798029 -98.876932)
			(xy 133.835246 -98.918469) (xy 133.866019 -98.964982) (xy 133.889691 -99.015479) (xy 133.905759 -99.068886)
			(xy 133.913879 -99.124062) (xy 133.914388 -99.151948) (xy 134.166862 -99.151948) (xy 134.170933 -99.096326)
			(xy 134.183059 -99.041889) (xy 134.202982 -98.989798) (xy 134.230278 -98.941163) (xy 134.264364 -98.89702)
			(xy 134.304513 -98.858311) (xy 134.349871 -98.82586) (xy 134.399471 -98.800359) (xy 134.452255 -98.782352)
			(xy 134.507098 -98.772222) (xy 134.562832 -98.770185) (xy 134.618269 -98.776285) (xy 134.672226 -98.790391)
			(xy 134.723555 -98.812203) (xy 134.771161 -98.841257) (xy 134.814029 -98.876932) (xy 134.851246 -98.918469)
			(xy 134.882019 -98.964982) (xy 134.905691 -99.015479) (xy 134.921759 -99.068886) (xy 134.929879 -99.124062)
			(xy 134.930388 -99.151948) (xy 134.929879 -99.179834) (xy 134.921759 -99.23501) (xy 134.905691 -99.288417)
			(xy 134.882019 -99.338914) (xy 134.851246 -99.385427) (xy 134.814029 -99.426964) (xy 134.771161 -99.462639)
			(xy 134.723555 -99.491693) (xy 134.672226 -99.513505) (xy 134.618269 -99.527611) (xy 134.562832 -99.533711)
			(xy 134.507098 -99.531674) (xy 134.452255 -99.521544) (xy 134.399471 -99.503537) (xy 134.349871 -99.478036)
			(xy 134.304513 -99.445585) (xy 134.264364 -99.406876) (xy 134.230278 -99.362733) (xy 134.202982 -99.314098)
			(xy 134.183059 -99.262007) (xy 134.170933 -99.20757) (xy 134.166862 -99.151948) (xy 133.914388 -99.151948)
			(xy 133.913879 -99.179834) (xy 133.905759 -99.23501) (xy 133.889691 -99.288417) (xy 133.866019 -99.338914)
			(xy 133.835246 -99.385427) (xy 133.798029 -99.426964) (xy 133.755161 -99.462639) (xy 133.707555 -99.491693)
			(xy 133.656226 -99.513505) (xy 133.602269 -99.527611) (xy 133.546832 -99.533711) (xy 133.491098 -99.531674)
			(xy 133.436255 -99.521544) (xy 133.383471 -99.503537) (xy 133.333871 -99.478036) (xy 133.288513 -99.445585)
			(xy 133.248364 -99.406876) (xy 133.214278 -99.362733) (xy 133.186982 -99.314098) (xy 133.167059 -99.262007)
			(xy 133.154933 -99.20757) (xy 133.150862 -99.151948) (xy 130.866388 -99.151948) (xy 130.865879 -99.179834)
			(xy 130.857759 -99.23501) (xy 130.841691 -99.288417) (xy 130.818019 -99.338914) (xy 130.787246 -99.385427)
			(xy 130.750029 -99.426964) (xy 130.707161 -99.462639) (xy 130.659555 -99.491693) (xy 130.608226 -99.513505)
			(xy 130.554269 -99.527611) (xy 130.498832 -99.533711) (xy 130.443098 -99.531674) (xy 130.388255 -99.521544)
			(xy 130.335471 -99.503537) (xy 130.285871 -99.478036) (xy 130.240513 -99.445585) (xy 130.200364 -99.406876)
			(xy 130.166278 -99.362733) (xy 130.138982 -99.314098) (xy 130.119059 -99.262007) (xy 130.106933 -99.20757)
			(xy 130.102862 -99.151948) (xy 129.850388 -99.151948) (xy 129.849879 -99.179834) (xy 129.841759 -99.23501)
			(xy 129.825691 -99.288417) (xy 129.802019 -99.338914) (xy 129.771246 -99.385427) (xy 129.734029 -99.426964)
			(xy 129.691161 -99.462639) (xy 129.643555 -99.491693) (xy 129.592226 -99.513505) (xy 129.538269 -99.527611)
			(xy 129.482832 -99.533711) (xy 129.427098 -99.531674) (xy 129.372255 -99.521544) (xy 129.319471 -99.503537)
			(xy 129.269871 -99.478036) (xy 129.224513 -99.445585) (xy 129.184364 -99.406876) (xy 129.150278 -99.362733)
			(xy 129.122982 -99.314098) (xy 129.103059 -99.262007) (xy 129.090933 -99.20757) (xy 129.086862 -99.151948)
			(xy 120.354859 -99.151948) (xy 120.373246 -99.172469) (xy 120.404019 -99.218982) (xy 120.427691 -99.269479)
			(xy 120.443759 -99.322886) (xy 120.451879 -99.378062) (xy 120.452388 -99.405948) (xy 120.451879 -99.433834)
			(xy 120.443759 -99.48901) (xy 120.427691 -99.542417) (xy 120.404019 -99.592914) (xy 120.373246 -99.639427)
			(xy 120.336029 -99.680964) (xy 120.293161 -99.716639) (xy 120.245555 -99.745693) (xy 120.194226 -99.767505)
			(xy 120.140269 -99.781611) (xy 120.084832 -99.787711) (xy 120.029098 -99.785674) (xy 119.974255 -99.775544)
			(xy 119.921471 -99.757537) (xy 119.871871 -99.732036) (xy 119.826513 -99.699585) (xy 119.786364 -99.660876)
			(xy 119.752278 -99.616733) (xy 119.724982 -99.568098) (xy 119.705059 -99.516007) (xy 119.692933 -99.46157)
			(xy 119.688862 -99.405948) (xy 110.511097 -99.405948) (xy 110.506689 -99.436606) (xy 110.491332 -99.488906)
			(xy 110.468688 -99.538487) (xy 110.439219 -99.584341) (xy 110.403523 -99.625535) (xy 110.362328 -99.661228)
			(xy 110.316473 -99.690696) (xy 110.266891 -99.713338) (xy 110.214591 -99.728693) (xy 110.160638 -99.736448)
			(xy 110.133384 -99.73691) (xy 110.10682 -99.736445) (xy 110.054205 -99.729071) (xy 110.003123 -99.714467)
			(xy 109.954561 -99.692918) (xy 109.909459 -99.664838) (xy 109.868689 -99.630772) (xy 109.833041 -99.591378)
			(xy 109.803203 -99.54742) (xy 109.779754 -99.499746) (xy 109.763146 -99.44928) (xy 109.757972 -99.42322)
			(xy 109.75481 -99.408695) (xy 109.741308 -99.382227) (xy 109.720749 -99.360775) (xy 109.694879 -99.346162)
			(xy 109.665894 -99.339627) (xy 109.651038 -99.340162) (xy 109.625384 -99.340924) (xy 109.598135 -99.340405)
			(xy 109.544191 -99.332647) (xy 109.4919 -99.317291) (xy 109.442327 -99.29465) (xy 109.396481 -99.265184)
			(xy 109.355294 -99.229494) (xy 109.319606 -99.188306) (xy 109.290143 -99.142459) (xy 109.267504 -99.092885)
			(xy 109.25215 -99.040593) (xy 109.244394 -98.986649) (xy 102.831416 -98.986649) (xy 102.829653 -98.993803)
			(xy 102.83007 -99.020018) (xy 102.837149 -99.045262) (xy 102.850424 -99.067871) (xy 102.869019 -99.086353)
			(xy 102.88016 -99.093274) (xy 102.904701 -99.107959) (xy 102.949456 -99.143566) (xy 102.988396 -99.185453)
			(xy 103.020649 -99.232681) (xy 103.045494 -99.284193) (xy 103.062374 -99.338836) (xy 103.070911 -99.395387)
			(xy 103.071422 -99.423982) (xy 103.070936 -99.451233) (xy 103.06318 -99.505181) (xy 103.047825 -99.557476)
			(xy 103.025183 -99.607053) (xy 103.023673 -99.609402) (xy 105.927652 -99.609402) (xy 105.928138 -99.582151)
			(xy 105.935894 -99.528203) (xy 105.951249 -99.475908) (xy 105.973891 -99.426331) (xy 106.003357 -99.380481)
			(xy 106.039048 -99.33929) (xy 106.080239 -99.303599) (xy 106.126089 -99.274133) (xy 106.175666 -99.251491)
			(xy 106.227961 -99.236136) (xy 106.281909 -99.22838) (xy 106.336411 -99.22838) (xy 106.390359 -99.236136)
			(xy 106.442654 -99.251491) (xy 106.492231 -99.274133) (xy 106.538081 -99.303599) (xy 106.579272 -99.33929)
			(xy 106.614963 -99.380481) (xy 106.644429 -99.426331) (xy 106.667071 -99.475908) (xy 106.682426 -99.528203)
			(xy 106.690182 -99.582151) (xy 106.690668 -99.609402) (xy 106.690194 -99.636664) (xy 106.682425 -99.690632)
			(xy 106.667058 -99.742946) (xy 106.644408 -99.792543) (xy 106.614933 -99.838414) (xy 106.59745 -99.859338)
			(xy 106.587968 -99.871008) (xy 106.575755 -99.898474) (xy 106.572063 -99.928305) (xy 106.577213 -99.957919)
			(xy 106.590757 -99.984753) (xy 106.600752 -99.99599) (xy 106.620464 -100.017394) (xy 106.653785 -100.065093)
			(xy 106.679487 -100.117295) (xy 106.696976 -100.17279) (xy 106.705846 -100.230296) (xy 106.706416 -100.259388)
			(xy 106.70593 -100.286639) (xy 106.698174 -100.340587) (xy 106.682819 -100.392882) (xy 106.660177 -100.442459)
			(xy 106.630711 -100.488309) (xy 106.59502 -100.5295) (xy 106.553829 -100.565191) (xy 106.507979 -100.594657)
			(xy 106.458402 -100.617299) (xy 106.406107 -100.632654) (xy 106.352159 -100.64041) (xy 106.297657 -100.64041)
			(xy 106.243709 -100.632654) (xy 106.191414 -100.617299) (xy 106.141837 -100.594657) (xy 106.095987 -100.565191)
			(xy 106.054796 -100.5295) (xy 106.019105 -100.488309) (xy 105.989639 -100.442459) (xy 105.966997 -100.392882)
			(xy 105.951642 -100.340587) (xy 105.943886 -100.286639) (xy 105.9434 -100.259388) (xy 105.943875 -100.232126)
			(xy 105.951645 -100.178158) (xy 105.967012 -100.125844) (xy 105.989662 -100.076248) (xy 106.019136 -100.030376)
			(xy 106.036618 -100.009452) (xy 106.046004 -99.997712) (xy 106.058219 -99.970271) (xy 106.061925 -99.940464)
			(xy 106.056802 -99.910867) (xy 106.043292 -99.884039) (xy 106.033316 -99.8728) (xy 106.013594 -99.851405)
			(xy 105.980276 -99.803702) (xy 105.954576 -99.751499) (xy 105.93709 -99.696002) (xy 105.928221 -99.638495)
			(xy 105.927652 -99.609402) (xy 103.023673 -99.609402) (xy 102.995717 -99.652903) (xy 102.960026 -99.694094)
			(xy 102.918835 -99.729785) (xy 102.872985 -99.759251) (xy 102.823408 -99.781893) (xy 102.771113 -99.797248)
			(xy 102.717165 -99.805004) (xy 102.662663 -99.805004) (xy 102.608715 -99.797248) (xy 102.55642 -99.781893)
			(xy 102.506843 -99.759251) (xy 102.460993 -99.729785) (xy 102.419802 -99.694094) (xy 102.384111 -99.652903)
			(xy 102.354645 -99.607053) (xy 102.332003 -99.557476) (xy 102.316648 -99.505181) (xy 102.308892 -99.451233)
			(xy 102.308406 -99.423982) (xy 102.309022 -99.392223) (xy 102.319504 -99.329578) (xy 102.34024 -99.269541)
			(xy 102.354888 -99.241356) (xy 102.360795 -99.229644) (xy 102.367065 -99.204182) (xy 102.366643 -99.177964)
			(xy 102.359559 -99.152717) (xy 102.346278 -99.130107) (xy 102.327677 -99.111624) (xy 102.316534 -99.104704)
			(xy 102.292004 -99.089999) (xy 102.247245 -99.054399) (xy 102.208301 -99.012518) (xy 102.176044 -98.965293)
			(xy 102.151197 -98.913783) (xy 102.134317 -98.859141) (xy 102.125782 -98.802591) (xy 102.125272 -98.773996)
			(xy 95.946871 -98.773996) (xy 95.950435 -98.780222) (xy 95.969671 -98.799413) (xy 95.981266 -98.806508)
			(xy 96.00598 -98.821135) (xy 96.051069 -98.856703) (xy 96.090317 -98.898628) (xy 96.122836 -98.945963)
			(xy 96.147892 -98.997637) (xy 96.164919 -99.052484) (xy 96.173531 -99.109264) (xy 96.174052 -99.137978)
			(xy 96.173566 -99.165229) (xy 96.16581 -99.219177) (xy 96.150455 -99.271472) (xy 96.127813 -99.321049)
			(xy 96.098347 -99.366899) (xy 96.062656 -99.40809) (xy 96.021465 -99.443781) (xy 95.975615 -99.473247)
			(xy 95.926038 -99.495889) (xy 95.873743 -99.511244) (xy 95.819795 -99.519) (xy 95.765293 -99.519)
			(xy 95.711345 -99.511244) (xy 95.65905 -99.495889) (xy 95.609473 -99.473247) (xy 95.563623 -99.443781)
			(xy 95.522432 -99.40809) (xy 95.486741 -99.366899) (xy 95.457275 -99.321049) (xy 95.434633 -99.271472)
			(xy 95.419278 -99.219177) (xy 95.411522 -99.165229) (xy 95.411036 -99.137978) (xy 95.411471 -99.112116)
			(xy 95.418455 -99.060865) (xy 95.432306 -99.011029) (xy 95.45277 -98.963525) (xy 95.47947 -98.919224)
			(xy 95.511915 -98.878941) (xy 95.530416 -98.860864) (xy 95.539949 -98.851175) (xy 95.554089 -98.827978)
			(xy 95.561612 -98.801874) (xy 95.561985 -98.77471) (xy 95.555183 -98.748409) (xy 95.541687 -98.724832)
			(xy 95.522452 -98.705648) (xy 95.510858 -98.698558) (xy 95.486179 -98.683875) (xy 95.441089 -98.648317)
			(xy 95.401839 -98.606402) (xy 95.369315 -98.559077) (xy 95.344253 -98.507411) (xy 95.327219 -98.452572)
			(xy 95.318598 -98.3958) (xy 95.318072 -98.367088) (xy 87.547447 -98.367088) (xy 87.568727 -98.412483)
			(xy 87.584795 -98.46589) (xy 87.592915 -98.521066) (xy 87.593424 -98.548952) (xy 87.592915 -98.576838)
			(xy 87.584795 -98.632014) (xy 87.568727 -98.685421) (xy 87.545055 -98.735918) (xy 87.514282 -98.782431)
			(xy 87.477065 -98.823968) (xy 87.434197 -98.859643) (xy 87.386591 -98.888697) (xy 87.335262 -98.910509)
			(xy 87.281305 -98.924615) (xy 87.225868 -98.930715) (xy 87.170134 -98.928678) (xy 87.115291 -98.918548)
			(xy 87.062507 -98.900541) (xy 87.012907 -98.87504) (xy 86.967549 -98.842589) (xy 86.9274 -98.80388)
			(xy 86.893314 -98.759737) (xy 86.866018 -98.711102) (xy 86.846095 -98.659011) (xy 86.833969 -98.604574)
			(xy 86.829898 -98.548952) (xy 48.801549 -98.548952) (xy 48.785886 -98.572627) (xy 48.748669 -98.614164)
			(xy 48.705801 -98.649839) (xy 48.658195 -98.678893) (xy 48.606866 -98.700705) (xy 48.552909 -98.714811)
			(xy 48.497472 -98.720911) (xy 48.441738 -98.718874) (xy 48.386895 -98.708744) (xy 48.334111 -98.690737)
			(xy 48.284511 -98.665236) (xy 48.239153 -98.632785) (xy 48.199004 -98.594076) (xy 48.164918 -98.549933)
			(xy 48.137622 -98.501298) (xy 48.117699 -98.449207) (xy 48.105573 -98.39477) (xy 48.101502 -98.339148)
			(xy 32.05586 -98.339148) (xy 32.084917 -98.383068) (xy 32.108589 -98.433565) (xy 32.124657 -98.486972)
			(xy 32.132777 -98.542148) (xy 32.133286 -98.570034) (xy 32.132777 -98.59792) (xy 32.124657 -98.653096)
			(xy 32.108589 -98.706503) (xy 32.084917 -98.757) (xy 32.054144 -98.803513) (xy 32.035757 -98.824034)
			(xy 46.97806 -98.824034) (xy 46.982131 -98.768412) (xy 46.994257 -98.713975) (xy 47.01418 -98.661884)
			(xy 47.041476 -98.613249) (xy 47.075562 -98.569106) (xy 47.115711 -98.530397) (xy 47.161069 -98.497946)
			(xy 47.210669 -98.472445) (xy 47.263453 -98.454438) (xy 47.318296 -98.444308) (xy 47.37403 -98.442271)
			(xy 47.429467 -98.448371) (xy 47.483424 -98.462477) (xy 47.534753 -98.484289) (xy 47.582359 -98.513343)
			(xy 47.625227 -98.549018) (xy 47.662444 -98.590555) (xy 47.693217 -98.637068) (xy 47.716889 -98.687565)
			(xy 47.732957 -98.740972) (xy 47.741077 -98.796148) (xy 47.741586 -98.824034) (xy 47.741077 -98.85192)
			(xy 47.732957 -98.907096) (xy 47.716889 -98.960503) (xy 47.693217 -99.011) (xy 47.662444 -99.057513)
			(xy 47.625227 -99.09905) (xy 47.582359 -99.134725) (xy 47.534753 -99.163779) (xy 47.483424 -99.185591)
			(xy 47.429467 -99.199697) (xy 47.37403 -99.205797) (xy 47.318296 -99.20376) (xy 47.263453 -99.19363)
			(xy 47.210669 -99.175623) (xy 47.161069 -99.150122) (xy 47.115711 -99.117671) (xy 47.075562 -99.078962)
			(xy 47.041476 -99.034819) (xy 47.01418 -98.986184) (xy 46.994257 -98.934093) (xy 46.982131 -98.879656)
			(xy 46.97806 -98.824034) (xy 32.035757 -98.824034) (xy 32.016927 -98.84505) (xy 31.974059 -98.880725)
			(xy 31.926453 -98.909779) (xy 31.875124 -98.931591) (xy 31.821167 -98.945697) (xy 31.76573 -98.951797)
			(xy 31.709996 -98.94976) (xy 31.655153 -98.93963) (xy 31.602369 -98.921623) (xy 31.552769 -98.896122)
			(xy 31.507411 -98.863671) (xy 31.467262 -98.824962) (xy 31.433176 -98.780819) (xy 31.40588 -98.732184)
			(xy 31.385957 -98.680093) (xy 31.373831 -98.625656) (xy 31.36976 -98.570034) (xy 30.723586 -98.570034)
			(xy 30.723077 -98.59792) (xy 30.714957 -98.653096) (xy 30.698889 -98.706503) (xy 30.675217 -98.757)
			(xy 30.644444 -98.803513) (xy 30.607227 -98.84505) (xy 30.564359 -98.880725) (xy 30.516753 -98.909779)
			(xy 30.465424 -98.931591) (xy 30.411467 -98.945697) (xy 30.35603 -98.951797) (xy 30.300296 -98.94976)
			(xy 30.245453 -98.93963) (xy 30.192669 -98.921623) (xy 30.143069 -98.896122) (xy 30.097711 -98.863671)
			(xy 30.057562 -98.824962) (xy 30.023476 -98.780819) (xy 29.99618 -98.732184) (xy 29.976257 -98.680093)
			(xy 29.964131 -98.625656) (xy 29.96006 -98.570034) (xy 27.635962 -98.570034) (xy 27.635453 -98.59792)
			(xy 27.627333 -98.653096) (xy 27.611265 -98.706503) (xy 27.587593 -98.757) (xy 27.55682 -98.803513)
			(xy 27.519603 -98.84505) (xy 27.476735 -98.880725) (xy 27.429129 -98.909779) (xy 27.3778 -98.931591)
			(xy 27.323843 -98.945697) (xy 27.268406 -98.951797) (xy 27.212672 -98.94976) (xy 27.157829 -98.93963)
			(xy 27.105045 -98.921623) (xy 27.055445 -98.896122) (xy 27.010087 -98.863671) (xy 26.969938 -98.824962)
			(xy 26.935852 -98.780819) (xy 26.908556 -98.732184) (xy 26.888633 -98.680093) (xy 26.876507 -98.625656)
			(xy 26.872436 -98.570034) (xy 10.726089 -98.570034) (xy 10.706871 -98.600557) (xy 10.67221 -98.641509)
			(xy 10.632157 -98.677204) (xy 10.610088 -98.692462) (xy 10.610088 -99.964748) (xy 26.846782 -99.964748)
			(xy 26.850853 -99.909126) (xy 26.862979 -99.854689) (xy 26.882902 -99.802598) (xy 26.910198 -99.753963)
			(xy 26.944284 -99.70982) (xy 26.984433 -99.671111) (xy 27.029791 -99.63866) (xy 27.079391 -99.613159)
			(xy 27.132175 -99.595152) (xy 27.187018 -99.585022) (xy 27.242752 -99.582985) (xy 27.270461 -99.586034)
			(xy 29.96006 -99.586034) (xy 29.964131 -99.530412) (xy 29.976257 -99.475975) (xy 29.99618 -99.423884)
			(xy 30.023476 -99.375249) (xy 30.057562 -99.331106) (xy 30.097711 -99.292397) (xy 30.143069 -99.259946)
			(xy 30.192669 -99.234445) (xy 30.245453 -99.216438) (xy 30.300296 -99.206308) (xy 30.35603 -99.204271)
			(xy 30.411467 -99.210371) (xy 30.465424 -99.224477) (xy 30.516753 -99.246289) (xy 30.564359 -99.275343)
			(xy 30.607227 -99.311018) (xy 30.644444 -99.352555) (xy 30.675217 -99.399068) (xy 30.698889 -99.449565)
			(xy 30.714957 -99.502972) (xy 30.723077 -99.558148) (xy 30.723586 -99.586034) (xy 31.36976 -99.586034)
			(xy 31.373831 -99.530412) (xy 31.385957 -99.475975) (xy 31.40588 -99.423884) (xy 31.433176 -99.375249)
			(xy 31.467262 -99.331106) (xy 31.507411 -99.292397) (xy 31.552769 -99.259946) (xy 31.602369 -99.234445)
			(xy 31.655153 -99.216438) (xy 31.709996 -99.206308) (xy 31.76573 -99.204271) (xy 31.821167 -99.210371)
			(xy 31.875124 -99.224477) (xy 31.926453 -99.246289) (xy 31.974059 -99.275343) (xy 32.016927 -99.311018)
			(xy 32.054144 -99.352555) (xy 32.057204 -99.35718) (xy 40.280842 -99.35718) (xy 40.284913 -99.301558)
			(xy 40.297039 -99.247121) (xy 40.316962 -99.19503) (xy 40.344258 -99.146395) (xy 40.378344 -99.102252)
			(xy 40.418493 -99.063543) (xy 40.463851 -99.031092) (xy 40.513451 -99.005591) (xy 40.566235 -98.987584)
			(xy 40.621078 -98.977454) (xy 40.676812 -98.975417) (xy 40.732249 -98.981517) (xy 40.786206 -98.995623)
			(xy 40.837535 -99.017435) (xy 40.885141 -99.046489) (xy 40.928009 -99.082164) (xy 40.965226 -99.123701)
			(xy 40.995999 -99.170214) (xy 41.019671 -99.220711) (xy 41.035739 -99.274118) (xy 41.043859 -99.329294)
			(xy 41.04396 -99.334828) (xy 48.101502 -99.334828) (xy 48.105573 -99.279206) (xy 48.117699 -99.224769)
			(xy 48.137622 -99.172678) (xy 48.164918 -99.124043) (xy 48.199004 -99.0799) (xy 48.239153 -99.041191)
			(xy 48.284511 -99.00874) (xy 48.334111 -98.983239) (xy 48.386895 -98.965232) (xy 48.441738 -98.955102)
			(xy 48.497472 -98.953065) (xy 48.552909 -98.959165) (xy 48.606866 -98.973271) (xy 48.658195 -98.995083)
			(xy 48.705801 -99.024137) (xy 48.748669 -99.059812) (xy 48.785886 -99.101349) (xy 48.816659 -99.147862)
			(xy 48.840331 -99.198359) (xy 48.856399 -99.251766) (xy 48.864519 -99.306942) (xy 48.865028 -99.334828)
			(xy 48.864519 -99.362714) (xy 48.856399 -99.41789) (xy 48.840331 -99.471297) (xy 48.837507 -99.477322)
			(xy 86.829898 -99.477322) (xy 86.833969 -99.4217) (xy 86.846095 -99.367263) (xy 86.866018 -99.315172)
			(xy 86.893314 -99.266537) (xy 86.9274 -99.222394) (xy 86.967549 -99.183685) (xy 87.012907 -99.151234)
			(xy 87.062507 -99.125733) (xy 87.115291 -99.107726) (xy 87.170134 -99.097596) (xy 87.225868 -99.095559)
			(xy 87.281305 -99.101659) (xy 87.335262 -99.115765) (xy 87.386591 -99.137577) (xy 87.434197 -99.166631)
			(xy 87.477065 -99.202306) (xy 87.514282 -99.243843) (xy 87.545055 -99.290356) (xy 87.568727 -99.340853)
			(xy 87.584795 -99.39426) (xy 87.592915 -99.449436) (xy 87.593424 -99.477322) (xy 87.592915 -99.505208)
			(xy 87.584795 -99.560384) (xy 87.568727 -99.613791) (xy 87.545055 -99.664288) (xy 87.514282 -99.710801)
			(xy 87.477065 -99.752338) (xy 87.434197 -99.788013) (xy 87.386591 -99.817067) (xy 87.335262 -99.838879)
			(xy 87.281305 -99.852985) (xy 87.225868 -99.859085) (xy 87.170134 -99.857048) (xy 87.115291 -99.846918)
			(xy 87.062507 -99.828911) (xy 87.012907 -99.80341) (xy 86.967549 -99.770959) (xy 86.9274 -99.73225)
			(xy 86.893314 -99.688107) (xy 86.866018 -99.639472) (xy 86.846095 -99.587381) (xy 86.833969 -99.532944)
			(xy 86.829898 -99.477322) (xy 48.837507 -99.477322) (xy 48.816659 -99.521794) (xy 48.785886 -99.568307)
			(xy 48.748669 -99.609844) (xy 48.705801 -99.645519) (xy 48.658195 -99.674573) (xy 48.606866 -99.696385)
			(xy 48.552909 -99.710491) (xy 48.497472 -99.716591) (xy 48.441738 -99.714554) (xy 48.386895 -99.704424)
			(xy 48.334111 -99.686417) (xy 48.284511 -99.660916) (xy 48.239153 -99.628465) (xy 48.199004 -99.589756)
			(xy 48.164918 -99.545613) (xy 48.137622 -99.496978) (xy 48.117699 -99.444887) (xy 48.105573 -99.39045)
			(xy 48.101502 -99.334828) (xy 41.04396 -99.334828) (xy 41.044368 -99.35718) (xy 41.043859 -99.385066)
			(xy 41.035739 -99.440242) (xy 41.019671 -99.493649) (xy 40.995999 -99.544146) (xy 40.965226 -99.590659)
			(xy 40.928009 -99.632196) (xy 40.885141 -99.667871) (xy 40.837535 -99.696925) (xy 40.786206 -99.718737)
			(xy 40.732249 -99.732843) (xy 40.676812 -99.738943) (xy 40.621078 -99.736906) (xy 40.566235 -99.726776)
			(xy 40.513451 -99.708769) (xy 40.463851 -99.683268) (xy 40.418493 -99.650817) (xy 40.378344 -99.612108)
			(xy 40.344258 -99.567965) (xy 40.316962 -99.51933) (xy 40.297039 -99.467239) (xy 40.284913 -99.412802)
			(xy 40.280842 -99.35718) (xy 32.057204 -99.35718) (xy 32.084917 -99.399068) (xy 32.108589 -99.449565)
			(xy 32.124657 -99.502972) (xy 32.132777 -99.558148) (xy 32.133286 -99.586034) (xy 32.132777 -99.61392)
			(xy 32.124657 -99.669096) (xy 32.108589 -99.722503) (xy 32.084917 -99.773) (xy 32.054144 -99.819513)
			(xy 32.016927 -99.86105) (xy 31.974059 -99.896725) (xy 31.926453 -99.925779) (xy 31.875124 -99.947591)
			(xy 31.872649 -99.948238) (xy 43.629832 -99.948238) (xy 43.633903 -99.892616) (xy 43.646029 -99.838179)
			(xy 43.665952 -99.786088) (xy 43.693248 -99.737453) (xy 43.727334 -99.69331) (xy 43.767483 -99.654601)
			(xy 43.812841 -99.62215) (xy 43.862441 -99.596649) (xy 43.915225 -99.578642) (xy 43.970068 -99.568512)
			(xy 44.025802 -99.566475) (xy 44.081239 -99.572575) (xy 44.135196 -99.586681) (xy 44.186525 -99.608493)
			(xy 44.234131 -99.637547) (xy 44.276999 -99.673222) (xy 44.314216 -99.714759) (xy 44.344989 -99.761272)
			(xy 44.368661 -99.811769) (xy 44.377165 -99.840034) (xy 46.97806 -99.840034) (xy 46.982131 -99.784412)
			(xy 46.994257 -99.729975) (xy 47.01418 -99.677884) (xy 47.041476 -99.629249) (xy 47.075562 -99.585106)
			(xy 47.115711 -99.546397) (xy 47.161069 -99.513946) (xy 47.210669 -99.488445) (xy 47.263453 -99.470438)
			(xy 47.318296 -99.460308) (xy 47.37403 -99.458271) (xy 47.429467 -99.464371) (xy 47.483424 -99.478477)
			(xy 47.534753 -99.500289) (xy 47.582359 -99.529343) (xy 47.625227 -99.565018) (xy 47.662444 -99.606555)
			(xy 47.693217 -99.653068) (xy 47.716889 -99.703565) (xy 47.732957 -99.756972) (xy 47.741077 -99.812148)
			(xy 47.741586 -99.840034) (xy 47.741077 -99.86792) (xy 47.732957 -99.923096) (xy 47.716889 -99.976503)
			(xy 47.693217 -100.027) (xy 47.662444 -100.073513) (xy 47.625227 -100.11505) (xy 47.582359 -100.150725)
			(xy 47.534753 -100.179779) (xy 47.483424 -100.201591) (xy 47.429467 -100.215697) (xy 47.37403 -100.221797)
			(xy 47.318296 -100.21976) (xy 47.263453 -100.20963) (xy 47.210669 -100.191623) (xy 47.161069 -100.166122)
			(xy 47.115711 -100.133671) (xy 47.075562 -100.094962) (xy 47.041476 -100.050819) (xy 47.01418 -100.002184)
			(xy 46.994257 -99.950093) (xy 46.982131 -99.895656) (xy 46.97806 -99.840034) (xy 44.377165 -99.840034)
			(xy 44.384729 -99.865176) (xy 44.392849 -99.920352) (xy 44.393358 -99.948238) (xy 44.392849 -99.976124)
			(xy 44.384729 -100.0313) (xy 44.368661 -100.084707) (xy 44.344989 -100.135204) (xy 44.314216 -100.181717)
			(xy 44.276999 -100.223254) (xy 44.234131 -100.258929) (xy 44.186525 -100.287983) (xy 44.135196 -100.309795)
			(xy 44.081239 -100.323901) (xy 44.025802 -100.330001) (xy 43.970068 -100.327964) (xy 43.915225 -100.317834)
			(xy 43.862441 -100.299827) (xy 43.812841 -100.274326) (xy 43.767483 -100.241875) (xy 43.727334 -100.203166)
			(xy 43.693248 -100.159023) (xy 43.665952 -100.110388) (xy 43.646029 -100.058297) (xy 43.633903 -100.00386)
			(xy 43.629832 -99.948238) (xy 31.872649 -99.948238) (xy 31.821167 -99.961697) (xy 31.76573 -99.967797)
			(xy 31.709996 -99.96576) (xy 31.655153 -99.95563) (xy 31.602369 -99.937623) (xy 31.552769 -99.912122)
			(xy 31.507411 -99.879671) (xy 31.467262 -99.840962) (xy 31.433176 -99.796819) (xy 31.40588 -99.748184)
			(xy 31.385957 -99.696093) (xy 31.373831 -99.641656) (xy 31.36976 -99.586034) (xy 30.723586 -99.586034)
			(xy 30.723077 -99.61392) (xy 30.714957 -99.669096) (xy 30.698889 -99.722503) (xy 30.675217 -99.773)
			(xy 30.644444 -99.819513) (xy 30.607227 -99.86105) (xy 30.564359 -99.896725) (xy 30.516753 -99.925779)
			(xy 30.465424 -99.947591) (xy 30.411467 -99.961697) (xy 30.35603 -99.967797) (xy 30.300296 -99.96576)
			(xy 30.245453 -99.95563) (xy 30.192669 -99.937623) (xy 30.143069 -99.912122) (xy 30.097711 -99.879671)
			(xy 30.057562 -99.840962) (xy 30.023476 -99.796819) (xy 29.99618 -99.748184) (xy 29.976257 -99.696093)
			(xy 29.964131 -99.641656) (xy 29.96006 -99.586034) (xy 27.270461 -99.586034) (xy 27.298189 -99.589085)
			(xy 27.352146 -99.603191) (xy 27.403475 -99.625003) (xy 27.451081 -99.654057) (xy 27.493949 -99.689732)
			(xy 27.531166 -99.731269) (xy 27.561939 -99.777782) (xy 27.585611 -99.828279) (xy 27.601679 -99.881686)
			(xy 27.609799 -99.936862) (xy 27.610308 -99.964748) (xy 27.609799 -99.992634) (xy 27.601679 -100.04781)
			(xy 27.585611 -100.101217) (xy 27.561939 -100.151714) (xy 27.531166 -100.198227) (xy 27.493949 -100.239764)
			(xy 27.451081 -100.275439) (xy 27.403475 -100.304493) (xy 27.352146 -100.326305) (xy 27.298189 -100.340411)
			(xy 27.242752 -100.346511) (xy 27.187018 -100.344474) (xy 27.132175 -100.334344) (xy 27.079391 -100.316337)
			(xy 27.029791 -100.290836) (xy 26.984433 -100.258385) (xy 26.944284 -100.219676) (xy 26.910198 -100.175533)
			(xy 26.882902 -100.126898) (xy 26.862979 -100.074807) (xy 26.850853 -100.02037) (xy 26.846782 -99.964748)
			(xy 10.610088 -99.964748) (xy 10.610088 -100.0633) (xy 10.610545 -100.073151) (xy 10.61797 -100.091401)
			(xy 10.631725 -100.105507) (xy 10.649782 -100.11339) (xy 10.659618 -100.1141) (xy 10.687746 -100.115239)
			(xy 10.743228 -100.124764) (xy 10.796709 -100.142338) (xy 10.847027 -100.167578) (xy 10.893092 -100.199937)
			(xy 10.933902 -100.238712) (xy 10.968573 -100.283062) (xy 10.996352 -100.332024) (xy 11.016636 -100.384537)
			(xy 11.028986 -100.439459) (xy 11.033132 -100.4956) (xy 11.028986 -100.551741) (xy 11.016636 -100.606664)
			(xy 10.996352 -100.659176) (xy 10.99116 -100.668328) (xy 12.127482 -100.668328) (xy 12.131553 -100.612706)
			(xy 12.143679 -100.558269) (xy 12.163602 -100.506178) (xy 12.190898 -100.457543) (xy 12.224984 -100.4134)
			(xy 12.265133 -100.374691) (xy 12.310491 -100.34224) (xy 12.360091 -100.316739) (xy 12.412875 -100.298732)
			(xy 12.467718 -100.288602) (xy 12.523452 -100.286565) (xy 12.578889 -100.292665) (xy 12.632846 -100.306771)
			(xy 12.684175 -100.328583) (xy 12.731781 -100.357637) (xy 12.774649 -100.393312) (xy 12.811866 -100.434849)
			(xy 12.842639 -100.481362) (xy 12.866311 -100.531859) (xy 12.882379 -100.585266) (xy 12.887501 -100.620068)
			(xy 15.175482 -100.620068) (xy 15.179553 -100.564446) (xy 15.191679 -100.510009) (xy 15.211602 -100.457918)
			(xy 15.238898 -100.409283) (xy 15.272984 -100.36514) (xy 15.313133 -100.326431) (xy 15.358491 -100.29398)
			(xy 15.408091 -100.268479) (xy 15.460875 -100.250472) (xy 15.515718 -100.240342) (xy 15.571452 -100.238305)
			(xy 15.626889 -100.244405) (xy 15.680846 -100.258511) (xy 15.732175 -100.280323) (xy 15.779781 -100.309377)
			(xy 15.822649 -100.345052) (xy 15.859686 -100.386388) (xy 16.895062 -100.386388) (xy 16.899133 -100.330766)
			(xy 16.911259 -100.276329) (xy 16.931182 -100.224238) (xy 16.958478 -100.175603) (xy 16.992564 -100.13146)
			(xy 17.032713 -100.092751) (xy 17.078071 -100.0603) (xy 17.127671 -100.034799) (xy 17.180455 -100.016792)
			(xy 17.235298 -100.006662) (xy 17.291032 -100.004625) (xy 17.346469 -100.010725) (xy 17.400426 -100.024831)
			(xy 17.451755 -100.046643) (xy 17.499361 -100.075697) (xy 17.542229 -100.111372) (xy 17.579446 -100.152909)
			(xy 17.610219 -100.199422) (xy 17.633891 -100.249919) (xy 17.649959 -100.303326) (xy 17.658079 -100.358502)
			(xy 17.658588 -100.386388) (xy 17.658079 -100.414274) (xy 17.649959 -100.46945) (xy 17.633891 -100.522857)
			(xy 17.610219 -100.573354) (xy 17.591244 -100.602034) (xy 31.36976 -100.602034) (xy 31.373831 -100.546412)
			(xy 31.385957 -100.491975) (xy 31.40588 -100.439884) (xy 31.433176 -100.391249) (xy 31.467262 -100.347106)
			(xy 31.507411 -100.308397) (xy 31.552769 -100.275946) (xy 31.602369 -100.250445) (xy 31.655153 -100.232438)
			(xy 31.709996 -100.222308) (xy 31.76573 -100.220271) (xy 31.821167 -100.226371) (xy 31.875124 -100.240477)
			(xy 31.926453 -100.262289) (xy 31.974059 -100.291343) (xy 32.016927 -100.327018) (xy 32.054144 -100.368555)
			(xy 32.084917 -100.415068) (xy 32.108589 -100.465565) (xy 32.124657 -100.518972) (xy 32.132777 -100.574148)
			(xy 32.133286 -100.602034) (xy 32.132777 -100.62992) (xy 32.124657 -100.685096) (xy 32.108589 -100.738503)
			(xy 32.084917 -100.789) (xy 32.054144 -100.835513) (xy 32.035757 -100.856034) (xy 33.963862 -100.856034)
			(xy 33.967933 -100.800412) (xy 33.980059 -100.745975) (xy 33.999982 -100.693884) (xy 34.027278 -100.645249)
			(xy 34.061364 -100.601106) (xy 34.101513 -100.562397) (xy 34.146871 -100.529946) (xy 34.196471 -100.504445)
			(xy 34.249255 -100.486438) (xy 34.304098 -100.476308) (xy 34.359832 -100.474271) (xy 34.415269 -100.480371)
			(xy 34.469226 -100.494477) (xy 34.520555 -100.516289) (xy 34.568161 -100.545343) (xy 34.611029 -100.581018)
			(xy 34.648246 -100.622555) (xy 34.679019 -100.669068) (xy 34.702691 -100.719565) (xy 34.718759 -100.772972)
			(xy 34.726879 -100.828148) (xy 34.727388 -100.856034) (xy 34.726879 -100.88392) (xy 34.718759 -100.939096)
			(xy 34.702691 -100.992503) (xy 34.679019 -101.043) (xy 34.648246 -101.089513) (xy 34.611029 -101.13105)
			(xy 34.568161 -101.166725) (xy 34.520555 -101.195779) (xy 34.469226 -101.217591) (xy 34.415269 -101.231697)
			(xy 34.359832 -101.237797) (xy 34.304098 -101.23576) (xy 34.249255 -101.22563) (xy 34.196471 -101.207623)
			(xy 34.146871 -101.182122) (xy 34.101513 -101.149671) (xy 34.061364 -101.110962) (xy 34.027278 -101.066819)
			(xy 33.999982 -101.018184) (xy 33.980059 -100.966093) (xy 33.967933 -100.911656) (xy 33.963862 -100.856034)
			(xy 32.035757 -100.856034) (xy 32.016927 -100.87705) (xy 31.974059 -100.912725) (xy 31.926453 -100.941779)
			(xy 31.875124 -100.963591) (xy 31.821167 -100.977697) (xy 31.76573 -100.983797) (xy 31.709996 -100.98176)
			(xy 31.655153 -100.97163) (xy 31.602369 -100.953623) (xy 31.552769 -100.928122) (xy 31.507411 -100.895671)
			(xy 31.467262 -100.856962) (xy 31.433176 -100.812819) (xy 31.40588 -100.764184) (xy 31.385957 -100.712093)
			(xy 31.373831 -100.657656) (xy 31.36976 -100.602034) (xy 17.591244 -100.602034) (xy 17.579446 -100.619867)
			(xy 17.542229 -100.661404) (xy 17.499361 -100.697079) (xy 17.451755 -100.726133) (xy 17.400426 -100.747945)
			(xy 17.346469 -100.762051) (xy 17.291032 -100.768151) (xy 17.235298 -100.766114) (xy 17.180455 -100.755984)
			(xy 17.127671 -100.737977) (xy 17.078071 -100.712476) (xy 17.032713 -100.680025) (xy 16.992564 -100.641316)
			(xy 16.958478 -100.597173) (xy 16.931182 -100.548538) (xy 16.911259 -100.496447) (xy 16.899133 -100.44201)
			(xy 16.895062 -100.386388) (xy 15.859686 -100.386388) (xy 15.859866 -100.386589) (xy 15.890639 -100.433102)
			(xy 15.914311 -100.483599) (xy 15.930379 -100.537006) (xy 15.938499 -100.592182) (xy 15.939008 -100.620068)
			(xy 15.938499 -100.647954) (xy 15.930379 -100.70313) (xy 15.914311 -100.756537) (xy 15.890639 -100.807034)
			(xy 15.859866 -100.853547) (xy 15.822649 -100.895084) (xy 15.779781 -100.930759) (xy 15.732175 -100.959813)
			(xy 15.680846 -100.981625) (xy 15.626889 -100.995731) (xy 15.571452 -101.001831) (xy 15.515718 -100.999794)
			(xy 15.460875 -100.989664) (xy 15.408091 -100.971657) (xy 15.358491 -100.946156) (xy 15.313133 -100.913705)
			(xy 15.272984 -100.874996) (xy 15.238898 -100.830853) (xy 15.211602 -100.782218) (xy 15.191679 -100.730127)
			(xy 15.179553 -100.67569) (xy 15.175482 -100.620068) (xy 12.887501 -100.620068) (xy 12.890499 -100.640442)
			(xy 12.891008 -100.668328) (xy 12.890499 -100.696214) (xy 12.882379 -100.75139) (xy 12.866311 -100.804797)
			(xy 12.842639 -100.855294) (xy 12.811866 -100.901807) (xy 12.774649 -100.943344) (xy 12.731781 -100.979019)
			(xy 12.684175 -101.008073) (xy 12.632846 -101.029885) (xy 12.578889 -101.043991) (xy 12.523452 -101.050091)
			(xy 12.467718 -101.048054) (xy 12.412875 -101.037924) (xy 12.360091 -101.019917) (xy 12.310491 -100.994416)
			(xy 12.265133 -100.961965) (xy 12.224984 -100.923256) (xy 12.190898 -100.879113) (xy 12.163602 -100.830478)
			(xy 12.143679 -100.778387) (xy 12.131553 -100.72395) (xy 12.127482 -100.668328) (xy 10.99116 -100.668328)
			(xy 10.968573 -100.708138) (xy 10.933902 -100.752488) (xy 10.893091 -100.791263) (xy 10.847027 -100.823622)
			(xy 10.796709 -100.848862) (xy 10.743228 -100.866436) (xy 10.687746 -100.875961) (xy 10.659618 -100.877116)
			(xy 10.649782 -100.877822) (xy 10.631726 -100.885706) (xy 10.617974 -100.899814) (xy 10.610554 -100.918065)
			(xy 10.610088 -100.927916) (xy 10.610088 -101.081078) (xy 10.05713 -101.634036) (xy 8.078724 -101.634036)
			(xy 8.063297 -101.634584) (xy 8.033852 -101.643806) (xy 8.008497 -101.661388) (xy 7.989537 -101.685731)
			(xy 7.978698 -101.71462) (xy 7.976966 -101.745426) (xy 7.980172 -101.760528) (xy 7.985635 -101.783509)
			(xy 7.991499 -101.830381) (xy 7.991738 -101.846201) (xy 25.455856 -101.846201) (xy 25.455856 -101.791699)
			(xy 25.463612 -101.737751) (xy 25.478968 -101.685456) (xy 25.501609 -101.635878) (xy 25.531075 -101.590027)
			(xy 25.566767 -101.548837) (xy 25.607957 -101.513145) (xy 25.653808 -101.483679) (xy 25.703386 -101.461038)
			(xy 25.755681 -101.445682) (xy 25.809629 -101.437926) (xy 25.83688 -101.43744) (xy 25.86425 -101.437908)
			(xy 25.91843 -101.445724) (xy 25.970933 -101.461212) (xy 26.02068 -101.484054) (xy 26.066647 -101.513778)
			(xy 26.087578 -101.53142) (xy 26.098906 -101.540656) (xy 26.125463 -101.552832) (xy 26.15438 -101.557005)
			(xy 26.183297 -101.552832) (xy 26.209854 -101.540656) (xy 26.221182 -101.53142) (xy 26.242113 -101.513779)
			(xy 26.288085 -101.484067) (xy 26.337833 -101.461231) (xy 26.390334 -101.44574) (xy 26.444511 -101.437913)
			(xy 26.47188 -101.43744) (xy 26.499137 -101.437806) (xy 26.553097 -101.445561) (xy 26.605404 -101.460917)
			(xy 26.654993 -101.483562) (xy 26.700854 -101.513033) (xy 26.742055 -101.548731) (xy 26.777755 -101.58993)
			(xy 26.807229 -101.635789) (xy 26.829876 -101.685377) (xy 26.845235 -101.737683) (xy 26.852993 -101.791643)
			(xy 26.852993 -101.846157) (xy 26.845235 -101.900117) (xy 26.829876 -101.952423) (xy 26.807229 -102.002011)
			(xy 26.777755 -102.04787) (xy 26.750962 -102.07879) (xy 35.425888 -102.07879) (xy 35.426351 -102.05142)
			(xy 35.43417 -101.997241) (xy 35.44966 -101.944738) (xy 35.472502 -101.894991) (xy 35.502227 -101.849024)
			(xy 35.519868 -101.828092) (xy 35.529117 -101.816773) (xy 35.541297 -101.790213) (xy 35.545469 -101.761292)
			(xy 35.541293 -101.732373) (xy 35.529109 -101.705814) (xy 35.519868 -101.694488) (xy 35.502216 -101.673564)
			(xy 35.472488 -101.627596) (xy 35.449641 -101.577848) (xy 35.434144 -101.525344) (xy 35.426315 -101.471164)
			(xy 35.426316 -101.416421) (xy 35.434147 -101.362241) (xy 35.449646 -101.309738) (xy 35.472496 -101.259991)
			(xy 35.502225 -101.214024) (xy 35.519868 -101.193092) (xy 35.529117 -101.181773) (xy 35.541297 -101.155213)
			(xy 35.545469 -101.126292) (xy 35.541293 -101.097373) (xy 35.529109 -101.070814) (xy 35.519868 -101.059488)
			(xy 35.502252 -101.038538) (xy 35.472538 -100.992569) (xy 35.449698 -100.942826) (xy 35.434201 -100.89033)
			(xy 35.426366 -100.836158) (xy 35.425888 -100.80879) (xy 35.426374 -100.781539) (xy 35.43413 -100.727591)
			(xy 35.449485 -100.675296) (xy 35.472127 -100.625719) (xy 35.501593 -100.579869) (xy 35.537284 -100.538678)
			(xy 35.578475 -100.502987) (xy 35.624325 -100.473521) (xy 35.673902 -100.450879) (xy 35.726197 -100.435524)
			(xy 35.780145 -100.427768) (xy 35.834647 -100.427768) (xy 35.888595 -100.435524) (xy 35.94089 -100.450879)
			(xy 35.990467 -100.473521) (xy 36.036317 -100.502987) (xy 36.077508 -100.538678) (xy 36.113199 -100.579869)
			(xy 36.142665 -100.625719) (xy 36.165307 -100.675296) (xy 36.180662 -100.727591) (xy 36.188418 -100.781539)
			(xy 36.188904 -100.80879) (xy 36.188431 -100.83616) (xy 36.180615 -100.890339) (xy 36.165127 -100.942842)
			(xy 36.158452 -100.95738) (xy 40.280842 -100.95738) (xy 40.284913 -100.901758) (xy 40.297039 -100.847321)
			(xy 40.316962 -100.79523) (xy 40.344258 -100.746595) (xy 40.378344 -100.702452) (xy 40.418493 -100.663743)
			(xy 40.463851 -100.631292) (xy 40.513451 -100.605791) (xy 40.566235 -100.587784) (xy 40.621078 -100.577654)
			(xy 40.676812 -100.575617) (xy 40.732249 -100.581717) (xy 40.786206 -100.595823) (xy 40.837535 -100.617635)
			(xy 40.885141 -100.646689) (xy 40.928009 -100.682364) (xy 40.965226 -100.723901) (xy 40.968622 -100.729034)
			(xy 44.925232 -100.729034) (xy 44.929303 -100.673412) (xy 44.941429 -100.618975) (xy 44.961352 -100.566884)
			(xy 44.988648 -100.518249) (xy 45.022734 -100.474106) (xy 45.062883 -100.435397) (xy 45.108241 -100.402946)
			(xy 45.157841 -100.377445) (xy 45.210625 -100.359438) (xy 45.265468 -100.349308) (xy 45.321202 -100.347271)
			(xy 45.376639 -100.353371) (xy 45.430596 -100.367477) (xy 45.481925 -100.389289) (xy 45.529531 -100.418343)
			(xy 45.545461 -100.4316) (xy 63.625982 -100.4316) (xy 63.630053 -100.375978) (xy 63.642179 -100.321541)
			(xy 63.662102 -100.26945) (xy 63.689398 -100.220815) (xy 63.723484 -100.176672) (xy 63.763633 -100.137963)
			(xy 63.808991 -100.105512) (xy 63.858591 -100.080011) (xy 63.911375 -100.062004) (xy 63.966218 -100.051874)
			(xy 64.021952 -100.049837) (xy 64.077389 -100.055937) (xy 64.131346 -100.070043) (xy 64.182675 -100.091855)
			(xy 64.230281 -100.120909) (xy 64.273149 -100.156584) (xy 64.310366 -100.198121) (xy 64.329726 -100.227384)
			(xy 92.119958 -100.227384) (xy 92.120458 -100.199226) (xy 92.12876 -100.143524) (xy 92.145165 -100.08965)
			(xy 92.169317 -100.038775) (xy 92.20069 -99.992006) (xy 92.219272 -99.970844) (xy 92.229039 -99.959371)
			(xy 92.241984 -99.93218) (xy 92.246427 -99.902393) (xy 92.24198 -99.872608) (xy 92.229032 -99.845418)
			(xy 92.219272 -99.833938) (xy 92.200705 -99.812765) (xy 92.16935 -99.76599) (xy 92.145207 -99.715116)
			(xy 92.128799 -99.661248) (xy 92.120483 -99.605554) (xy 92.119958 -99.577398) (xy 92.120444 -99.550147)
			(xy 92.1282 -99.496199) (xy 92.143555 -99.443904) (xy 92.166197 -99.394327) (xy 92.195663 -99.348477)
			(xy 92.231354 -99.307286) (xy 92.272545 -99.271595) (xy 92.318395 -99.242129) (xy 92.367972 -99.219487)
			(xy 92.420267 -99.204132) (xy 92.474215 -99.196376) (xy 92.528717 -99.196376) (xy 92.582665 -99.204132)
			(xy 92.63496 -99.219487) (xy 92.684537 -99.242129) (xy 92.730387 -99.271595) (xy 92.771578 -99.307286)
			(xy 92.807269 -99.348477) (xy 92.836735 -99.394327) (xy 92.859377 -99.443904) (xy 92.874732 -99.496199)
			(xy 92.882488 -99.550147) (xy 92.882974 -99.577398) (xy 92.882857 -99.583748) (xy 98.734372 -99.583748)
			(xy 98.734858 -99.556497) (xy 98.742614 -99.502549) (xy 98.757969 -99.450254) (xy 98.780611 -99.400677)
			(xy 98.810077 -99.354827) (xy 98.845768 -99.313636) (xy 98.886959 -99.277945) (xy 98.932809 -99.248479)
			(xy 98.982386 -99.225837) (xy 99.034681 -99.210482) (xy 99.088629 -99.202726) (xy 99.143131 -99.202726)
			(xy 99.197079 -99.210482) (xy 99.249374 -99.225837) (xy 99.298951 -99.248479) (xy 99.344801 -99.277945)
			(xy 99.385992 -99.313636) (xy 99.421683 -99.354827) (xy 99.451149 -99.400677) (xy 99.473791 -99.450254)
			(xy 99.489146 -99.502549) (xy 99.496902 -99.556497) (xy 99.497388 -99.583748) (xy 99.496973 -99.608969)
			(xy 99.490335 -99.658974) (xy 99.477168 -99.707668) (xy 99.457702 -99.754203) (xy 99.432275 -99.797768)
			(xy 99.417124 -99.817936) (xy 99.40879 -99.829504) (xy 99.398229 -99.855972) (xy 99.395396 -99.884329)
			(xy 99.400512 -99.912363) (xy 99.413177 -99.937891) (xy 99.432405 -99.958924) (xy 99.444302 -99.96678)
			(xy 99.467809 -99.981772) (xy 99.510641 -100.01746) (xy 99.547827 -100.058998) (xy 99.578575 -100.105504)
			(xy 99.60223 -100.155988) (xy 99.618291 -100.209376) (xy 99.626414 -100.264532) (xy 99.626928 -100.292408)
			(xy 99.626442 -100.319659) (xy 99.618686 -100.373607) (xy 99.603331 -100.425902) (xy 99.580689 -100.475479)
			(xy 99.551223 -100.521329) (xy 99.515532 -100.56252) (xy 99.474341 -100.598211) (xy 99.428491 -100.627677)
			(xy 99.378914 -100.650319) (xy 99.326619 -100.665674) (xy 99.272671 -100.67343) (xy 99.218169 -100.67343)
			(xy 99.164221 -100.665674) (xy 99.111926 -100.650319) (xy 99.062349 -100.627677) (xy 99.016499 -100.598211)
			(xy 98.975308 -100.56252) (xy 98.939617 -100.521329) (xy 98.910151 -100.475479) (xy 98.887509 -100.425902)
			(xy 98.872154 -100.373607) (xy 98.864398 -100.319659) (xy 98.863912 -100.292408) (xy 98.864303 -100.267186)
			(xy 98.870947 -100.217181) (xy 98.884119 -100.168486) (xy 98.903591 -100.121951) (xy 98.929023 -100.078387)
			(xy 98.944176 -100.05822) (xy 98.95256 -100.046685) (xy 98.963115 -100.020205) (xy 98.96594 -99.99184)
			(xy 98.960816 -99.963798) (xy 98.94814 -99.938266) (xy 98.9289 -99.917231) (xy 98.916998 -99.909376)
			(xy 98.893471 -99.894413) (xy 98.850639 -99.858721) (xy 98.813454 -99.817178) (xy 98.782709 -99.770667)
			(xy 98.759057 -99.720178) (xy 98.743001 -99.666785) (xy 98.734883 -99.611625) (xy 98.734372 -99.583748)
			(xy 92.882857 -99.583748) (xy 92.882455 -99.605555) (xy 92.874156 -99.661256) (xy 92.857755 -99.715129)
			(xy 92.833608 -99.766005) (xy 92.80224 -99.812774) (xy 92.78366 -99.833938) (xy 92.773965 -99.845448)
			(xy 92.761104 -99.87264) (xy 92.756689 -99.902393) (xy 92.7611 -99.932147) (xy 92.773957 -99.95934)
			(xy 92.78366 -99.970844) (xy 92.802224 -99.992019) (xy 92.833578 -100.038794) (xy 92.857722 -100.089667)
			(xy 92.87413 -100.143535) (xy 92.882448 -100.199229) (xy 92.882974 -100.227384) (xy 92.882488 -100.254635)
			(xy 92.874732 -100.308583) (xy 92.859377 -100.360878) (xy 92.836735 -100.410455) (xy 92.807269 -100.456305)
			(xy 92.771578 -100.497496) (xy 92.730387 -100.533187) (xy 92.684537 -100.562653) (xy 92.63496 -100.585295)
			(xy 92.582665 -100.60065) (xy 92.528717 -100.608406) (xy 92.474215 -100.608406) (xy 92.420267 -100.60065)
			(xy 92.367972 -100.585295) (xy 92.318395 -100.562653) (xy 92.272545 -100.533187) (xy 92.231354 -100.497496)
			(xy 92.195663 -100.456305) (xy 92.166197 -100.410455) (xy 92.143555 -100.360878) (xy 92.1282 -100.308583)
			(xy 92.120444 -100.254635) (xy 92.119958 -100.227384) (xy 64.329726 -100.227384) (xy 64.341139 -100.244634)
			(xy 64.364811 -100.295131) (xy 64.380879 -100.348538) (xy 64.388999 -100.403714) (xy 64.389508 -100.4316)
			(xy 64.388999 -100.459486) (xy 64.380879 -100.514662) (xy 64.364811 -100.568069) (xy 64.341139 -100.618566)
			(xy 64.310366 -100.665079) (xy 64.273149 -100.706616) (xy 64.230281 -100.742291) (xy 64.182675 -100.771345)
			(xy 64.131346 -100.793157) (xy 64.077389 -100.807263) (xy 64.021952 -100.813363) (xy 63.966218 -100.811326)
			(xy 63.911375 -100.801196) (xy 63.858591 -100.783189) (xy 63.808991 -100.757688) (xy 63.763633 -100.725237)
			(xy 63.723484 -100.686528) (xy 63.689398 -100.642385) (xy 63.662102 -100.59375) (xy 63.642179 -100.541659)
			(xy 63.630053 -100.487222) (xy 63.625982 -100.4316) (xy 45.545461 -100.4316) (xy 45.572399 -100.454018)
			(xy 45.609616 -100.495555) (xy 45.640389 -100.542068) (xy 45.664061 -100.592565) (xy 45.680129 -100.645972)
			(xy 45.688249 -100.701148) (xy 45.688758 -100.729034) (xy 45.688249 -100.75692) (xy 45.680129 -100.812096)
			(xy 45.664061 -100.865503) (xy 45.645757 -100.904548) (xy 114.18773 -100.904548) (xy 114.191801 -100.848926)
			(xy 114.203927 -100.794489) (xy 114.22385 -100.742398) (xy 114.251146 -100.693763) (xy 114.285232 -100.64962)
			(xy 114.325381 -100.610911) (xy 114.370739 -100.57846) (xy 114.420339 -100.552959) (xy 114.473123 -100.534952)
			(xy 114.527966 -100.524822) (xy 114.5837 -100.522785) (xy 114.639137 -100.528885) (xy 114.693094 -100.542991)
			(xy 114.744423 -100.564803) (xy 114.792029 -100.593857) (xy 114.834897 -100.629532) (xy 114.872114 -100.671069)
			(xy 114.902887 -100.717582) (xy 114.926559 -100.768079) (xy 114.942627 -100.821486) (xy 114.950747 -100.876662)
			(xy 114.951256 -100.904548) (xy 114.950747 -100.932434) (xy 114.942627 -100.98761) (xy 114.926559 -101.041017)
			(xy 114.902887 -101.091514) (xy 114.872114 -101.138027) (xy 114.834897 -101.179564) (xy 114.792029 -101.215239)
			(xy 114.744423 -101.244293) (xy 114.693094 -101.266105) (xy 114.639137 -101.280211) (xy 114.5837 -101.286311)
			(xy 114.527966 -101.284274) (xy 114.473123 -101.274144) (xy 114.420339 -101.256137) (xy 114.370739 -101.230636)
			(xy 114.325381 -101.198185) (xy 114.285232 -101.159476) (xy 114.251146 -101.115333) (xy 114.22385 -101.066698)
			(xy 114.203927 -101.014607) (xy 114.191801 -100.96017) (xy 114.18773 -100.904548) (xy 45.645757 -100.904548)
			(xy 45.640389 -100.916) (xy 45.609616 -100.962513) (xy 45.572399 -101.00405) (xy 45.529531 -101.039725)
			(xy 45.481925 -101.068779) (xy 45.430596 -101.090591) (xy 45.376639 -101.104697) (xy 45.321202 -101.110797)
			(xy 45.265468 -101.10876) (xy 45.210625 -101.09863) (xy 45.157841 -101.080623) (xy 45.108241 -101.055122)
			(xy 45.062883 -101.022671) (xy 45.022734 -100.983962) (xy 44.988648 -100.939819) (xy 44.961352 -100.891184)
			(xy 44.941429 -100.839093) (xy 44.929303 -100.784656) (xy 44.925232 -100.729034) (xy 40.968622 -100.729034)
			(xy 40.995999 -100.770414) (xy 41.019671 -100.820911) (xy 41.035739 -100.874318) (xy 41.043859 -100.929494)
			(xy 41.044368 -100.95738) (xy 41.043859 -100.985266) (xy 41.035739 -101.040442) (xy 41.019671 -101.093849)
			(xy 40.995999 -101.144346) (xy 40.965226 -101.190859) (xy 40.928009 -101.232396) (xy 40.885141 -101.268071)
			(xy 40.837535 -101.297125) (xy 40.786206 -101.318937) (xy 40.732249 -101.333043) (xy 40.676812 -101.339143)
			(xy 40.621078 -101.337106) (xy 40.566235 -101.326976) (xy 40.513451 -101.308969) (xy 40.463851 -101.283468)
			(xy 40.418493 -101.251017) (xy 40.378344 -101.212308) (xy 40.344258 -101.168165) (xy 40.316962 -101.11953)
			(xy 40.297039 -101.067439) (xy 40.284913 -101.013002) (xy 40.280842 -100.95738) (xy 36.158452 -100.95738)
			(xy 36.142287 -100.992589) (xy 36.112564 -101.038556) (xy 36.094924 -101.059488) (xy 36.085695 -101.070822)
			(xy 36.073513 -101.097377) (xy 36.069338 -101.126292) (xy 36.073509 -101.155209) (xy 36.085687 -101.181766)
			(xy 36.094924 -101.193092) (xy 36.112557 -101.214032) (xy 36.142286 -101.259997) (xy 36.165135 -101.309742)
			(xy 36.180634 -101.362243) (xy 36.188465 -101.416422) (xy 36.188466 -101.471163) (xy 36.180637 -101.525342)
			(xy 36.16514 -101.577844) (xy 36.142293 -101.62759) (xy 36.112566 -101.673556) (xy 36.094924 -101.694488)
			(xy 36.085695 -101.705822) (xy 36.073513 -101.732377) (xy 36.069338 -101.761292) (xy 36.073509 -101.790209)
			(xy 36.085687 -101.816766) (xy 36.094924 -101.828092) (xy 36.112577 -101.849013) (xy 36.142286 -101.894989)
			(xy 36.165118 -101.94474) (xy 36.180606 -101.997243) (xy 36.188432 -102.05142) (xy 36.188904 -102.07879)
			(xy 43.097702 -102.07879) (xy 43.101773 -102.023168) (xy 43.113899 -101.968731) (xy 43.133822 -101.91664)
			(xy 43.161118 -101.868005) (xy 43.195204 -101.823862) (xy 43.235353 -101.785153) (xy 43.280711 -101.752702)
			(xy 43.330311 -101.727201) (xy 43.383095 -101.709194) (xy 43.437938 -101.699064) (xy 43.493672 -101.697027)
			(xy 43.549109 -101.703127) (xy 43.603066 -101.717233) (xy 43.654395 -101.739045) (xy 43.702001 -101.768099)
			(xy 43.744869 -101.803774) (xy 43.782086 -101.845311) (xy 43.812859 -101.891824) (xy 43.816341 -101.899252)
			(xy 45.807589 -101.899252) (xy 45.807589 -101.844748) (xy 45.815346 -101.790799) (xy 45.830703 -101.738504)
			(xy 45.853345 -101.688926) (xy 45.882813 -101.643076) (xy 45.918507 -101.601886) (xy 45.9597 -101.566195)
			(xy 46.005553 -101.536731) (xy 46.055132 -101.514092) (xy 46.107429 -101.49874) (xy 46.161378 -101.490987)
			(xy 46.18863 -101.490526) (xy 46.215394 -101.491023) (xy 46.268395 -101.498508) (xy 46.31983 -101.513329)
			(xy 46.368688 -101.535193) (xy 46.414011 -101.563672) (xy 46.454908 -101.598206) (xy 46.490577 -101.638118)
			(xy 46.520317 -101.682623) (xy 46.543545 -101.730848) (xy 46.552104 -101.75621) (xy 46.553281 -101.759512)
			(xy 86.922862 -101.759512) (xy 86.926933 -101.70389) (xy 86.939059 -101.649453) (xy 86.958982 -101.597362)
			(xy 86.986278 -101.548727) (xy 87.020364 -101.504584) (xy 87.060513 -101.465875) (xy 87.105871 -101.433424)
			(xy 87.155471 -101.407923) (xy 87.208255 -101.389916) (xy 87.263098 -101.379786) (xy 87.318832 -101.377749)
			(xy 87.374269 -101.383849) (xy 87.428226 -101.397955) (xy 87.479555 -101.419767) (xy 87.527161 -101.448821)
			(xy 87.570029 -101.484496) (xy 87.607246 -101.526033) (xy 87.638019 -101.572546) (xy 87.661691 -101.623043)
			(xy 87.677759 -101.67645) (xy 87.685879 -101.731626) (xy 87.686388 -101.759512) (xy 93.868746 -101.759512)
			(xy 93.872817 -101.70389) (xy 93.884943 -101.649453) (xy 93.904866 -101.597362) (xy 93.932162 -101.548727)
			(xy 93.966248 -101.504584) (xy 94.006397 -101.465875) (xy 94.051755 -101.433424) (xy 94.101355 -101.407923)
			(xy 94.154139 -101.389916) (xy 94.208982 -101.379786) (xy 94.264716 -101.377749) (xy 94.320153 -101.383849)
			(xy 94.37411 -101.397955) (xy 94.425439 -101.419767) (xy 94.473045 -101.448821) (xy 94.515913 -101.484496)
			(xy 94.55313 -101.526033) (xy 94.583903 -101.572546) (xy 94.607575 -101.623043) (xy 94.623643 -101.67645)
			(xy 94.631763 -101.731626) (xy 94.632272 -101.759512) (xy 94.631763 -101.787398) (xy 94.623643 -101.842574)
			(xy 94.607575 -101.895981) (xy 94.583903 -101.946478) (xy 94.55313 -101.992991) (xy 94.515913 -102.034528)
			(xy 94.473045 -102.070203) (xy 94.425439 -102.099257) (xy 94.37411 -102.121069) (xy 94.320153 -102.135175)
			(xy 94.264716 -102.141275) (xy 94.208982 -102.139238) (xy 94.154139 -102.129108) (xy 94.101355 -102.111101)
			(xy 94.051755 -102.0856) (xy 94.006397 -102.053149) (xy 93.966248 -102.01444) (xy 93.932162 -101.970297)
			(xy 93.904866 -101.921662) (xy 93.884943 -101.869571) (xy 93.872817 -101.815134) (xy 93.868746 -101.759512)
			(xy 87.686388 -101.759512) (xy 87.685879 -101.787398) (xy 87.677759 -101.842574) (xy 87.661691 -101.895981)
			(xy 87.638019 -101.946478) (xy 87.607246 -101.992991) (xy 87.570029 -102.034528) (xy 87.527161 -102.070203)
			(xy 87.479555 -102.099257) (xy 87.428226 -102.121069) (xy 87.374269 -102.135175) (xy 87.318832 -102.141275)
			(xy 87.263098 -102.139238) (xy 87.208255 -102.129108) (xy 87.155471 -102.111101) (xy 87.105871 -102.0856)
			(xy 87.060513 -102.053149) (xy 87.020364 -102.01444) (xy 86.986278 -101.970297) (xy 86.958982 -101.921662)
			(xy 86.939059 -101.869571) (xy 86.926933 -101.815134) (xy 86.922862 -101.759512) (xy 46.553281 -101.759512)
			(xy 46.556992 -101.769918) (xy 46.573294 -101.794013) (xy 46.595726 -101.812537) (xy 46.622469 -101.823988)
			(xy 46.651356 -101.827436) (xy 46.680043 -101.822603) (xy 46.693328 -101.816662) (xy 46.719492 -101.804492)
			(xy 46.774567 -101.787283) (xy 46.831609 -101.778583) (xy 46.86046 -101.778054) (xy 46.887712 -101.778591)
			(xy 46.941662 -101.786342) (xy 46.993959 -101.801693) (xy 47.04354 -101.824331) (xy 47.089393 -101.853795)
			(xy 47.130586 -101.889485) (xy 47.166281 -101.930675) (xy 47.19575 -101.976525) (xy 47.218393 -102.026103)
			(xy 47.233749 -102.078399) (xy 47.241507 -102.132348) (xy 47.241507 -102.186852) (xy 47.233749 -102.240801)
			(xy 47.218393 -102.293097) (xy 47.19575 -102.342675) (xy 47.184635 -102.359968) (xy 85.031072 -102.359968)
			(xy 85.031558 -102.332717) (xy 85.039314 -102.278769) (xy 85.054669 -102.226474) (xy 85.077311 -102.176897)
			(xy 85.106777 -102.131047) (xy 85.142468 -102.089856) (xy 85.183659 -102.054165) (xy 85.229509 -102.024699)
			(xy 85.279086 -102.002057) (xy 85.331381 -101.986702) (xy 85.385329 -101.978946) (xy 85.439831 -101.978946)
			(xy 85.493779 -101.986702) (xy 85.546074 -102.002057) (xy 85.595651 -102.024699) (xy 85.641501 -102.054165)
			(xy 85.682692 -102.089856) (xy 85.718383 -102.131047) (xy 85.747849 -102.176897) (xy 85.770491 -102.226474)
			(xy 85.785846 -102.278769) (xy 85.793602 -102.332717) (xy 85.794088 -102.359968) (xy 85.793593 -102.387954)
			(xy 85.785431 -102.443327) (xy 85.769264 -102.496913) (xy 85.767968 -102.499668) (xy 96.915222 -102.499668)
			(xy 96.919293 -102.444046) (xy 96.931419 -102.389609) (xy 96.951342 -102.337518) (xy 96.978638 -102.288883)
			(xy 97.012724 -102.24474) (xy 97.052873 -102.206031) (xy 97.098231 -102.17358) (xy 97.147831 -102.148079)
			(xy 97.200615 -102.130072) (xy 97.255458 -102.119942) (xy 97.311192 -102.117905) (xy 97.366629 -102.124005)
			(xy 97.420586 -102.138111) (xy 97.471915 -102.159923) (xy 97.519521 -102.188977) (xy 97.551017 -102.215188)
			(xy 102.158292 -102.215188) (xy 102.158778 -102.187937) (xy 102.166534 -102.133989) (xy 102.181889 -102.081694)
			(xy 102.204531 -102.032117) (xy 102.233997 -101.986267) (xy 102.269688 -101.945076) (xy 102.310879 -101.909385)
			(xy 102.356729 -101.879919) (xy 102.406306 -101.857277) (xy 102.458601 -101.841922) (xy 102.512549 -101.834166)
			(xy 102.567051 -101.834166) (xy 102.620999 -101.841922) (xy 102.673294 -101.857277) (xy 102.722871 -101.879919)
			(xy 102.768721 -101.909385) (xy 102.809912 -101.945076) (xy 102.845603 -101.986267) (xy 102.875069 -102.032117)
			(xy 102.897711 -102.081694) (xy 102.913066 -102.133989) (xy 102.920822 -102.187937) (xy 102.921308 -102.215188)
			(xy 102.920834 -102.241356) (xy 102.913669 -102.293166) (xy 109.20984 -102.293166) (xy 109.210326 -102.265915)
			(xy 109.218082 -102.211967) (xy 109.233437 -102.159672) (xy 109.256079 -102.110095) (xy 109.285545 -102.064245)
			(xy 109.321236 -102.023054) (xy 109.362427 -101.987363) (xy 109.408277 -101.957897) (xy 109.457854 -101.935255)
			(xy 109.510149 -101.9199) (xy 109.564097 -101.912144) (xy 109.618599 -101.912144) (xy 109.672547 -101.9199)
			(xy 109.724842 -101.935255) (xy 109.774419 -101.957897) (xy 109.820269 -101.987363) (xy 109.86146 -102.023054)
			(xy 109.897151 -102.064245) (xy 109.926617 -102.110095) (xy 109.949259 -102.159672) (xy 109.964614 -102.211967)
			(xy 109.97237 -102.265915) (xy 109.972856 -102.293166) (xy 109.972388 -102.320611) (xy 109.964514 -102.374933)
			(xy 109.948922 -102.427562) (xy 109.925937 -102.477408) (xy 109.911388 -102.500684) (xy 109.903531 -102.513853)
			(xy 109.895246 -102.543361) (xy 109.89609 -102.573998) (xy 109.905986 -102.603005) (xy 109.924043 -102.62777)
			(xy 109.936026 -102.637336) (xy 109.959412 -102.655446) (xy 110.000769 -102.697732) (xy 110.0351 -102.745897)
			(xy 110.061582 -102.798786) (xy 110.079578 -102.85513) (xy 110.088658 -102.913577) (xy 110.089188 -102.943152)
			(xy 110.088702 -102.970403) (xy 110.080946 -103.024351) (xy 110.065591 -103.076646) (xy 110.042949 -103.126223)
			(xy 110.013483 -103.172073) (xy 109.977792 -103.213264) (xy 109.936601 -103.248955) (xy 109.890751 -103.278421)
			(xy 109.841174 -103.301063) (xy 109.788879 -103.316418) (xy 109.734931 -103.324174) (xy 109.680429 -103.324174)
			(xy 109.626481 -103.316418) (xy 109.574186 -103.301063) (xy 109.524609 -103.278421) (xy 109.478759 -103.248955)
			(xy 109.437568 -103.213264) (xy 109.401877 -103.172073) (xy 109.372411 -103.126223) (xy 109.349769 -103.076646)
			(xy 109.334414 -103.024351) (xy 109.326658 -102.970403) (xy 109.326172 -102.943152) (xy 109.326644 -102.915707)
			(xy 109.334517 -102.861385) (xy 109.350107 -102.808756) (xy 109.373091 -102.75891) (xy 109.38764 -102.735634)
			(xy 109.395577 -102.722509) (xy 109.403844 -102.692983) (xy 109.402982 -102.662333) (xy 109.393068 -102.633318)
			(xy 109.374993 -102.608549) (xy 109.363002 -102.598982) (xy 109.33963 -102.580854) (xy 109.298271 -102.538572)
			(xy 109.263938 -102.490411) (xy 109.237454 -102.437526) (xy 109.219454 -102.381184) (xy 109.210371 -102.32274)
			(xy 109.20984 -102.293166) (xy 102.913669 -102.293166) (xy 102.913665 -102.293198) (xy 102.899476 -102.343573)
			(xy 102.878531 -102.391534) (xy 102.851224 -102.436181) (xy 102.818069 -102.476675) (xy 102.779689 -102.512255)
			(xy 102.758494 -102.527608) (xy 102.74728 -102.53611) (xy 102.729541 -102.557935) (xy 102.718419 -102.583768)
			(xy 102.714756 -102.611654) (xy 102.718829 -102.639483) (xy 102.730331 -102.665149) (xy 102.748391 -102.686711)
			(xy 102.759764 -102.694994) (xy 102.781399 -102.710321) (xy 102.820658 -102.745956) (xy 102.854602 -102.786686)
			(xy 102.882577 -102.831724) (xy 102.904045 -102.880204) (xy 102.91859 -102.931189) (xy 102.925933 -102.983698)
			(xy 102.926388 -103.010208) (xy 102.925902 -103.037459) (xy 102.918146 -103.091407) (xy 102.902791 -103.143702)
			(xy 102.880149 -103.193279) (xy 102.850683 -103.239129) (xy 102.814992 -103.28032) (xy 102.773801 -103.316011)
			(xy 102.727951 -103.345477) (xy 102.678374 -103.368119) (xy 102.626079 -103.383474) (xy 102.572131 -103.39123)
			(xy 102.517629 -103.39123) (xy 102.463681 -103.383474) (xy 102.411386 -103.368119) (xy 102.361809 -103.345477)
			(xy 102.315959 -103.316011) (xy 102.274768 -103.28032) (xy 102.239077 -103.239129) (xy 102.209611 -103.193279)
			(xy 102.186969 -103.143702) (xy 102.171614 -103.091407) (xy 102.163858 -103.037459) (xy 102.163372 -103.010208)
			(xy 102.163852 -102.984041) (xy 102.17102 -102.932199) (xy 102.18521 -102.881825) (xy 102.206154 -102.833863)
			(xy 102.233459 -102.789216) (xy 102.266613 -102.748722) (xy 102.304992 -102.713141) (xy 102.326186 -102.697788)
			(xy 102.337406 -102.689293) (xy 102.355149 -102.667467) (xy 102.366273 -102.641632) (xy 102.369936 -102.613744)
			(xy 102.365861 -102.585912) (xy 102.354356 -102.560245) (xy 102.336291 -102.538684) (xy 102.324916 -102.530402)
			(xy 102.303274 -102.515084) (xy 102.264017 -102.479446) (xy 102.230074 -102.438715) (xy 102.2021 -102.393675)
			(xy 102.180633 -102.345194) (xy 102.166089 -102.294208) (xy 102.158747 -102.241698) (xy 102.158292 -102.215188)
			(xy 97.551017 -102.215188) (xy 97.562389 -102.224652) (xy 97.599606 -102.266189) (xy 97.630379 -102.312702)
			(xy 97.654051 -102.363199) (xy 97.670119 -102.416606) (xy 97.678239 -102.471782) (xy 97.678748 -102.499668)
			(xy 97.678239 -102.527554) (xy 97.670119 -102.58273) (xy 97.654051 -102.636137) (xy 97.630379 -102.686634)
			(xy 97.599606 -102.733147) (xy 97.562389 -102.774684) (xy 97.519521 -102.810359) (xy 97.471915 -102.839413)
			(xy 97.420586 -102.861225) (xy 97.366629 -102.875331) (xy 97.311192 -102.881431) (xy 97.255458 -102.879394)
			(xy 97.200615 -102.869264) (xy 97.147831 -102.851257) (xy 97.098231 -102.825756) (xy 97.052873 -102.793305)
			(xy 97.012724 -102.754596) (xy 96.978638 -102.710453) (xy 96.951342 -102.661818) (xy 96.931419 -102.609727)
			(xy 96.919293 -102.55529) (xy 96.915222 -102.499668) (xy 85.767968 -102.499668) (xy 85.745437 -102.54756)
			(xy 85.714464 -102.59418) (xy 85.67701 -102.635773) (xy 85.633878 -102.671445) (xy 85.610192 -102.686358)
			(xy 85.598856 -102.6936) (xy 85.580277 -102.713045) (xy 85.567423 -102.73667) (xy 85.561188 -102.762832)
			(xy 85.562005 -102.789714) (xy 85.569818 -102.815449) (xy 85.584082 -102.83825) (xy 85.603809 -102.856531)
			(xy 85.615526 -102.863142) (xy 85.638285 -102.875549) (xy 85.68048 -102.905659) (xy 85.718207 -102.941207)
			(xy 85.750773 -102.981537) (xy 85.777576 -103.025906) (xy 85.798122 -103.073496) (xy 85.812034 -103.123431)
			(xy 85.819053 -103.17479) (xy 85.819488 -103.200708) (xy 85.819002 -103.227959) (xy 85.811246 -103.281907)
			(xy 85.795891 -103.334202) (xy 85.773249 -103.383779) (xy 85.743783 -103.429629) (xy 85.708092 -103.47082)
			(xy 85.679784 -103.495348) (xy 87.842342 -103.495348) (xy 87.846413 -103.439726) (xy 87.858539 -103.385289)
			(xy 87.878462 -103.333198) (xy 87.905758 -103.284563) (xy 87.939844 -103.24042) (xy 87.979993 -103.201711)
			(xy 88.025351 -103.16926) (xy 88.074951 -103.143759) (xy 88.127735 -103.125752) (xy 88.182578 -103.115622)
			(xy 88.238312 -103.113585) (xy 88.293749 -103.119685) (xy 88.347706 -103.133791) (xy 88.399035 -103.155603)
			(xy 88.446641 -103.184657) (xy 88.489509 -103.220332) (xy 88.526726 -103.261869) (xy 88.557499 -103.308382)
			(xy 88.573822 -103.343202) (xy 98.90506 -103.343202) (xy 98.905536 -103.316409) (xy 98.91304 -103.263351)
			(xy 98.927887 -103.211862) (xy 98.949786 -103.162955) (xy 98.978306 -103.117588) (xy 99.012887 -103.076654)
			(xy 99.032568 -103.058468) (xy 99.043504 -103.048012) (xy 99.059228 -103.022184) (xy 99.06668 -102.992877)
			(xy 99.065202 -102.962674) (xy 99.054925 -102.934235) (xy 99.046284 -102.921816) (xy 99.028396 -102.896916)
			(xy 99.000003 -102.842579) (xy 98.980678 -102.784397) (xy 98.970921 -102.72387) (xy 98.970338 -102.693216)
			(xy 98.970824 -102.665965) (xy 98.97858 -102.612017) (xy 98.993935 -102.559722) (xy 99.016577 -102.510145)
			(xy 99.046043 -102.464295) (xy 99.081734 -102.423104) (xy 99.122925 -102.387413) (xy 99.168775 -102.357947)
			(xy 99.218352 -102.335305) (xy 99.270647 -102.31995) (xy 99.324595 -102.312194) (xy 99.379097 -102.312194)
			(xy 99.433045 -102.31995) (xy 99.48534 -102.335305) (xy 99.534917 -102.357947) (xy 99.580767 -102.387413)
			(xy 99.621958 -102.423104) (xy 99.657649 -102.464295) (xy 99.687115 -102.510145) (xy 99.709757 -102.559722)
			(xy 99.725112 -102.612017) (xy 99.732868 -102.665965) (xy 99.733354 -102.693216) (xy 99.732886 -102.720009)
			(xy 99.725379 -102.773068) (xy 99.71053 -102.824556) (xy 99.68863 -102.873463) (xy 99.660109 -102.91883)
			(xy 99.625527 -102.959764) (xy 99.605846 -102.97795) (xy 99.594894 -102.988391) (xy 99.579169 -103.014224)
			(xy 99.571719 -103.043535) (xy 99.573201 -103.073742) (xy 99.583485 -103.102183) (xy 99.59213 -103.114602)
			(xy 99.609984 -103.139526) (xy 99.638384 -103.193854) (xy 99.657718 -103.252029) (xy 99.667487 -103.31255)
			(xy 99.668076 -103.343202) (xy 99.66759 -103.370453) (xy 99.661567 -103.412348) (xy 105.41359 -103.412348)
			(xy 105.41359 -103.357852) (xy 105.421345 -103.30391) (xy 105.436698 -103.25162) (xy 105.459335 -103.202047)
			(xy 105.488796 -103.156201) (xy 105.524482 -103.115013) (xy 105.565665 -103.079322) (xy 105.611509 -103.049856)
			(xy 105.661079 -103.027213) (xy 105.713366 -103.011855) (xy 105.767308 -103.004093) (xy 105.794556 -103.003604)
			(xy 105.82382 -103.004153) (xy 105.881663 -103.013073) (xy 105.937465 -103.030726) (xy 105.989915 -103.056696)
			(xy 106.037781 -103.090375) (xy 106.07994 -103.130972) (xy 106.115402 -103.177532) (xy 106.129836 -103.202994)
			(xy 106.13761 -103.216222) (xy 106.15957 -103.23763) (xy 106.1869 -103.251545) (xy 106.21713 -103.256709)
			(xy 106.24753 -103.252656) (xy 106.261662 -103.246682) (xy 106.286831 -103.235625) (xy 106.339539 -103.220009)
			(xy 106.393942 -103.212114) (xy 106.421428 -103.21163) (xy 106.448681 -103.212042) (xy 106.502631 -103.219802)
			(xy 106.554927 -103.235161) (xy 106.604506 -103.257806) (xy 106.650357 -103.287276) (xy 106.691548 -103.322971)
			(xy 106.72724 -103.364165) (xy 106.756707 -103.410019) (xy 106.779348 -103.459599) (xy 106.794704 -103.511897)
			(xy 106.80246 -103.565847) (xy 106.80246 -103.620353) (xy 106.794704 -103.674303) (xy 106.779348 -103.726601)
			(xy 106.756707 -103.776181) (xy 106.72724 -103.822035) (xy 106.691548 -103.863229) (xy 106.650357 -103.898924)
			(xy 106.604506 -103.928394) (xy 106.554927 -103.951039) (xy 106.502631 -103.966398) (xy 106.448681 -103.974158)
			(xy 106.421428 -103.974646) (xy 106.392165 -103.974084) (xy 106.334323 -103.965163) (xy 106.278523 -103.947511)
			(xy 106.226074 -103.921542) (xy 106.178208 -103.887865) (xy 106.136048 -103.847272) (xy 106.100584 -103.800716)
			(xy 106.086148 -103.775256) (xy 106.078404 -103.762009) (xy 106.056433 -103.740607) (xy 106.029095 -103.726698)
			(xy 105.99886 -103.721538) (xy 105.968456 -103.725593) (xy 105.954322 -103.731568) (xy 105.929154 -103.742627)
			(xy 105.876445 -103.758243) (xy 105.822042 -103.766137) (xy 105.794556 -103.76662) (xy 105.767308 -103.766107)
			(xy 105.713366 -103.758345) (xy 105.661079 -103.742987) (xy 105.611509 -103.720344) (xy 105.565665 -103.690878)
			(xy 105.524482 -103.655187) (xy 105.488796 -103.613999) (xy 105.459335 -103.568153) (xy 105.436698 -103.51858)
			(xy 105.421345 -103.46629) (xy 105.41359 -103.412348) (xy 99.661567 -103.412348) (xy 99.659834 -103.424401)
			(xy 99.644479 -103.476696) (xy 99.621837 -103.526273) (xy 99.592371 -103.572123) (xy 99.55668 -103.613314)
			(xy 99.515489 -103.649005) (xy 99.469639 -103.678471) (xy 99.420062 -103.701113) (xy 99.367767 -103.716468)
			(xy 99.313819 -103.724224) (xy 99.259317 -103.724224) (xy 99.205369 -103.716468) (xy 99.153074 -103.701113)
			(xy 99.103497 -103.678471) (xy 99.057647 -103.649005) (xy 99.016456 -103.613314) (xy 98.980765 -103.572123)
			(xy 98.951299 -103.526273) (xy 98.928657 -103.476696) (xy 98.913302 -103.424401) (xy 98.905546 -103.370453)
			(xy 98.90506 -103.343202) (xy 88.573822 -103.343202) (xy 88.581171 -103.358879) (xy 88.597239 -103.412286)
			(xy 88.605359 -103.467462) (xy 88.605868 -103.495348) (xy 88.605359 -103.523234) (xy 88.597239 -103.57841)
			(xy 88.581171 -103.631817) (xy 88.557499 -103.682314) (xy 88.526726 -103.728827) (xy 88.489509 -103.770364)
			(xy 88.446641 -103.806039) (xy 88.399035 -103.835093) (xy 88.347706 -103.856905) (xy 88.293749 -103.871011)
			(xy 88.238312 -103.877111) (xy 88.182578 -103.875074) (xy 88.127735 -103.864944) (xy 88.074951 -103.846937)
			(xy 88.025351 -103.821436) (xy 87.979993 -103.788985) (xy 87.939844 -103.750276) (xy 87.905758 -103.706133)
			(xy 87.878462 -103.657498) (xy 87.858539 -103.605407) (xy 87.846413 -103.55097) (xy 87.842342 -103.495348)
			(xy 85.679784 -103.495348) (xy 85.666901 -103.506511) (xy 85.621051 -103.535977) (xy 85.571474 -103.558619)
			(xy 85.519179 -103.573974) (xy 85.465231 -103.58173) (xy 85.410729 -103.58173) (xy 85.356781 -103.573974)
			(xy 85.304486 -103.558619) (xy 85.254909 -103.535977) (xy 85.209059 -103.506511) (xy 85.167868 -103.47082)
			(xy 85.132177 -103.429629) (xy 85.102711 -103.383779) (xy 85.080069 -103.334202) (xy 85.064714 -103.281907)
			(xy 85.056958 -103.227959) (xy 85.056472 -103.200708) (xy 85.056967 -103.172722) (xy 85.065131 -103.11735)
			(xy 85.0813 -103.063765) (xy 85.105127 -103.013119) (xy 85.136099 -102.966498) (xy 85.173553 -102.924905)
			(xy 85.216682 -102.889232) (xy 85.240368 -102.874318) (xy 85.251623 -102.866965) (xy 85.270187 -102.847537)
			(xy 85.283033 -102.823934) (xy 85.289269 -102.797796) (xy 85.288463 -102.770936) (xy 85.28067 -102.745219)
			(xy 85.266431 -102.72243) (xy 85.246736 -102.70415) (xy 85.235034 -102.697534) (xy 85.212298 -102.685087)
			(xy 85.170106 -102.654981) (xy 85.132379 -102.619438) (xy 85.099814 -102.579113) (xy 85.073008 -102.534751)
			(xy 85.052457 -102.487166) (xy 85.03854 -102.437238) (xy 85.031512 -102.385884) (xy 85.031072 -102.359968)
			(xy 47.184635 -102.359968) (xy 47.166281 -102.388525) (xy 47.130586 -102.429715) (xy 47.089393 -102.465405)
			(xy 47.04354 -102.494869) (xy 46.993959 -102.517507) (xy 46.941662 -102.532858) (xy 46.887712 -102.540609)
			(xy 46.86046 -102.54107) (xy 46.833696 -102.540585) (xy 46.780694 -102.533098) (xy 46.729259 -102.518276)
			(xy 46.6804 -102.49641) (xy 46.635077 -102.46793) (xy 46.59418 -102.433394) (xy 46.558512 -102.393481)
			(xy 46.528772 -102.348975) (xy 46.505545 -102.300749) (xy 46.496986 -102.275386) (xy 46.492112 -102.261672)
			(xy 46.475807 -102.237576) (xy 46.453372 -102.219052) (xy 46.426626 -102.207603) (xy 46.397737 -102.204156)
			(xy 46.369048 -102.208991) (xy 46.355762 -102.214934) (xy 46.329599 -102.227107) (xy 46.274523 -102.244315)
			(xy 46.217481 -102.253014) (xy 46.18863 -102.253542) (xy 46.161378 -102.253013) (xy 46.107429 -102.24526)
			(xy 46.055132 -102.229908) (xy 46.005553 -102.207269) (xy 45.9597 -102.177805) (xy 45.918507 -102.142114)
			(xy 45.882813 -102.100924) (xy 45.853345 -102.055074) (xy 45.830703 -102.005496) (xy 45.815346 -101.953201)
			(xy 45.807589 -101.899252) (xy 43.816341 -101.899252) (xy 43.836531 -101.942321) (xy 43.852599 -101.995728)
			(xy 43.860719 -102.050904) (xy 43.861228 -102.07879) (xy 43.860719 -102.106676) (xy 43.852599 -102.161852)
			(xy 43.836531 -102.215259) (xy 43.812859 -102.265756) (xy 43.782086 -102.312269) (xy 43.744869 -102.353806)
			(xy 43.702001 -102.389481) (xy 43.654395 -102.418535) (xy 43.603066 -102.440347) (xy 43.549109 -102.454453)
			(xy 43.493672 -102.460553) (xy 43.437938 -102.458516) (xy 43.383095 -102.448386) (xy 43.330311 -102.430379)
			(xy 43.280711 -102.404878) (xy 43.235353 -102.372427) (xy 43.195204 -102.333718) (xy 43.161118 -102.289575)
			(xy 43.133822 -102.24094) (xy 43.113899 -102.188849) (xy 43.101773 -102.134412) (xy 43.097702 -102.07879)
			(xy 36.188904 -102.07879) (xy 36.188418 -102.106041) (xy 36.180662 -102.159989) (xy 36.165307 -102.212284)
			(xy 36.142665 -102.261861) (xy 36.113199 -102.307711) (xy 36.077508 -102.348902) (xy 36.036317 -102.384593)
			(xy 35.990467 -102.414059) (xy 35.94089 -102.436701) (xy 35.888595 -102.452056) (xy 35.834647 -102.459812)
			(xy 35.780145 -102.459812) (xy 35.726197 -102.452056) (xy 35.673902 -102.436701) (xy 35.624325 -102.414059)
			(xy 35.578475 -102.384593) (xy 35.537284 -102.348902) (xy 35.501593 -102.307711) (xy 35.472127 -102.261861)
			(xy 35.449485 -102.212284) (xy 35.43413 -102.159989) (xy 35.426374 -102.106041) (xy 35.425888 -102.07879)
			(xy 26.750962 -102.07879) (xy 26.742055 -102.089069) (xy 26.700854 -102.124767) (xy 26.654993 -102.154238)
			(xy 26.605404 -102.176883) (xy 26.553097 -102.192239) (xy 26.499137 -102.199994) (xy 26.47188 -102.200456)
			(xy 26.444509 -102.200012) (xy 26.390328 -102.192191) (xy 26.337825 -102.176697) (xy 26.288078 -102.15385)
			(xy 26.242113 -102.12412) (xy 26.221182 -102.106476) (xy 26.209854 -102.09724) (xy 26.183297 -102.085064)
			(xy 26.15438 -102.080891) (xy 26.125463 -102.085064) (xy 26.098906 -102.09724) (xy 26.087578 -102.106476)
			(xy 26.066624 -102.124088) (xy 26.020658 -102.153805) (xy 25.970916 -102.176646) (xy 25.91842 -102.192144)
			(xy 25.864248 -102.199979) (xy 25.83688 -102.200456) (xy 25.809629 -102.199974) (xy 25.755681 -102.192218)
			(xy 25.703386 -102.176862) (xy 25.653808 -102.154221) (xy 25.607957 -102.124755) (xy 25.566767 -102.089063)
			(xy 25.531075 -102.047873) (xy 25.501609 -102.002022) (xy 25.478968 -101.952444) (xy 25.463612 -101.900149)
			(xy 25.455856 -101.846201) (xy 7.991738 -101.846201) (xy 7.991856 -101.854) (xy 7.99137 -101.881251)
			(xy 7.983614 -101.935199) (xy 7.968259 -101.987494) (xy 7.945617 -102.037071) (xy 7.916151 -102.082921)
			(xy 7.88046 -102.124112) (xy 7.839269 -102.159803) (xy 7.793419 -102.189269) (xy 7.743842 -102.211911)
			(xy 7.691547 -102.227266) (xy 7.637599 -102.235022) (xy 7.583097 -102.235022) (xy 7.529149 -102.227266)
			(xy 7.476854 -102.211911) (xy 7.427277 -102.189269) (xy 7.381427 -102.159803) (xy 7.340236 -102.124112)
			(xy 7.304545 -102.082921) (xy 7.275079 -102.037071) (xy 7.252437 -101.987494) (xy 7.237082 -101.935199)
			(xy 7.229326 -101.881251) (xy 7.22884 -101.854) (xy 7.229211 -101.830382) (xy 7.235071 -101.783511)
			(xy 7.240524 -101.760528) (xy 7.243789 -101.745427) (xy 7.242081 -101.714592) (xy 7.231246 -101.685673)
			(xy 7.212272 -101.661307) (xy 7.186889 -101.643717) (xy 7.157413 -101.634506) (xy 7.141972 -101.634036)
			(xy 6.055868 -101.634036) (xy 6.055868 -102.326948) (xy 13.183106 -102.326948) (xy 13.187177 -102.271326)
			(xy 13.199303 -102.216889) (xy 13.219226 -102.164798) (xy 13.246522 -102.116163) (xy 13.280608 -102.07202)
			(xy 13.320757 -102.033311) (xy 13.366115 -102.00086) (xy 13.415715 -101.975359) (xy 13.468499 -101.957352)
			(xy 13.523342 -101.947222) (xy 13.579076 -101.945185) (xy 13.634513 -101.951285) (xy 13.68847 -101.965391)
			(xy 13.739799 -101.987203) (xy 13.787405 -102.016257) (xy 13.830273 -102.051932) (xy 13.86749 -102.093469)
			(xy 13.898263 -102.139982) (xy 13.921935 -102.190479) (xy 13.938003 -102.243886) (xy 13.946123 -102.299062)
			(xy 13.946632 -102.326948) (xy 13.946123 -102.354834) (xy 13.938003 -102.41001) (xy 13.921935 -102.463417)
			(xy 13.898263 -102.513914) (xy 13.86749 -102.560427) (xy 13.830273 -102.601964) (xy 13.787405 -102.637639)
			(xy 13.739799 -102.666693) (xy 13.68847 -102.688505) (xy 13.634513 -102.702611) (xy 13.579076 -102.708711)
			(xy 13.523342 -102.706674) (xy 13.468499 -102.696544) (xy 13.415715 -102.678537) (xy 13.366115 -102.653036)
			(xy 13.320757 -102.620585) (xy 13.280608 -102.581876) (xy 13.246522 -102.537733) (xy 13.219226 -102.489098)
			(xy 13.199303 -102.437007) (xy 13.187177 -102.38257) (xy 13.183106 -102.326948) (xy 6.055868 -102.326948)
			(xy 6.055868 -102.761034) (xy 28.70276 -102.761034) (xy 28.706831 -102.705412) (xy 28.718957 -102.650975)
			(xy 28.73888 -102.598884) (xy 28.766176 -102.550249) (xy 28.800262 -102.506106) (xy 28.840411 -102.467397)
			(xy 28.885769 -102.434946) (xy 28.935369 -102.409445) (xy 28.988153 -102.391438) (xy 29.042996 -102.381308)
			(xy 29.09873 -102.379271) (xy 29.154167 -102.385371) (xy 29.208124 -102.399477) (xy 29.259453 -102.421289)
			(xy 29.307059 -102.450343) (xy 29.349927 -102.486018) (xy 29.387144 -102.527555) (xy 29.417917 -102.574068)
			(xy 29.441589 -102.624565) (xy 29.457657 -102.677972) (xy 29.465777 -102.733148) (xy 29.466286 -102.761034)
			(xy 29.465777 -102.78892) (xy 29.457657 -102.844096) (xy 29.444438 -102.888034) (xy 46.97806 -102.888034)
			(xy 46.982131 -102.832412) (xy 46.994257 -102.777975) (xy 47.01418 -102.725884) (xy 47.041476 -102.677249)
			(xy 47.075562 -102.633106) (xy 47.115711 -102.594397) (xy 47.161069 -102.561946) (xy 47.210669 -102.536445)
			(xy 47.263453 -102.518438) (xy 47.318296 -102.508308) (xy 47.37403 -102.506271) (xy 47.429467 -102.512371)
			(xy 47.483424 -102.526477) (xy 47.534753 -102.548289) (xy 47.582359 -102.577343) (xy 47.625227 -102.613018)
			(xy 47.662444 -102.654555) (xy 47.693217 -102.701068) (xy 47.716889 -102.751565) (xy 47.732957 -102.804972)
			(xy 47.741077 -102.860148) (xy 47.741586 -102.888034) (xy 47.741077 -102.91592) (xy 47.732957 -102.971096)
			(xy 47.718897 -103.017828) (xy 64.593722 -103.017828) (xy 64.597793 -102.962206) (xy 64.609919 -102.907769)
			(xy 64.629842 -102.855678) (xy 64.657138 -102.807043) (xy 64.691224 -102.7629) (xy 64.731373 -102.724191)
			(xy 64.776731 -102.69174) (xy 64.826331 -102.666239) (xy 64.879115 -102.648232) (xy 64.933958 -102.638102)
			(xy 64.989692 -102.636065) (xy 65.045129 -102.642165) (xy 65.099086 -102.656271) (xy 65.150415 -102.678083)
			(xy 65.198021 -102.707137) (xy 65.240889 -102.742812) (xy 65.278106 -102.784349) (xy 65.308879 -102.830862)
			(xy 65.332551 -102.881359) (xy 65.348619 -102.934766) (xy 65.356739 -102.989942) (xy 65.357248 -103.017828)
			(xy 65.356739 -103.045714) (xy 65.348619 -103.10089) (xy 65.332551 -103.154297) (xy 65.308879 -103.204794)
			(xy 65.278106 -103.251307) (xy 65.240889 -103.292844) (xy 65.198021 -103.328519) (xy 65.150415 -103.357573)
			(xy 65.099086 -103.379385) (xy 65.045129 -103.393491) (xy 64.989692 -103.399591) (xy 64.933958 -103.397554)
			(xy 64.879115 -103.387424) (xy 64.826331 -103.369417) (xy 64.776731 -103.343916) (xy 64.731373 -103.311465)
			(xy 64.691224 -103.272756) (xy 64.657138 -103.228613) (xy 64.629842 -103.179978) (xy 64.609919 -103.127887)
			(xy 64.597793 -103.07345) (xy 64.593722 -103.017828) (xy 47.718897 -103.017828) (xy 47.716889 -103.024503)
			(xy 47.693217 -103.075) (xy 47.662444 -103.121513) (xy 47.625227 -103.16305) (xy 47.582359 -103.198725)
			(xy 47.534753 -103.227779) (xy 47.483424 -103.249591) (xy 47.429467 -103.263697) (xy 47.37403 -103.269797)
			(xy 47.318296 -103.26776) (xy 47.263453 -103.25763) (xy 47.210669 -103.239623) (xy 47.161069 -103.214122)
			(xy 47.115711 -103.181671) (xy 47.075562 -103.142962) (xy 47.041476 -103.098819) (xy 47.01418 -103.050184)
			(xy 46.994257 -102.998093) (xy 46.982131 -102.943656) (xy 46.97806 -102.888034) (xy 29.444438 -102.888034)
			(xy 29.441589 -102.897503) (xy 29.417917 -102.948) (xy 29.387144 -102.994513) (xy 29.349927 -103.03605)
			(xy 29.307059 -103.071725) (xy 29.259453 -103.100779) (xy 29.208124 -103.122591) (xy 29.154167 -103.136697)
			(xy 29.09873 -103.142797) (xy 29.042996 -103.14076) (xy 28.988153 -103.13063) (xy 28.935369 -103.112623)
			(xy 28.885769 -103.087122) (xy 28.840411 -103.054671) (xy 28.800262 -103.015962) (xy 28.766176 -102.971819)
			(xy 28.73888 -102.923184) (xy 28.718957 -102.871093) (xy 28.706831 -102.816656) (xy 28.70276 -102.761034)
			(xy 6.055868 -102.761034) (xy 6.055868 -106.40187) (xy 11.713464 -106.40187) (xy 11.713464 -105.565702)
			(xy 11.713464 -105.556558) (xy 11.713464 -105.53827) (xy 11.714063 -105.508534) (xy 11.723339 -105.449788)
			(xy 11.741617 -105.393192) (xy 11.768453 -105.340117) (xy 11.803198 -105.291847) (xy 11.8237 -105.2703)
			(xy 11.830267 -105.262847) (xy 11.837743 -105.24447) (xy 11.837684 -105.224631) (xy 11.830099 -105.206299)
			(xy 11.823446 -105.198926) (xy 11.802948 -105.177353) (xy 11.768224 -105.129028) (xy 11.741427 -105.075896)
			(xy 11.723209 -105.019247) (xy 11.714012 -104.960456) (xy 11.713464 -104.930702) (xy 11.71395 -104.903451)
			(xy 11.721706 -104.849503) (xy 11.737061 -104.797208) (xy 11.759703 -104.747631) (xy 11.789169 -104.701781)
			(xy 11.82486 -104.66059) (xy 11.866051 -104.624899) (xy 11.911901 -104.595433) (xy 11.961478 -104.572791)
			(xy 12.013773 -104.557436) (xy 12.067721 -104.54968) (xy 12.122223 -104.54968) (xy 12.176171 -104.557436)
			(xy 12.228466 -104.572791) (xy 12.278043 -104.595433) (xy 12.323893 -104.624899) (xy 12.365084 -104.66059)
			(xy 12.400775 -104.701781) (xy 12.430241 -104.747631) (xy 12.452883 -104.797208) (xy 12.468238 -104.849503)
			(xy 12.475994 -104.903451) (xy 12.47648 -104.930702) (xy 12.475937 -104.96043) (xy 12.4667 -105.019164)
			(xy 12.448466 -105.075756) (xy 12.421675 -105.128834) (xy 12.386977 -105.177115) (xy 12.366498 -105.198672)
			(xy 12.359859 -105.206068) (xy 12.352395 -105.224471) (xy 12.352474 -105.24433) (xy 12.360085 -105.262673)
			(xy 12.366752 -105.270046) (xy 12.3873 -105.291587) (xy 12.422074 -105.339904) (xy 12.448919 -105.393037)
			(xy 12.467183 -105.449696) (xy 12.476422 -105.508505) (xy 12.476988 -105.53827) (xy 12.476988 -106.27995)
			(xy 15.571724 -106.27995) (xy 15.572308 -106.24961) (xy 15.581919 -106.189697) (xy 15.600891 -106.13206)
			(xy 15.628745 -106.078152) (xy 15.664781 -106.029331) (xy 15.686024 -106.007662) (xy 15.693004 -106.000299)
			(xy 15.700882 -105.981615) (xy 15.700873 -105.961339) (xy 15.692978 -105.942663) (xy 15.686024 -105.935272)
			(xy 15.664967 -105.913622) (xy 15.629239 -105.864933) (xy 15.601631 -105.811223) (xy 15.582833 -105.753832)
			(xy 15.573315 -105.694195) (xy 15.57274 -105.664) (xy 15.57274 -104.827832) (xy 15.57274 -104.818688)
			(xy 15.57274 -104.8004) (xy 15.573247 -104.772006) (xy 15.581681 -104.715846) (xy 15.598346 -104.661557)
			(xy 15.622876 -104.610339) (xy 15.654727 -104.563323) (xy 15.673578 -104.542082) (xy 15.683301 -104.530672)
			(xy 15.696301 -104.50368) (xy 15.700917 -104.474077) (xy 15.696752 -104.444408) (xy 15.684163 -104.417221)
			(xy 15.674594 -104.405684) (xy 15.656527 -104.384592) (xy 15.626017 -104.338189) (xy 15.602552 -104.287855)
			(xy 15.586626 -104.234653) (xy 15.578576 -104.179705) (xy 15.578074 -104.151938) (xy 15.57856 -104.124687)
			(xy 15.586316 -104.070739) (xy 15.601671 -104.018444) (xy 15.624313 -103.968867) (xy 15.653779 -103.923017)
			(xy 15.68947 -103.881826) (xy 15.730661 -103.846135) (xy 15.776511 -103.816669) (xy 15.826088 -103.794027)
			(xy 15.878383 -103.778672) (xy 15.932331 -103.770916) (xy 15.986833 -103.770916) (xy 16.040781 -103.778672)
			(xy 16.093076 -103.794027) (xy 16.142653 -103.816669) (xy 16.188503 -103.846135) (xy 16.229694 -103.881826)
			(xy 16.265385 -103.923017) (xy 16.294851 -103.968867) (xy 16.298998 -103.977948) (xy 41.248582 -103.977948)
			(xy 41.252653 -103.922326) (xy 41.264779 -103.867889) (xy 41.284702 -103.815798) (xy 41.311998 -103.767163)
			(xy 41.346084 -103.72302) (xy 41.386233 -103.684311) (xy 41.431591 -103.65186) (xy 41.481191 -103.626359)
			(xy 41.533975 -103.608352) (xy 41.588818 -103.598222) (xy 41.644552 -103.596185) (xy 41.699989 -103.602285)
			(xy 41.753946 -103.616391) (xy 41.805275 -103.638203) (xy 41.852881 -103.667257) (xy 41.895749 -103.702932)
			(xy 41.932966 -103.744469) (xy 41.963739 -103.790982) (xy 41.968036 -103.800148) (xy 48.441862 -103.800148)
			(xy 48.445933 -103.744526) (xy 48.458059 -103.690089) (xy 48.477982 -103.637998) (xy 48.505278 -103.589363)
			(xy 48.539364 -103.54522) (xy 48.579513 -103.506511) (xy 48.624871 -103.47406) (xy 48.674471 -103.448559)
			(xy 48.727255 -103.430552) (xy 48.782098 -103.420422) (xy 48.837832 -103.418385) (xy 48.893269 -103.424485)
			(xy 48.947226 -103.438591) (xy 48.998555 -103.460403) (xy 49.046161 -103.489457) (xy 49.089029 -103.525132)
			(xy 49.126246 -103.566669) (xy 49.142918 -103.591868) (xy 65.339466 -103.591868) (xy 65.343537 -103.536246)
			(xy 65.355663 -103.481809) (xy 65.375586 -103.429718) (xy 65.402882 -103.381083) (xy 65.436968 -103.33694)
			(xy 65.477117 -103.298231) (xy 65.522475 -103.26578) (xy 65.572075 -103.240279) (xy 65.624859 -103.222272)
			(xy 65.679702 -103.212142) (xy 65.735436 -103.210105) (xy 65.790873 -103.216205) (xy 65.84483 -103.230311)
			(xy 65.896159 -103.252123) (xy 65.943765 -103.281177) (xy 65.986633 -103.316852) (xy 66.02385 -103.358389)
			(xy 66.054623 -103.404902) (xy 66.078295 -103.455399) (xy 66.094363 -103.508806) (xy 66.102483 -103.563982)
			(xy 66.102992 -103.591868) (xy 66.102483 -103.619754) (xy 66.094363 -103.67493) (xy 66.078295 -103.728337)
			(xy 66.054623 -103.778834) (xy 66.02385 -103.825347) (xy 65.986633 -103.866884) (xy 65.943765 -103.902559)
			(xy 65.896159 -103.931613) (xy 65.84483 -103.953425) (xy 65.790873 -103.967531) (xy 65.735436 -103.973631)
			(xy 65.679702 -103.971594) (xy 65.624859 -103.961464) (xy 65.572075 -103.943457) (xy 65.522475 -103.917956)
			(xy 65.477117 -103.885505) (xy 65.436968 -103.846796) (xy 65.402882 -103.802653) (xy 65.375586 -103.754018)
			(xy 65.355663 -103.701927) (xy 65.343537 -103.64749) (xy 65.339466 -103.591868) (xy 49.142918 -103.591868)
			(xy 49.157019 -103.613182) (xy 49.180691 -103.663679) (xy 49.196759 -103.717086) (xy 49.204879 -103.772262)
			(xy 49.205388 -103.800148) (xy 49.204879 -103.828034) (xy 49.196759 -103.88321) (xy 49.180691 -103.936617)
			(xy 49.157019 -103.987114) (xy 49.126246 -104.033627) (xy 49.126066 -104.033828) (xy 93.648782 -104.033828)
			(xy 93.652853 -103.978206) (xy 93.664979 -103.923769) (xy 93.684902 -103.871678) (xy 93.712198 -103.823043)
			(xy 93.746284 -103.7789) (xy 93.786433 -103.740191) (xy 93.831791 -103.70774) (xy 93.881391 -103.682239)
			(xy 93.934175 -103.664232) (xy 93.989018 -103.654102) (xy 94.044752 -103.652065) (xy 94.100189 -103.658165)
			(xy 94.154146 -103.672271) (xy 94.205475 -103.694083) (xy 94.253081 -103.723137) (xy 94.295949 -103.758812)
			(xy 94.333166 -103.800349) (xy 94.363939 -103.846862) (xy 94.387611 -103.897359) (xy 94.403679 -103.950766)
			(xy 94.411799 -104.005942) (xy 94.412308 -104.033828) (xy 94.411799 -104.061714) (xy 94.403679 -104.11689)
			(xy 94.387611 -104.170297) (xy 94.363939 -104.220794) (xy 94.333166 -104.267307) (xy 94.295949 -104.308844)
			(xy 94.253081 -104.344519) (xy 94.205475 -104.373573) (xy 94.154146 -104.395385) (xy 94.100189 -104.409491)
			(xy 94.044752 -104.415591) (xy 93.989018 -104.413554) (xy 93.934175 -104.403424) (xy 93.881391 -104.385417)
			(xy 93.831791 -104.359916) (xy 93.786433 -104.327465) (xy 93.746284 -104.288756) (xy 93.712198 -104.244613)
			(xy 93.684902 -104.195978) (xy 93.664979 -104.143887) (xy 93.652853 -104.08945) (xy 93.648782 -104.033828)
			(xy 49.126066 -104.033828) (xy 49.089029 -104.075164) (xy 49.046161 -104.110839) (xy 48.998555 -104.139893)
			(xy 48.947226 -104.161705) (xy 48.893269 -104.175811) (xy 48.837832 -104.181911) (xy 48.782098 -104.179874)
			(xy 48.727255 -104.169744) (xy 48.674471 -104.151737) (xy 48.624871 -104.126236) (xy 48.579513 -104.093785)
			(xy 48.539364 -104.055076) (xy 48.505278 -104.010933) (xy 48.477982 -103.962298) (xy 48.458059 -103.910207)
			(xy 48.445933 -103.85577) (xy 48.441862 -103.800148) (xy 41.968036 -103.800148) (xy 41.987411 -103.841479)
			(xy 42.003479 -103.894886) (xy 42.011599 -103.950062) (xy 42.012108 -103.977948) (xy 42.011599 -104.005834)
			(xy 42.003479 -104.06101) (xy 41.987411 -104.114417) (xy 41.963739 -104.164914) (xy 41.932966 -104.211427)
			(xy 41.895749 -104.252964) (xy 41.852881 -104.288639) (xy 41.805275 -104.317693) (xy 41.753946 -104.339505)
			(xy 41.699989 -104.353611) (xy 41.644552 -104.359711) (xy 41.588818 -104.357674) (xy 41.533975 -104.347544)
			(xy 41.481191 -104.329537) (xy 41.431591 -104.304036) (xy 41.386233 -104.271585) (xy 41.346084 -104.232876)
			(xy 41.311998 -104.188733) (xy 41.284702 -104.140098) (xy 41.264779 -104.088007) (xy 41.252653 -104.03357)
			(xy 41.248582 -103.977948) (xy 16.298998 -103.977948) (xy 16.317493 -104.018444) (xy 16.332848 -104.070739)
			(xy 16.340604 -104.124687) (xy 16.34109 -104.151938) (xy 16.340599 -104.180299) (xy 16.332201 -104.236395)
			(xy 16.315582 -104.290628) (xy 16.291109 -104.341798) (xy 16.259322 -104.388776) (xy 16.240506 -104.410002)
			(xy 16.2308 -104.421424) (xy 16.2178 -104.448413) (xy 16.213182 -104.478011) (xy 16.217343 -104.507677)
			(xy 16.229924 -104.534862) (xy 16.23949 -104.5464) (xy 16.257607 -104.567496) (xy 16.288197 -104.613932)
			(xy 16.311725 -104.664315) (xy 16.327324 -104.716347) (xy 48.442926 -104.716347) (xy 48.442926 -104.661853)
			(xy 48.450681 -104.607914) (xy 48.466033 -104.555627) (xy 48.48867 -104.506058) (xy 48.518131 -104.460214)
			(xy 48.553816 -104.41903) (xy 48.594998 -104.383343) (xy 48.64084 -104.35388) (xy 48.690409 -104.33124)
			(xy 48.742694 -104.315885) (xy 48.796633 -104.308128) (xy 48.82388 -104.30764) (xy 48.8494 -104.308053)
			(xy 48.899987 -104.314846) (xy 48.949216 -104.328325) (xy 48.996207 -104.34825) (xy 49.04012 -104.374266)
			(xy 49.08017 -104.405906) (xy 49.0982 -104.423972) (xy 49.108488 -104.43384) (xy 49.133175 -104.448059)
			(xy 49.160833 -104.45489) (xy 49.189302 -104.453798) (xy 49.216356 -104.444869) (xy 49.239881 -104.428801)
			(xy 49.24933 -104.41813) (xy 49.267556 -104.396993) (xy 49.309093 -104.359717) (xy 49.355619 -104.328893)
			(xy 49.406141 -104.305179) (xy 49.45958 -104.289083) (xy 49.514795 -104.280948) (xy 49.5427 -104.280462)
			(xy 49.569949 -104.281008) (xy 49.623893 -104.288764) (xy 49.676183 -104.304118) (xy 49.725756 -104.326757)
			(xy 49.771603 -104.356221) (xy 49.81279 -104.39191) (xy 49.848479 -104.433097) (xy 49.877943 -104.478944)
			(xy 49.900582 -104.528517) (xy 49.915936 -104.580807) (xy 49.923692 -104.634751) (xy 49.923692 -104.689249)
			(xy 49.915936 -104.743193) (xy 49.900582 -104.795483) (xy 49.877943 -104.845056) (xy 49.848479 -104.890903)
			(xy 49.81279 -104.93209) (xy 49.771603 -104.967779) (xy 49.725756 -104.997243) (xy 49.676183 -105.019882)
			(xy 49.623893 -105.035236) (xy 49.569949 -105.042992) (xy 49.5427 -105.043478) (xy 49.517179 -105.043072)
			(xy 49.466592 -105.036278) (xy 49.417364 -105.022796) (xy 49.370373 -105.00287) (xy 49.32646 -104.976853)
			(xy 49.28641 -104.945212) (xy 49.26838 -104.927146) (xy 49.258112 -104.917255) (xy 49.23342 -104.903034)
			(xy 49.205755 -104.896205) (xy 49.177282 -104.897301) (xy 49.150224 -104.906236) (xy 49.126698 -104.922313)
			(xy 49.11725 -104.932988) (xy 49.099038 -104.954138) (xy 49.057498 -104.991413) (xy 49.010969 -105.022235)
			(xy 48.960444 -105.045946) (xy 48.907002 -105.062039) (xy 48.851786 -105.070171) (xy 48.82388 -105.070656)
			(xy 48.796633 -105.070072) (xy 48.742694 -105.062315) (xy 48.690409 -105.04696) (xy 48.64084 -105.02432)
			(xy 48.594998 -104.994857) (xy 48.553816 -104.95917) (xy 48.518131 -104.917986) (xy 48.48867 -104.872142)
			(xy 48.466033 -104.822573) (xy 48.450681 -104.770286) (xy 48.442926 -104.716347) (xy 16.327324 -104.716347)
			(xy 16.327693 -104.717579) (xy 16.335762 -104.772597) (xy 16.336264 -104.8004) (xy 16.336264 -105.501948)
			(xy 41.273982 -105.501948) (xy 41.278053 -105.446326) (xy 41.290179 -105.391889) (xy 41.310102 -105.339798)
			(xy 41.337398 -105.291163) (xy 41.371484 -105.24702) (xy 41.411633 -105.208311) (xy 41.456991 -105.17586)
			(xy 41.506591 -105.150359) (xy 41.559375 -105.132352) (xy 41.614218 -105.122222) (xy 41.669952 -105.120185)
			(xy 41.725389 -105.126285) (xy 41.779346 -105.140391) (xy 41.830675 -105.162203) (xy 41.878281 -105.191257)
			(xy 41.921149 -105.226932) (xy 41.958366 -105.268469) (xy 41.989139 -105.314982) (xy 42.012811 -105.365479)
			(xy 42.028879 -105.418886) (xy 42.036999 -105.474062) (xy 42.037508 -105.501948) (xy 42.036999 -105.529834)
			(xy 42.028879 -105.58501) (xy 42.012811 -105.638417) (xy 41.989139 -105.688914) (xy 41.958366 -105.735427)
			(xy 41.921149 -105.776964) (xy 41.878281 -105.812639) (xy 41.830675 -105.841693) (xy 41.779346 -105.863505)
			(xy 41.725389 -105.877611) (xy 41.669952 -105.883711) (xy 41.614218 -105.881674) (xy 41.559375 -105.871544)
			(xy 41.506591 -105.853537) (xy 41.456991 -105.828036) (xy 41.411633 -105.795585) (xy 41.371484 -105.756876)
			(xy 41.337398 -105.712733) (xy 41.310102 -105.664098) (xy 41.290179 -105.612007) (xy 41.278053 -105.55757)
			(xy 41.273982 -105.501948) (xy 16.336264 -105.501948) (xy 16.336264 -105.664) (xy 16.335652 -105.694375)
			(xy 16.326026 -105.754356) (xy 16.307017 -105.812055) (xy 16.279105 -105.866012) (xy 16.242995 -105.914865)
			(xy 16.22171 -105.936542) (xy 16.214831 -105.943923) (xy 16.207056 -105.962526) (xy 16.207057 -105.97007)
			(xy 43.43476 -105.97007) (xy 43.438831 -105.914448) (xy 43.450957 -105.860011) (xy 43.47088 -105.80792)
			(xy 43.498176 -105.759285) (xy 43.532262 -105.715142) (xy 43.572411 -105.676433) (xy 43.617769 -105.643982)
			(xy 43.667369 -105.618481) (xy 43.720153 -105.600474) (xy 43.774996 -105.590344) (xy 43.83073 -105.588307)
			(xy 43.886167 -105.594407) (xy 43.940124 -105.608513) (xy 43.988213 -105.628948) (xy 63.752982 -105.628948)
			(xy 63.757053 -105.573326) (xy 63.769179 -105.518889) (xy 63.789102 -105.466798) (xy 63.816398 -105.418163)
			(xy 63.850484 -105.37402) (xy 63.890633 -105.335311) (xy 63.935991 -105.30286) (xy 63.985591 -105.277359)
			(xy 64.038375 -105.259352) (xy 64.093218 -105.249222) (xy 64.148952 -105.247185) (xy 64.204389 -105.253285)
			(xy 64.258346 -105.267391) (xy 64.309675 -105.289203) (xy 64.357281 -105.318257) (xy 64.400149 -105.353932)
			(xy 64.437366 -105.395469) (xy 64.468139 -105.441982) (xy 64.491811 -105.492479) (xy 64.507879 -105.545886)
			(xy 64.515999 -105.601062) (xy 64.516508 -105.628948) (xy 64.51635 -105.637584) (xy 65.006218 -105.637584)
			(xy 65.010289 -105.581962) (xy 65.022415 -105.527525) (xy 65.042338 -105.475434) (xy 65.069634 -105.426799)
			(xy 65.10372 -105.382656) (xy 65.143869 -105.343947) (xy 65.189227 -105.311496) (xy 65.238827 -105.285995)
			(xy 65.291611 -105.267988) (xy 65.346454 -105.257858) (xy 65.402188 -105.255821) (xy 65.457625 -105.261921)
			(xy 65.511582 -105.276027) (xy 65.562911 -105.297839) (xy 65.610517 -105.326893) (xy 65.653385 -105.362568)
			(xy 65.690602 -105.404105) (xy 65.721375 -105.450618) (xy 65.745047 -105.501115) (xy 65.761115 -105.554522)
			(xy 65.769235 -105.609698) (xy 65.769744 -105.637584) (xy 65.769235 -105.66547) (xy 65.761115 -105.720646)
			(xy 65.745047 -105.774053) (xy 65.721375 -105.82455) (xy 65.690602 -105.871063) (xy 65.653385 -105.9126)
			(xy 65.610517 -105.948275) (xy 65.562911 -105.977329) (xy 65.511582 -105.999141) (xy 65.457625 -106.013247)
			(xy 65.402188 -106.019347) (xy 65.346454 -106.01731) (xy 65.291611 -106.00718) (xy 65.238827 -105.989173)
			(xy 65.189227 -105.963672) (xy 65.143869 -105.931221) (xy 65.10372 -105.892512) (xy 65.069634 -105.848369)
			(xy 65.042338 -105.799734) (xy 65.022415 -105.747643) (xy 65.010289 -105.693206) (xy 65.006218 -105.637584)
			(xy 64.51635 -105.637584) (xy 64.515999 -105.656834) (xy 64.507879 -105.71201) (xy 64.491811 -105.765417)
			(xy 64.468139 -105.815914) (xy 64.437366 -105.862427) (xy 64.400149 -105.903964) (xy 64.357281 -105.939639)
			(xy 64.309675 -105.968693) (xy 64.258346 -105.990505) (xy 64.204389 -106.004611) (xy 64.148952 -106.010711)
			(xy 64.093218 -106.008674) (xy 64.038375 -105.998544) (xy 63.985591 -105.980537) (xy 63.935991 -105.955036)
			(xy 63.890633 -105.922585) (xy 63.850484 -105.883876) (xy 63.816398 -105.839733) (xy 63.789102 -105.791098)
			(xy 63.769179 -105.739007) (xy 63.757053 -105.68457) (xy 63.752982 -105.628948) (xy 43.988213 -105.628948)
			(xy 43.991453 -105.630325) (xy 44.039059 -105.659379) (xy 44.081927 -105.695054) (xy 44.119144 -105.736591)
			(xy 44.149917 -105.783104) (xy 44.173589 -105.833601) (xy 44.189657 -105.887008) (xy 44.197777 -105.942184)
			(xy 44.198286 -105.97007) (xy 44.197777 -105.997956) (xy 44.192162 -106.03611) (xy 49.160682 -106.03611)
			(xy 49.164753 -105.980488) (xy 49.176879 -105.926051) (xy 49.196802 -105.87396) (xy 49.224098 -105.825325)
			(xy 49.258184 -105.781182) (xy 49.298333 -105.742473) (xy 49.343691 -105.710022) (xy 49.393291 -105.684521)
			(xy 49.446075 -105.666514) (xy 49.500918 -105.656384) (xy 49.556652 -105.654347) (xy 49.612089 -105.660447)
			(xy 49.666046 -105.674553) (xy 49.717375 -105.696365) (xy 49.764981 -105.725419) (xy 49.807849 -105.761094)
			(xy 49.845066 -105.802631) (xy 49.875839 -105.849144) (xy 49.899511 -105.899641) (xy 49.915579 -105.953048)
			(xy 49.923699 -106.008224) (xy 49.924208 -106.03611) (xy 49.923699 -106.063996) (xy 49.915579 -106.119172)
			(xy 49.899511 -106.172579) (xy 49.875839 -106.223076) (xy 49.845066 -106.269589) (xy 49.807849 -106.311126)
			(xy 49.764981 -106.346801) (xy 49.717375 -106.375855) (xy 49.666046 -106.397667) (xy 49.612089 -106.411773)
			(xy 49.556652 -106.417873) (xy 49.500918 -106.415836) (xy 49.446075 -106.405706) (xy 49.393291 -106.387699)
			(xy 49.343691 -106.362198) (xy 49.298333 -106.329747) (xy 49.258184 -106.291038) (xy 49.224098 -106.246895)
			(xy 49.196802 -106.19826) (xy 49.176879 -106.146169) (xy 49.164753 -106.091732) (xy 49.160682 -106.03611)
			(xy 44.192162 -106.03611) (xy 44.189657 -106.053132) (xy 44.173589 -106.106539) (xy 44.149917 -106.157036)
			(xy 44.119144 -106.203549) (xy 44.081927 -106.245086) (xy 44.039059 -106.280761) (xy 43.991453 -106.309815)
			(xy 43.940124 -106.331627) (xy 43.886167 -106.345733) (xy 43.83073 -106.351833) (xy 43.774996 -106.349796)
			(xy 43.720153 -106.339666) (xy 43.667369 -106.321659) (xy 43.617769 -106.296158) (xy 43.572411 -106.263707)
			(xy 43.532262 -106.224998) (xy 43.498176 -106.180855) (xy 43.47088 -106.13222) (xy 43.450957 -106.080129)
			(xy 43.438831 -106.025692) (xy 43.43476 -105.97007) (xy 16.207057 -105.97007) (xy 16.207059 -105.982688)
			(xy 16.214839 -106.001288) (xy 16.22171 -106.008678) (xy 16.242736 -106.030344) (xy 16.27841 -106.079045)
			(xy 16.305965 -106.132759) (xy 16.324713 -106.190143) (xy 16.334186 -106.249765) (xy 16.33474 -106.27995)
			(xy 16.334254 -106.307201) (xy 16.326498 -106.361149) (xy 16.311143 -106.413444) (xy 16.288501 -106.463021)
			(xy 16.259035 -106.508871) (xy 16.223344 -106.550062) (xy 16.182153 -106.585753) (xy 16.136303 -106.615219)
			(xy 16.086726 -106.637861) (xy 16.034431 -106.653216) (xy 15.980483 -106.660972) (xy 15.925981 -106.660972)
			(xy 15.872033 -106.653216) (xy 15.819738 -106.637861) (xy 15.770161 -106.615219) (xy 15.724311 -106.585753)
			(xy 15.68312 -106.550062) (xy 15.647429 -106.508871) (xy 15.617963 -106.463021) (xy 15.595321 -106.413444)
			(xy 15.579966 -106.361149) (xy 15.57221 -106.307201) (xy 15.571724 -106.27995) (xy 12.476988 -106.27995)
			(xy 12.476988 -106.40187) (xy 12.47647 -106.429445) (xy 12.468463 -106.484013) (xy 12.452698 -106.536864)
			(xy 12.429502 -106.586901) (xy 12.399356 -106.633086) (xy 12.381484 -106.654092) (xy 12.375659 -106.661248)
			(xy 12.369179 -106.678514) (xy 12.369191 -106.696956) (xy 12.375695 -106.714214) (xy 12.381484 -106.721402)
			(xy 12.39935 -106.742371) (xy 12.429435 -106.788519) (xy 12.452572 -106.838513) (xy 12.46828 -106.891315)
			(xy 12.476234 -106.945826) (xy 12.476734 -106.97337) (xy 12.476248 -107.000621) (xy 12.468492 -107.054569)
			(xy 12.453137 -107.106864) (xy 12.445547 -107.123484) (xy 13.289532 -107.123484) (xy 13.293603 -107.067862)
			(xy 13.305729 -107.013425) (xy 13.325652 -106.961334) (xy 13.352948 -106.912699) (xy 13.387034 -106.868556)
			(xy 13.427183 -106.829847) (xy 13.472541 -106.797396) (xy 13.522141 -106.771895) (xy 13.574925 -106.753888)
			(xy 13.629768 -106.743758) (xy 13.685502 -106.741721) (xy 13.740939 -106.747821) (xy 13.794896 -106.761927)
			(xy 13.846225 -106.783739) (xy 13.893831 -106.812793) (xy 13.936699 -106.848468) (xy 13.973916 -106.890005)
			(xy 14.004689 -106.936518) (xy 14.028361 -106.987015) (xy 14.044429 -107.040422) (xy 14.052549 -107.095598)
			(xy 14.053058 -107.123484) (xy 17.84807 -107.123484) (xy 17.852141 -107.067862) (xy 17.864267 -107.013425)
			(xy 17.88419 -106.961334) (xy 17.911486 -106.912699) (xy 17.945572 -106.868556) (xy 17.985721 -106.829847)
			(xy 18.031079 -106.797396) (xy 18.080679 -106.771895) (xy 18.133463 -106.753888) (xy 18.188306 -106.743758)
			(xy 18.24404 -106.741721) (xy 18.299477 -106.747821) (xy 18.349988 -106.761026) (xy 21.417786 -106.761026)
			(xy 21.421857 -106.705404) (xy 21.433983 -106.650967) (xy 21.453906 -106.598876) (xy 21.481202 -106.550241)
			(xy 21.515288 -106.506098) (xy 21.555437 -106.467389) (xy 21.600795 -106.434938) (xy 21.650395 -106.409437)
			(xy 21.703179 -106.39143) (xy 21.758022 -106.3813) (xy 21.813756 -106.379263) (xy 21.869193 -106.385363)
			(xy 21.92315 -106.399469) (xy 21.974479 -106.421281) (xy 22.022085 -106.450335) (xy 22.064953 -106.48601)
			(xy 22.10217 -106.527547) (xy 22.132943 -106.57406) (xy 22.156615 -106.624557) (xy 22.172683 -106.677964)
			(xy 22.1753 -106.695748) (xy 33.270442 -106.695748) (xy 33.274513 -106.640126) (xy 33.286639 -106.585689)
			(xy 33.306562 -106.533598) (xy 33.333858 -106.484963) (xy 33.367944 -106.44082) (xy 33.408093 -106.402111)
			(xy 33.453451 -106.36966) (xy 33.503051 -106.344159) (xy 33.555835 -106.326152) (xy 33.610678 -106.316022)
			(xy 33.666412 -106.313985) (xy 33.721849 -106.320085) (xy 33.775806 -106.334191) (xy 33.827135 -106.356003)
			(xy 33.874741 -106.385057) (xy 33.917609 -106.420732) (xy 33.954826 -106.462269) (xy 33.985599 -106.508782)
			(xy 33.992396 -106.523282) (xy 37.558216 -106.523282) (xy 37.562287 -106.46766) (xy 37.574413 -106.413223)
			(xy 37.594336 -106.361132) (xy 37.621632 -106.312497) (xy 37.655718 -106.268354) (xy 37.695867 -106.229645)
			(xy 37.741225 -106.197194) (xy 37.790825 -106.171693) (xy 37.843609 -106.153686) (xy 37.898452 -106.143556)
			(xy 37.954186 -106.141519) (xy 38.009623 -106.147619) (xy 38.06358 -106.161725) (xy 38.114909 -106.183537)
			(xy 38.162515 -106.212591) (xy 38.205383 -106.248266) (xy 38.2426 -106.289803) (xy 38.273373 -106.336316)
			(xy 38.297045 -106.386813) (xy 38.313113 -106.44022) (xy 38.321233 -106.495396) (xy 38.321742 -106.523282)
			(xy 38.321233 -106.551168) (xy 38.313113 -106.606344) (xy 38.297045 -106.659751) (xy 38.273373 -106.710248)
			(xy 38.2426 -106.756761) (xy 38.228993 -106.771948) (xy 41.273982 -106.771948) (xy 41.278053 -106.716326)
			(xy 41.290179 -106.661889) (xy 41.310102 -106.609798) (xy 41.337398 -106.561163) (xy 41.371484 -106.51702)
			(xy 41.411633 -106.478311) (xy 41.456991 -106.44586) (xy 41.506591 -106.420359) (xy 41.559375 -106.402352)
			(xy 41.614218 -106.392222) (xy 41.669952 -106.390185) (xy 41.725389 -106.396285) (xy 41.779346 -106.410391)
			(xy 41.830675 -106.432203) (xy 41.878281 -106.461257) (xy 41.921149 -106.496932) (xy 41.958366 -106.538469)
			(xy 41.989139 -106.584982) (xy 42.012811 -106.635479) (xy 42.028879 -106.688886) (xy 42.036999 -106.744062)
			(xy 42.037508 -106.771948) (xy 42.036999 -106.799834) (xy 42.028879 -106.85501) (xy 42.012811 -106.908417)
			(xy 41.989139 -106.958914) (xy 41.958366 -107.005427) (xy 41.9352 -107.031282) (xy 44.797216 -107.031282)
			(xy 44.801287 -106.97566) (xy 44.813413 -106.921223) (xy 44.833336 -106.869132) (xy 44.860632 -106.820497)
			(xy 44.894718 -106.776354) (xy 44.934867 -106.737645) (xy 44.980225 -106.705194) (xy 45.029825 -106.679693)
			(xy 45.082609 -106.661686) (xy 45.137452 -106.651556) (xy 45.193186 -106.649519) (xy 45.248623 -106.655619)
			(xy 45.30258 -106.669725) (xy 45.353909 -106.691537) (xy 45.401515 -106.720591) (xy 45.444383 -106.756266)
			(xy 45.469813 -106.784648) (xy 57.669682 -106.784648) (xy 57.673753 -106.729026) (xy 57.685879 -106.674589)
			(xy 57.705802 -106.622498) (xy 57.733098 -106.573863) (xy 57.767184 -106.52972) (xy 57.807333 -106.491011)
			(xy 57.852691 -106.45856) (xy 57.902291 -106.433059) (xy 57.955075 -106.415052) (xy 58.009918 -106.404922)
			(xy 58.065652 -106.402885) (xy 58.121089 -106.408985) (xy 58.175046 -106.423091) (xy 58.226375 -106.444903)
			(xy 58.273981 -106.473957) (xy 58.316849 -106.509632) (xy 58.354066 -106.551169) (xy 58.384839 -106.597682)
			(xy 58.408511 -106.648179) (xy 58.424579 -106.701586) (xy 58.432699 -106.756762) (xy 58.433208 -106.784648)
			(xy 58.432699 -106.812534) (xy 58.424579 -106.86771) (xy 58.408511 -106.921117) (xy 58.384839 -106.971614)
			(xy 58.354066 -107.018127) (xy 58.316849 -107.059664) (xy 58.273981 -107.095339) (xy 58.226375 -107.124393)
			(xy 58.175046 -107.146205) (xy 58.121089 -107.160311) (xy 58.065652 -107.166411) (xy 58.009918 -107.164374)
			(xy 57.955075 -107.154244) (xy 57.902291 -107.136237) (xy 57.852691 -107.110736) (xy 57.807333 -107.078285)
			(xy 57.767184 -107.039576) (xy 57.733098 -106.995433) (xy 57.705802 -106.946798) (xy 57.685879 -106.894707)
			(xy 57.673753 -106.84027) (xy 57.669682 -106.784648) (xy 45.469813 -106.784648) (xy 45.4816 -106.797803)
			(xy 45.512373 -106.844316) (xy 45.536045 -106.894813) (xy 45.552113 -106.94822) (xy 45.560233 -107.003396)
			(xy 45.560742 -107.031282) (xy 45.560233 -107.059168) (xy 45.552113 -107.114344) (xy 45.536045 -107.167751)
			(xy 45.512373 -107.218248) (xy 45.4816 -107.264761) (xy 45.444383 -107.306298) (xy 45.401515 -107.341973)
			(xy 45.353909 -107.371027) (xy 45.30258 -107.392839) (xy 45.248623 -107.406945) (xy 45.202429 -107.412028)
			(xy 50.199288 -107.412028) (xy 50.203359 -107.356406) (xy 50.215485 -107.301969) (xy 50.235408 -107.249878)
			(xy 50.262704 -107.201243) (xy 50.29679 -107.1571) (xy 50.336939 -107.118391) (xy 50.382297 -107.08594)
			(xy 50.431897 -107.060439) (xy 50.484681 -107.042432) (xy 50.539524 -107.032302) (xy 50.595258 -107.030265)
			(xy 50.650695 -107.036365) (xy 50.704652 -107.050471) (xy 50.755981 -107.072283) (xy 50.803587 -107.101337)
			(xy 50.846455 -107.137012) (xy 50.883672 -107.178549) (xy 50.914445 -107.225062) (xy 50.938117 -107.275559)
			(xy 50.954185 -107.328966) (xy 50.962305 -107.384142) (xy 50.962814 -107.412028) (xy 50.962305 -107.439914)
			(xy 50.954185 -107.49509) (xy 50.951664 -107.503468) (xy 51.611528 -107.503468) (xy 51.615599 -107.447846)
			(xy 51.627725 -107.393409) (xy 51.647648 -107.341318) (xy 51.674944 -107.292683) (xy 51.70903 -107.24854)
			(xy 51.749179 -107.209831) (xy 51.794537 -107.17738) (xy 51.844137 -107.151879) (xy 51.896921 -107.133872)
			(xy 51.951764 -107.123742) (xy 52.007498 -107.121705) (xy 52.062935 -107.127805) (xy 52.116892 -107.141911)
			(xy 52.168221 -107.163723) (xy 52.215827 -107.192777) (xy 52.258695 -107.228452) (xy 52.295912 -107.269989)
			(xy 52.326685 -107.316502) (xy 52.350357 -107.366999) (xy 52.366425 -107.420406) (xy 52.368743 -107.436158)
			(xy 56.591452 -107.436158) (xy 56.595523 -107.380536) (xy 56.607649 -107.326099) (xy 56.627572 -107.274008)
			(xy 56.654868 -107.225373) (xy 56.688954 -107.18123) (xy 56.729103 -107.142521) (xy 56.774461 -107.11007)
			(xy 56.824061 -107.084569) (xy 56.876845 -107.066562) (xy 56.931688 -107.056432) (xy 56.987422 -107.054395)
			(xy 57.042859 -107.060495) (xy 57.096816 -107.074601) (xy 57.148145 -107.096413) (xy 57.195751 -107.125467)
			(xy 57.238619 -107.161142) (xy 57.275836 -107.202679) (xy 57.306609 -107.249192) (xy 57.330281 -107.299689)
			(xy 57.346349 -107.353096) (xy 57.354469 -107.408272) (xy 57.354978 -107.436158) (xy 57.354469 -107.464044)
			(xy 57.346349 -107.51922) (xy 57.330281 -107.572627) (xy 57.306609 -107.623124) (xy 57.275836 -107.669637)
			(xy 57.238619 -107.711174) (xy 57.195751 -107.746849) (xy 57.155899 -107.771171) (xy 65.863915 -107.771171)
			(xy 65.871669 -107.717214) (xy 65.887023 -107.664909) (xy 65.909665 -107.615322) (xy 65.939133 -107.569462)
			(xy 65.974828 -107.528263) (xy 66.016023 -107.492563) (xy 66.061879 -107.463088) (xy 66.111463 -107.44044)
			(xy 66.163766 -107.42508) (xy 66.217722 -107.417319) (xy 66.244978 -107.416854) (xy 66.271492 -107.417314)
			(xy 66.324005 -107.424697) (xy 66.374989 -107.439283) (xy 66.39941 -107.44962) (xy 66.412487 -107.454911)
			(xy 66.440409 -107.458855) (xy 66.468344 -107.455015) (xy 66.494166 -107.443684) (xy 66.515907 -107.425726)
			(xy 66.531909 -107.402508) (xy 66.540954 -107.375799) (xy 66.542352 -107.347635) (xy 66.539618 -107.333796)
			(xy 66.534989 -107.312571) (xy 66.53003 -107.269412) (xy 66.529712 -107.24769) (xy 66.530189 -107.22044)
			(xy 66.537946 -107.166495) (xy 66.553302 -107.114203) (xy 66.575943 -107.064628) (xy 66.605409 -107.01878)
			(xy 66.641099 -106.977592) (xy 66.682288 -106.941903) (xy 66.728137 -106.912438) (xy 66.777712 -106.889798)
			(xy 66.830005 -106.874444) (xy 66.88395 -106.866688) (xy 66.93845 -106.866688) (xy 66.992395 -106.874444)
			(xy 67.044688 -106.889798) (xy 67.094263 -106.912438) (xy 67.140112 -106.941903) (xy 67.181301 -106.977592)
			(xy 67.216991 -107.01878) (xy 67.246457 -107.064628) (xy 67.269098 -107.114203) (xy 67.284454 -107.166495)
			(xy 67.292211 -107.22044) (xy 67.292212 -107.27494) (xy 67.284458 -107.328886) (xy 67.269105 -107.381179)
			(xy 67.246467 -107.430754) (xy 67.217003 -107.476604) (xy 67.181315 -107.517794) (xy 67.140128 -107.553485)
			(xy 67.094281 -107.582952) (xy 67.044707 -107.605595) (xy 66.992415 -107.620951) (xy 66.93847 -107.62871)
			(xy 66.91122 -107.629198) (xy 66.884706 -107.628735) (xy 66.832193 -107.621352) (xy 66.781209 -107.606768)
			(xy 66.756788 -107.596432) (xy 66.743694 -107.591193) (xy 66.715783 -107.587254) (xy 66.687858 -107.591093)
			(xy 66.662046 -107.602419) (xy 66.640312 -107.620367) (xy 66.624311 -107.643573) (xy 66.615261 -107.670269)
			(xy 66.613853 -107.698421) (xy 66.61658 -107.712256) (xy 66.621201 -107.733483) (xy 66.626165 -107.776641)
			(xy 66.626486 -107.798362) (xy 66.626086 -107.825618) (xy 66.618333 -107.879575) (xy 66.602981 -107.931881)
			(xy 66.58034 -107.981468) (xy 66.550873 -108.027329) (xy 66.51518 -108.06853) (xy 66.473986 -108.104231)
			(xy 66.42813 -108.133706) (xy 66.378547 -108.156356) (xy 66.326245 -108.171718) (xy 66.272288 -108.179481)
			(xy 66.217777 -108.179485) (xy 66.163819 -108.171732) (xy 66.111514 -108.156379) (xy 66.061927 -108.133738)
			(xy 66.016067 -108.10427) (xy 65.974867 -108.068576) (xy 65.939166 -108.027382) (xy 65.909691 -107.981526)
			(xy 65.887042 -107.931942) (xy 65.871681 -107.879639) (xy 65.863919 -107.825683) (xy 65.863915 -107.771171)
			(xy 57.155899 -107.771171) (xy 57.148145 -107.775903) (xy 57.096816 -107.797715) (xy 57.042859 -107.811821)
			(xy 56.987422 -107.817921) (xy 56.931688 -107.815884) (xy 56.876845 -107.805754) (xy 56.824061 -107.787747)
			(xy 56.774461 -107.762246) (xy 56.729103 -107.729795) (xy 56.688954 -107.691086) (xy 56.654868 -107.646943)
			(xy 56.627572 -107.598308) (xy 56.607649 -107.546217) (xy 56.595523 -107.49178) (xy 56.591452 -107.436158)
			(xy 52.368743 -107.436158) (xy 52.374545 -107.475582) (xy 52.375054 -107.503468) (xy 52.374545 -107.531354)
			(xy 52.366425 -107.58653) (xy 52.350357 -107.639937) (xy 52.326685 -107.690434) (xy 52.295912 -107.736947)
			(xy 52.258695 -107.778484) (xy 52.215827 -107.814159) (xy 52.168221 -107.843213) (xy 52.116892 -107.865025)
			(xy 52.062935 -107.879131) (xy 52.007498 -107.885231) (xy 51.951764 -107.883194) (xy 51.896921 -107.873064)
			(xy 51.844137 -107.855057) (xy 51.794537 -107.829556) (xy 51.749179 -107.797105) (xy 51.70903 -107.758396)
			(xy 51.674944 -107.714253) (xy 51.647648 -107.665618) (xy 51.627725 -107.613527) (xy 51.615599 -107.55909)
			(xy 51.611528 -107.503468) (xy 50.951664 -107.503468) (xy 50.938117 -107.548497) (xy 50.914445 -107.598994)
			(xy 50.883672 -107.645507) (xy 50.846455 -107.687044) (xy 50.803587 -107.722719) (xy 50.755981 -107.751773)
			(xy 50.704652 -107.773585) (xy 50.650695 -107.787691) (xy 50.595258 -107.793791) (xy 50.539524 -107.791754)
			(xy 50.484681 -107.781624) (xy 50.431897 -107.763617) (xy 50.382297 -107.738116) (xy 50.336939 -107.705665)
			(xy 50.29679 -107.666956) (xy 50.262704 -107.622813) (xy 50.235408 -107.574178) (xy 50.215485 -107.522087)
			(xy 50.203359 -107.46765) (xy 50.199288 -107.412028) (xy 45.202429 -107.412028) (xy 45.193186 -107.413045)
			(xy 45.137452 -107.411008) (xy 45.082609 -107.400878) (xy 45.029825 -107.382871) (xy 44.980225 -107.35737)
			(xy 44.934867 -107.324919) (xy 44.894718 -107.28621) (xy 44.860632 -107.242067) (xy 44.833336 -107.193432)
			(xy 44.813413 -107.141341) (xy 44.801287 -107.086904) (xy 44.797216 -107.031282) (xy 41.9352 -107.031282)
			(xy 41.921149 -107.046964) (xy 41.878281 -107.082639) (xy 41.830675 -107.111693) (xy 41.779346 -107.133505)
			(xy 41.725389 -107.147611) (xy 41.669952 -107.153711) (xy 41.614218 -107.151674) (xy 41.559375 -107.141544)
			(xy 41.506591 -107.123537) (xy 41.456991 -107.098036) (xy 41.411633 -107.065585) (xy 41.371484 -107.026876)
			(xy 41.337398 -106.982733) (xy 41.310102 -106.934098) (xy 41.290179 -106.882007) (xy 41.278053 -106.82757)
			(xy 41.273982 -106.771948) (xy 38.228993 -106.771948) (xy 38.205383 -106.798298) (xy 38.162515 -106.833973)
			(xy 38.114909 -106.863027) (xy 38.06358 -106.884839) (xy 38.009623 -106.898945) (xy 37.954186 -106.905045)
			(xy 37.898452 -106.903008) (xy 37.843609 -106.892878) (xy 37.790825 -106.874871) (xy 37.741225 -106.84937)
			(xy 37.695867 -106.816919) (xy 37.655718 -106.77821) (xy 37.621632 -106.734067) (xy 37.594336 -106.685432)
			(xy 37.574413 -106.633341) (xy 37.562287 -106.578904) (xy 37.558216 -106.523282) (xy 33.992396 -106.523282)
			(xy 34.009271 -106.559279) (xy 34.025339 -106.612686) (xy 34.033459 -106.667862) (xy 34.033968 -106.695748)
			(xy 34.033459 -106.723634) (xy 34.025339 -106.77881) (xy 34.009271 -106.832217) (xy 33.985599 -106.882714)
			(xy 33.954826 -106.929227) (xy 33.917609 -106.970764) (xy 33.874741 -107.006439) (xy 33.827135 -107.035493)
			(xy 33.775806 -107.057305) (xy 33.721849 -107.071411) (xy 33.666412 -107.077511) (xy 33.610678 -107.075474)
			(xy 33.555835 -107.065344) (xy 33.503051 -107.047337) (xy 33.453451 -107.021836) (xy 33.408093 -106.989385)
			(xy 33.367944 -106.950676) (xy 33.333858 -106.906533) (xy 33.306562 -106.857898) (xy 33.286639 -106.805807)
			(xy 33.274513 -106.75137) (xy 33.270442 -106.695748) (xy 22.1753 -106.695748) (xy 22.180803 -106.73314)
			(xy 22.181312 -106.761026) (xy 22.180803 -106.788912) (xy 22.172683 -106.844088) (xy 22.156615 -106.897495)
			(xy 22.132943 -106.947992) (xy 22.10217 -106.994505) (xy 22.064953 -107.036042) (xy 22.022085 -107.071717)
			(xy 21.974479 -107.100771) (xy 21.92315 -107.122583) (xy 21.869193 -107.136689) (xy 21.813756 -107.142789)
			(xy 21.758022 -107.140752) (xy 21.703179 -107.130622) (xy 21.650395 -107.112615) (xy 21.600795 -107.087114)
			(xy 21.555437 -107.054663) (xy 21.515288 -107.015954) (xy 21.481202 -106.971811) (xy 21.453906 -106.923176)
			(xy 21.433983 -106.871085) (xy 21.421857 -106.816648) (xy 21.417786 -106.761026) (xy 18.349988 -106.761026)
			(xy 18.353434 -106.761927) (xy 18.404763 -106.783739) (xy 18.452369 -106.812793) (xy 18.495237 -106.848468)
			(xy 18.532454 -106.890005) (xy 18.563227 -106.936518) (xy 18.586899 -106.987015) (xy 18.602967 -107.040422)
			(xy 18.611087 -107.095598) (xy 18.611596 -107.123484) (xy 18.611087 -107.15137) (xy 18.602967 -107.206546)
			(xy 18.586899 -107.259953) (xy 18.563227 -107.31045) (xy 18.532454 -107.356963) (xy 18.495237 -107.3985)
			(xy 18.452369 -107.434175) (xy 18.404763 -107.463229) (xy 18.353434 -107.485041) (xy 18.299477 -107.499147)
			(xy 18.24404 -107.505247) (xy 18.188306 -107.50321) (xy 18.133463 -107.49308) (xy 18.080679 -107.475073)
			(xy 18.031079 -107.449572) (xy 17.985721 -107.417121) (xy 17.945572 -107.378412) (xy 17.911486 -107.334269)
			(xy 17.88419 -107.285634) (xy 17.864267 -107.233543) (xy 17.852141 -107.179106) (xy 17.84807 -107.123484)
			(xy 14.053058 -107.123484) (xy 14.052549 -107.15137) (xy 14.044429 -107.206546) (xy 14.028361 -107.259953)
			(xy 14.004689 -107.31045) (xy 13.973916 -107.356963) (xy 13.936699 -107.3985) (xy 13.893831 -107.434175)
			(xy 13.846225 -107.463229) (xy 13.794896 -107.485041) (xy 13.740939 -107.499147) (xy 13.685502 -107.505247)
			(xy 13.629768 -107.50321) (xy 13.574925 -107.49308) (xy 13.522141 -107.475073) (xy 13.472541 -107.449572)
			(xy 13.427183 -107.417121) (xy 13.387034 -107.378412) (xy 13.352948 -107.334269) (xy 13.325652 -107.285634)
			(xy 13.305729 -107.233543) (xy 13.293603 -107.179106) (xy 13.289532 -107.123484) (xy 12.445547 -107.123484)
			(xy 12.430495 -107.156441) (xy 12.401029 -107.202291) (xy 12.365338 -107.243482) (xy 12.324147 -107.279173)
			(xy 12.278297 -107.308639) (xy 12.22872 -107.331281) (xy 12.176425 -107.346636) (xy 12.122477 -107.354392)
			(xy 12.067975 -107.354392) (xy 12.014027 -107.346636) (xy 11.961732 -107.331281) (xy 11.912155 -107.308639)
			(xy 11.866305 -107.279173) (xy 11.825114 -107.243482) (xy 11.789423 -107.202291) (xy 11.759957 -107.156441)
			(xy 11.737315 -107.106864) (xy 11.72196 -107.054569) (xy 11.714204 -107.000621) (xy 11.713718 -106.97337)
			(xy 11.714189 -106.945825) (xy 11.722147 -106.891314) (xy 11.737866 -106.838514) (xy 11.761016 -106.788525)
			(xy 11.791118 -106.742386) (xy 11.808968 -106.721402) (xy 11.814764 -106.714206) (xy 11.821346 -106.696963)
			(xy 11.821359 -106.678507) (xy 11.814801 -106.661254) (xy 11.808968 -106.654092) (xy 11.791079 -106.633096)
			(xy 11.760901 -106.586925) (xy 11.737693 -106.536888) (xy 11.721937 -106.484028) (xy 11.713964 -106.429449)
			(xy 11.713464 -106.40187) (xy 6.055868 -106.40187) (xy 6.055868 -107.777026) (xy 21.417786 -107.777026)
			(xy 21.421857 -107.721404) (xy 21.433983 -107.666967) (xy 21.453906 -107.614876) (xy 21.481202 -107.566241)
			(xy 21.515288 -107.522098) (xy 21.555437 -107.483389) (xy 21.600795 -107.450938) (xy 21.650395 -107.425437)
			(xy 21.703179 -107.40743) (xy 21.758022 -107.3973) (xy 21.813756 -107.395263) (xy 21.869193 -107.401363)
			(xy 21.92315 -107.415469) (xy 21.974479 -107.437281) (xy 22.022085 -107.466335) (xy 22.064953 -107.50201)
			(xy 22.098349 -107.539282) (xy 37.558216 -107.539282) (xy 37.562287 -107.48366) (xy 37.574413 -107.429223)
			(xy 37.594336 -107.377132) (xy 37.621632 -107.328497) (xy 37.655718 -107.284354) (xy 37.695867 -107.245645)
			(xy 37.741225 -107.213194) (xy 37.790825 -107.187693) (xy 37.843609 -107.169686) (xy 37.898452 -107.159556)
			(xy 37.954186 -107.157519) (xy 38.009623 -107.163619) (xy 38.06358 -107.177725) (xy 38.114909 -107.199537)
			(xy 38.162515 -107.228591) (xy 38.205383 -107.264266) (xy 38.2426 -107.305803) (xy 38.273373 -107.352316)
			(xy 38.297045 -107.402813) (xy 38.313113 -107.45622) (xy 38.321233 -107.511396) (xy 38.321742 -107.539282)
			(xy 38.321233 -107.567168) (xy 38.313113 -107.622344) (xy 38.297045 -107.675751) (xy 38.273373 -107.726248)
			(xy 38.2426 -107.772761) (xy 38.205383 -107.814298) (xy 38.162515 -107.849973) (xy 38.114909 -107.879027)
			(xy 38.06358 -107.900839) (xy 38.009623 -107.914945) (xy 37.954186 -107.921045) (xy 37.898452 -107.919008)
			(xy 37.843609 -107.908878) (xy 37.790825 -107.890871) (xy 37.741225 -107.86537) (xy 37.695867 -107.832919)
			(xy 37.655718 -107.79421) (xy 37.621632 -107.750067) (xy 37.594336 -107.701432) (xy 37.574413 -107.649341)
			(xy 37.562287 -107.594904) (xy 37.558216 -107.539282) (xy 22.098349 -107.539282) (xy 22.10217 -107.543547)
			(xy 22.132943 -107.59006) (xy 22.156615 -107.640557) (xy 22.172683 -107.693964) (xy 22.180803 -107.74914)
			(xy 22.181312 -107.777026) (xy 22.180803 -107.804912) (xy 22.172683 -107.860088) (xy 22.156615 -107.913495)
			(xy 22.132943 -107.963992) (xy 22.10217 -108.010505) (xy 22.069218 -108.047282) (xy 41.255186 -108.047282)
			(xy 41.259257 -107.99166) (xy 41.271383 -107.937223) (xy 41.291306 -107.885132) (xy 41.318602 -107.836497)
			(xy 41.352688 -107.792354) (xy 41.392837 -107.753645) (xy 41.438195 -107.721194) (xy 41.487795 -107.695693)
			(xy 41.540579 -107.677686) (xy 41.595422 -107.667556) (xy 41.651156 -107.665519) (xy 41.706593 -107.671619)
			(xy 41.76055 -107.685725) (xy 41.811879 -107.707537) (xy 41.859485 -107.736591) (xy 41.902353 -107.772266)
			(xy 41.93957 -107.813803) (xy 41.970343 -107.860316) (xy 41.994015 -107.910813) (xy 42.010083 -107.96422)
			(xy 42.018203 -108.019396) (xy 42.018712 -108.047282) (xy 44.797216 -108.047282) (xy 44.801287 -107.99166)
			(xy 44.813413 -107.937223) (xy 44.833336 -107.885132) (xy 44.860632 -107.836497) (xy 44.894718 -107.792354)
			(xy 44.934867 -107.753645) (xy 44.980225 -107.721194) (xy 45.029825 -107.695693) (xy 45.082609 -107.677686)
			(xy 45.137452 -107.667556) (xy 45.193186 -107.665519) (xy 45.248623 -107.671619) (xy 45.30258 -107.685725)
			(xy 45.353909 -107.707537) (xy 45.401515 -107.736591) (xy 45.444383 -107.772266) (xy 45.4816 -107.813803)
			(xy 45.512373 -107.860316) (xy 45.536045 -107.910813) (xy 45.552113 -107.96422) (xy 45.560233 -108.019396)
			(xy 45.560742 -108.047282) (xy 47.210216 -108.047282) (xy 47.214287 -107.99166) (xy 47.226413 -107.937223)
			(xy 47.246336 -107.885132) (xy 47.273632 -107.836497) (xy 47.307718 -107.792354) (xy 47.347867 -107.753645)
			(xy 47.393225 -107.721194) (xy 47.442825 -107.695693) (xy 47.495609 -107.677686) (xy 47.550452 -107.667556)
			(xy 47.606186 -107.665519) (xy 47.661623 -107.671619) (xy 47.71558 -107.685725) (xy 47.766909 -107.707537)
			(xy 47.814515 -107.736591) (xy 47.857383 -107.772266) (xy 47.8946 -107.813803) (xy 47.925373 -107.860316)
			(xy 47.949045 -107.910813) (xy 47.965113 -107.96422) (xy 47.973233 -108.019396) (xy 47.973742 -108.047282)
			(xy 47.973233 -108.075168) (xy 47.965113 -108.130344) (xy 47.949045 -108.183751) (xy 47.925373 -108.234248)
			(xy 47.91312 -108.252768) (xy 52.838602 -108.252768) (xy 52.842673 -108.197146) (xy 52.854799 -108.142709)
			(xy 52.874722 -108.090618) (xy 52.902018 -108.041983) (xy 52.936104 -107.99784) (xy 52.976253 -107.959131)
			(xy 53.021611 -107.92668) (xy 53.071211 -107.901179) (xy 53.123995 -107.883172) (xy 53.178838 -107.873042)
			(xy 53.234572 -107.871005) (xy 53.290009 -107.877105) (xy 53.343966 -107.891211) (xy 53.395295 -107.913023)
			(xy 53.442901 -107.942077) (xy 53.485769 -107.977752) (xy 53.522986 -108.019289) (xy 53.553759 -108.065802)
			(xy 53.577431 -108.116299) (xy 53.593499 -108.169706) (xy 53.601619 -108.224882) (xy 53.602128 -108.252768)
			(xy 53.601619 -108.280654) (xy 53.593499 -108.33583) (xy 53.577431 -108.389237) (xy 53.553759 -108.439734)
			(xy 53.522986 -108.486247) (xy 53.485769 -108.527784) (xy 53.442901 -108.563459) (xy 53.395295 -108.592513)
			(xy 53.343966 -108.614325) (xy 53.290009 -108.628431) (xy 53.234572 -108.634531) (xy 53.178838 -108.632494)
			(xy 53.123995 -108.622364) (xy 53.071211 -108.604357) (xy 53.021611 -108.578856) (xy 52.976253 -108.546405)
			(xy 52.936104 -108.507696) (xy 52.902018 -108.463553) (xy 52.874722 -108.414918) (xy 52.854799 -108.362827)
			(xy 52.842673 -108.30839) (xy 52.838602 -108.252768) (xy 47.91312 -108.252768) (xy 47.8946 -108.280761)
			(xy 47.857383 -108.322298) (xy 47.814515 -108.357973) (xy 47.766909 -108.387027) (xy 47.71558 -108.408839)
			(xy 47.661623 -108.422945) (xy 47.606186 -108.429045) (xy 47.550452 -108.427008) (xy 47.495609 -108.416878)
			(xy 47.442825 -108.398871) (xy 47.393225 -108.37337) (xy 47.347867 -108.340919) (xy 47.307718 -108.30221)
			(xy 47.273632 -108.258067) (xy 47.246336 -108.209432) (xy 47.226413 -108.157341) (xy 47.214287 -108.102904)
			(xy 47.210216 -108.047282) (xy 45.560742 -108.047282) (xy 45.560233 -108.075168) (xy 45.552113 -108.130344)
			(xy 45.536045 -108.183751) (xy 45.512373 -108.234248) (xy 45.4816 -108.280761) (xy 45.444383 -108.322298)
			(xy 45.401515 -108.357973) (xy 45.353909 -108.387027) (xy 45.30258 -108.408839) (xy 45.248623 -108.422945)
			(xy 45.193186 -108.429045) (xy 45.137452 -108.427008) (xy 45.082609 -108.416878) (xy 45.029825 -108.398871)
			(xy 44.980225 -108.37337) (xy 44.934867 -108.340919) (xy 44.894718 -108.30221) (xy 44.860632 -108.258067)
			(xy 44.833336 -108.209432) (xy 44.813413 -108.157341) (xy 44.801287 -108.102904) (xy 44.797216 -108.047282)
			(xy 42.018712 -108.047282) (xy 42.018203 -108.075168) (xy 42.010083 -108.130344) (xy 41.994015 -108.183751)
			(xy 41.970343 -108.234248) (xy 41.93957 -108.280761) (xy 41.902353 -108.322298) (xy 41.859485 -108.357973)
			(xy 41.811879 -108.387027) (xy 41.76055 -108.408839) (xy 41.706593 -108.422945) (xy 41.651156 -108.429045)
			(xy 41.595422 -108.427008) (xy 41.540579 -108.416878) (xy 41.487795 -108.398871) (xy 41.438195 -108.37337)
			(xy 41.392837 -108.340919) (xy 41.352688 -108.30221) (xy 41.318602 -108.258067) (xy 41.291306 -108.209432)
			(xy 41.271383 -108.157341) (xy 41.259257 -108.102904) (xy 41.255186 -108.047282) (xy 22.069218 -108.047282)
			(xy 22.064953 -108.052042) (xy 22.022085 -108.087717) (xy 21.974479 -108.116771) (xy 21.92315 -108.138583)
			(xy 21.869193 -108.152689) (xy 21.813756 -108.158789) (xy 21.758022 -108.156752) (xy 21.703179 -108.146622)
			(xy 21.650395 -108.128615) (xy 21.600795 -108.103114) (xy 21.555437 -108.070663) (xy 21.515288 -108.031954)
			(xy 21.481202 -107.987811) (xy 21.453906 -107.939176) (xy 21.433983 -107.887085) (xy 21.421857 -107.832648)
			(xy 21.417786 -107.777026) (xy 6.055868 -107.777026) (xy 6.055868 -108.28274) (xy 11.09472 -108.28274)
			(xy 11.095206 -108.255489) (xy 11.102962 -108.201541) (xy 11.118317 -108.149246) (xy 11.140959 -108.099669)
			(xy 11.170425 -108.053819) (xy 11.206116 -108.012628) (xy 11.247307 -107.976937) (xy 11.293157 -107.947471)
			(xy 11.342734 -107.924829) (xy 11.395029 -107.909474) (xy 11.448977 -107.901718) (xy 11.503479 -107.901718)
			(xy 11.557427 -107.909474) (xy 11.609722 -107.924829) (xy 11.659299 -107.947471) (xy 11.705149 -107.976937)
			(xy 11.74634 -108.012628) (xy 11.782031 -108.053819) (xy 11.811497 -108.099669) (xy 11.834139 -108.149246)
			(xy 11.849494 -108.201541) (xy 11.85725 -108.255489) (xy 11.857736 -108.28274) (xy 11.857156 -108.313045)
			(xy 11.847592 -108.372894) (xy 11.838686 -108.401866) (xy 11.834807 -108.415044) (xy 11.833493 -108.442473)
			(xy 11.839537 -108.469259) (xy 11.852501 -108.493467) (xy 11.871449 -108.513343) (xy 11.895009 -108.527449)
			(xy 11.921476 -108.534767) (xy 11.935206 -108.535216) (xy 12.276074 -108.535216) (xy 12.289801 -108.534732)
			(xy 12.316263 -108.52742) (xy 12.339819 -108.51332) (xy 12.358764 -108.49345) (xy 12.371727 -108.469249)
			(xy 12.37777 -108.442469) (xy 12.376455 -108.415046) (xy 12.372594 -108.401866) (xy 12.363691 -108.372893)
			(xy 12.354126 -108.313044) (xy 12.353544 -108.28274) (xy 12.35403 -108.255489) (xy 12.361786 -108.201541)
			(xy 12.377141 -108.149246) (xy 12.399783 -108.099669) (xy 12.429249 -108.053819) (xy 12.46494 -108.012628)
			(xy 12.506131 -107.976937) (xy 12.551981 -107.947471) (xy 12.601558 -107.924829) (xy 12.653853 -107.909474)
			(xy 12.707801 -107.901718) (xy 12.762303 -107.901718) (xy 12.816251 -107.909474) (xy 12.868546 -107.924829)
			(xy 12.918123 -107.947471) (xy 12.963973 -107.976937) (xy 13.005164 -108.012628) (xy 13.040855 -108.053819)
			(xy 13.070321 -108.099669) (xy 13.092963 -108.149246) (xy 13.108318 -108.201541) (xy 13.116074 -108.255489)
			(xy 13.11656 -108.28274) (xy 14.958314 -108.28274) (xy 14.9588 -108.255489) (xy 14.966556 -108.201541)
			(xy 14.981911 -108.149246) (xy 15.004553 -108.099669) (xy 15.034019 -108.053819) (xy 15.06971 -108.012628)
			(xy 15.110901 -107.976937) (xy 15.156751 -107.947471) (xy 15.206328 -107.924829) (xy 15.258623 -107.909474)
			(xy 15.312571 -107.901718) (xy 15.367073 -107.901718) (xy 15.421021 -107.909474) (xy 15.473316 -107.924829)
			(xy 15.522893 -107.947471) (xy 15.568743 -107.976937) (xy 15.609934 -108.012628) (xy 15.645625 -108.053819)
			(xy 15.675091 -108.099669) (xy 15.697733 -108.149246) (xy 15.713088 -108.201541) (xy 15.720844 -108.255489)
			(xy 15.72133 -108.28274) (xy 15.72075 -108.313045) (xy 15.711186 -108.372894) (xy 15.70228 -108.401866)
			(xy 15.698407 -108.415045) (xy 15.697093 -108.442473) (xy 15.703136 -108.469259) (xy 15.7161 -108.493465)
			(xy 15.735046 -108.513341) (xy 15.758605 -108.527448) (xy 15.78507 -108.534766) (xy 15.7988 -108.535216)
			(xy 16.139668 -108.535216) (xy 16.153395 -108.534727) (xy 16.179857 -108.527417) (xy 16.203413 -108.513317)
			(xy 16.222358 -108.493448) (xy 16.235321 -108.469248) (xy 16.241364 -108.442468) (xy 16.240049 -108.415046)
			(xy 16.236188 -108.401866) (xy 16.227285 -108.372893) (xy 16.21772 -108.313044) (xy 16.217138 -108.28274)
			(xy 16.217624 -108.255489) (xy 16.22538 -108.201541) (xy 16.240735 -108.149246) (xy 16.263377 -108.099669)
			(xy 16.292843 -108.053819) (xy 16.328534 -108.012628) (xy 16.369725 -107.976937) (xy 16.415575 -107.947471)
			(xy 16.465152 -107.924829) (xy 16.517447 -107.909474) (xy 16.571395 -107.901718) (xy 16.625897 -107.901718)
			(xy 16.679845 -107.909474) (xy 16.73214 -107.924829) (xy 16.781717 -107.947471) (xy 16.827567 -107.976937)
			(xy 16.868758 -108.012628) (xy 16.904449 -108.053819) (xy 16.933915 -108.099669) (xy 16.956557 -108.149246)
			(xy 16.971912 -108.201541) (xy 16.979668 -108.255489) (xy 16.980154 -108.28274) (xy 16.979629 -108.311628)
			(xy 16.970924 -108.368746) (xy 16.953706 -108.423897) (xy 16.928367 -108.475821) (xy 16.895488 -108.52333)
			(xy 16.855819 -108.565337) (xy 16.81027 -108.600881) (xy 16.785336 -108.61548) (xy 16.772105 -108.623467)
			(xy 16.750866 -108.645898) (xy 16.737304 -108.673654) (xy 16.732661 -108.704194) (xy 16.73736 -108.734726)
			(xy 16.74368 -108.74883) (xy 16.755977 -108.775094) (xy 16.761616 -108.793026) (xy 21.417786 -108.793026)
			(xy 21.421857 -108.737404) (xy 21.433983 -108.682967) (xy 21.453906 -108.630876) (xy 21.481202 -108.582241)
			(xy 21.515288 -108.538098) (xy 21.555437 -108.499389) (xy 21.600795 -108.466938) (xy 21.650395 -108.441437)
			(xy 21.703179 -108.42343) (xy 21.758022 -108.4133) (xy 21.813756 -108.411263) (xy 21.869193 -108.417363)
			(xy 21.92315 -108.431469) (xy 21.974479 -108.453281) (xy 22.022085 -108.482335) (xy 22.064953 -108.51801)
			(xy 22.098349 -108.555282) (xy 37.558216 -108.555282) (xy 37.562287 -108.49966) (xy 37.574413 -108.445223)
			(xy 37.594336 -108.393132) (xy 37.621632 -108.344497) (xy 37.655718 -108.300354) (xy 37.695867 -108.261645)
			(xy 37.741225 -108.229194) (xy 37.790825 -108.203693) (xy 37.843609 -108.185686) (xy 37.898452 -108.175556)
			(xy 37.954186 -108.173519) (xy 38.009623 -108.179619) (xy 38.06358 -108.193725) (xy 38.114909 -108.215537)
			(xy 38.162515 -108.244591) (xy 38.205383 -108.280266) (xy 38.2426 -108.321803) (xy 38.273373 -108.368316)
			(xy 38.297045 -108.418813) (xy 38.313113 -108.47222) (xy 38.321233 -108.527396) (xy 38.321742 -108.555282)
			(xy 38.321233 -108.583168) (xy 38.313113 -108.638344) (xy 38.297045 -108.691751) (xy 38.273373 -108.742248)
			(xy 38.2426 -108.788761) (xy 38.205383 -108.830298) (xy 38.162515 -108.865973) (xy 38.154272 -108.871004)
			(xy 50.17592 -108.871004) (xy 50.179991 -108.815382) (xy 50.192117 -108.760945) (xy 50.21204 -108.708854)
			(xy 50.239336 -108.660219) (xy 50.273422 -108.616076) (xy 50.313571 -108.577367) (xy 50.358929 -108.544916)
			(xy 50.408529 -108.519415) (xy 50.461313 -108.501408) (xy 50.516156 -108.491278) (xy 50.57189 -108.489241)
			(xy 50.627327 -108.495341) (xy 50.681284 -108.509447) (xy 50.732613 -108.531259) (xy 50.780219 -108.560313)
			(xy 50.823087 -108.595988) (xy 50.860304 -108.637525) (xy 50.891077 -108.684038) (xy 50.914749 -108.734535)
			(xy 50.930817 -108.787942) (xy 50.938937 -108.843118) (xy 50.939446 -108.871004) (xy 50.938937 -108.89889)
			(xy 50.938705 -108.900468) (xy 51.611528 -108.900468) (xy 51.615599 -108.844846) (xy 51.627725 -108.790409)
			(xy 51.647648 -108.738318) (xy 51.674944 -108.689683) (xy 51.70903 -108.64554) (xy 51.749179 -108.606831)
			(xy 51.794537 -108.57438) (xy 51.844137 -108.548879) (xy 51.896921 -108.530872) (xy 51.951764 -108.520742)
			(xy 52.007498 -108.518705) (xy 52.062935 -108.524805) (xy 52.116892 -108.538911) (xy 52.168221 -108.560723)
			(xy 52.215827 -108.589777) (xy 52.258695 -108.625452) (xy 52.295912 -108.666989) (xy 52.326685 -108.713502)
			(xy 52.350357 -108.763999) (xy 52.362916 -108.805744) (xy 54.932626 -108.805744) (xy 54.932626 -108.751251)
			(xy 54.940382 -108.697312) (xy 54.955734 -108.645026) (xy 54.978371 -108.595456) (xy 55.007832 -108.549613)
			(xy 55.043517 -108.508429) (xy 55.084699 -108.472742) (xy 55.130541 -108.443279) (xy 55.180109 -108.42064)
			(xy 55.232395 -108.405285) (xy 55.286333 -108.397528) (xy 55.31358 -108.39704) (xy 55.330046 -108.397197)
			(xy 55.362858 -108.399993) (xy 55.379112 -108.402628) (xy 55.394307 -108.404687) (xy 55.424702 -108.400773)
			(xy 55.452571 -108.388026) (xy 55.475408 -108.36759) (xy 55.491161 -108.341303) (xy 55.498413 -108.311528)
			(xy 55.497984 -108.296202) (xy 55.497222 -108.271818) (xy 55.497672 -108.244564) (xy 55.505427 -108.190611)
			(xy 55.520783 -108.138311) (xy 55.543425 -108.088729) (xy 55.572894 -108.042875) (xy 55.608589 -108.001681)
			(xy 55.649784 -107.965987) (xy 55.69564 -107.93652) (xy 55.745223 -107.913879) (xy 55.797523 -107.898525)
			(xy 55.851476 -107.890771) (xy 55.87873 -107.89031) (xy 55.90574 -107.890799) (xy 55.959222 -107.898398)
			(xy 56.011096 -107.913468) (xy 56.060325 -107.935708) (xy 56.105923 -107.964672) (xy 56.146977 -107.99978)
			(xy 56.182666 -108.040331) (xy 56.212276 -108.085512) (xy 56.22417 -108.109766) (xy 56.230355 -108.121922)
			(xy 56.248065 -108.142652) (xy 56.270632 -108.157953) (xy 56.296445 -108.166732) (xy 56.323661 -108.168362)
			(xy 56.350338 -108.162727) (xy 56.37457 -108.15023) (xy 56.394627 -108.131762) (xy 56.402224 -108.120434)
			(xy 56.417303 -108.097312) (xy 56.453001 -108.055212) (xy 56.494392 -108.018693) (xy 56.540612 -107.988517)
			(xy 56.590696 -107.965313) (xy 56.6436 -107.949566) (xy 56.698221 -107.941603) (xy 56.72582 -107.94111)
			(xy 56.753072 -107.941561) (xy 56.80702 -107.94932) (xy 56.859315 -107.964678) (xy 56.908892 -107.987321)
			(xy 56.954742 -108.01679) (xy 56.995931 -108.052483) (xy 57.031622 -108.093674) (xy 57.061088 -108.139526)
			(xy 57.083729 -108.189104) (xy 57.099084 -108.2414) (xy 57.10684 -108.295348) (xy 57.10684 -108.349852)
			(xy 57.100969 -108.39069) (xy 65.166746 -108.39069) (xy 65.170817 -108.335068) (xy 65.182943 -108.280631)
			(xy 65.202866 -108.22854) (xy 65.230162 -108.179905) (xy 65.264248 -108.135762) (xy 65.304397 -108.097053)
			(xy 65.349755 -108.064602) (xy 65.399355 -108.039101) (xy 65.452139 -108.021094) (xy 65.506982 -108.010964)
			(xy 65.562716 -108.008927) (xy 65.618153 -108.015027) (xy 65.67211 -108.029133) (xy 65.723439 -108.050945)
			(xy 65.771045 -108.079999) (xy 65.813913 -108.115674) (xy 65.85113 -108.157211) (xy 65.881903 -108.203724)
			(xy 65.905575 -108.254221) (xy 65.921643 -108.307628) (xy 65.929763 -108.362804) (xy 65.930272 -108.39069)
			(xy 65.929763 -108.418576) (xy 65.921643 -108.473752) (xy 65.905575 -108.527159) (xy 65.881903 -108.577656)
			(xy 65.85113 -108.624169) (xy 65.813913 -108.665706) (xy 65.771045 -108.701381) (xy 65.723439 -108.730435)
			(xy 65.67211 -108.752247) (xy 65.618153 -108.766353) (xy 65.562716 -108.772453) (xy 65.506982 -108.770416)
			(xy 65.452139 -108.760286) (xy 65.399355 -108.742279) (xy 65.349755 -108.716778) (xy 65.304397 -108.684327)
			(xy 65.264248 -108.645618) (xy 65.230162 -108.601475) (xy 65.202866 -108.55284) (xy 65.182943 -108.500749)
			(xy 65.170817 -108.446312) (xy 65.166746 -108.39069) (xy 57.100969 -108.39069) (xy 57.099084 -108.4038)
			(xy 57.083729 -108.456096) (xy 57.061088 -108.505674) (xy 57.031622 -108.551526) (xy 56.995931 -108.592717)
			(xy 56.954742 -108.62841) (xy 56.908892 -108.657879) (xy 56.859315 -108.680522) (xy 56.80702 -108.69588)
			(xy 56.753072 -108.703639) (xy 56.72582 -108.704126) (xy 56.69881 -108.703658) (xy 56.645328 -108.696053)
			(xy 56.593454 -108.680978) (xy 56.544226 -108.658734) (xy 56.498629 -108.629768) (xy 56.457575 -108.594657)
			(xy 56.421885 -108.554106) (xy 56.392275 -108.508924) (xy 56.38038 -108.48467) (xy 56.374121 -108.472558)
			(xy 56.356418 -108.451844) (xy 56.333864 -108.436555) (xy 56.308068 -108.427779) (xy 56.280869 -108.426144)
			(xy 56.254207 -108.431766) (xy 56.229984 -108.444243) (xy 56.209926 -108.462686) (xy 56.202326 -108.474002)
			(xy 56.187293 -108.497155) (xy 56.151585 -108.539253) (xy 56.110186 -108.575769) (xy 56.063959 -108.605941)
			(xy 56.013868 -108.629139) (xy 55.960957 -108.644881) (xy 55.906331 -108.652836) (xy 55.87873 -108.653326)
			(xy 55.862264 -108.653169) (xy 55.829452 -108.650372) (xy 55.813198 -108.647738) (xy 55.798007 -108.645619)
			(xy 55.767599 -108.649532) (xy 55.73972 -108.662288) (xy 55.716878 -108.682737) (xy 55.701128 -108.709041)
			(xy 55.693888 -108.738832) (xy 55.694326 -108.754164) (xy 55.695088 -108.778548) (xy 55.69457 -108.805795)
			(xy 55.686809 -108.859733) (xy 55.67145 -108.912017) (xy 55.648807 -108.961584) (xy 55.619341 -109.007423)
			(xy 55.583651 -109.048603) (xy 55.542465 -109.084285) (xy 55.496619 -109.113742) (xy 55.447048 -109.136376)
			(xy 55.394761 -109.151724) (xy 55.340821 -109.159476) (xy 55.286328 -109.159472) (xy 55.23239 -109.151714)
			(xy 55.180104 -109.136358) (xy 55.130536 -109.113718) (xy 55.084695 -109.084255) (xy 55.043513 -109.048567)
			(xy 55.007829 -109.007383) (xy 54.978368 -108.961539) (xy 54.955732 -108.911969) (xy 54.94038 -108.859683)
			(xy 54.932626 -108.805744) (xy 52.362916 -108.805744) (xy 52.366425 -108.817406) (xy 52.374545 -108.872582)
			(xy 52.375054 -108.900468) (xy 52.374545 -108.928354) (xy 52.366425 -108.98353) (xy 52.350357 -109.036937)
			(xy 52.326685 -109.087434) (xy 52.295912 -109.133947) (xy 52.258695 -109.175484) (xy 52.215827 -109.211159)
			(xy 52.199676 -109.221016) (xy 55.712104 -109.221016) (xy 55.716175 -109.165394) (xy 55.728301 -109.110957)
			(xy 55.748224 -109.058866) (xy 55.77552 -109.010231) (xy 55.809606 -108.966088) (xy 55.849755 -108.927379)
			(xy 55.895113 -108.894928) (xy 55.944713 -108.869427) (xy 55.997497 -108.85142) (xy 56.05234 -108.84129)
			(xy 56.108074 -108.839253) (xy 56.163511 -108.845353) (xy 56.217468 -108.859459) (xy 56.268797 -108.881271)
			(xy 56.316403 -108.910325) (xy 56.359271 -108.946) (xy 56.396488 -108.987537) (xy 56.427261 -109.03405)
			(xy 56.450933 -109.084547) (xy 56.467001 -109.137954) (xy 56.475121 -109.19313) (xy 56.47563 -109.221016)
			(xy 56.475121 -109.248902) (xy 56.467001 -109.304078) (xy 56.450933 -109.357485) (xy 56.427261 -109.407982)
			(xy 56.396488 -109.454495) (xy 56.359271 -109.496032) (xy 56.316403 -109.531707) (xy 56.268797 -109.560761)
			(xy 56.217468 -109.582573) (xy 56.163511 -109.596679) (xy 56.121933 -109.601254) (xy 56.567322 -109.601254)
			(xy 56.571393 -109.545632) (xy 56.583519 -109.491195) (xy 56.603442 -109.439104) (xy 56.630738 -109.390469)
			(xy 56.664824 -109.346326) (xy 56.704973 -109.307617) (xy 56.750331 -109.275166) (xy 56.799931 -109.249665)
			(xy 56.852715 -109.231658) (xy 56.907558 -109.221528) (xy 56.963292 -109.219491) (xy 57.018729 -109.225591)
			(xy 57.072686 -109.239697) (xy 57.124015 -109.261509) (xy 57.171621 -109.290563) (xy 57.214489 -109.326238)
			(xy 57.251706 -109.367775) (xy 57.282479 -109.414288) (xy 57.306151 -109.464785) (xy 57.322219 -109.518192)
			(xy 57.330339 -109.573368) (xy 57.330848 -109.601254) (xy 57.330339 -109.62914) (xy 57.322219 -109.684316)
			(xy 57.306151 -109.737723) (xy 57.282479 -109.78822) (xy 57.251706 -109.834733) (xy 57.214489 -109.87627)
			(xy 57.171621 -109.911945) (xy 57.124015 -109.940999) (xy 57.072686 -109.962811) (xy 57.018729 -109.976917)
			(xy 56.963292 -109.983017) (xy 56.907558 -109.98098) (xy 56.852715 -109.97085) (xy 56.799931 -109.952843)
			(xy 56.750331 -109.927342) (xy 56.704973 -109.894891) (xy 56.664824 -109.856182) (xy 56.630738 -109.812039)
			(xy 56.603442 -109.763404) (xy 56.583519 -109.711313) (xy 56.571393 -109.656876) (xy 56.567322 -109.601254)
			(xy 56.121933 -109.601254) (xy 56.108074 -109.602779) (xy 56.05234 -109.600742) (xy 55.997497 -109.590612)
			(xy 55.944713 -109.572605) (xy 55.895113 -109.547104) (xy 55.849755 -109.514653) (xy 55.809606 -109.475944)
			(xy 55.77552 -109.431801) (xy 55.748224 -109.383166) (xy 55.728301 -109.331075) (xy 55.716175 -109.276638)
			(xy 55.712104 -109.221016) (xy 52.199676 -109.221016) (xy 52.168221 -109.240213) (xy 52.116892 -109.262025)
			(xy 52.062935 -109.276131) (xy 52.007498 -109.282231) (xy 51.951764 -109.280194) (xy 51.896921 -109.270064)
			(xy 51.844137 -109.252057) (xy 51.794537 -109.226556) (xy 51.749179 -109.194105) (xy 51.70903 -109.155396)
			(xy 51.674944 -109.111253) (xy 51.647648 -109.062618) (xy 51.627725 -109.010527) (xy 51.615599 -108.95609)
			(xy 51.611528 -108.900468) (xy 50.938705 -108.900468) (xy 50.930817 -108.954066) (xy 50.914749 -109.007473)
			(xy 50.891077 -109.05797) (xy 50.860304 -109.104483) (xy 50.823087 -109.14602) (xy 50.780219 -109.181695)
			(xy 50.732613 -109.210749) (xy 50.681284 -109.232561) (xy 50.627327 -109.246667) (xy 50.57189 -109.252767)
			(xy 50.516156 -109.25073) (xy 50.461313 -109.2406) (xy 50.408529 -109.222593) (xy 50.358929 -109.197092)
			(xy 50.313571 -109.164641) (xy 50.273422 -109.125932) (xy 50.239336 -109.081789) (xy 50.21204 -109.033154)
			(xy 50.192117 -108.981063) (xy 50.179991 -108.926626) (xy 50.17592 -108.871004) (xy 38.154272 -108.871004)
			(xy 38.114909 -108.895027) (xy 38.06358 -108.916839) (xy 38.009623 -108.930945) (xy 37.954186 -108.937045)
			(xy 37.898452 -108.935008) (xy 37.843609 -108.924878) (xy 37.790825 -108.906871) (xy 37.741225 -108.88137)
			(xy 37.695867 -108.848919) (xy 37.655718 -108.81021) (xy 37.621632 -108.766067) (xy 37.594336 -108.717432)
			(xy 37.574413 -108.665341) (xy 37.562287 -108.610904) (xy 37.558216 -108.555282) (xy 22.098349 -108.555282)
			(xy 22.10217 -108.559547) (xy 22.132943 -108.60606) (xy 22.156615 -108.656557) (xy 22.172683 -108.709964)
			(xy 22.180803 -108.76514) (xy 22.181312 -108.793026) (xy 22.180803 -108.820912) (xy 22.172683 -108.876088)
			(xy 22.156615 -108.929495) (xy 22.132943 -108.979992) (xy 22.10217 -109.026505) (xy 22.064953 -109.068042)
			(xy 22.022085 -109.103717) (xy 21.974479 -109.132771) (xy 21.92315 -109.154583) (xy 21.869193 -109.168689)
			(xy 21.813756 -109.174789) (xy 21.758022 -109.172752) (xy 21.703179 -109.162622) (xy 21.650395 -109.144615)
			(xy 21.600795 -109.119114) (xy 21.555437 -109.086663) (xy 21.515288 -109.047954) (xy 21.481202 -109.003811)
			(xy 21.453906 -108.955176) (xy 21.433983 -108.903085) (xy 21.421857 -108.848648) (xy 21.417786 -108.793026)
			(xy 16.761616 -108.793026) (xy 16.773373 -108.830416) (xy 16.782216 -108.887729) (xy 16.782796 -108.916724)
			(xy 16.782367 -108.94399) (xy 16.7746 -108.997965) (xy 16.759227 -109.050284) (xy 16.736562 -109.099882)
			(xy 16.707067 -109.145748) (xy 16.671342 -109.186948) (xy 16.630116 -109.222641) (xy 16.584227 -109.252101)
			(xy 16.534612 -109.274728) (xy 16.482281 -109.290061) (xy 16.4283 -109.297787) (xy 16.401034 -109.298232)
			(xy 15.537434 -109.298232) (xy 15.510176 -109.297745) (xy 15.456213 -109.289993) (xy 15.403902 -109.274644)
			(xy 15.354307 -109.252008) (xy 15.308436 -109.222546) (xy 15.267224 -109.186859) (xy 15.231508 -109.14567)
			(xy 15.202016 -109.09982) (xy 15.179347 -109.05024) (xy 15.163961 -108.99794) (xy 15.156174 -108.943982)
			(xy 15.155672 -108.916724) (xy 15.156252 -108.887728) (xy 15.165077 -108.830411) (xy 15.182483 -108.775091)
			(xy 15.194788 -108.74883) (xy 15.201061 -108.734711) (xy 15.205755 -108.704191) (xy 15.201116 -108.673663)
			(xy 15.187566 -108.645916) (xy 15.166345 -108.623485) (xy 15.153132 -108.61548) (xy 15.128213 -108.600859)
			(xy 15.082671 -108.565312) (xy 15.043007 -108.523306) (xy 15.01013 -108.475801) (xy 14.984789 -108.423883)
			(xy 14.967564 -108.368738) (xy 14.958849 -108.311626) (xy 14.958314 -108.28274) (xy 13.11656 -108.28274)
			(xy 13.116032 -108.311628) (xy 13.107327 -108.368745) (xy 13.090109 -108.423897) (xy 13.064771 -108.47582)
			(xy 13.031892 -108.523329) (xy 12.992225 -108.565337) (xy 12.946676 -108.600881) (xy 12.921742 -108.61548)
			(xy 12.908497 -108.623443) (xy 12.88727 -108.645887) (xy 12.873717 -108.673648) (xy 12.869076 -108.70419)
			(xy 12.873771 -108.734723) (xy 12.880086 -108.74883) (xy 12.892347 -108.775103) (xy 12.909684 -108.830425)
			(xy 12.918429 -108.887736) (xy 12.918948 -108.916724) (xy 12.918445 -108.943974) (xy 12.910686 -108.997919)
			(xy 12.89533 -109.050211) (xy 12.872689 -109.099786) (xy 12.843224 -109.145634) (xy 12.807534 -109.186823)
			(xy 12.766347 -109.222514) (xy 12.7205 -109.251981) (xy 12.670926 -109.274624) (xy 12.618635 -109.289983)
			(xy 12.56469 -109.297744) (xy 12.53744 -109.298232) (xy 11.67384 -109.298232) (xy 11.646589 -109.297708)
			(xy 11.592642 -109.289957) (xy 11.540346 -109.274607) (xy 11.490768 -109.251971) (xy 11.444916 -109.222509)
			(xy 11.403723 -109.186822) (xy 11.368029 -109.145635) (xy 11.33856 -109.099788) (xy 11.315915 -109.050214)
			(xy 11.300557 -108.997921) (xy 11.292797 -108.943975) (xy 11.292332 -108.916724) (xy 11.292877 -108.887738)
			(xy 11.301637 -108.830433) (xy 11.318945 -108.775106) (xy 11.331194 -108.74883) (xy 11.337465 -108.73471)
			(xy 11.342159 -108.704191) (xy 11.337519 -108.673663) (xy 11.323971 -108.645916) (xy 11.302751 -108.623485)
			(xy 11.289538 -108.61548) (xy 11.26462 -108.600857) (xy 11.219078 -108.565311) (xy 11.179414 -108.523305)
			(xy 11.146536 -108.475801) (xy 11.121195 -108.423882) (xy 11.10397 -108.368738) (xy 11.095255 -108.311626)
			(xy 11.09472 -108.28274) (xy 6.055868 -108.28274) (xy 6.055868 -109.859826) (xy 18.792442 -109.859826)
			(xy 18.796513 -109.804204) (xy 18.808639 -109.749767) (xy 18.828562 -109.697676) (xy 18.855858 -109.649041)
			(xy 18.889944 -109.604898) (xy 18.930093 -109.566189) (xy 18.975451 -109.533738) (xy 19.025051 -109.508237)
			(xy 19.077835 -109.49023) (xy 19.132678 -109.4801) (xy 19.188412 -109.478063) (xy 19.243849 -109.484163)
			(xy 19.297806 -109.498269) (xy 19.349135 -109.520081) (xy 19.396741 -109.549135) (xy 19.439609 -109.58481)
			(xy 19.476826 -109.626347) (xy 19.498203 -109.658658) (xy 25.3525 -109.658658) (xy 25.356571 -109.603036)
			(xy 25.368697 -109.548599) (xy 25.38862 -109.496508) (xy 25.415916 -109.447873) (xy 25.450002 -109.40373)
			(xy 25.490151 -109.365021) (xy 25.535509 -109.33257) (xy 25.585109 -109.307069) (xy 25.637893 -109.289062)
			(xy 25.692736 -109.278932) (xy 25.74847 -109.276895) (xy 25.803907 -109.282995) (xy 25.857864 -109.297101)
			(xy 25.909193 -109.318913) (xy 25.956799 -109.347967) (xy 25.999667 -109.383642) (xy 26.036884 -109.425179)
			(xy 26.067657 -109.471692) (xy 26.091329 -109.522189) (xy 26.106099 -109.571282) (xy 37.558216 -109.571282)
			(xy 37.562287 -109.51566) (xy 37.574413 -109.461223) (xy 37.594336 -109.409132) (xy 37.621632 -109.360497)
			(xy 37.655718 -109.316354) (xy 37.695867 -109.277645) (xy 37.741225 -109.245194) (xy 37.790825 -109.219693)
			(xy 37.843609 -109.201686) (xy 37.898452 -109.191556) (xy 37.954186 -109.189519) (xy 38.009623 -109.195619)
			(xy 38.06358 -109.209725) (xy 38.114909 -109.231537) (xy 38.162515 -109.260591) (xy 38.205383 -109.296266)
			(xy 38.2426 -109.337803) (xy 38.273373 -109.384316) (xy 38.297045 -109.434813) (xy 38.299894 -109.444282)
			(xy 41.255186 -109.444282) (xy 41.259257 -109.38866) (xy 41.271383 -109.334223) (xy 41.291306 -109.282132)
			(xy 41.318602 -109.233497) (xy 41.352688 -109.189354) (xy 41.392837 -109.150645) (xy 41.438195 -109.118194)
			(xy 41.487795 -109.092693) (xy 41.540579 -109.074686) (xy 41.595422 -109.064556) (xy 41.651156 -109.062519)
			(xy 41.706593 -109.068619) (xy 41.76055 -109.082725) (xy 41.811879 -109.104537) (xy 41.859485 -109.133591)
			(xy 41.902353 -109.169266) (xy 41.93957 -109.210803) (xy 41.970343 -109.257316) (xy 41.994015 -109.307813)
			(xy 42.010083 -109.36122) (xy 42.018203 -109.416396) (xy 42.018712 -109.444282) (xy 44.797216 -109.444282)
			(xy 44.801287 -109.38866) (xy 44.813413 -109.334223) (xy 44.833336 -109.282132) (xy 44.860632 -109.233497)
			(xy 44.894718 -109.189354) (xy 44.934867 -109.150645) (xy 44.980225 -109.118194) (xy 45.029825 -109.092693)
			(xy 45.082609 -109.074686) (xy 45.137452 -109.064556) (xy 45.193186 -109.062519) (xy 45.248623 -109.068619)
			(xy 45.30258 -109.082725) (xy 45.353909 -109.104537) (xy 45.401515 -109.133591) (xy 45.444383 -109.169266)
			(xy 45.4816 -109.210803) (xy 45.512373 -109.257316) (xy 45.536045 -109.307813) (xy 45.552113 -109.36122)
			(xy 45.560233 -109.416396) (xy 45.560742 -109.444282) (xy 47.210216 -109.444282) (xy 47.214287 -109.38866)
			(xy 47.226413 -109.334223) (xy 47.246336 -109.282132) (xy 47.273632 -109.233497) (xy 47.307718 -109.189354)
			(xy 47.347867 -109.150645) (xy 47.393225 -109.118194) (xy 47.442825 -109.092693) (xy 47.495609 -109.074686)
			(xy 47.550452 -109.064556) (xy 47.606186 -109.062519) (xy 47.661623 -109.068619) (xy 47.71558 -109.082725)
			(xy 47.766909 -109.104537) (xy 47.814515 -109.133591) (xy 47.857383 -109.169266) (xy 47.8946 -109.210803)
			(xy 47.925373 -109.257316) (xy 47.933599 -109.274864) (xy 48.209452 -109.274864) (xy 48.213523 -109.219242)
			(xy 48.225649 -109.164805) (xy 48.245572 -109.112714) (xy 48.272868 -109.064079) (xy 48.306954 -109.019936)
			(xy 48.347103 -108.981227) (xy 48.392461 -108.948776) (xy 48.442061 -108.923275) (xy 48.494845 -108.905268)
			(xy 48.549688 -108.895138) (xy 48.605422 -108.893101) (xy 48.660859 -108.899201) (xy 48.714816 -108.913307)
			(xy 48.766145 -108.935119) (xy 48.813751 -108.964173) (xy 48.856619 -108.999848) (xy 48.893836 -109.041385)
			(xy 48.924609 -109.087898) (xy 48.948281 -109.138395) (xy 48.964349 -109.191802) (xy 48.972469 -109.246978)
			(xy 48.972978 -109.274864) (xy 48.972469 -109.30275) (xy 48.964349 -109.357926) (xy 48.948281 -109.411333)
			(xy 48.924609 -109.46183) (xy 48.893836 -109.508343) (xy 48.856619 -109.54988) (xy 48.813751 -109.585555)
			(xy 48.766145 -109.614609) (xy 48.714816 -109.636421) (xy 48.660859 -109.650527) (xy 48.605422 -109.656627)
			(xy 48.549688 -109.65459) (xy 48.494845 -109.64446) (xy 48.442061 -109.626453) (xy 48.392461 -109.600952)
			(xy 48.347103 -109.568501) (xy 48.306954 -109.529792) (xy 48.272868 -109.485649) (xy 48.245572 -109.437014)
			(xy 48.225649 -109.384923) (xy 48.213523 -109.330486) (xy 48.209452 -109.274864) (xy 47.933599 -109.274864)
			(xy 47.949045 -109.307813) (xy 47.965113 -109.36122) (xy 47.973233 -109.416396) (xy 47.973742 -109.444282)
			(xy 47.973233 -109.472168) (xy 47.965113 -109.527344) (xy 47.949045 -109.580751) (xy 47.925373 -109.631248)
			(xy 47.8946 -109.677761) (xy 47.857383 -109.719298) (xy 47.814515 -109.754973) (xy 47.766909 -109.784027)
			(xy 47.71558 -109.805839) (xy 47.661623 -109.819945) (xy 47.606186 -109.826045) (xy 47.550452 -109.824008)
			(xy 47.495609 -109.813878) (xy 47.442825 -109.795871) (xy 47.393225 -109.77037) (xy 47.347867 -109.737919)
			(xy 47.307718 -109.69921) (xy 47.273632 -109.655067) (xy 47.246336 -109.606432) (xy 47.226413 -109.554341)
			(xy 47.214287 -109.499904) (xy 47.210216 -109.444282) (xy 45.560742 -109.444282) (xy 45.560233 -109.472168)
			(xy 45.552113 -109.527344) (xy 45.536045 -109.580751) (xy 45.512373 -109.631248) (xy 45.4816 -109.677761)
			(xy 45.444383 -109.719298) (xy 45.401515 -109.754973) (xy 45.353909 -109.784027) (xy 45.30258 -109.805839)
			(xy 45.248623 -109.819945) (xy 45.193186 -109.826045) (xy 45.137452 -109.824008) (xy 45.082609 -109.813878)
			(xy 45.029825 -109.795871) (xy 44.980225 -109.77037) (xy 44.934867 -109.737919) (xy 44.894718 -109.69921)
			(xy 44.860632 -109.655067) (xy 44.833336 -109.606432) (xy 44.813413 -109.554341) (xy 44.801287 -109.499904)
			(xy 44.797216 -109.444282) (xy 42.018712 -109.444282) (xy 42.018203 -109.472168) (xy 42.010083 -109.527344)
			(xy 41.994015 -109.580751) (xy 41.970343 -109.631248) (xy 41.93957 -109.677761) (xy 41.902353 -109.719298)
			(xy 41.859485 -109.754973) (xy 41.811879 -109.784027) (xy 41.76055 -109.805839) (xy 41.706593 -109.819945)
			(xy 41.651156 -109.826045) (xy 41.595422 -109.824008) (xy 41.540579 -109.813878) (xy 41.487795 -109.795871)
			(xy 41.438195 -109.77037) (xy 41.392837 -109.737919) (xy 41.352688 -109.69921) (xy 41.318602 -109.655067)
			(xy 41.291306 -109.606432) (xy 41.271383 -109.554341) (xy 41.259257 -109.499904) (xy 41.255186 -109.444282)
			(xy 38.299894 -109.444282) (xy 38.313113 -109.48822) (xy 38.321233 -109.543396) (xy 38.321742 -109.571282)
			(xy 38.321233 -109.599168) (xy 38.313113 -109.654344) (xy 38.297045 -109.707751) (xy 38.273373 -109.758248)
			(xy 38.2426 -109.804761) (xy 38.205383 -109.846298) (xy 38.162515 -109.881973) (xy 38.114909 -109.911027)
			(xy 38.06358 -109.932839) (xy 38.009623 -109.946945) (xy 37.954186 -109.953045) (xy 37.898452 -109.951008)
			(xy 37.843609 -109.940878) (xy 37.790825 -109.922871) (xy 37.741225 -109.89737) (xy 37.695867 -109.864919)
			(xy 37.655718 -109.82621) (xy 37.621632 -109.782067) (xy 37.594336 -109.733432) (xy 37.574413 -109.681341)
			(xy 37.562287 -109.626904) (xy 37.558216 -109.571282) (xy 26.106099 -109.571282) (xy 26.107397 -109.575596)
			(xy 26.115517 -109.630772) (xy 26.116026 -109.658658) (xy 26.115517 -109.686544) (xy 26.107397 -109.74172)
			(xy 26.091329 -109.795127) (xy 26.067657 -109.845624) (xy 26.036884 -109.892137) (xy 25.999667 -109.933674)
			(xy 25.956799 -109.969349) (xy 25.909193 -109.998403) (xy 25.857864 -110.020215) (xy 25.803907 -110.034321)
			(xy 25.74847 -110.040421) (xy 25.692736 -110.038384) (xy 25.637893 -110.028254) (xy 25.585109 -110.010247)
			(xy 25.535509 -109.984746) (xy 25.490151 -109.952295) (xy 25.450002 -109.913586) (xy 25.415916 -109.869443)
			(xy 25.38862 -109.820808) (xy 25.368697 -109.768717) (xy 25.356571 -109.71428) (xy 25.3525 -109.658658)
			(xy 19.498203 -109.658658) (xy 19.507599 -109.67286) (xy 19.531271 -109.723357) (xy 19.547339 -109.776764)
			(xy 19.555459 -109.83194) (xy 19.555968 -109.859826) (xy 19.555459 -109.887712) (xy 19.547339 -109.942888)
			(xy 19.531271 -109.996295) (xy 19.507599 -110.046792) (xy 19.476826 -110.093305) (xy 19.439609 -110.134842)
			(xy 19.396741 -110.170517) (xy 19.349135 -110.199571) (xy 19.297806 -110.221383) (xy 19.243849 -110.235489)
			(xy 19.188412 -110.241589) (xy 19.132678 -110.239552) (xy 19.077835 -110.229422) (xy 19.025051 -110.211415)
			(xy 18.975451 -110.185914) (xy 18.930093 -110.153463) (xy 18.889944 -110.114754) (xy 18.855858 -110.070611)
			(xy 18.828562 -110.021976) (xy 18.808639 -109.969885) (xy 18.796513 -109.915448) (xy 18.792442 -109.859826)
			(xy 6.055868 -109.859826) (xy 6.055868 -110.604554) (xy 13.283182 -110.604554) (xy 13.287253 -110.548932)
			(xy 13.299379 -110.494495) (xy 13.319302 -110.442404) (xy 13.346598 -110.393769) (xy 13.380684 -110.349626)
			(xy 13.420833 -110.310917) (xy 13.466191 -110.278466) (xy 13.515791 -110.252965) (xy 13.568575 -110.234958)
			(xy 13.623418 -110.224828) (xy 13.679152 -110.222791) (xy 13.734589 -110.228891) (xy 13.788546 -110.242997)
			(xy 13.839875 -110.264809) (xy 13.887481 -110.293863) (xy 13.930349 -110.329538) (xy 13.967566 -110.371075)
			(xy 13.998339 -110.417588) (xy 14.022011 -110.468085) (xy 14.026465 -110.482888) (xy 15.912082 -110.482888)
			(xy 15.916153 -110.427266) (xy 15.928279 -110.372829) (xy 15.948202 -110.320738) (xy 15.975498 -110.272103)
			(xy 16.009584 -110.22796) (xy 16.049733 -110.189251) (xy 16.095091 -110.1568) (xy 16.144691 -110.131299)
			(xy 16.197475 -110.113292) (xy 16.252318 -110.103162) (xy 16.308052 -110.101125) (xy 16.363489 -110.107225)
			(xy 16.417446 -110.121331) (xy 16.468775 -110.143143) (xy 16.516381 -110.172197) (xy 16.559249 -110.207872)
			(xy 16.596466 -110.249409) (xy 16.627239 -110.295922) (xy 16.650911 -110.346419) (xy 16.666979 -110.399826)
			(xy 16.675099 -110.455002) (xy 16.675608 -110.482888) (xy 16.675099 -110.510774) (xy 16.666979 -110.56595)
			(xy 16.650911 -110.619357) (xy 16.627239 -110.669854) (xy 16.596466 -110.716367) (xy 16.559249 -110.757904)
			(xy 16.516381 -110.793579) (xy 16.468775 -110.822633) (xy 16.417446 -110.844445) (xy 16.363489 -110.858551)
			(xy 16.308052 -110.864651) (xy 16.252318 -110.862614) (xy 16.197475 -110.852484) (xy 16.144691 -110.834477)
			(xy 16.095091 -110.808976) (xy 16.049733 -110.776525) (xy 16.009584 -110.737816) (xy 15.975498 -110.693673)
			(xy 15.948202 -110.645038) (xy 15.928279 -110.592947) (xy 15.916153 -110.53851) (xy 15.912082 -110.482888)
			(xy 14.026465 -110.482888) (xy 14.038079 -110.521492) (xy 14.046199 -110.576668) (xy 14.046708 -110.604554)
			(xy 14.046199 -110.63244) (xy 14.038079 -110.687616) (xy 14.022011 -110.741023) (xy 13.998339 -110.79152)
			(xy 13.967566 -110.838033) (xy 13.933704 -110.875826) (xy 18.799046 -110.875826) (xy 18.803117 -110.820204)
			(xy 18.815243 -110.765767) (xy 18.835166 -110.713676) (xy 18.862462 -110.665041) (xy 18.896548 -110.620898)
			(xy 18.936697 -110.582189) (xy 18.982055 -110.549738) (xy 19.031655 -110.524237) (xy 19.084439 -110.50623)
			(xy 19.139282 -110.4961) (xy 19.195016 -110.494063) (xy 19.250453 -110.500163) (xy 19.30441 -110.514269)
			(xy 19.355739 -110.536081) (xy 19.403345 -110.565135) (xy 19.429957 -110.587282) (xy 37.558216 -110.587282)
			(xy 37.562287 -110.53166) (xy 37.574413 -110.477223) (xy 37.594336 -110.425132) (xy 37.621632 -110.376497)
			(xy 37.655718 -110.332354) (xy 37.695867 -110.293645) (xy 37.741225 -110.261194) (xy 37.790825 -110.235693)
			(xy 37.843609 -110.217686) (xy 37.898452 -110.207556) (xy 37.954186 -110.205519) (xy 38.009623 -110.211619)
			(xy 38.06358 -110.225725) (xy 38.114909 -110.247537) (xy 38.162515 -110.276591) (xy 38.205383 -110.312266)
			(xy 38.219434 -110.327948) (xy 38.435786 -110.327948) (xy 38.439857 -110.272326) (xy 38.451983 -110.217889)
			(xy 38.471906 -110.165798) (xy 38.499202 -110.117163) (xy 38.533288 -110.07302) (xy 38.573437 -110.034311)
			(xy 38.618795 -110.00186) (xy 38.668395 -109.976359) (xy 38.721179 -109.958352) (xy 38.776022 -109.948222)
			(xy 38.831756 -109.946185) (xy 38.887193 -109.952285) (xy 38.94115 -109.966391) (xy 38.992479 -109.988203)
			(xy 39.040085 -110.017257) (xy 39.082953 -110.052932) (xy 39.12017 -110.094469) (xy 39.150943 -110.140982)
			(xy 39.174615 -110.191479) (xy 39.190683 -110.244886) (xy 39.198803 -110.300062) (xy 39.199312 -110.327948)
			(xy 39.198803 -110.355834) (xy 39.190683 -110.41101) (xy 39.174615 -110.464417) (xy 39.150943 -110.514914)
			(xy 39.12017 -110.561427) (xy 39.097004 -110.587282) (xy 41.255186 -110.587282) (xy 41.259257 -110.53166)
			(xy 41.271383 -110.477223) (xy 41.291306 -110.425132) (xy 41.318602 -110.376497) (xy 41.352688 -110.332354)
			(xy 41.392837 -110.293645) (xy 41.438195 -110.261194) (xy 41.487795 -110.235693) (xy 41.540579 -110.217686)
			(xy 41.595422 -110.207556) (xy 41.651156 -110.205519) (xy 41.706593 -110.211619) (xy 41.76055 -110.225725)
			(xy 41.811879 -110.247537) (xy 41.859485 -110.276591) (xy 41.902353 -110.312266) (xy 41.93957 -110.353803)
			(xy 41.970343 -110.400316) (xy 41.994015 -110.450813) (xy 42.010083 -110.50422) (xy 42.018203 -110.559396)
			(xy 42.018712 -110.587282) (xy 42.018203 -110.615168) (xy 42.010083 -110.670344) (xy 41.994015 -110.723751)
			(xy 41.970343 -110.774248) (xy 41.93957 -110.820761) (xy 41.902353 -110.862298) (xy 41.859485 -110.897973)
			(xy 41.811879 -110.927027) (xy 41.76055 -110.948839) (xy 41.706593 -110.962945) (xy 41.651156 -110.969045)
			(xy 41.595422 -110.967008) (xy 41.540579 -110.956878) (xy 41.487795 -110.938871) (xy 41.438195 -110.91337)
			(xy 41.392837 -110.880919) (xy 41.352688 -110.84221) (xy 41.318602 -110.798067) (xy 41.291306 -110.749432)
			(xy 41.271383 -110.697341) (xy 41.259257 -110.642904) (xy 41.255186 -110.587282) (xy 39.097004 -110.587282)
			(xy 39.082953 -110.602964) (xy 39.040085 -110.638639) (xy 38.992479 -110.667693) (xy 38.94115 -110.689505)
			(xy 38.887193 -110.703611) (xy 38.831756 -110.709711) (xy 38.776022 -110.707674) (xy 38.721179 -110.697544)
			(xy 38.668395 -110.679537) (xy 38.618795 -110.654036) (xy 38.573437 -110.621585) (xy 38.533288 -110.582876)
			(xy 38.499202 -110.538733) (xy 38.471906 -110.490098) (xy 38.451983 -110.438007) (xy 38.439857 -110.38357)
			(xy 38.435786 -110.327948) (xy 38.219434 -110.327948) (xy 38.2426 -110.353803) (xy 38.273373 -110.400316)
			(xy 38.297045 -110.450813) (xy 38.313113 -110.50422) (xy 38.321233 -110.559396) (xy 38.321742 -110.587282)
			(xy 38.321233 -110.615168) (xy 38.313113 -110.670344) (xy 38.297045 -110.723751) (xy 38.273373 -110.774248)
			(xy 38.2426 -110.820761) (xy 38.205383 -110.862298) (xy 38.162515 -110.897973) (xy 38.114909 -110.927027)
			(xy 38.06358 -110.948839) (xy 38.009623 -110.962945) (xy 37.954186 -110.969045) (xy 37.898452 -110.967008)
			(xy 37.843609 -110.956878) (xy 37.790825 -110.938871) (xy 37.741225 -110.91337) (xy 37.695867 -110.880919)
			(xy 37.655718 -110.84221) (xy 37.621632 -110.798067) (xy 37.594336 -110.749432) (xy 37.574413 -110.697341)
			(xy 37.562287 -110.642904) (xy 37.558216 -110.587282) (xy 19.429957 -110.587282) (xy 19.446213 -110.60081)
			(xy 19.48343 -110.642347) (xy 19.514203 -110.68886) (xy 19.537875 -110.739357) (xy 19.553943 -110.792764)
			(xy 19.562063 -110.84794) (xy 19.562572 -110.875826) (xy 19.562063 -110.903712) (xy 19.553943 -110.958888)
			(xy 19.537875 -111.012295) (xy 19.514203 -111.062792) (xy 19.48343 -111.109305) (xy 19.446213 -111.150842)
			(xy 19.403345 -111.186517) (xy 19.355739 -111.215571) (xy 19.30441 -111.237383) (xy 19.250453 -111.251489)
			(xy 19.195016 -111.257589) (xy 19.139282 -111.255552) (xy 19.084439 -111.245422) (xy 19.031655 -111.227415)
			(xy 18.982055 -111.201914) (xy 18.936697 -111.169463) (xy 18.896548 -111.130754) (xy 18.862462 -111.086611)
			(xy 18.835166 -111.037976) (xy 18.815243 -110.985885) (xy 18.803117 -110.931448) (xy 18.799046 -110.875826)
			(xy 13.933704 -110.875826) (xy 13.930349 -110.87957) (xy 13.887481 -110.915245) (xy 13.839875 -110.944299)
			(xy 13.788546 -110.966111) (xy 13.734589 -110.980217) (xy 13.679152 -110.986317) (xy 13.623418 -110.98428)
			(xy 13.568575 -110.97415) (xy 13.515791 -110.956143) (xy 13.466191 -110.930642) (xy 13.420833 -110.898191)
			(xy 13.380684 -110.859482) (xy 13.346598 -110.815339) (xy 13.319302 -110.766704) (xy 13.299379 -110.714613)
			(xy 13.287253 -110.660176) (xy 13.283182 -110.604554) (xy 6.055868 -110.604554) (xy 6.055868 -111.288068)
			(xy 7.410702 -111.288068) (xy 7.414773 -111.232446) (xy 7.426899 -111.178009) (xy 7.446822 -111.125918)
			(xy 7.474118 -111.077283) (xy 7.508204 -111.03314) (xy 7.548353 -110.994431) (xy 7.593711 -110.96198)
			(xy 7.643311 -110.936479) (xy 7.696095 -110.918472) (xy 7.750938 -110.908342) (xy 7.806672 -110.906305)
			(xy 7.862109 -110.912405) (xy 7.916066 -110.926511) (xy 7.967395 -110.948323) (xy 8.015001 -110.977377)
			(xy 8.057869 -111.013052) (xy 8.095086 -111.054589) (xy 8.125859 -111.101102) (xy 8.149531 -111.151599)
			(xy 8.165599 -111.205006) (xy 8.173719 -111.260182) (xy 8.174228 -111.288068) (xy 8.173719 -111.315954)
			(xy 8.165599 -111.37113) (xy 8.161779 -111.383826) (xy 21.058122 -111.383826) (xy 21.062193 -111.328204)
			(xy 21.074319 -111.273767) (xy 21.094242 -111.221676) (xy 21.121538 -111.173041) (xy 21.155624 -111.128898)
			(xy 21.195773 -111.090189) (xy 21.241131 -111.057738) (xy 21.290731 -111.032237) (xy 21.343515 -111.01423)
			(xy 21.398358 -111.0041) (xy 21.454092 -111.002063) (xy 21.509529 -111.008163) (xy 21.563486 -111.022269)
			(xy 21.614815 -111.044081) (xy 21.662421 -111.073135) (xy 21.705289 -111.10881) (xy 21.742506 -111.150347)
			(xy 21.773279 -111.19686) (xy 21.796951 -111.247357) (xy 21.813019 -111.300764) (xy 21.821139 -111.35594)
			(xy 21.821648 -111.383826) (xy 21.821139 -111.411712) (xy 21.813019 -111.466888) (xy 21.796951 -111.520295)
			(xy 21.773279 -111.570792) (xy 21.751784 -111.603282) (xy 37.558216 -111.603282) (xy 37.562287 -111.54766)
			(xy 37.574413 -111.493223) (xy 37.594336 -111.441132) (xy 37.621632 -111.392497) (xy 37.655718 -111.348354)
			(xy 37.695867 -111.309645) (xy 37.741225 -111.277194) (xy 37.790825 -111.251693) (xy 37.843609 -111.233686)
			(xy 37.898452 -111.223556) (xy 37.954186 -111.221519) (xy 38.009623 -111.227619) (xy 38.06358 -111.241725)
			(xy 38.114909 -111.263537) (xy 38.162515 -111.292591) (xy 38.205383 -111.328266) (xy 38.2426 -111.369803)
			(xy 38.273373 -111.416316) (xy 38.297045 -111.466813) (xy 38.313113 -111.52022) (xy 38.321233 -111.575396)
			(xy 38.321742 -111.603282) (xy 38.321677 -111.606838) (xy 38.435786 -111.606838) (xy 38.439857 -111.551216)
			(xy 38.451983 -111.496779) (xy 38.471906 -111.444688) (xy 38.499202 -111.396053) (xy 38.533288 -111.35191)
			(xy 38.573437 -111.313201) (xy 38.618795 -111.28075) (xy 38.668395 -111.255249) (xy 38.721179 -111.237242)
			(xy 38.776022 -111.227112) (xy 38.831756 -111.225075) (xy 38.887193 -111.231175) (xy 38.94115 -111.245281)
			(xy 38.992479 -111.267093) (xy 39.040085 -111.296147) (xy 39.082953 -111.331822) (xy 39.12017 -111.373359)
			(xy 39.150943 -111.419872) (xy 39.174615 -111.470369) (xy 39.190683 -111.523776) (xy 39.198803 -111.578952)
			(xy 39.199312 -111.606838) (xy 41.255186 -111.606838) (xy 41.259257 -111.551216) (xy 41.271383 -111.496779)
			(xy 41.291306 -111.444688) (xy 41.318602 -111.396053) (xy 41.352688 -111.35191) (xy 41.392837 -111.313201)
			(xy 41.438195 -111.28075) (xy 41.487795 -111.255249) (xy 41.540579 -111.237242) (xy 41.595422 -111.227112)
			(xy 41.651156 -111.225075) (xy 41.706593 -111.231175) (xy 41.76055 -111.245281) (xy 41.811879 -111.267093)
			(xy 41.859485 -111.296147) (xy 41.902353 -111.331822) (xy 41.93957 -111.373359) (xy 41.970343 -111.419872)
			(xy 41.994015 -111.470369) (xy 42.010083 -111.523776) (xy 42.018203 -111.578952) (xy 42.018712 -111.606838)
			(xy 42.018203 -111.634724) (xy 42.010083 -111.6899) (xy 41.994015 -111.743307) (xy 41.970343 -111.793804)
			(xy 41.93957 -111.840317) (xy 41.902353 -111.881854) (xy 41.859485 -111.917529) (xy 41.811879 -111.946583)
			(xy 41.76055 -111.968395) (xy 41.706593 -111.982501) (xy 41.651156 -111.988601) (xy 41.595422 -111.986564)
			(xy 41.540579 -111.976434) (xy 41.487795 -111.958427) (xy 41.438195 -111.932926) (xy 41.392837 -111.900475)
			(xy 41.352688 -111.861766) (xy 41.318602 -111.817623) (xy 41.291306 -111.768988) (xy 41.271383 -111.716897)
			(xy 41.259257 -111.66246) (xy 41.255186 -111.606838) (xy 39.199312 -111.606838) (xy 39.198803 -111.634724)
			(xy 39.190683 -111.6899) (xy 39.174615 -111.743307) (xy 39.150943 -111.793804) (xy 39.12017 -111.840317)
			(xy 39.082953 -111.881854) (xy 39.040085 -111.917529) (xy 38.992479 -111.946583) (xy 38.94115 -111.968395)
			(xy 38.887193 -111.982501) (xy 38.831756 -111.988601) (xy 38.776022 -111.986564) (xy 38.721179 -111.976434)
			(xy 38.668395 -111.958427) (xy 38.618795 -111.932926) (xy 38.573437 -111.900475) (xy 38.533288 -111.861766)
			(xy 38.499202 -111.817623) (xy 38.471906 -111.768988) (xy 38.451983 -111.716897) (xy 38.439857 -111.66246)
			(xy 38.435786 -111.606838) (xy 38.321677 -111.606838) (xy 38.321233 -111.631168) (xy 38.313113 -111.686344)
			(xy 38.297045 -111.739751) (xy 38.273373 -111.790248) (xy 38.2426 -111.836761) (xy 38.205383 -111.878298)
			(xy 38.162515 -111.913973) (xy 38.114909 -111.943027) (xy 38.06358 -111.964839) (xy 38.009623 -111.978945)
			(xy 37.954186 -111.985045) (xy 37.898452 -111.983008) (xy 37.843609 -111.972878) (xy 37.790825 -111.954871)
			(xy 37.741225 -111.92937) (xy 37.695867 -111.896919) (xy 37.655718 -111.85821) (xy 37.621632 -111.814067)
			(xy 37.594336 -111.765432) (xy 37.574413 -111.713341) (xy 37.562287 -111.658904) (xy 37.558216 -111.603282)
			(xy 21.751784 -111.603282) (xy 21.742506 -111.617305) (xy 21.705289 -111.658842) (xy 21.662421 -111.694517)
			(xy 21.614815 -111.723571) (xy 21.563486 -111.745383) (xy 21.509529 -111.759489) (xy 21.454092 -111.765589)
			(xy 21.398358 -111.763552) (xy 21.343515 -111.753422) (xy 21.290731 -111.735415) (xy 21.241131 -111.709914)
			(xy 21.195773 -111.677463) (xy 21.155624 -111.638754) (xy 21.121538 -111.594611) (xy 21.094242 -111.545976)
			(xy 21.074319 -111.493885) (xy 21.062193 -111.439448) (xy 21.058122 -111.383826) (xy 8.161779 -111.383826)
			(xy 8.149531 -111.424537) (xy 8.125859 -111.475034) (xy 8.095086 -111.521547) (xy 8.057869 -111.563084)
			(xy 8.015001 -111.598759) (xy 7.967395 -111.627813) (xy 7.916066 -111.649625) (xy 7.862109 -111.663731)
			(xy 7.806672 -111.669831) (xy 7.750938 -111.667794) (xy 7.696095 -111.657664) (xy 7.643311 -111.639657)
			(xy 7.593711 -111.614156) (xy 7.548353 -111.581705) (xy 7.508204 -111.542996) (xy 7.474118 -111.498853)
			(xy 7.446822 -111.450218) (xy 7.426899 -111.398127) (xy 7.414773 -111.34369) (xy 7.410702 -111.288068)
			(xy 6.055868 -111.288068) (xy 6.055868 -112.625886) (xy 6.458204 -113.028222) (xy 13.52753 -113.028222)
			(xy 13.531601 -112.9726) (xy 13.543727 -112.918163) (xy 13.56365 -112.866072) (xy 13.590946 -112.817437)
			(xy 13.625032 -112.773294) (xy 13.665181 -112.734585) (xy 13.710539 -112.702134) (xy 13.760139 -112.676633)
			(xy 13.812923 -112.658626) (xy 13.867766 -112.648496) (xy 13.9235 -112.646459) (xy 13.978937 -112.652559)
			(xy 14.032894 -112.666665) (xy 14.084223 -112.688477) (xy 14.093204 -112.693958) (xy 16.982692 -112.693958)
			(xy 16.986763 -112.638336) (xy 16.998889 -112.583899) (xy 17.018812 -112.531808) (xy 17.046108 -112.483173)
			(xy 17.080194 -112.43903) (xy 17.120343 -112.400321) (xy 17.165701 -112.36787) (xy 17.215301 -112.342369)
			(xy 17.268085 -112.324362) (xy 17.322928 -112.314232) (xy 17.378662 -112.312195) (xy 17.434099 -112.318295)
			(xy 17.488056 -112.332401) (xy 17.539385 -112.354213) (xy 17.586991 -112.383267) (xy 17.629859 -112.418942)
			(xy 17.667076 -112.460479) (xy 17.697849 -112.506992) (xy 17.721521 -112.557489) (xy 17.737589 -112.610896)
			(xy 17.738823 -112.619282) (xy 37.558216 -112.619282) (xy 37.562287 -112.56366) (xy 37.574413 -112.509223)
			(xy 37.594336 -112.457132) (xy 37.621632 -112.408497) (xy 37.655718 -112.364354) (xy 37.695867 -112.325645)
			(xy 37.741225 -112.293194) (xy 37.790825 -112.267693) (xy 37.843609 -112.249686) (xy 37.898452 -112.239556)
			(xy 37.954186 -112.237519) (xy 38.009623 -112.243619) (xy 38.06358 -112.257725) (xy 38.114909 -112.279537)
			(xy 38.162515 -112.308591) (xy 38.205383 -112.344266) (xy 38.2426 -112.385803) (xy 38.273373 -112.432316)
			(xy 38.297045 -112.482813) (xy 38.313113 -112.53622) (xy 38.321233 -112.591396) (xy 38.321445 -112.603026)
			(xy 41.255186 -112.603026) (xy 41.259257 -112.547404) (xy 41.271383 -112.492967) (xy 41.291306 -112.440876)
			(xy 41.318602 -112.392241) (xy 41.352688 -112.348098) (xy 41.392837 -112.309389) (xy 41.438195 -112.276938)
			(xy 41.487795 -112.251437) (xy 41.540579 -112.23343) (xy 41.595422 -112.2233) (xy 41.651156 -112.221263)
			(xy 41.706593 -112.227363) (xy 41.76055 -112.241469) (xy 41.811879 -112.263281) (xy 41.859485 -112.292335)
			(xy 41.902353 -112.32801) (xy 41.93957 -112.369547) (xy 41.970343 -112.41606) (xy 41.994015 -112.466557)
			(xy 42.010083 -112.519964) (xy 42.018203 -112.57514) (xy 42.018712 -112.603026) (xy 42.018203 -112.630912)
			(xy 42.010083 -112.686088) (xy 41.994015 -112.739495) (xy 41.970343 -112.789992) (xy 41.93957 -112.836505)
			(xy 41.902353 -112.878042) (xy 41.859485 -112.913717) (xy 41.811879 -112.942771) (xy 41.76055 -112.964583)
			(xy 41.706593 -112.978689) (xy 41.651156 -112.984789) (xy 41.595422 -112.982752) (xy 41.540579 -112.972622)
			(xy 41.487795 -112.954615) (xy 41.438195 -112.929114) (xy 41.392837 -112.896663) (xy 41.352688 -112.857954)
			(xy 41.318602 -112.813811) (xy 41.291306 -112.765176) (xy 41.271383 -112.713085) (xy 41.259257 -112.658648)
			(xy 41.255186 -112.603026) (xy 38.321445 -112.603026) (xy 38.321742 -112.619282) (xy 38.321233 -112.647168)
			(xy 38.313113 -112.702344) (xy 38.297045 -112.755751) (xy 38.273373 -112.806248) (xy 38.2426 -112.852761)
			(xy 38.205383 -112.894298) (xy 38.162515 -112.929973) (xy 38.114909 -112.959027) (xy 38.06358 -112.980839)
			(xy 38.009623 -112.994945) (xy 37.954186 -113.001045) (xy 37.898452 -112.999008) (xy 37.843609 -112.988878)
			(xy 37.790825 -112.970871) (xy 37.741225 -112.94537) (xy 37.695867 -112.912919) (xy 37.655718 -112.87421)
			(xy 37.621632 -112.830067) (xy 37.594336 -112.781432) (xy 37.574413 -112.729341) (xy 37.562287 -112.674904)
			(xy 37.558216 -112.619282) (xy 17.738823 -112.619282) (xy 17.745709 -112.666072) (xy 17.746218 -112.693958)
			(xy 17.745709 -112.721844) (xy 17.737589 -112.77702) (xy 17.721521 -112.830427) (xy 17.697849 -112.880924)
			(xy 17.667076 -112.927437) (xy 17.629859 -112.968974) (xy 17.586991 -113.004649) (xy 17.539385 -113.033703)
			(xy 17.488056 -113.055515) (xy 17.434099 -113.069621) (xy 17.378662 -113.075721) (xy 17.322928 -113.073684)
			(xy 17.268085 -113.063554) (xy 17.215301 -113.045547) (xy 17.165701 -113.020046) (xy 17.120343 -112.987595)
			(xy 17.080194 -112.948886) (xy 17.046108 -112.904743) (xy 17.018812 -112.856108) (xy 16.998889 -112.804017)
			(xy 16.986763 -112.74958) (xy 16.982692 -112.693958) (xy 14.093204 -112.693958) (xy 14.131829 -112.717531)
			(xy 14.174697 -112.753206) (xy 14.211914 -112.794743) (xy 14.242687 -112.841256) (xy 14.266359 -112.891753)
			(xy 14.282427 -112.94516) (xy 14.290547 -113.000336) (xy 14.291056 -113.028222) (xy 14.290547 -113.056108)
			(xy 14.282427 -113.111284) (xy 14.266359 -113.164691) (xy 14.242687 -113.215188) (xy 14.211914 -113.261701)
			(xy 14.174697 -113.303238) (xy 14.131829 -113.338913) (xy 14.084223 -113.367967) (xy 14.032894 -113.389779)
			(xy 13.978937 -113.403885) (xy 13.9235 -113.409985) (xy 13.867766 -113.407948) (xy 13.812923 -113.397818)
			(xy 13.760139 -113.379811) (xy 13.710539 -113.35431) (xy 13.665181 -113.321859) (xy 13.625032 -113.28315)
			(xy 13.590946 -113.239007) (xy 13.56365 -113.190372) (xy 13.543727 -113.138281) (xy 13.531601 -113.083844)
			(xy 13.52753 -113.028222) (xy 6.458204 -113.028222) (xy 7.06374 -113.633758) (xy 20.320762 -113.633758)
			(xy 20.321222 -113.607132) (xy 20.328633 -113.554398) (xy 20.343306 -113.503207) (xy 20.364955 -113.454553)
			(xy 20.393159 -113.409383) (xy 20.42737 -113.368574) (xy 20.466924 -113.332919) (xy 20.511052 -113.30311)
			(xy 20.558897 -113.279728) (xy 20.609528 -113.263226) (xy 20.661962 -113.253926) (xy 20.688554 -113.252504)
			(xy 20.702729 -113.251584) (xy 20.729727 -113.242771) (xy 20.753259 -113.226874) (xy 20.771513 -113.205118)
			(xy 20.78308 -113.179181) (xy 20.787068 -113.151063) (xy 20.785582 -113.136934) (xy 20.783825 -113.123732)
			(xy 20.781916 -113.097165) (xy 20.781772 -113.083848) (xy 20.782258 -113.056597) (xy 20.790014 -113.002649)
			(xy 20.805369 -112.950354) (xy 20.828011 -112.900777) (xy 20.857477 -112.854927) (xy 20.893168 -112.813736)
			(xy 20.934359 -112.778045) (xy 20.980209 -112.748579) (xy 21.029786 -112.725937) (xy 21.082081 -112.710582)
			(xy 21.136029 -112.702826) (xy 21.190531 -112.702826) (xy 21.244479 -112.710582) (xy 21.296774 -112.725937)
			(xy 21.346351 -112.748579) (xy 21.392201 -112.778045) (xy 21.433392 -112.813736) (xy 21.469083 -112.854927)
			(xy 21.498549 -112.900777) (xy 21.521191 -112.950354) (xy 21.536546 -113.002649) (xy 21.544302 -113.056597)
			(xy 21.544788 -113.083848) (xy 21.544381 -113.110476) (xy 21.536968 -113.163215) (xy 21.522293 -113.21441)
			(xy 21.50064 -113.263067) (xy 21.472431 -113.308239) (xy 21.438213 -113.349049) (xy 21.398653 -113.384705)
			(xy 21.354519 -113.414511) (xy 21.306668 -113.437891) (xy 21.25603 -113.454388) (xy 21.203591 -113.463683)
			(xy 21.176996 -113.465102) (xy 21.162837 -113.466167) (xy 21.135856 -113.474957) (xy 21.112332 -113.490827)
			(xy 21.094079 -113.512553) (xy 21.082502 -113.538461) (xy 21.078495 -113.566553) (xy 21.079968 -113.580672)
			(xy 21.081726 -113.593874) (xy 21.083634 -113.620441) (xy 21.083778 -113.633758) (xy 21.08341 -113.656788)
			(xy 21.077803 -113.702506) (xy 21.072602 -113.724944) (xy 21.06956 -113.739327) (xy 21.070981 -113.76868)
			(xy 21.080672 -113.796424) (xy 21.097836 -113.820279) (xy 21.121063 -113.838283) (xy 21.134578 -113.84407)
			(xy 21.161014 -113.854984) (xy 21.210601 -113.883475) (xy 21.255376 -113.919052) (xy 21.294337 -113.960917)
			(xy 21.326608 -114.008131) (xy 21.351466 -114.059635) (xy 21.368354 -114.114273) (xy 21.376892 -114.170821)
			(xy 21.377402 -114.199416) (xy 21.376916 -114.226667) (xy 21.36916 -114.280615) (xy 21.357427 -114.320574)
			(xy 23.605488 -114.320574) (xy 23.609559 -114.264952) (xy 23.621685 -114.210515) (xy 23.641608 -114.158424)
			(xy 23.668904 -114.109789) (xy 23.70299 -114.065646) (xy 23.743139 -114.026937) (xy 23.788497 -113.994486)
			(xy 23.838097 -113.968985) (xy 23.890881 -113.950978) (xy 23.945724 -113.940848) (xy 24.001458 -113.938811)
			(xy 24.056895 -113.944911) (xy 24.110852 -113.959017) (xy 24.162181 -113.980829) (xy 24.209787 -114.009883)
			(xy 24.252655 -114.045558) (xy 24.289872 -114.087095) (xy 24.299502 -114.101651) (xy 38.572403 -114.101651)
			(xy 38.572403 -114.047149) (xy 38.58016 -113.993201) (xy 38.595516 -113.940907) (xy 38.618159 -113.89133)
			(xy 38.647627 -113.845481) (xy 38.683321 -113.804292) (xy 38.724513 -113.768603) (xy 38.770365 -113.73914)
			(xy 38.819944 -113.716502) (xy 38.87224 -113.701152) (xy 38.926189 -113.6934) (xy 38.95344 -113.69294)
			(xy 38.980909 -113.693451) (xy 39.035279 -113.70133) (xy 39.087958 -113.71692) (xy 39.13786 -113.739899)
			(xy 39.183953 -113.769793) (xy 39.225286 -113.805984) (xy 39.243508 -113.826544) (xy 39.253723 -113.83756)
			(xy 39.279041 -113.853696) (xy 39.307956 -113.861777) (xy 39.337971 -113.861104) (xy 39.366495 -113.851737)
			(xy 39.391065 -113.834484) (xy 39.400734 -113.822988) (xy 39.418903 -113.800486) (xy 39.460928 -113.760752)
			(xy 39.508467 -113.727816) (xy 39.560433 -113.702431) (xy 39.615634 -113.685179) (xy 39.672807 -113.676454)
			(xy 39.701724 -113.675922) (xy 39.728847 -113.676396) (xy 39.782549 -113.684052) (xy 39.834626 -113.699234)
			(xy 39.884029 -113.721637) (xy 39.929763 -113.750809) (xy 39.950644 -113.768124) (xy 39.961777 -113.77714)
			(xy 39.987813 -113.789066) (xy 40.01614 -113.793275) (xy 40.044519 -113.789434) (xy 40.070707 -113.777846)
			(xy 40.092636 -113.759428) (xy 40.101012 -113.747804) (xy 40.11625 -113.725879) (xy 40.151941 -113.686165)
			(xy 40.192818 -113.651812) (xy 40.238084 -113.623491) (xy 40.286854 -113.601753) (xy 40.338177 -113.587024)
			(xy 40.391052 -113.57959) (xy 40.41775 -113.579148) (xy 40.445002 -113.579696) (xy 40.498952 -113.587446)
			(xy 40.55125 -113.602796) (xy 40.600831 -113.625433) (xy 40.646685 -113.654896) (xy 40.687879 -113.690586)
			(xy 40.723574 -113.731775) (xy 40.753043 -113.777625) (xy 40.775686 -113.827203) (xy 40.791043 -113.879499)
			(xy 40.798801 -113.933448) (xy 40.798801 -113.987952) (xy 40.791043 -114.041901) (xy 40.775686 -114.094197)
			(xy 40.753043 -114.143775) (xy 40.723574 -114.189625) (xy 40.687879 -114.230814) (xy 40.646685 -114.266504)
			(xy 40.600831 -114.295967) (xy 40.55125 -114.318604) (xy 40.498952 -114.333954) (xy 40.445002 -114.341704)
			(xy 40.41775 -114.342164) (xy 40.390627 -114.341708) (xy 40.336923 -114.334048) (xy 40.284846 -114.318862)
			(xy 40.235443 -114.296455) (xy 40.189711 -114.267279) (xy 40.16883 -114.249962) (xy 40.157635 -114.241031)
			(xy 40.131619 -114.229099) (xy 40.10331 -114.224879) (xy 40.074945 -114.228704) (xy 40.048765 -114.240272)
			(xy 40.026839 -114.258669) (xy 40.018462 -114.270282) (xy 40.003172 -114.29217) (xy 39.96749 -114.331885)
			(xy 39.926622 -114.366241) (xy 39.881366 -114.394567) (xy 39.832604 -114.416311) (xy 39.781288 -114.431048)
			(xy 39.728419 -114.43849) (xy 39.701724 -114.438938) (xy 39.674254 -114.438459) (xy 39.619882 -114.430575)
			(xy 39.567202 -114.414979) (xy 39.5173 -114.391993) (xy 39.471208 -114.362094) (xy 39.429877 -114.325897)
			(xy 39.411656 -114.305334) (xy 39.401477 -114.294284) (xy 39.376148 -114.278153) (xy 39.347224 -114.270078)
			(xy 39.317202 -114.270758) (xy 39.288674 -114.280132) (xy 39.2641 -114.297391) (xy 39.25443 -114.30889)
			(xy 39.23622 -114.331357) (xy 39.194204 -114.371094) (xy 39.146673 -114.404035) (xy 39.094716 -114.429426)
			(xy 39.039522 -114.446686) (xy 38.982355 -114.455419) (xy 38.95344 -114.455956) (xy 38.926189 -114.4554)
			(xy 38.87224 -114.447648) (xy 38.819944 -114.432298) (xy 38.770365 -114.40966) (xy 38.724513 -114.380197)
			(xy 38.683321 -114.344508) (xy 38.647627 -114.303319) (xy 38.618159 -114.25747) (xy 38.595516 -114.207893)
			(xy 38.58016 -114.155599) (xy 38.572403 -114.101651) (xy 24.299502 -114.101651) (xy 24.320645 -114.133608)
			(xy 24.344317 -114.184105) (xy 24.360385 -114.237512) (xy 24.368505 -114.292688) (xy 24.369014 -114.320574)
			(xy 24.368505 -114.34846) (xy 24.360385 -114.403636) (xy 24.344317 -114.457043) (xy 24.320645 -114.50754)
			(xy 24.289872 -114.554053) (xy 24.252655 -114.59559) (xy 24.209787 -114.631265) (xy 24.162181 -114.660319)
			(xy 24.110852 -114.682131) (xy 24.056895 -114.696237) (xy 24.001458 -114.702337) (xy 23.945724 -114.7003)
			(xy 23.890881 -114.69017) (xy 23.838097 -114.672163) (xy 23.788497 -114.646662) (xy 23.743139 -114.614211)
			(xy 23.70299 -114.575502) (xy 23.668904 -114.531359) (xy 23.641608 -114.482724) (xy 23.621685 -114.430633)
			(xy 23.609559 -114.376196) (xy 23.605488 -114.320574) (xy 21.357427 -114.320574) (xy 21.353805 -114.33291)
			(xy 21.331163 -114.382487) (xy 21.301697 -114.428337) (xy 21.266006 -114.469528) (xy 21.224815 -114.505219)
			(xy 21.178965 -114.534685) (xy 21.129388 -114.557327) (xy 21.077093 -114.572682) (xy 21.023145 -114.580438)
			(xy 20.968643 -114.580438) (xy 20.914695 -114.572682) (xy 20.8624 -114.557327) (xy 20.812823 -114.534685)
			(xy 20.766973 -114.505219) (xy 20.725782 -114.469528) (xy 20.690091 -114.428337) (xy 20.660625 -114.382487)
			(xy 20.637983 -114.33291) (xy 20.622628 -114.280615) (xy 20.614872 -114.226667) (xy 20.614386 -114.199416)
			(xy 20.614752 -114.176386) (xy 20.620351 -114.130666) (xy 20.625562 -114.10823) (xy 20.628551 -114.093837)
			(xy 20.627148 -114.064489) (xy 20.617472 -114.036746) (xy 20.600318 -114.012892) (xy 20.577098 -113.99489)
			(xy 20.563586 -113.989104) (xy 20.537133 -113.978231) (xy 20.487546 -113.949733) (xy 20.442771 -113.914149)
			(xy 20.403813 -113.872278) (xy 20.371544 -113.825058) (xy 20.346689 -113.773549) (xy 20.329805 -113.718906)
			(xy 20.32127 -113.662354) (xy 20.320762 -113.633758) (xy 7.06374 -113.633758) (xy 8.441944 -115.011962)
		)
		(stroke
			(width 0)
			(type solid)
		)
		(fill yes)
		(layer "In13.Cu")
		(net "P3V3_AUX")
	)
	(gr_poly
		(pts
			(xy 89.532206 -265.797792) (xy 89.553362 -265.789687) (xy 89.597207 -265.778277) (xy 89.642142 -265.7725)
			(xy 89.664794 -265.772138) (xy 89.687448 -265.77249) (xy 89.732388 -265.778245) (xy 89.776229 -265.789675)
			(xy 89.797382 -265.797792) (xy 89.806272 -265.801348) (xy 90.463116 -265.801348) (xy 90.472006 -265.797792)
			(xy 90.493162 -265.789687) (xy 90.537007 -265.778277) (xy 90.581942 -265.7725) (xy 90.604594 -265.772138)
			(xy 90.627248 -265.77249) (xy 90.672188 -265.778245) (xy 90.716029 -265.789675) (xy 90.737182 -265.797792)
			(xy 90.746072 -265.801348) (xy 91.402916 -265.801348) (xy 91.411806 -265.797792) (xy 91.432962 -265.789687)
			(xy 91.476807 -265.778277) (xy 91.521742 -265.7725) (xy 91.544394 -265.772138) (xy 91.567048 -265.77249)
			(xy 91.611988 -265.778245) (xy 91.655829 -265.789675) (xy 91.676982 -265.797792) (xy 91.685872 -265.801348)
			(xy 92.342716 -265.801348) (xy 92.351606 -265.797792) (xy 92.372762 -265.789687) (xy 92.416607 -265.778277)
			(xy 92.461542 -265.7725) (xy 92.484194 -265.772138) (xy 92.506848 -265.77249) (xy 92.551788 -265.778245)
			(xy 92.595629 -265.789675) (xy 92.616782 -265.797792) (xy 92.625672 -265.801348) (xy 93.282516 -265.801348)
			(xy 93.291406 -265.797792) (xy 93.312562 -265.789687) (xy 93.356407 -265.778277) (xy 93.401342 -265.7725)
			(xy 93.423994 -265.772138) (xy 93.446648 -265.77249) (xy 93.491588 -265.778245) (xy 93.535429 -265.789675)
			(xy 93.556582 -265.797792) (xy 93.565472 -265.801348) (xy 94.222316 -265.801348) (xy 94.231206 -265.797792)
			(xy 94.252362 -265.789687) (xy 94.296207 -265.778277) (xy 94.341142 -265.7725) (xy 94.363794 -265.772138)
			(xy 94.386448 -265.77249) (xy 94.431388 -265.778245) (xy 94.475229 -265.789675) (xy 94.496382 -265.797792)
			(xy 94.505272 -265.801348) (xy 95.162116 -265.801348) (xy 95.171006 -265.797792) (xy 95.192162 -265.789687)
			(xy 95.236007 -265.778277) (xy 95.280942 -265.7725) (xy 95.303594 -265.772138) (xy 95.326248 -265.77249)
			(xy 95.371188 -265.778245) (xy 95.415029 -265.789675) (xy 95.436182 -265.797792) (xy 95.445072 -265.801348)
			(xy 96.101916 -265.801348) (xy 96.110806 -265.797792) (xy 96.131962 -265.789687) (xy 96.175807 -265.778277)
			(xy 96.220742 -265.7725) (xy 96.243394 -265.772138) (xy 96.266048 -265.77249) (xy 96.310988 -265.778245)
			(xy 96.354829 -265.789675) (xy 96.375982 -265.797792) (xy 96.384872 -265.801348) (xy 97.041716 -265.801348)
			(xy 97.050606 -265.797792) (xy 97.071762 -265.789687) (xy 97.115607 -265.778277) (xy 97.160542 -265.7725)
			(xy 97.183194 -265.772138) (xy 97.205848 -265.77249) (xy 97.250788 -265.778245) (xy 97.294629 -265.789675)
			(xy 97.315782 -265.797792) (xy 97.324672 -265.801348) (xy 97.981516 -265.801348) (xy 97.990406 -265.797792)
			(xy 98.011562 -265.789687) (xy 98.055407 -265.778277) (xy 98.100342 -265.7725) (xy 98.122994 -265.772138)
			(xy 98.145648 -265.77249) (xy 98.190588 -265.778245) (xy 98.234429 -265.789675) (xy 98.255582 -265.797792)
			(xy 98.264472 -265.801348) (xy 98.921316 -265.801348) (xy 98.930206 -265.797792) (xy 98.951362 -265.789687)
			(xy 98.995207 -265.778277) (xy 99.040142 -265.7725) (xy 99.062794 -265.772138) (xy 99.085448 -265.77249)
			(xy 99.130388 -265.778245) (xy 99.174229 -265.789675) (xy 99.195382 -265.797792) (xy 99.204272 -265.801348)
			(xy 99.861116 -265.801348) (xy 99.870006 -265.797792) (xy 99.891162 -265.789687) (xy 99.935007 -265.778277)
			(xy 99.979942 -265.7725) (xy 100.002594 -265.772138) (xy 100.025248 -265.77249) (xy 100.070188 -265.778245)
			(xy 100.114029 -265.789675) (xy 100.135182 -265.797792) (xy 100.144072 -265.801348) (xy 100.800916 -265.801348)
			(xy 100.809806 -265.797792) (xy 100.830962 -265.789687) (xy 100.874807 -265.778277) (xy 100.919742 -265.7725)
			(xy 100.942394 -265.772138) (xy 100.965048 -265.77249) (xy 101.009988 -265.778245) (xy 101.053829 -265.789675)
			(xy 101.074982 -265.797792) (xy 101.083872 -265.801348) (xy 101.740716 -265.801348) (xy 101.749606 -265.797792)
			(xy 101.770762 -265.789687) (xy 101.814607 -265.778277) (xy 101.859542 -265.7725) (xy 101.882194 -265.772138)
			(xy 101.904848 -265.77249) (xy 101.949788 -265.778245) (xy 101.993629 -265.789675) (xy 102.014782 -265.797792)
			(xy 102.023672 -265.801348) (xy 102.680516 -265.801348) (xy 102.689406 -265.797792) (xy 102.710562 -265.789687)
			(xy 102.754407 -265.778277) (xy 102.799342 -265.7725) (xy 102.821994 -265.772138) (xy 102.844648 -265.77249)
			(xy 102.889588 -265.778245) (xy 102.933429 -265.789675) (xy 102.954582 -265.797792) (xy 102.963472 -265.801348)
			(xy 103.620316 -265.801348) (xy 103.629206 -265.797792) (xy 103.650362 -265.789687) (xy 103.694207 -265.778277)
			(xy 103.739142 -265.7725) (xy 103.761794 -265.772138) (xy 103.784448 -265.77249) (xy 103.829388 -265.778245)
			(xy 103.873229 -265.789675) (xy 103.894382 -265.797792) (xy 103.903272 -265.801348) (xy 104.55148 -265.801348)
			(xy 104.861106 -265.491722) (xy 104.846882 -265.459718) (xy 104.837029 -265.436732) (xy 104.82313 -265.388692)
			(xy 104.816078 -265.339181) (xy 104.81564 -265.314176) (xy 104.81617 -265.286086) (xy 104.824994 -265.230603)
			(xy 104.842419 -265.177193) (xy 104.868012 -265.127181) (xy 104.90114 -265.081808) (xy 104.940981 -265.042197)
			(xy 104.986545 -265.009333) (xy 105.036705 -264.98403) (xy 105.090215 -264.966915) (xy 105.1179 -264.962132)
			(xy 105.16108 -264.955528) (xy 105.16108 -262.047228) (xy 104.85882 -261.744968) (xy 104.081072 -261.744968)
			(xy 104.067004 -261.745412) (xy 104.039935 -261.753082) (xy 104.015993 -261.76786) (xy 103.997001 -261.788618)
			(xy 103.984407 -261.813777) (xy 103.979168 -261.84142) (xy 103.981685 -261.869443) (xy 103.991764 -261.89571)
			(xy 103.999792 -261.907274) (xy 104.016435 -261.930508) (xy 104.042886 -261.981166) (xy 104.060917 -262.035395)
			(xy 104.070067 -262.091806) (xy 104.070658 -262.12038) (xy 104.070658 -262.120634) (xy 104.070236 -262.145302)
			(xy 104.063419 -262.194165) (xy 104.049922 -262.24162) (xy 104.030003 -262.286756) (xy 104.004043 -262.32871)
			(xy 103.988616 -262.347964) (xy 103.97999 -262.359092) (xy 103.968647 -262.38485) (xy 103.964772 -262.412726)
			(xy 103.968661 -262.440601) (xy 103.980018 -262.466353) (xy 103.988616 -262.477504) (xy 104.004051 -262.496752)
			(xy 104.03002 -262.538703) (xy 104.049941 -262.58384) (xy 104.063432 -262.631298) (xy 104.070233 -262.680165)
			(xy 104.070658 -262.704834) (xy 104.07016 -262.731483) (xy 104.062217 -262.784187) (xy 104.046507 -262.835117)
			(xy 104.023381 -262.883138) (xy 103.993357 -262.927175) (xy 103.957105 -262.966246) (xy 103.915434 -262.999477)
			(xy 103.869276 -263.026126) (xy 103.819662 -263.045598) (xy 103.7677 -263.057458) (xy 103.71455 -263.061442)
			(xy 103.6614 -263.057458) (xy 103.609438 -263.045598) (xy 103.559824 -263.026126) (xy 103.513666 -262.999477)
			(xy 103.471995 -262.966246) (xy 103.435743 -262.927175) (xy 103.405719 -262.883138) (xy 103.382593 -262.835117)
			(xy 103.366883 -262.784187) (xy 103.35894 -262.731483) (xy 103.358442 -262.704834) (xy 103.358867 -262.680167)
			(xy 103.365687 -262.631305) (xy 103.379187 -262.583854) (xy 103.399109 -262.53872) (xy 103.425072 -262.496769)
			(xy 103.440484 -262.477504) (xy 103.449119 -262.466375) (xy 103.460481 -262.440613) (xy 103.464371 -262.412726)
			(xy 103.460495 -262.384838) (xy 103.449147 -262.359069) (xy 103.440484 -262.347964) (xy 103.425051 -262.328715)
			(xy 103.399086 -262.286764) (xy 103.379169 -262.241626) (xy 103.365682 -262.194169) (xy 103.358885 -262.145303)
			(xy 103.358442 -262.120634) (xy 103.358442 -262.12038) (xy 103.359005 -262.091803) (xy 103.368133 -262.035382)
			(xy 103.386166 -261.981147) (xy 103.41264 -261.930494) (xy 103.429308 -261.907274) (xy 103.437344 -261.895739)
			(xy 103.447356 -261.869479) (xy 103.449825 -261.841485) (xy 103.444565 -261.813879) (xy 103.431975 -261.788753)
			(xy 103.41301 -261.768015) (xy 103.389107 -261.753236) (xy 103.362079 -261.745537) (xy 103.348028 -261.744968)
			(xy 102.757732 -261.744968) (xy 102.742834 -261.745525) (xy 102.714324 -261.754196) (xy 102.689527 -261.770722)
			(xy 102.67055 -261.793698) (xy 102.659008 -261.821171) (xy 102.65588 -261.850805) (xy 102.661434 -261.880083)
			(xy 102.667816 -261.893558) (xy 102.680582 -261.91919) (xy 102.69868 -261.973513) (xy 102.707874 -262.030029)
			(xy 102.708456 -262.058658) (xy 102.707958 -262.085307) (xy 102.700015 -262.138011) (xy 102.684305 -262.188941)
			(xy 102.661179 -262.236962) (xy 102.631155 -262.280999) (xy 102.594903 -262.32007) (xy 102.553232 -262.353301)
			(xy 102.507074 -262.37995) (xy 102.45746 -262.399422) (xy 102.405498 -262.411282) (xy 102.352348 -262.415266)
			(xy 102.299198 -262.411282) (xy 102.247236 -262.399422) (xy 102.197622 -262.37995) (xy 102.151464 -262.353301)
			(xy 102.109793 -262.32007) (xy 102.073541 -262.280999) (xy 102.043517 -262.236962) (xy 102.020391 -262.188941)
			(xy 102.004681 -262.138011) (xy 101.996738 -262.085307) (xy 101.99624 -262.058658) (xy 101.996811 -262.030027)
			(xy 102.005986 -261.973506) (xy 102.024108 -261.919189) (xy 102.03688 -261.893558) (xy 102.043309 -261.880102)
			(xy 102.048871 -261.850819) (xy 102.045744 -261.821177) (xy 102.034194 -261.793698) (xy 102.015204 -261.770724)
			(xy 101.990391 -261.754209) (xy 101.961867 -261.745559) (xy 101.946964 -261.744968) (xy 101.817932 -261.744968)
			(xy 101.803034 -261.745525) (xy 101.774524 -261.754196) (xy 101.749727 -261.770722) (xy 101.73075 -261.793698)
			(xy 101.719208 -261.821171) (xy 101.71608 -261.850805) (xy 101.721634 -261.880083) (xy 101.728016 -261.893558)
			(xy 101.740782 -261.91919) (xy 101.75888 -261.973513) (xy 101.768074 -262.030029) (xy 101.768656 -262.058658)
			(xy 101.768158 -262.085307) (xy 101.760215 -262.138011) (xy 101.744505 -262.188941) (xy 101.721379 -262.236962)
			(xy 101.691355 -262.280999) (xy 101.655103 -262.32007) (xy 101.613432 -262.353301) (xy 101.567274 -262.37995)
			(xy 101.51766 -262.399422) (xy 101.465698 -262.411282) (xy 101.412548 -262.415266) (xy 101.359398 -262.411282)
			(xy 101.307436 -262.399422) (xy 101.257822 -262.37995) (xy 101.211664 -262.353301) (xy 101.169993 -262.32007)
			(xy 101.133741 -262.280999) (xy 101.103717 -262.236962) (xy 101.080591 -262.188941) (xy 101.064881 -262.138011)
			(xy 101.056938 -262.085307) (xy 101.05644 -262.058658) (xy 101.057011 -262.030027) (xy 101.066186 -261.973506)
			(xy 101.084308 -261.919189) (xy 101.09708 -261.893558) (xy 101.103509 -261.880102) (xy 101.109071 -261.850819)
			(xy 101.105944 -261.821177) (xy 101.094394 -261.793698) (xy 101.075404 -261.770724) (xy 101.050591 -261.754209)
			(xy 101.022067 -261.745559) (xy 101.007164 -261.744968) (xy 100.878132 -261.744968) (xy 100.863234 -261.745525)
			(xy 100.834724 -261.754196) (xy 100.809927 -261.770722) (xy 100.79095 -261.793698) (xy 100.779408 -261.821171)
			(xy 100.77628 -261.850805) (xy 100.781834 -261.880083) (xy 100.788216 -261.893558) (xy 100.800982 -261.91919)
			(xy 100.81908 -261.973513) (xy 100.828274 -262.030029) (xy 100.828856 -262.058658) (xy 100.828358 -262.085307)
			(xy 100.820415 -262.138011) (xy 100.804705 -262.188941) (xy 100.781579 -262.236962) (xy 100.751555 -262.280999)
			(xy 100.715303 -262.32007) (xy 100.673632 -262.353301) (xy 100.627474 -262.37995) (xy 100.57786 -262.399422)
			(xy 100.525898 -262.411282) (xy 100.472748 -262.415266) (xy 100.419598 -262.411282) (xy 100.367636 -262.399422)
			(xy 100.318022 -262.37995) (xy 100.271864 -262.353301) (xy 100.230193 -262.32007) (xy 100.193941 -262.280999)
			(xy 100.163917 -262.236962) (xy 100.140791 -262.188941) (xy 100.125081 -262.138011) (xy 100.117138 -262.085307)
			(xy 100.11664 -262.058658) (xy 100.117087 -262.032952) (xy 100.124471 -261.982074) (xy 100.139093 -261.932786)
			(xy 100.16065 -261.886112) (xy 100.188694 -261.843023) (xy 100.222642 -261.804414) (xy 100.261788 -261.771087)
			(xy 100.30532 -261.743735) (xy 100.352332 -261.722926) (xy 100.401847 -261.709093) (xy 100.427282 -261.705344)
			(xy 100.441281 -261.703094) (xy 100.467328 -261.691923) (xy 100.489294 -261.674015) (xy 100.505483 -261.650752)
			(xy 100.514644 -261.623932) (xy 100.516069 -261.595626) (xy 100.509649 -261.568021) (xy 100.495879 -261.54325)
			(xy 100.48621 -261.532878) (xy 100.422964 -261.469632) (xy 100.412734 -261.460077) (xy 100.388288 -261.446461)
			(xy 100.361068 -261.439978) (xy 100.333108 -261.441113) (xy 100.306503 -261.449782) (xy 100.283241 -261.465336)
			(xy 100.273866 -261.475728) (xy 100.256853 -261.495002) (xy 100.218235 -261.528935) (xy 100.17514 -261.556964)
			(xy 100.128464 -261.578509) (xy 100.079175 -261.59312) (xy 100.028298 -261.600494) (xy 100.002594 -261.60095)
			(xy 99.97461 -261.600401) (xy 99.919331 -261.591645) (xy 99.866102 -261.574351) (xy 99.816234 -261.548943)
			(xy 99.770953 -261.516047) (xy 99.731376 -261.476474) (xy 99.698476 -261.431197) (xy 99.673063 -261.381331)
			(xy 99.655763 -261.328104) (xy 99.647002 -261.272826) (xy 99.646486 -261.244842) (xy 99.64694 -261.219139)
			(xy 99.654331 -261.168268) (xy 99.668952 -261.118986) (xy 99.690499 -261.072314) (xy 99.718526 -261.029222)
			(xy 99.752452 -260.990601) (xy 99.771708 -260.97357) (xy 99.782108 -260.96418) (xy 99.797749 -260.940945)
			(xy 99.806473 -260.914328) (xy 99.807621 -260.886342) (xy 99.801105 -260.859101) (xy 99.787419 -260.834663)
			(xy 99.777804 -260.824472) (xy 99.700334 -260.747002) (xy 99.668838 -260.759956) (xy 99.647206 -260.768471)
			(xy 99.602288 -260.780455) (xy 99.556193 -260.786496) (xy 99.532948 -260.78688) (xy 99.504961 -260.786363)
			(xy 99.449675 -260.777613) (xy 99.396439 -260.760321) (xy 99.346564 -260.734913) (xy 99.301279 -260.702015)
			(xy 99.261698 -260.662436) (xy 99.228797 -260.617153) (xy 99.203387 -260.567279) (xy 99.186092 -260.514044)
			(xy 99.177339 -260.458759) (xy 99.17684 -260.430772) (xy 99.177373 -260.402925) (xy 99.186033 -260.347909)
			(xy 99.203154 -260.294912) (xy 99.228317 -260.245227) (xy 99.260909 -260.200066) (xy 99.300135 -260.16053)
			(xy 99.345039 -260.127584) (xy 99.394524 -260.102031) (xy 99.447385 -260.084495) (xy 99.474782 -260.07949)
			(xy 99.5172 -260.072378) (xy 99.5172 -259.908548) (xy 99.516739 -259.894692) (xy 99.509298 -259.867997)
			(xy 99.494951 -259.844288) (xy 99.474756 -259.825311) (xy 99.450201 -259.812466) (xy 99.423096 -259.806698)
			(xy 99.395438 -259.808433) (xy 99.369267 -259.817544) (xy 99.34651 -259.833358) (xy 99.337368 -259.843778)
			(xy 99.320367 -259.86364) (xy 99.281537 -259.898648) (xy 99.238004 -259.927599) (xy 99.190704 -259.949872)
			(xy 99.140656 -259.964987) (xy 99.088935 -259.972618) (xy 99.062794 -259.973064) (xy 99.036148 -259.972566)
			(xy 98.983452 -259.964622) (xy 98.932529 -259.948913) (xy 98.884515 -259.925791) (xy 98.840484 -259.89577)
			(xy 98.801419 -259.859522) (xy 98.768193 -259.817857) (xy 98.741547 -259.771705) (xy 98.722078 -259.722098)
			(xy 98.710219 -259.670142) (xy 98.706237 -259.617) (xy 98.710219 -259.563858) (xy 98.722078 -259.511902)
			(xy 98.741547 -259.462295) (xy 98.768193 -259.416143) (xy 98.801419 -259.374478) (xy 98.840484 -259.33823)
			(xy 98.884515 -259.308209) (xy 98.932529 -259.285087) (xy 98.983452 -259.269378) (xy 99.036148 -259.261434)
			(xy 99.062794 -259.260848) (xy 99.088934 -259.261307) (xy 99.140652 -259.268947) (xy 99.190698 -259.284063)
			(xy 99.237998 -259.306331) (xy 99.281535 -259.335273) (xy 99.320375 -259.370267) (xy 99.337368 -259.390134)
			(xy 99.346562 -259.400497) (xy 99.369312 -259.416285) (xy 99.395468 -259.425378) (xy 99.423106 -259.427107)
			(xy 99.450191 -259.421344) (xy 99.474731 -259.408513) (xy 99.49492 -259.38956) (xy 99.509272 -259.365878)
			(xy 99.516731 -259.33921) (xy 99.5172 -259.325364) (xy 99.5172 -259.161534) (xy 99.474782 -259.154422)
			(xy 99.448834 -259.149645) (xy 99.398622 -259.133449) (xy 99.35135 -259.110021) (xy 99.308052 -259.079874)
			(xy 99.269675 -259.043669) (xy 99.237061 -259.002198) (xy 99.210922 -258.956369) (xy 99.191832 -258.907184)
			(xy 99.180208 -258.855721) (xy 99.176304 -258.803107) (xy 99.180206 -258.750492) (xy 99.191828 -258.699028)
			(xy 99.210917 -258.649843) (xy 99.237054 -258.604013) (xy 99.269666 -258.56254) (xy 99.308041 -258.526334)
			(xy 99.351339 -258.496186) (xy 99.39861 -258.472756) (xy 99.448821 -258.456558) (xy 99.474782 -258.451858)
			(xy 99.5172 -258.444746) (xy 99.5172 -258.280916) (xy 99.516735 -258.267063) (xy 99.509289 -258.240377)
			(xy 99.494941 -258.216675) (xy 99.474748 -258.197706) (xy 99.450198 -258.184865) (xy 99.423099 -258.179098)
			(xy 99.395447 -258.180832) (xy 99.36928 -258.189937) (xy 99.346526 -258.205743) (xy 99.337368 -258.216146)
			(xy 99.320367 -258.235965) (xy 99.281553 -258.270892) (xy 99.238054 -258.299776) (xy 99.190802 -258.321997)
			(xy 99.140812 -258.337079) (xy 99.089156 -258.344697) (xy 99.063048 -258.345178) (xy 99.036397 -258.344708)
			(xy 98.983689 -258.33677) (xy 98.932753 -258.321065) (xy 98.884727 -258.297942) (xy 98.840684 -258.26792)
			(xy 98.801608 -258.231668) (xy 98.768372 -258.189996) (xy 98.741719 -258.143836) (xy 98.722244 -258.094219)
			(xy 98.710382 -258.042253) (xy 98.706398 -257.9891) (xy 98.710382 -257.935947) (xy 98.722244 -257.883981)
			(xy 98.741719 -257.834364) (xy 98.768372 -257.788204) (xy 98.801608 -257.746532) (xy 98.840684 -257.71028)
			(xy 98.884727 -257.680258) (xy 98.932753 -257.657135) (xy 98.983689 -257.64143) (xy 99.036397 -257.633492)
			(xy 99.063048 -257.632962) (xy 99.089155 -257.633423) (xy 99.140809 -257.641054) (xy 99.190795 -257.656145)
			(xy 99.238042 -257.678374) (xy 99.281536 -257.707263) (xy 99.320346 -257.742193) (xy 99.337368 -257.761994)
			(xy 99.346559 -257.77236) (xy 99.369306 -257.788154) (xy 99.395462 -257.797251) (xy 99.4231 -257.798982)
			(xy 99.450187 -257.793218) (xy 99.474726 -257.780385) (xy 99.494913 -257.761428) (xy 99.50926 -257.737742)
			(xy 99.516711 -257.71107) (xy 99.5172 -257.697224) (xy 99.5172 -257.533648) (xy 99.474782 -257.526536)
			(xy 99.44883 -257.521772) (xy 99.398608 -257.505597) (xy 99.351323 -257.482186) (xy 99.308012 -257.452053)
			(xy 99.269623 -257.415856) (xy 99.236997 -257.37439) (xy 99.21085 -257.328562) (xy 99.191753 -257.279376)
			(xy 99.180125 -257.227911) (xy 99.176222 -257.175293) (xy 99.180128 -257.122675) (xy 99.191757 -257.07121)
			(xy 99.210856 -257.022025) (xy 99.237006 -256.976198) (xy 99.269633 -256.934733) (xy 99.308023 -256.898538)
			(xy 99.351336 -256.868406) (xy 99.398622 -256.844998) (xy 99.448845 -256.828825) (xy 99.474782 -256.823972)
			(xy 99.5172 -256.81686) (xy 99.5172 -256.65303) (xy 99.516737 -256.639176) (xy 99.509293 -256.612486)
			(xy 99.494946 -256.588781) (xy 99.474752 -256.569808) (xy 99.450199 -256.556965) (xy 99.423098 -256.551198)
			(xy 99.395443 -256.552932) (xy 99.369274 -256.56204) (xy 99.346519 -256.57785) (xy 99.337368 -256.58826)
			(xy 99.320367 -256.608123) (xy 99.281538 -256.643132) (xy 99.238005 -256.672085) (xy 99.190706 -256.694359)
			(xy 99.140657 -256.709475) (xy 99.088935 -256.717107) (xy 99.062794 -256.717546) (xy 99.036142 -256.717048)
			(xy 98.983434 -256.709103) (xy 98.932499 -256.69339) (xy 98.884474 -256.670262) (xy 98.840432 -256.640235)
			(xy 98.801358 -256.603978) (xy 98.768124 -256.562304) (xy 98.741473 -256.516141) (xy 98.721999 -256.466522)
			(xy 98.710138 -256.414555) (xy 98.706154 -256.3614) (xy 98.710138 -256.308245) (xy 98.721999 -256.256278)
			(xy 98.741473 -256.206659) (xy 98.768124 -256.160496) (xy 98.801358 -256.118822) (xy 98.840432 -256.082565)
			(xy 98.884474 -256.052538) (xy 98.932499 -256.02941) (xy 98.983434 -256.013697) (xy 99.036142 -256.005752)
			(xy 99.062794 -256.00533) (xy 99.088934 -256.005789) (xy 99.140652 -256.013428) (xy 99.190699 -256.028544)
			(xy 99.237999 -256.050811) (xy 99.281538 -256.079752) (xy 99.320379 -256.114745) (xy 99.337368 -256.134616)
			(xy 99.34656 -256.144981) (xy 99.369309 -256.160771) (xy 99.395465 -256.169866) (xy 99.423103 -256.171595)
			(xy 99.450189 -256.165832) (xy 99.474729 -256.153001) (xy 99.494917 -256.134045) (xy 99.509266 -256.110361)
			(xy 99.516722 -256.083692) (xy 99.5172 -256.069846) (xy 99.5172 -255.906016) (xy 99.474782 -255.898904)
			(xy 99.448835 -255.894127) (xy 99.398626 -255.877931) (xy 99.351357 -255.854504) (xy 99.308061 -255.824358)
			(xy 99.269687 -255.788155) (xy 99.237074 -255.746685) (xy 99.210938 -255.700858) (xy 99.191849 -255.651676)
			(xy 99.180225 -255.600216) (xy 99.176322 -255.547604) (xy 99.180224 -255.494991) (xy 99.191847 -255.443531)
			(xy 99.210935 -255.394348) (xy 99.23707 -255.348521) (xy 99.269682 -255.307051) (xy 99.308055 -255.270846)
			(xy 99.35135 -255.2407) (xy 99.39862 -255.217272) (xy 99.448828 -255.201075) (xy 99.474782 -255.19634)
			(xy 99.5172 -255.189228) (xy 99.5172 -255.025144) (xy 99.516739 -255.011288) (xy 99.509297 -254.984595)
			(xy 99.49495 -254.960887) (xy 99.474755 -254.941911) (xy 99.450201 -254.929066) (xy 99.423096 -254.923298)
			(xy 99.395439 -254.925033) (xy 99.369268 -254.934143) (xy 99.346512 -254.949956) (xy 99.337368 -254.960374)
			(xy 99.320367 -254.980236) (xy 99.281537 -255.015244) (xy 99.238004 -255.044196) (xy 99.190705 -255.066469)
			(xy 99.140656 -255.081584) (xy 99.088935 -255.089216) (xy 99.062794 -255.08966) (xy 99.036149 -255.089162)
			(xy 98.983453 -255.081218) (xy 98.93253 -255.06551) (xy 98.884517 -255.042387) (xy 98.840486 -255.012367)
			(xy 98.801422 -254.97612) (xy 98.768196 -254.934455) (xy 98.741551 -254.888304) (xy 98.722082 -254.838697)
			(xy 98.710223 -254.786742) (xy 98.706241 -254.7336) (xy 98.710223 -254.680458) (xy 98.722082 -254.628503)
			(xy 98.741551 -254.578896) (xy 98.768196 -254.532745) (xy 98.801422 -254.49108) (xy 98.840486 -254.454833)
			(xy 98.884517 -254.424813) (xy 98.93253 -254.40169) (xy 98.983453 -254.385982) (xy 99.036149 -254.378038)
			(xy 99.062794 -254.377444) (xy 99.088934 -254.377903) (xy 99.140652 -254.385543) (xy 99.190698 -254.400659)
			(xy 99.237998 -254.422927) (xy 99.281536 -254.451868) (xy 99.320376 -254.486862) (xy 99.337368 -254.50673)
			(xy 99.346561 -254.517094) (xy 99.369311 -254.532882) (xy 99.395467 -254.541976) (xy 99.423105 -254.543704)
			(xy 99.450191 -254.537941) (xy 99.474731 -254.525111) (xy 99.494919 -254.506157) (xy 99.509271 -254.482474)
			(xy 99.516729 -254.455806) (xy 99.5172 -254.44196) (xy 99.5172 -254.27813) (xy 99.474782 -254.271018)
			(xy 99.448834 -254.266241) (xy 99.398623 -254.250044) (xy 99.351351 -254.226617) (xy 99.308054 -254.19647)
			(xy 99.269678 -254.160266) (xy 99.237064 -254.118795) (xy 99.210926 -254.072966) (xy 99.191836 -254.023782)
			(xy 99.180212 -253.97232) (xy 99.176308 -253.919706) (xy 99.18021 -253.867092) (xy 99.191833 -253.815629)
			(xy 99.210921 -253.766445) (xy 99.237058 -253.720615) (xy 99.26967 -253.679143) (xy 99.308045 -253.642937)
			(xy 99.351341 -253.612789) (xy 99.398612 -253.58936) (xy 99.448823 -253.573162) (xy 99.474782 -253.568454)
			(xy 99.5172 -253.561342) (xy 99.5172 -249.263916) (xy 99.516784 -249.250722) (xy 99.510022 -249.225217)
			(xy 99.496945 -249.202298) (xy 99.478428 -249.183498) (xy 99.45571 -249.170076) (xy 99.43031 -249.162927)
			(xy 99.417124 -249.162316) (xy 99.390761 -249.161404) (xy 99.338726 -249.152765) (xy 99.288533 -249.136545)
			(xy 99.241281 -249.1131) (xy 99.198005 -249.082942) (xy 99.159649 -249.046732) (xy 99.127053 -249.00526)
			(xy 99.100931 -248.959434) (xy 99.081853 -248.910257) (xy 99.070237 -248.858804) (xy 99.066336 -248.8062)
			(xy 99.070237 -248.753596) (xy 99.081853 -248.702143) (xy 99.100931 -248.652966) (xy 99.127053 -248.60714)
			(xy 99.159649 -248.565669) (xy 99.198004 -248.529458) (xy 99.241281 -248.4993) (xy 99.288533 -248.475855)
			(xy 99.338725 -248.459635) (xy 99.390761 -248.450996) (xy 99.417124 -248.4501) (xy 99.43031 -248.449484)
			(xy 99.455711 -248.442337) (xy 99.47843 -248.428915) (xy 99.496948 -248.410117) (xy 99.510028 -248.387199)
			(xy 99.516793 -248.361694) (xy 99.5172 -248.3485) (xy 99.5172 -247.63603) (xy 99.516786 -247.622835)
			(xy 99.510026 -247.597326) (xy 99.49695 -247.574404) (xy 99.478433 -247.555602) (xy 99.455714 -247.542177)
			(xy 99.430311 -247.535028) (xy 99.417124 -247.53443) (xy 99.39076 -247.533518) (xy 99.338722 -247.524878)
			(xy 99.288528 -247.508658) (xy 99.241275 -247.485212) (xy 99.197996 -247.455053) (xy 99.159639 -247.418841)
			(xy 99.127042 -247.377368) (xy 99.100918 -247.331541) (xy 99.08184 -247.282361) (xy 99.070223 -247.230906)
			(xy 99.066322 -247.1783) (xy 99.070223 -247.125695) (xy 99.081839 -247.074239) (xy 99.100918 -247.02506)
			(xy 99.127042 -246.979233) (xy 99.159638 -246.937759) (xy 99.197995 -246.901547) (xy 99.241274 -246.871388)
			(xy 99.288527 -246.847942) (xy 99.338722 -246.831722) (xy 99.39076 -246.823082) (xy 99.417124 -246.822214)
			(xy 99.430311 -246.821598) (xy 99.455713 -246.814451) (xy 99.478434 -246.80103) (xy 99.496954 -246.782232)
			(xy 99.510037 -246.759314) (xy 99.516806 -246.733808) (xy 99.5172 -246.720614) (xy 99.5172 -246.008398)
			(xy 99.516782 -245.995206) (xy 99.510016 -245.969704) (xy 99.496938 -245.946789) (xy 99.478422 -245.927993)
			(xy 99.455706 -245.914574) (xy 99.430308 -245.907427) (xy 99.417124 -245.906798) (xy 99.390763 -245.905886)
			(xy 99.338729 -245.897247) (xy 99.288539 -245.881028) (xy 99.24129 -245.857584) (xy 99.198016 -245.827428)
			(xy 99.159662 -245.791219) (xy 99.127068 -245.74975) (xy 99.100947 -245.703926) (xy 99.08187 -245.654752)
			(xy 99.070254 -245.603301) (xy 99.066354 -245.5507) (xy 99.070254 -245.498099) (xy 99.08187 -245.446648)
			(xy 99.100947 -245.397473) (xy 99.127068 -245.35165) (xy 99.159662 -245.310181) (xy 99.198016 -245.273972)
			(xy 99.241291 -245.243816) (xy 99.28854 -245.220372) (xy 99.33873 -245.204153) (xy 99.390763 -245.195514)
			(xy 99.417124 -245.194582) (xy 99.430309 -245.193966) (xy 99.455708 -245.186818) (xy 99.478425 -245.173396)
			(xy 99.49694 -245.154598) (xy 99.510016 -245.13168) (xy 99.516778 -245.106175) (xy 99.5172 -245.092982)
			(xy 99.5172 -244.380512) (xy 99.516784 -244.367319) (xy 99.51002 -244.341814) (xy 99.496943 -244.318896)
			(xy 99.478427 -244.300097) (xy 99.455709 -244.286675) (xy 99.430309 -244.279527) (xy 99.417124 -244.278912)
			(xy 99.390762 -244.278) (xy 99.338726 -244.269361) (xy 99.288534 -244.253141) (xy 99.241283 -244.229696)
			(xy 99.198007 -244.199539) (xy 99.159652 -244.163329) (xy 99.127057 -244.121858) (xy 99.100935 -244.076033)
			(xy 99.081857 -244.026856) (xy 99.070241 -243.975403) (xy 99.06634 -243.9228) (xy 99.070241 -243.870197)
			(xy 99.081857 -243.818744) (xy 99.100935 -243.769568) (xy 99.127057 -243.723743) (xy 99.159652 -243.682271)
			(xy 99.198007 -243.646061) (xy 99.241283 -243.615904) (xy 99.288534 -243.592459) (xy 99.338726 -243.576239)
			(xy 99.390762 -243.5676) (xy 99.417124 -243.566696) (xy 99.43031 -243.56608) (xy 99.45571 -243.558932)
			(xy 99.478429 -243.545511) (xy 99.496947 -243.526713) (xy 99.510025 -243.503795) (xy 99.51679 -243.47829)
			(xy 99.5172 -243.465096) (xy 99.5172 -242.752626) (xy 99.516785 -242.739432) (xy 99.510025 -242.713924)
			(xy 99.496949 -242.691002) (xy 99.478432 -242.672201) (xy 99.455713 -242.658777) (xy 99.430311 -242.651627)
			(xy 99.417124 -242.651026) (xy 99.390761 -242.650114) (xy 99.338723 -242.641474) (xy 99.288529 -242.625254)
			(xy 99.241277 -242.601809) (xy 99.197998 -242.57165) (xy 99.159642 -242.535438) (xy 99.127045 -242.493966)
			(xy 99.100922 -242.448139) (xy 99.081843 -242.39896) (xy 99.070227 -242.347506) (xy 99.066326 -242.2949)
			(xy 99.070227 -242.242295) (xy 99.081843 -242.19084) (xy 99.100922 -242.141662) (xy 99.127045 -242.095835)
			(xy 99.159641 -242.054362) (xy 99.197998 -242.01815) (xy 99.241276 -241.987992) (xy 99.288529 -241.964546)
			(xy 99.338723 -241.948326) (xy 99.39076 -241.939686) (xy 99.417124 -241.93881) (xy 99.43031 -241.938194)
			(xy 99.455712 -241.931047) (xy 99.478433 -241.917626) (xy 99.496953 -241.898828) (xy 99.510034 -241.87591)
			(xy 99.516802 -241.850404) (xy 99.5172 -241.83721) (xy 99.5172 -241.124994) (xy 99.516781 -241.111802)
			(xy 99.510015 -241.086301) (xy 99.496937 -241.063387) (xy 99.478421 -241.044592) (xy 99.455705 -241.031173)
			(xy 99.430308 -241.024027) (xy 99.417124 -241.023394) (xy 99.390763 -241.022482) (xy 99.33873 -241.013843)
			(xy 99.288541 -240.997624) (xy 99.241292 -240.974181) (xy 99.198018 -240.944025) (xy 99.159665 -240.907816)
			(xy 99.127072 -240.866347) (xy 99.100951 -240.820525) (xy 99.081874 -240.77135) (xy 99.070258 -240.7199)
			(xy 99.066358 -240.6673) (xy 99.070258 -240.614699) (xy 99.081874 -240.563249) (xy 99.100951 -240.514075)
			(xy 99.127072 -240.468252) (xy 99.159665 -240.426783) (xy 99.198019 -240.390575) (xy 99.241293 -240.360419)
			(xy 99.288541 -240.336975) (xy 99.338731 -240.320757) (xy 99.390763 -240.312118) (xy 99.417124 -240.311178)
			(xy 99.430309 -240.310562) (xy 99.455708 -240.303414) (xy 99.478424 -240.289992) (xy 99.496939 -240.271193)
			(xy 99.510014 -240.248275) (xy 99.516774 -240.222771) (xy 99.5172 -240.209578) (xy 99.5172 -239.497108)
			(xy 99.516783 -239.483915) (xy 99.510019 -239.458411) (xy 99.496942 -239.435494) (xy 99.478426 -239.416696)
			(xy 99.455708 -239.403275) (xy 99.430309 -239.396127) (xy 99.417124 -239.395508) (xy 99.390762 -239.394596)
			(xy 99.338727 -239.385957) (xy 99.288536 -239.369738) (xy 99.241285 -239.346293) (xy 99.19801 -239.316136)
			(xy 99.159655 -239.279926) (xy 99.12706 -239.238455) (xy 99.100938 -239.192631) (xy 99.081861 -239.143455)
			(xy 99.070244 -239.092003) (xy 99.066344 -239.0394) (xy 99.070244 -238.986797) (xy 99.081861 -238.935345)
			(xy 99.100938 -238.886169) (xy 99.12706 -238.840345) (xy 99.159655 -238.798874) (xy 99.19801 -238.762664)
			(xy 99.241285 -238.732507) (xy 99.288536 -238.709062) (xy 99.338727 -238.692843) (xy 99.390762 -238.684204)
			(xy 99.417124 -238.683292) (xy 99.43031 -238.682676) (xy 99.45571 -238.675528) (xy 99.478428 -238.662107)
			(xy 99.496945 -238.643308) (xy 99.510023 -238.62039) (xy 99.516786 -238.594885) (xy 99.5172 -238.581692)
			(xy 99.5172 -237.869222) (xy 99.516785 -237.856028) (xy 99.510023 -237.830521) (xy 99.496947 -237.8076)
			(xy 99.47843 -237.7888) (xy 99.455712 -237.775376) (xy 99.43031 -237.768227) (xy 99.417124 -237.767622)
			(xy 99.38944 -237.766646) (xy 99.334863 -237.757182) (xy 99.282409 -237.73938) (xy 99.233346 -237.71367)
			(xy 99.188855 -237.680673) (xy 99.150011 -237.641184) (xy 99.11775 -237.596156) (xy 99.092851 -237.546675)
			(xy 99.075916 -237.493936) (xy 99.067351 -237.43921) (xy 99.066858 -237.411514) (xy 99.067406 -237.383529)
			(xy 99.076159 -237.328248) (xy 99.093452 -237.275017) (xy 99.118859 -237.225147) (xy 99.151754 -237.179864)
			(xy 99.191328 -237.140285) (xy 99.236606 -237.107384) (xy 99.286473 -237.08197) (xy 99.339702 -237.06467)
			(xy 99.394981 -237.05591) (xy 99.422966 -237.055406) (xy 99.451631 -237.055978) (xy 99.508222 -237.065158)
			(xy 99.562611 -237.083286) (xy 99.613393 -237.109894) (xy 99.659255 -237.144294) (xy 99.699014 -237.185598)
			(xy 99.715828 -237.208822) (xy 99.724675 -237.220752) (xy 99.747845 -237.23931) (xy 99.775374 -237.250417)
			(xy 99.804936 -237.253135) (xy 99.834029 -237.247232) (xy 99.860194 -237.233209) (xy 99.871022 -237.223046)
			(xy 99.966526 -237.127542) (xy 99.976763 -237.116551) (xy 99.990907 -237.090071) (xy 99.996743 -237.060623)
			(xy 99.993769 -237.030751) (xy 99.98224 -237.003032) (xy 99.963152 -236.979862) (xy 99.938153 -236.963239)
			(xy 99.909402 -236.954601) (xy 99.89439 -236.95406) (xy 99.892612 -236.95406) (xy 99.865536 -236.953555)
			(xy 99.812008 -236.945357) (xy 99.760339 -236.929148) (xy 99.71172 -236.905302) (xy 99.667273 -236.874369)
			(xy 99.628022 -236.837062) (xy 99.594873 -236.794242) (xy 99.56859 -236.746896) (xy 99.54978 -236.696116)
			(xy 99.538876 -236.643073) (xy 99.53613 -236.588991) (xy 99.541605 -236.535117) (xy 99.555174 -236.482692)
			(xy 99.576525 -236.432927) (xy 99.605166 -236.386969) (xy 99.640436 -236.345878) (xy 99.681521 -236.310602)
			(xy 99.727474 -236.281953) (xy 99.777235 -236.260593) (xy 99.829657 -236.247015) (xy 99.883531 -236.241531)
			(xy 99.937614 -236.244269) (xy 99.990658 -236.255164) (xy 100.041441 -236.273965) (xy 100.088792 -236.30024)
			(xy 100.131618 -236.333382) (xy 100.168931 -236.372626) (xy 100.199872 -236.417069) (xy 100.223726 -236.465683)
			(xy 100.239944 -236.51735) (xy 100.248151 -236.570876) (xy 100.24872 -236.597952) (xy 100.24872 -236.59973)
			(xy 100.249214 -236.614749) (xy 100.257865 -236.643512) (xy 100.274499 -236.668521) (xy 100.297682 -236.687618)
			(xy 100.325414 -236.699155) (xy 100.355301 -236.702137) (xy 100.384766 -236.696307) (xy 100.411265 -236.682167)
			(xy 100.422202 -236.671866) (xy 100.476558 -236.61751) (xy 100.476558 -236.596682) (xy 100.4772 -236.568829)
			(xy 100.486078 -236.513831) (xy 100.503411 -236.460886) (xy 100.528777 -236.411286) (xy 100.561557 -236.36624)
			(xy 100.600951 -236.326848) (xy 100.645998 -236.29407) (xy 100.695599 -236.268706) (xy 100.748545 -236.251375)
			(xy 100.803543 -236.242499) (xy 100.831396 -236.241844) (xy 100.852224 -236.241844) (xy 101.05263 -236.041438)
			(xy 101.024182 -236.006132) (xy 101.005972 -235.982305) (xy 100.976961 -235.929825) (xy 100.957139 -235.873231)
			(xy 100.947066 -235.814118) (xy 100.946458 -235.784136) (xy 100.946458 -235.783882) (xy 100.947008 -235.755899)
			(xy 100.955765 -235.700622) (xy 100.973061 -235.647395) (xy 100.99847 -235.597529) (xy 101.031365 -235.552251)
			(xy 101.070939 -235.512676) (xy 101.116215 -235.479778) (xy 101.16608 -235.454367) (xy 101.219306 -235.437069)
			(xy 101.274583 -235.42831) (xy 101.302566 -235.427774) (xy 101.331087 -235.428336) (xy 101.3874 -235.437434)
			(xy 101.441539 -235.455401) (xy 101.492117 -235.481778) (xy 101.537837 -235.515888) (xy 101.55809 -235.535978)
			(xy 101.641656 -235.452412) (xy 101.651099 -235.442326) (xy 101.664691 -235.418284) (xy 101.671345 -235.39148)
			(xy 101.670575 -235.363873) (xy 101.662436 -235.337481) (xy 101.647524 -235.314235) (xy 101.626929 -235.295834)
			(xy 101.614732 -235.289344) (xy 101.589575 -235.276344) (xy 101.54338 -235.243596) (xy 101.502957 -235.203944)
			(xy 101.469325 -235.158389) (xy 101.443334 -235.108081) (xy 101.425641 -235.054292) (xy 101.416692 -234.998379)
			(xy 101.416104 -234.970066) (xy 101.416656 -234.942085) (xy 101.425415 -234.886813) (xy 101.442713 -234.833591)
			(xy 101.468123 -234.78373) (xy 101.50102 -234.738458) (xy 101.540593 -234.69889) (xy 101.58587 -234.665999)
			(xy 101.635733 -234.640595) (xy 101.688957 -234.623304) (xy 101.744231 -234.614552) (xy 101.772212 -234.613958)
			(xy 101.800525 -234.614506) (xy 101.856436 -234.623473) (xy 101.910222 -234.64118) (xy 101.960527 -234.667179)
			(xy 102.00608 -234.700814) (xy 102.045734 -234.741238) (xy 102.078487 -234.78743) (xy 102.09149 -234.812586)
			(xy 102.098009 -234.824766) (xy 102.11641 -234.845357) (xy 102.139653 -234.860268) (xy 102.16604 -234.868411)
			(xy 102.193644 -234.869191) (xy 102.220448 -234.86255) (xy 102.244496 -234.848974) (xy 102.254558 -234.83951)
			(xy 102.839012 -234.255056) (xy 102.833424 -234.228386) (xy 102.829976 -234.210616) (xy 102.826286 -234.174604)
			(xy 102.826058 -234.156504) (xy 102.826058 -234.15625) (xy 102.826611 -234.128268) (xy 102.835372 -234.072995)
			(xy 102.85267 -234.019773) (xy 102.87808 -233.969911) (xy 102.910977 -233.924637) (xy 102.95055 -233.885066)
			(xy 102.995825 -233.852172) (xy 103.045688 -233.826764) (xy 103.098911 -233.809468) (xy 103.154184 -233.800709)
			(xy 103.182166 -233.800142) (xy 103.18242 -233.800142) (xy 103.200519 -233.800386) (xy 103.23653 -233.804075)
			(xy 103.254302 -233.807508) (xy 103.280972 -233.813096) (xy 103.3272 -233.766868) (xy 103.327708 -233.766868)
			(xy 103.342685 -233.766349) (xy 103.371357 -233.757678) (xy 103.396274 -233.741055) (xy 103.415292 -233.717912)
			(xy 103.42677 -233.690245) (xy 103.42972 -233.660437) (xy 103.423888 -233.631056) (xy 103.409775 -233.604635)
			(xy 103.39959 -233.59364) (xy 103.380268 -233.573466) (xy 103.347509 -233.528221) (xy 103.322209 -233.47842)
			(xy 103.304985 -233.425283) (xy 103.296261 -233.370109) (xy 103.295704 -233.34218) (xy 103.296202 -233.315531)
			(xy 103.304145 -233.262827) (xy 103.319855 -233.211897) (xy 103.342981 -233.163876) (xy 103.373005 -233.119839)
			(xy 103.409257 -233.080768) (xy 103.450928 -233.047537) (xy 103.497086 -233.020888) (xy 103.5467 -233.001416)
			(xy 103.598662 -232.989556) (xy 103.651812 -232.985573) (xy 103.704962 -232.989556) (xy 103.756924 -233.001416)
			(xy 103.806538 -233.020888) (xy 103.852696 -233.047537) (xy 103.894367 -233.080768) (xy 103.930619 -233.119839)
			(xy 103.960643 -233.163876) (xy 103.983769 -233.211897) (xy 103.999479 -233.262827) (xy 104.007422 -233.315531)
			(xy 104.00792 -233.34218) (xy 104.007378 -233.370111) (xy 103.998661 -233.425288) (xy 103.981438 -233.478429)
			(xy 103.956132 -233.528229) (xy 103.923362 -233.573469) (xy 103.904034 -233.59364) (xy 103.893848 -233.604619)
			(xy 103.879784 -233.631044) (xy 103.873984 -233.660412) (xy 103.876949 -233.690199) (xy 103.888422 -233.717848)
			(xy 103.907419 -233.740982) (xy 103.932308 -233.757615) (xy 103.960949 -233.766318) (xy 103.975916 -233.766868)
			(xy 104.267762 -233.766868) (xy 104.282733 -233.766342) (xy 104.31139 -233.757662) (xy 104.336293 -233.741038)
			(xy 104.355299 -233.7179) (xy 104.366771 -233.690243) (xy 104.369721 -233.660446) (xy 104.363895 -233.631076)
			(xy 104.349795 -233.604661) (xy 104.339644 -233.59364) (xy 104.320324 -233.573465) (xy 104.28757 -233.528218)
			(xy 104.262272 -233.478417) (xy 104.245051 -233.425281) (xy 104.236328 -233.370109) (xy 104.235758 -233.34218)
			(xy 104.236256 -233.315531) (xy 104.244199 -233.262827) (xy 104.259909 -233.211897) (xy 104.283035 -233.163876)
			(xy 104.313059 -233.119839) (xy 104.349311 -233.080768) (xy 104.390982 -233.047537) (xy 104.43714 -233.020888)
			(xy 104.486754 -233.001416) (xy 104.538716 -232.989556) (xy 104.591866 -232.985573) (xy 104.645016 -232.989556)
			(xy 104.696978 -233.001416) (xy 104.746592 -233.020888) (xy 104.79275 -233.047537) (xy 104.834421 -233.080768)
			(xy 104.870673 -233.119839) (xy 104.900697 -233.163876) (xy 104.923823 -233.211897) (xy 104.939533 -233.262827)
			(xy 104.947476 -233.315531) (xy 104.947974 -233.34218) (xy 104.947431 -233.37011) (xy 104.938713 -233.425287)
			(xy 104.921489 -233.478426) (xy 104.89618 -233.528224) (xy 104.863407 -233.573461) (xy 104.844088 -233.59364)
			(xy 104.833905 -233.604622) (xy 104.819846 -233.63105) (xy 104.814051 -233.660418) (xy 104.817016 -233.690205)
			(xy 104.828488 -233.717855) (xy 104.847481 -233.740992) (xy 104.872365 -233.757631) (xy 104.901003 -233.766344)
			(xy 104.91597 -233.766868) (xy 105.207562 -233.766868) (xy 105.222533 -233.766342) (xy 105.25119 -233.757662)
			(xy 105.276093 -233.741038) (xy 105.295099 -233.7179) (xy 105.306571 -233.690243) (xy 105.309521 -233.660446)
			(xy 105.303695 -233.631076) (xy 105.289595 -233.604661) (xy 105.279444 -233.59364) (xy 105.260124 -233.573465)
			(xy 105.22737 -233.528218) (xy 105.202072 -233.478417) (xy 105.184851 -233.425281) (xy 105.176128 -233.370109)
			(xy 105.175558 -233.34218) (xy 105.176056 -233.315531) (xy 105.183999 -233.262827) (xy 105.199709 -233.211897)
			(xy 105.222835 -233.163876) (xy 105.252859 -233.119839) (xy 105.289111 -233.080768) (xy 105.330782 -233.047537)
			(xy 105.37694 -233.020888) (xy 105.426554 -233.001416) (xy 105.478516 -232.989556) (xy 105.531666 -232.985573)
			(xy 105.584816 -232.989556) (xy 105.636778 -233.001416) (xy 105.686392 -233.020888) (xy 105.73255 -233.047537)
			(xy 105.774221 -233.080768) (xy 105.810473 -233.119839) (xy 105.840497 -233.163876) (xy 105.863623 -233.211897)
			(xy 105.879333 -233.262827) (xy 105.887276 -233.315531) (xy 105.887774 -233.34218) (xy 105.887231 -233.37011)
			(xy 105.878513 -233.425287) (xy 105.861289 -233.478426) (xy 105.83598 -233.528224) (xy 105.803207 -233.573461)
			(xy 105.783888 -233.59364) (xy 105.773705 -233.604622) (xy 105.759646 -233.63105) (xy 105.753851 -233.660418)
			(xy 105.756816 -233.690205) (xy 105.768288 -233.717855) (xy 105.787281 -233.740992) (xy 105.812165 -233.757631)
			(xy 105.840803 -233.766344) (xy 105.85577 -233.766868) (xy 106.147108 -233.766868) (xy 106.162085 -233.766349)
			(xy 106.190757 -233.757678) (xy 106.215674 -233.741055) (xy 106.234692 -233.717912) (xy 106.24617 -233.690245)
			(xy 106.24912 -233.660437) (xy 106.243288 -233.631056) (xy 106.229175 -233.604635) (xy 106.21899 -233.59364)
			(xy 106.199668 -233.573466) (xy 106.166909 -233.528221) (xy 106.141609 -233.47842) (xy 106.124385 -233.425283)
			(xy 106.115661 -233.370109) (xy 106.115104 -233.34218) (xy 106.115602 -233.315531) (xy 106.123545 -233.262827)
			(xy 106.139255 -233.211897) (xy 106.162381 -233.163876) (xy 106.192405 -233.119839) (xy 106.228657 -233.080768)
			(xy 106.270328 -233.047537) (xy 106.316486 -233.020888) (xy 106.3661 -233.001416) (xy 106.418062 -232.989556)
			(xy 106.471212 -232.985573) (xy 106.524362 -232.989556) (xy 106.576324 -233.001416) (xy 106.625938 -233.020888)
			(xy 106.672096 -233.047537) (xy 106.713767 -233.080768) (xy 106.750019 -233.119839) (xy 106.780043 -233.163876)
			(xy 106.803169 -233.211897) (xy 106.818879 -233.262827) (xy 106.826822 -233.315531) (xy 106.82732 -233.34218)
			(xy 106.826778 -233.370111) (xy 106.818061 -233.425288) (xy 106.800838 -233.478429) (xy 106.775532 -233.528229)
			(xy 106.742762 -233.573469) (xy 106.723434 -233.59364) (xy 106.713248 -233.604619) (xy 106.699184 -233.631044)
			(xy 106.693384 -233.660412) (xy 106.696349 -233.690199) (xy 106.707822 -233.717848) (xy 106.726819 -233.740982)
			(xy 106.751708 -233.757615) (xy 106.780349 -233.766318) (xy 106.795316 -233.766868) (xy 107.086908 -233.766868)
			(xy 107.101885 -233.766349) (xy 107.130557 -233.757678) (xy 107.155474 -233.741055) (xy 107.174492 -233.717912)
			(xy 107.18597 -233.690245) (xy 107.18892 -233.660437) (xy 107.183088 -233.631056) (xy 107.168975 -233.604635)
			(xy 107.15879 -233.59364) (xy 107.139468 -233.573466) (xy 107.106709 -233.528221) (xy 107.081409 -233.47842)
			(xy 107.064185 -233.425283) (xy 107.055461 -233.370109) (xy 107.054904 -233.34218) (xy 107.055402 -233.315531)
			(xy 107.063345 -233.262827) (xy 107.079055 -233.211897) (xy 107.102181 -233.163876) (xy 107.132205 -233.119839)
			(xy 107.168457 -233.080768) (xy 107.210128 -233.047537) (xy 107.256286 -233.020888) (xy 107.3059 -233.001416)
			(xy 107.357862 -232.989556) (xy 107.411012 -232.985573) (xy 107.464162 -232.989556) (xy 107.516124 -233.001416)
			(xy 107.565738 -233.020888) (xy 107.611896 -233.047537) (xy 107.653567 -233.080768) (xy 107.689819 -233.119839)
			(xy 107.719843 -233.163876) (xy 107.742969 -233.211897) (xy 107.758679 -233.262827) (xy 107.766622 -233.315531)
			(xy 107.76712 -233.34218) (xy 107.766578 -233.370111) (xy 107.757861 -233.425288) (xy 107.740638 -233.478429)
			(xy 107.715332 -233.528229) (xy 107.682562 -233.573469) (xy 107.663234 -233.59364) (xy 107.653048 -233.604619)
			(xy 107.638984 -233.631044) (xy 107.633184 -233.660412) (xy 107.636149 -233.690199) (xy 107.647622 -233.717848)
			(xy 107.666619 -233.740982) (xy 107.691508 -233.757615) (xy 107.720149 -233.766318) (xy 107.735116 -233.766868)
			(xy 108.026708 -233.766868) (xy 108.041685 -233.766349) (xy 108.070357 -233.757678) (xy 108.095274 -233.741055)
			(xy 108.114292 -233.717912) (xy 108.12577 -233.690245) (xy 108.12872 -233.660437) (xy 108.122888 -233.631056)
			(xy 108.108775 -233.604635) (xy 108.09859 -233.59364) (xy 108.079268 -233.573466) (xy 108.046509 -233.528221)
			(xy 108.021209 -233.47842) (xy 108.003985 -233.425283) (xy 107.995261 -233.370109) (xy 107.994704 -233.34218)
			(xy 107.995254 -233.314198) (xy 108.004012 -233.258924) (xy 108.021308 -233.205701) (xy 108.046718 -233.155838)
			(xy 108.079615 -233.110564) (xy 108.119189 -233.070994) (xy 108.164465 -233.038101) (xy 108.21433 -233.012696)
			(xy 108.267555 -232.995405) (xy 108.32283 -232.986652) (xy 108.350812 -232.986072) (xy 108.378123 -232.98657)
			(xy 108.432104 -232.994912) (xy 108.484178 -233.011398) (xy 108.533124 -233.035642) (xy 108.577794 -233.067076)
			(xy 108.617141 -233.104962) (xy 108.650242 -233.148411) (xy 108.67632 -233.196405) (xy 108.694765 -233.247819)
			(xy 108.705143 -233.301445) (xy 108.706666 -233.328718) (xy 108.707704 -233.343436) (xy 108.717165 -233.37137)
			(xy 108.734218 -233.395433) (xy 108.757439 -233.413616) (xy 108.78489 -233.424401) (xy 108.814277 -233.426888)
			(xy 108.84315 -233.420869) (xy 108.869096 -233.406846) (xy 108.879894 -233.39679) (xy 108.933996 -233.342688)
			(xy 108.935012 -233.323384) (xy 108.936848 -233.297345) (xy 108.947187 -233.246181) (xy 108.964884 -233.197074)
			(xy 108.989561 -233.151077) (xy 109.020689 -233.109175) (xy 109.057601 -233.072267) (xy 109.099505 -233.041143)
			(xy 109.145505 -233.01647) (xy 109.194613 -232.998777) (xy 109.245779 -232.988444) (xy 109.271816 -232.98658)
			(xy 109.29112 -232.985564) (xy 109.500924 -232.77576) (xy 109.474762 -232.740454) (xy 109.458273 -232.717303)
			(xy 109.432088 -232.666859) (xy 109.414254 -232.612895) (xy 109.405225 -232.556782) (xy 109.404658 -232.528364)
			(xy 109.40521 -232.500382) (xy 109.413969 -232.445107) (xy 109.431266 -232.391883) (xy 109.456676 -232.342019)
			(xy 109.489572 -232.296743) (xy 109.529145 -232.257171) (xy 109.574421 -232.224275) (xy 109.624284 -232.198865)
			(xy 109.677509 -232.181568) (xy 109.732784 -232.172809) (xy 109.760766 -232.172256) (xy 109.789185 -232.172809)
			(xy 109.845302 -232.181836) (xy 109.899271 -232.199666) (xy 109.949721 -232.225847) (xy 109.972856 -232.24236)
			(xy 110.008162 -232.268522) (xy 110.086902 -232.189782) (xy 110.096143 -232.179874) (xy 110.109508 -232.156317)
			(xy 110.116216 -232.130076) (xy 110.115798 -232.102995) (xy 110.108283 -232.076975) (xy 110.094197 -232.053841)
			(xy 110.074531 -232.035219) (xy 110.062772 -232.028492) (xy 110.038774 -232.0151) (xy 109.994853 -231.982071)
			(xy 109.956534 -231.94268) (xy 109.92473 -231.897865) (xy 109.900195 -231.848691) (xy 109.883516 -231.796329)
			(xy 109.875087 -231.742025) (xy 109.874558 -231.714548) (xy 109.875074 -231.686559) (xy 109.883824 -231.63127)
			(xy 109.901115 -231.57803) (xy 109.926522 -231.52815) (xy 109.95942 -231.48286) (xy 109.998997 -231.443273)
			(xy 110.04428 -231.410365) (xy 110.094154 -231.384947) (xy 110.14739 -231.367643) (xy 110.202677 -231.358881)
			(xy 110.230666 -231.35844) (xy 110.258142 -231.358955) (xy 110.312439 -231.367407) (xy 110.364793 -231.384101)
			(xy 110.413961 -231.408641) (xy 110.458775 -231.440443) (xy 110.498171 -231.478753) (xy 110.531214 -231.52266)
			(xy 110.54461 -231.546654) (xy 110.551373 -231.55839) (xy 110.569978 -231.578065) (xy 110.593101 -231.592156)
			(xy 110.619114 -231.599673) (xy 110.646189 -231.600088) (xy 110.672421 -231.59337) (xy 110.695963 -231.579993)
			(xy 110.7059 -231.570784) (xy 111.161576 -231.115108) (xy 111.161576 -230.44531) (xy 111.118142 -230.43896)
			(xy 111.091811 -230.434565) (xy 111.040771 -230.418923) (xy 110.992638 -230.395839) (xy 110.948489 -230.365829)
			(xy 110.909314 -230.329566) (xy 110.87599 -230.287861) (xy 110.849264 -230.24165) (xy 110.829735 -230.191968)
			(xy 110.81784 -230.139927) (xy 110.813846 -230.086694) (xy 110.817842 -230.033461) (xy 110.829739 -229.981421)
			(xy 110.849269 -229.93174) (xy 110.875996 -229.885529) (xy 110.909321 -229.843826) (xy 110.948498 -229.807564)
			(xy 110.992647 -229.777555) (xy 111.040781 -229.754473) (xy 111.091822 -229.738833) (xy 111.118142 -229.734364)
			(xy 111.161576 -229.728014) (xy 111.161576 -228.817678) (xy 111.118142 -228.811328) (xy 111.091806 -228.806933)
			(xy 111.040756 -228.79129) (xy 110.992613 -228.768202) (xy 110.948455 -228.738188) (xy 110.909271 -228.701919)
			(xy 110.87594 -228.660208) (xy 110.849208 -228.613989) (xy 110.829674 -228.564298) (xy 110.817775 -228.512247)
			(xy 110.813779 -228.459004) (xy 110.817774 -228.405761) (xy 110.829671 -228.353711) (xy 110.849204 -228.304019)
			(xy 110.875935 -228.2578) (xy 110.909265 -228.216088) (xy 110.948448 -228.179818) (xy 110.992605 -228.149802)
			(xy 111.040748 -228.126714) (xy 111.091797 -228.111069) (xy 111.118142 -228.106732) (xy 111.161576 -228.100382)
			(xy 111.161576 -227.189792) (xy 111.118142 -227.183442) (xy 111.091789 -227.179066) (xy 111.040702 -227.163453)
			(xy 110.992519 -227.140386) (xy 110.948322 -227.110382) (xy 110.909101 -227.074114) (xy 110.875737 -227.032396)
			(xy 110.848977 -226.986162) (xy 110.829422 -226.93645) (xy 110.81751 -226.884376) (xy 110.813509 -226.831106)
			(xy 110.817508 -226.777837) (xy 110.829418 -226.725762) (xy 110.848971 -226.67605) (xy 110.87573 -226.629815)
			(xy 110.909092 -226.588095) (xy 110.948312 -226.551826) (xy 110.992508 -226.52182) (xy 111.04069 -226.498751)
			(xy 111.091776 -226.483137) (xy 111.118142 -226.478846) (xy 111.161576 -226.472496) (xy 111.161576 -225.561906)
			(xy 111.118142 -225.555556) (xy 111.091795 -225.55118) (xy 111.040721 -225.535569) (xy 110.992551 -225.512506)
			(xy 110.948365 -225.482508) (xy 110.909155 -225.446247) (xy 110.8758 -225.404537) (xy 110.849048 -225.358314)
			(xy 110.829499 -225.308613) (xy 110.817592 -225.256551) (xy 110.813594 -225.203294) (xy 110.817594 -225.150037)
			(xy 110.829503 -225.097975) (xy 110.849053 -225.048275) (xy 110.875807 -225.002053) (xy 110.909163 -224.960344)
			(xy 110.948375 -224.924084) (xy 110.992561 -224.894088) (xy 111.040732 -224.871026) (xy 111.091807 -224.855417)
			(xy 111.118142 -224.85096) (xy 111.161576 -224.84461) (xy 111.161576 -224.175066) (xy 111.161191 -224.165525)
			(xy 111.154237 -224.147757) (xy 111.141269 -224.133762) (xy 111.124082 -224.125477) (xy 111.105055 -224.124049)
			(xy 111.086824 -224.129678) (xy 111.071913 -224.141582) (xy 111.066834 -224.149666) (xy 111.020098 -224.230438)
			(xy 111.02975 -224.253552) (xy 111.038266 -224.275184) (xy 111.050252 -224.320102) (xy 111.056293 -224.366197)
			(xy 111.056674 -224.389442) (xy 111.056176 -224.416091) (xy 111.048233 -224.468795) (xy 111.032523 -224.519725)
			(xy 111.009397 -224.567746) (xy 110.979373 -224.611783) (xy 110.943121 -224.650854) (xy 110.90145 -224.684085)
			(xy 110.855292 -224.710734) (xy 110.805678 -224.730206) (xy 110.753716 -224.742066) (xy 110.700566 -224.74605)
			(xy 110.647416 -224.742066) (xy 110.595454 -224.730206) (xy 110.54584 -224.710734) (xy 110.499682 -224.684085)
			(xy 110.458011 -224.650854) (xy 110.421759 -224.611783) (xy 110.391735 -224.567746) (xy 110.368609 -224.519725)
			(xy 110.352899 -224.468795) (xy 110.344956 -224.416091) (xy 110.344458 -224.389442) (xy 110.344907 -224.363817)
			(xy 110.35226 -224.313096) (xy 110.366805 -224.263953) (xy 110.388242 -224.217401) (xy 110.416129 -224.174401)
			(xy 110.44989 -224.135842) (xy 110.488828 -224.102518) (xy 110.53214 -224.075119) (xy 110.578931 -224.054208)
			(xy 110.628236 -224.040219) (xy 110.653576 -224.036382) (xy 110.678214 -224.03308) (xy 110.850426 -223.734376)
			(xy 110.841028 -223.711516) (xy 110.832508 -223.689885) (xy 110.820514 -223.644967) (xy 110.814464 -223.598872)
			(xy 110.814104 -223.575626) (xy 110.814639 -223.547435) (xy 110.823519 -223.491758) (xy 110.841062 -223.438176)
			(xy 110.86683 -223.388027) (xy 110.900178 -223.342566) (xy 110.940273 -223.302927) (xy 110.986113 -223.270102)
			(xy 111.036553 -223.24491) (xy 111.090333 -223.227982) (xy 111.118142 -223.223328) (xy 111.161576 -223.216978)
			(xy 111.161576 -222.306388) (xy 111.118142 -222.300038) (xy 111.091805 -222.295643) (xy 111.040754 -222.279999)
			(xy 110.992609 -222.256912) (xy 110.94845 -222.226896) (xy 110.909265 -222.190627) (xy 110.875933 -222.148914)
			(xy 110.8492 -222.102694) (xy 110.829665 -222.053002) (xy 110.817766 -222.00095) (xy 110.813769 -221.947706)
			(xy 110.817764 -221.894461) (xy 110.829661 -221.842409) (xy 110.849195 -221.792716) (xy 110.875926 -221.746495)
			(xy 110.909257 -221.704782) (xy 110.94844 -221.668511) (xy 110.992599 -221.638494) (xy 111.040743 -221.615405)
			(xy 111.091793 -221.59976) (xy 111.118142 -221.595442) (xy 111.161576 -221.589092) (xy 111.161576 -220.699076)
			(xy 111.148622 -220.676724) (xy 111.118142 -220.672152) (xy 111.091796 -220.667776) (xy 111.040722 -220.652166)
			(xy 110.992552 -220.629103) (xy 110.948367 -220.599104) (xy 110.909157 -220.562844) (xy 110.875803 -220.521134)
			(xy 110.849051 -220.474911) (xy 110.829503 -220.425211) (xy 110.817596 -220.37315) (xy 110.813598 -220.319893)
			(xy 110.817598 -220.266637) (xy 110.829507 -220.214576) (xy 110.849057 -220.164877) (xy 110.87581 -220.118654)
			(xy 110.909167 -220.076946) (xy 110.948378 -220.040687) (xy 110.992564 -220.010691) (xy 111.040734 -219.98763)
			(xy 111.091809 -219.972021) (xy 111.118142 -219.967556) (xy 111.161576 -219.961206) (xy 111.161576 -219.050616)
			(xy 111.118142 -219.044266) (xy 111.091821 -219.039858) (xy 111.040803 -219.024196) (xy 110.992694 -219.001097)
			(xy 110.948569 -218.971079) (xy 110.909417 -218.934814) (xy 110.876114 -218.893113) (xy 110.849406 -218.84691)
			(xy 110.829889 -218.79724) (xy 110.818002 -218.745213) (xy 110.814011 -218.691995) (xy 110.818004 -218.638778)
			(xy 110.829892 -218.586751) (xy 110.84941 -218.537081) (xy 110.87612 -218.490879) (xy 110.909424 -218.449179)
			(xy 110.948577 -218.412915) (xy 110.992702 -218.382898) (xy 111.040812 -218.359801) (xy 111.09183 -218.34414)
			(xy 111.118142 -218.33967) (xy 111.161576 -218.33332) (xy 111.161576 -217.66403) (xy 111.161185 -217.654494)
			(xy 111.154226 -217.636739) (xy 111.141259 -217.622754) (xy 111.124079 -217.614476) (xy 111.105062 -217.613049)
			(xy 111.086839 -217.61867) (xy 111.07193 -217.630562) (xy 111.066834 -217.63863) (xy 111.020098 -217.719402)
			(xy 111.02975 -217.742516) (xy 111.038268 -217.764148) (xy 111.050258 -217.809065) (xy 111.056305 -217.855161)
			(xy 111.056674 -217.878406) (xy 111.056176 -217.905055) (xy 111.048233 -217.957759) (xy 111.032523 -218.008689)
			(xy 111.009397 -218.05671) (xy 110.979373 -218.100747) (xy 110.943121 -218.139818) (xy 110.90145 -218.173049)
			(xy 110.855292 -218.199698) (xy 110.805678 -218.21917) (xy 110.753716 -218.23103) (xy 110.700566 -218.235014)
			(xy 110.647416 -218.23103) (xy 110.595454 -218.21917) (xy 110.54584 -218.199698) (xy 110.499682 -218.173049)
			(xy 110.458011 -218.139818) (xy 110.421759 -218.100747) (xy 110.391735 -218.05671) (xy 110.368609 -218.008689)
			(xy 110.352899 -217.957759) (xy 110.344956 -217.905055) (xy 110.344458 -217.878406) (xy 110.34491 -217.852782)
			(xy 110.352267 -217.802065) (xy 110.366815 -217.752926) (xy 110.388254 -217.706379) (xy 110.416142 -217.663384)
			(xy 110.449903 -217.624829) (xy 110.488841 -217.591509) (xy 110.532151 -217.564113) (xy 110.57894 -217.543205)
			(xy 110.628242 -217.529218) (xy 110.653576 -217.525346) (xy 110.678214 -217.522044) (xy 110.85068 -217.223086)
			(xy 110.841282 -217.199972) (xy 110.832771 -217.178382) (xy 110.820784 -217.13355) (xy 110.814731 -217.087539)
			(xy 110.814358 -217.064336) (xy 110.814898 -217.03616) (xy 110.823779 -216.980513) (xy 110.841311 -216.926957)
			(xy 110.867056 -216.87683) (xy 110.900371 -216.831381) (xy 110.940426 -216.791743) (xy 110.986222 -216.758906)
			(xy 111.036616 -216.733689) (xy 111.090352 -216.716719) (xy 111.118142 -216.712038) (xy 111.161576 -216.705688)
			(xy 111.161576 -215.795352) (xy 111.118142 -215.789002) (xy 111.090332 -215.78435) (xy 111.036549 -215.767422)
			(xy 110.986106 -215.742231) (xy 110.940263 -215.709407) (xy 110.900165 -215.669768) (xy 110.866813 -215.624307)
			(xy 110.841042 -215.574158) (xy 110.823494 -215.520575) (xy 110.814609 -215.464896) (xy 110.814104 -215.436704)
			(xy 110.814639 -215.408887) (xy 110.823285 -215.353928) (xy 110.84037 -215.300981) (xy 110.852458 -215.275922)
			(xy 110.864142 -215.252554) (xy 110.679738 -214.902796) (xy 110.65383 -214.899494) (xy 110.628469 -214.89569)
			(xy 110.579121 -214.881745) (xy 110.532283 -214.860865) (xy 110.488925 -214.833481) (xy 110.449944 -214.800161)
			(xy 110.416147 -214.761594) (xy 110.388231 -214.718576) (xy 110.366776 -214.672) (xy 110.352224 -214.622827)
			(xy 110.344877 -214.572075) (xy 110.344458 -214.546434) (xy 110.344956 -214.519785) (xy 110.352899 -214.467081)
			(xy 110.368609 -214.416151) (xy 110.391735 -214.36813) (xy 110.421759 -214.324093) (xy 110.458011 -214.285022)
			(xy 110.499682 -214.251791) (xy 110.54584 -214.225142) (xy 110.595454 -214.20567) (xy 110.647416 -214.19381)
			(xy 110.700566 -214.189827) (xy 110.753716 -214.19381) (xy 110.805678 -214.20567) (xy 110.855292 -214.225142)
			(xy 110.90145 -214.251791) (xy 110.943121 -214.285022) (xy 110.979373 -214.324093) (xy 111.009397 -214.36813)
			(xy 111.032523 -214.416151) (xy 111.048233 -214.467081) (xy 111.056176 -214.519785) (xy 111.056674 -214.546434)
			(xy 111.056136 -214.574251) (xy 111.047484 -214.629207) (xy 111.030394 -214.68215) (xy 111.01832 -214.707216)
			(xy 111.006636 -214.730584) (xy 111.065818 -214.843106) (xy 111.070694 -214.851483) (xy 111.085409 -214.864073)
			(xy 111.103743 -214.87031) (xy 111.123083 -214.869305) (xy 111.140672 -214.861202) (xy 111.154004 -214.847155)
			(xy 111.161178 -214.829167) (xy 111.161576 -214.819484) (xy 111.161576 -210.232244) (xy 96.77908 -195.849748)
			(xy 86.433914 -195.849748) (xy 86.42045 -195.850173) (xy 86.394464 -195.857233) (xy 86.371226 -195.87084)
			(xy 86.352352 -195.890047) (xy 86.339155 -195.913519) (xy 86.332551 -195.939625) (xy 86.333 -195.96655)
			(xy 86.34047 -195.992421) (xy 86.347046 -196.00418) (xy 86.360306 -196.0267) (xy 86.381208 -196.0746)
			(xy 86.395365 -196.124907) (xy 86.40251 -196.176677) (xy 86.402926 -196.202808) (xy 86.40244 -196.230059)
			(xy 86.394684 -196.284007) (xy 86.379329 -196.336302) (xy 86.356687 -196.385879) (xy 86.327427 -196.431408)
			(xy 90.77909 -196.431408) (xy 90.783161 -196.375786) (xy 90.795287 -196.321349) (xy 90.81521 -196.269258)
			(xy 90.842506 -196.220623) (xy 90.876592 -196.17648) (xy 90.916741 -196.137771) (xy 90.962099 -196.10532)
			(xy 91.011699 -196.079819) (xy 91.064483 -196.061812) (xy 91.119326 -196.051682) (xy 91.17506 -196.049645)
			(xy 91.230497 -196.055745) (xy 91.284454 -196.069851) (xy 91.335783 -196.091663) (xy 91.383389 -196.120717)
			(xy 91.426257 -196.156392) (xy 91.463474 -196.197929) (xy 91.494247 -196.244442) (xy 91.517919 -196.294939)
			(xy 91.533987 -196.348346) (xy 91.542107 -196.403522) (xy 91.542616 -196.431408) (xy 91.542107 -196.459294)
			(xy 91.533987 -196.51447) (xy 91.517919 -196.567877) (xy 91.494247 -196.618374) (xy 91.463474 -196.664887)
			(xy 91.426257 -196.706424) (xy 91.383389 -196.742099) (xy 91.335783 -196.771153) (xy 91.284454 -196.792965)
			(xy 91.230497 -196.807071) (xy 91.17506 -196.813171) (xy 91.119326 -196.811134) (xy 91.064483 -196.801004)
			(xy 91.011699 -196.782997) (xy 90.962099 -196.757496) (xy 90.916741 -196.725045) (xy 90.876592 -196.686336)
			(xy 90.842506 -196.642193) (xy 90.81521 -196.593558) (xy 90.795287 -196.541467) (xy 90.783161 -196.48703)
			(xy 90.77909 -196.431408) (xy 86.327427 -196.431408) (xy 86.327221 -196.431729) (xy 86.29153 -196.47292)
			(xy 86.250339 -196.508611) (xy 86.204489 -196.538077) (xy 86.154912 -196.560719) (xy 86.102617 -196.576074)
			(xy 86.048669 -196.58383) (xy 85.994167 -196.58383) (xy 85.940219 -196.576074) (xy 85.887924 -196.560719)
			(xy 85.838347 -196.538077) (xy 85.792497 -196.508611) (xy 85.751306 -196.47292) (xy 85.715615 -196.431729)
			(xy 85.686149 -196.385879) (xy 85.663507 -196.336302) (xy 85.648152 -196.284007) (xy 85.640396 -196.230059)
			(xy 85.63991 -196.202808) (xy 85.640348 -196.176531) (xy 85.647557 -196.124474) (xy 85.66184 -196.073898)
			(xy 85.682926 -196.02576) (xy 85.710417 -195.98097) (xy 85.743793 -195.940375) (xy 85.782423 -195.904743)
			(xy 85.80374 -195.889372) (xy 85.815616 -195.880484) (xy 85.834064 -195.857274) (xy 85.84508 -195.829747)
			(xy 85.847741 -195.800218) (xy 85.841822 -195.771166) (xy 85.82782 -195.745031) (xy 85.81771 -195.734178)
			(xy 72.95388 -182.870348) (xy 72.95388 -177.909728) (xy 66.106802 -171.06265) (xy 61.143134 -171.06265)
			(xy 61.110114 -171.09567) (xy 61.061854 -171.09567) (xy 60.7187 -171.438824) (xy 60.7187 -171.439078)
			(xy 60.661804 -171.495974) (xy 60.661804 -177.947504) (xy 67.755004 -177.947504) (xy 67.755004 -177.862808)
			(xy 67.763055 -177.778494) (xy 67.779084 -177.695328) (xy 67.802945 -177.614061) (xy 67.834424 -177.535431)
			(xy 67.873235 -177.46015) (xy 67.919025 -177.388898) (xy 67.971381 -177.322322) (xy 68.029829 -177.261024)
			(xy 68.093839 -177.205559) (xy 68.162831 -177.15643) (xy 68.236181 -177.114081) (xy 68.313224 -177.078897)
			(xy 68.393263 -177.051195) (xy 68.475572 -177.031227) (xy 68.559407 -177.019174) (xy 68.644008 -177.015144)
			(xy 68.728609 -177.019174) (xy 68.812444 -177.031227) (xy 68.894753 -177.051195) (xy 68.974792 -177.078897)
			(xy 69.051835 -177.114081) (xy 69.125185 -177.15643) (xy 69.194177 -177.205559) (xy 69.258187 -177.261024)
			(xy 69.316635 -177.322322) (xy 69.368991 -177.388898) (xy 69.414781 -177.46015) (xy 69.453592 -177.535431)
			(xy 69.485071 -177.614061) (xy 69.508932 -177.695328) (xy 69.524961 -177.778494) (xy 69.533012 -177.862808)
			(xy 69.533516 -177.905156) (xy 69.728593 -177.905156) (xy 69.732615 -177.819436) (xy 69.744646 -177.734468)
			(xy 69.764582 -177.651001) (xy 69.792245 -177.569767) (xy 69.827394 -177.491481) (xy 69.86972 -177.41683)
			(xy 69.918849 -177.346471) (xy 69.974352 -177.281021) (xy 70.035739 -177.221057) (xy 70.102472 -177.167104)
			(xy 70.173964 -177.119637) (xy 70.249586 -177.079073) (xy 70.328675 -177.045769) (xy 70.410535 -177.020017)
			(xy 70.494446 -177.002044) (xy 70.579672 -176.992008) (xy 70.665464 -176.989996) (xy 70.751066 -176.996027)
			(xy 70.835728 -177.010047) (xy 70.918705 -177.031933) (xy 70.999268 -177.061494) (xy 71.076708 -177.098468)
			(xy 71.150347 -177.142532) (xy 71.219535 -177.193298) (xy 71.283666 -177.250319) (xy 71.342175 -177.313095)
			(xy 71.394548 -177.381075) (xy 71.440326 -177.45366) (xy 71.479106 -177.530212) (xy 71.510547 -177.61006)
			(xy 71.534373 -177.692501) (xy 71.550374 -177.776811) (xy 71.558409 -177.862249) (xy 71.558912 -177.905156)
			(xy 71.558409 -177.948063) (xy 71.550374 -178.033501) (xy 71.534373 -178.117811) (xy 71.510547 -178.200252)
			(xy 71.479106 -178.2801) (xy 71.440326 -178.356652) (xy 71.394548 -178.429237) (xy 71.342175 -178.497217)
			(xy 71.283666 -178.559993) (xy 71.219535 -178.617014) (xy 71.150347 -178.66778) (xy 71.076708 -178.711844)
			(xy 70.999268 -178.748818) (xy 70.918705 -178.778379) (xy 70.835728 -178.800265) (xy 70.751066 -178.814285)
			(xy 70.665464 -178.820316) (xy 70.579672 -178.818304) (xy 70.494446 -178.808268) (xy 70.410535 -178.790295)
			(xy 70.328675 -178.764543) (xy 70.249586 -178.731239) (xy 70.173964 -178.690675) (xy 70.102472 -178.643208)
			(xy 70.035739 -178.589255) (xy 69.974352 -178.529291) (xy 69.918849 -178.463841) (xy 69.86972 -178.393482)
			(xy 69.827394 -178.318831) (xy 69.792245 -178.240545) (xy 69.764582 -178.159311) (xy 69.744646 -178.075844)
			(xy 69.732615 -177.990876) (xy 69.728593 -177.905156) (xy 69.533516 -177.905156) (xy 69.533012 -177.947504)
			(xy 69.524961 -178.031818) (xy 69.508932 -178.114984) (xy 69.485071 -178.196251) (xy 69.453592 -178.274881)
			(xy 69.414781 -178.350162) (xy 69.368991 -178.421414) (xy 69.316635 -178.48799) (xy 69.258187 -178.549288)
			(xy 69.194177 -178.604753) (xy 69.125185 -178.653882) (xy 69.051835 -178.696231) (xy 68.974792 -178.731415)
			(xy 68.894753 -178.759117) (xy 68.812444 -178.779085) (xy 68.728609 -178.791138) (xy 68.644008 -178.795169)
			(xy 68.559407 -178.791138) (xy 68.475572 -178.779085) (xy 68.393263 -178.759117) (xy 68.313224 -178.731415)
			(xy 68.236181 -178.696231) (xy 68.162831 -178.653882) (xy 68.093839 -178.604753) (xy 68.029829 -178.549288)
			(xy 67.971381 -178.48799) (xy 67.919025 -178.421414) (xy 67.873235 -178.350162) (xy 67.834424 -178.274881)
			(xy 67.802945 -178.196251) (xy 67.779084 -178.114984) (xy 67.763055 -178.031818) (xy 67.755004 -177.947504)
			(xy 60.661804 -177.947504) (xy 60.661804 -181.597808) (xy 60.66223 -181.607507) (xy 60.669423 -181.625522)
			(xy 60.68278 -181.639587) (xy 60.700399 -181.647701) (xy 60.710064 -181.648608) (xy 60.739007 -181.650621)
			(xy 60.795835 -181.662306) (xy 60.850238 -181.68246) (xy 60.900962 -181.71062) (xy 60.946837 -181.746135)
			(xy 60.986806 -181.788188) (xy 61.019946 -181.835807) (xy 61.045494 -181.887896) (xy 61.062859 -181.943252)
			(xy 61.071643 -182.0006) (xy 61.072268 -182.029608) (xy 61.202822 -182.029608) (xy 61.206893 -181.973986)
			(xy 61.219019 -181.919549) (xy 61.238942 -181.867458) (xy 61.266238 -181.818823) (xy 61.300324 -181.77468)
			(xy 61.340473 -181.735971) (xy 61.385831 -181.70352) (xy 61.435431 -181.678019) (xy 61.488215 -181.660012)
			(xy 61.543058 -181.649882) (xy 61.598792 -181.647845) (xy 61.654229 -181.653945) (xy 61.708186 -181.668051)
			(xy 61.759515 -181.689863) (xy 61.807121 -181.718917) (xy 61.849989 -181.754592) (xy 61.887206 -181.796129)
			(xy 61.897156 -181.811168) (xy 68.096382 -181.811168) (xy 68.100453 -181.755546) (xy 68.112579 -181.701109)
			(xy 68.132502 -181.649018) (xy 68.159798 -181.600383) (xy 68.193884 -181.55624) (xy 68.234033 -181.517531)
			(xy 68.279391 -181.48508) (xy 68.328991 -181.459579) (xy 68.381775 -181.441572) (xy 68.436618 -181.431442)
			(xy 68.492352 -181.429405) (xy 68.547789 -181.435505) (xy 68.601746 -181.449611) (xy 68.653075 -181.471423)
			(xy 68.700681 -181.500477) (xy 68.743549 -181.536152) (xy 68.780766 -181.577689) (xy 68.811539 -181.624202)
			(xy 68.835211 -181.674699) (xy 68.851279 -181.728106) (xy 68.859399 -181.783282) (xy 68.859908 -181.811168)
			(xy 68.859399 -181.839054) (xy 68.855167 -181.86781) (xy 71.82688 -181.86781) (xy 71.830951 -181.812188)
			(xy 71.843077 -181.757751) (xy 71.863 -181.70566) (xy 71.890296 -181.657025) (xy 71.924382 -181.612882)
			(xy 71.964531 -181.574173) (xy 72.009889 -181.541722) (xy 72.059489 -181.516221) (xy 72.112273 -181.498214)
			(xy 72.167116 -181.488084) (xy 72.22285 -181.486047) (xy 72.278287 -181.492147) (xy 72.332244 -181.506253)
			(xy 72.383573 -181.528065) (xy 72.431179 -181.557119) (xy 72.474047 -181.592794) (xy 72.511264 -181.634331)
			(xy 72.542037 -181.680844) (xy 72.565709 -181.731341) (xy 72.581777 -181.784748) (xy 72.589897 -181.839924)
			(xy 72.590406 -181.86781) (xy 72.589897 -181.895696) (xy 72.581777 -181.950872) (xy 72.565709 -182.004279)
			(xy 72.542037 -182.054776) (xy 72.511264 -182.101289) (xy 72.474047 -182.142826) (xy 72.431179 -182.178501)
			(xy 72.383573 -182.207555) (xy 72.332244 -182.229367) (xy 72.278287 -182.243473) (xy 72.22285 -182.249573)
			(xy 72.167116 -182.247536) (xy 72.112273 -182.237406) (xy 72.059489 -182.219399) (xy 72.009889 -182.193898)
			(xy 71.964531 -182.161447) (xy 71.924382 -182.122738) (xy 71.890296 -182.078595) (xy 71.863 -182.02996)
			(xy 71.843077 -181.977869) (xy 71.830951 -181.923432) (xy 71.82688 -181.86781) (xy 68.855167 -181.86781)
			(xy 68.851279 -181.89423) (xy 68.835211 -181.947637) (xy 68.811539 -181.998134) (xy 68.780766 -182.044647)
			(xy 68.743549 -182.086184) (xy 68.700681 -182.121859) (xy 68.653075 -182.150913) (xy 68.601746 -182.172725)
			(xy 68.547789 -182.186831) (xy 68.492352 -182.192931) (xy 68.436618 -182.190894) (xy 68.381775 -182.180764)
			(xy 68.328991 -182.162757) (xy 68.279391 -182.137256) (xy 68.234033 -182.104805) (xy 68.193884 -182.066096)
			(xy 68.159798 -182.021953) (xy 68.132502 -181.973318) (xy 68.112579 -181.921227) (xy 68.100453 -181.86679)
			(xy 68.096382 -181.811168) (xy 61.897156 -181.811168) (xy 61.917979 -181.842642) (xy 61.941651 -181.893139)
			(xy 61.957719 -181.946546) (xy 61.965839 -182.001722) (xy 61.966348 -182.029608) (xy 61.965839 -182.057494)
			(xy 61.957719 -182.11267) (xy 61.941651 -182.166077) (xy 61.917979 -182.216574) (xy 61.887206 -182.263087)
			(xy 61.849989 -182.304624) (xy 61.807121 -182.340299) (xy 61.759515 -182.369353) (xy 61.708186 -182.391165)
			(xy 61.654229 -182.405271) (xy 61.598792 -182.411371) (xy 61.543058 -182.409334) (xy 61.488215 -182.399204)
			(xy 61.435431 -182.381197) (xy 61.385831 -182.355696) (xy 61.340473 -182.323245) (xy 61.300324 -182.284536)
			(xy 61.266238 -182.240393) (xy 61.238942 -182.191758) (xy 61.219019 -182.139667) (xy 61.206893 -182.08523)
			(xy 61.202822 -182.029608) (xy 61.072268 -182.029608) (xy 61.071733 -182.058322) (xy 61.063093 -182.115098)
			(xy 61.04604 -182.169938) (xy 61.02096 -182.221601) (xy 60.988418 -182.268921) (xy 60.969144 -182.290212)
			(xy 62.26048 -183.581548) (xy 69.32168 -183.581548) (xy 69.887338 -184.147206) (xy 69.898517 -184.157649)
			(xy 69.925569 -184.171906) (xy 69.955627 -184.17753) (xy 69.986004 -184.174019) (xy 70.013985 -184.161685)
			(xy 70.037071 -184.141632) (xy 70.04558 -184.128918) (xy 70.060597 -184.105664) (xy 70.096282 -184.063346)
			(xy 70.137707 -184.026628) (xy 70.184002 -183.996281) (xy 70.234195 -183.97294) (xy 70.287235 -183.957097)
			(xy 70.342007 -183.949083) (xy 70.369684 -183.948578) (xy 70.397569 -183.949061) (xy 70.452743 -183.95718)
			(xy 70.506148 -183.973246) (xy 70.556644 -183.996919) (xy 70.603154 -184.027691) (xy 70.644687 -184.064909)
			(xy 70.680358 -184.107778) (xy 70.709407 -184.155385) (xy 70.731213 -184.206714) (xy 70.738746 -184.233566)
			(xy 70.742728 -184.246971) (xy 70.756908 -184.271062) (xy 70.777089 -184.290405) (xy 70.801759 -184.303551)
			(xy 70.82907 -184.309516) (xy 70.856974 -184.307852) (xy 70.870318 -184.30367) (xy 70.900441 -184.293933)
			(xy 70.962872 -184.283465) (xy 70.994524 -184.282842) (xy 70.994778 -184.282842) (xy 71.022031 -184.283304)
			(xy 71.075981 -184.291059) (xy 71.128279 -184.306413) (xy 71.177859 -184.329055) (xy 71.223711 -184.358523)
			(xy 71.264902 -184.394218) (xy 71.300593 -184.435412) (xy 71.330058 -184.481266) (xy 71.352697 -184.530847)
			(xy 71.368047 -184.583146) (xy 71.375798 -184.637097) (xy 71.376286 -184.66435) (xy 71.37578 -184.692945)
			(xy 71.36725 -184.749496) (xy 71.350374 -184.804139) (xy 71.325531 -184.855652) (xy 71.293277 -184.902878)
			(xy 71.254334 -184.944761) (xy 71.209575 -184.980362) (xy 71.160004 -185.008882) (xy 71.106731 -185.029683)
			(xy 71.084628 -185.034682) (xy 71.588882 -185.034682) (xy 71.592953 -184.97906) (xy 71.605079 -184.924623)
			(xy 71.625002 -184.872532) (xy 71.652298 -184.823897) (xy 71.686384 -184.779754) (xy 71.726533 -184.741045)
			(xy 71.771891 -184.708594) (xy 71.821491 -184.683093) (xy 71.874275 -184.665086) (xy 71.929118 -184.654956)
			(xy 71.984852 -184.652919) (xy 72.040289 -184.659019) (xy 72.094246 -184.673125) (xy 72.145575 -184.694937)
			(xy 72.193181 -184.723991) (xy 72.236049 -184.759666) (xy 72.273266 -184.801203) (xy 72.304039 -184.847716)
			(xy 72.327711 -184.898213) (xy 72.328955 -184.902348) (xy 72.724262 -184.902348) (xy 72.728333 -184.846726)
			(xy 72.740459 -184.792289) (xy 72.760382 -184.740198) (xy 72.787678 -184.691563) (xy 72.821764 -184.64742)
			(xy 72.861913 -184.608711) (xy 72.907271 -184.57626) (xy 72.956871 -184.550759) (xy 73.009655 -184.532752)
			(xy 73.064498 -184.522622) (xy 73.120232 -184.520585) (xy 73.175669 -184.526685) (xy 73.229626 -184.540791)
			(xy 73.280955 -184.562603) (xy 73.328561 -184.591657) (xy 73.371429 -184.627332) (xy 73.408646 -184.668869)
			(xy 73.439419 -184.715382) (xy 73.463091 -184.765879) (xy 73.479159 -184.819286) (xy 73.487279 -184.874462)
			(xy 73.487788 -184.902348) (xy 73.487279 -184.930234) (xy 73.479159 -184.98541) (xy 73.463091 -185.038817)
			(xy 73.439419 -185.089314) (xy 73.408646 -185.135827) (xy 73.371429 -185.177364) (xy 73.328561 -185.213039)
			(xy 73.280955 -185.242093) (xy 73.229626 -185.263905) (xy 73.175669 -185.278011) (xy 73.120232 -185.284111)
			(xy 73.064498 -185.282074) (xy 73.009655 -185.271944) (xy 72.956871 -185.253937) (xy 72.907271 -185.228436)
			(xy 72.861913 -185.195985) (xy 72.821764 -185.157276) (xy 72.787678 -185.113133) (xy 72.760382 -185.064498)
			(xy 72.740459 -185.012407) (xy 72.728333 -184.95797) (xy 72.724262 -184.902348) (xy 72.328955 -184.902348)
			(xy 72.343779 -184.95162) (xy 72.351899 -185.006796) (xy 72.352408 -185.034682) (xy 72.351899 -185.062568)
			(xy 72.343779 -185.117744) (xy 72.327711 -185.171151) (xy 72.304039 -185.221648) (xy 72.273266 -185.268161)
			(xy 72.236049 -185.309698) (xy 72.193181 -185.345373) (xy 72.145575 -185.374427) (xy 72.094246 -185.396239)
			(xy 72.040289 -185.410345) (xy 71.984852 -185.416445) (xy 71.929118 -185.414408) (xy 71.874275 -185.404278)
			(xy 71.821491 -185.386271) (xy 71.771891 -185.36077) (xy 71.726533 -185.328319) (xy 71.686384 -185.28961)
			(xy 71.652298 -185.245467) (xy 71.625002 -185.196832) (xy 71.605079 -185.144741) (xy 71.592953 -185.090304)
			(xy 71.588882 -185.034682) (xy 71.084628 -185.034682) (xy 71.05095 -185.042299) (xy 71.022464 -185.044842)
			(xy 71.008051 -185.04644) (xy 70.980923 -185.056647) (xy 70.957752 -185.074061) (xy 70.940405 -185.097281)
			(xy 70.930277 -185.124439) (xy 70.928183 -185.153348) (xy 70.934291 -185.181682) (xy 70.948111 -185.20716)
			(xy 70.957948 -185.217816) (xy 71.705724 -185.965592) (xy 71.716264 -185.975448) (xy 71.741533 -185.989353)
			(xy 71.769683 -185.995632) (xy 71.798466 -185.993784) (xy 71.825582 -185.983955) (xy 71.848864 -185.966931)
			(xy 71.866453 -185.944073) (xy 71.872094 -185.930794) (xy 71.883051 -185.904473) (xy 71.911635 -185.855146)
			(xy 71.947239 -185.81062) (xy 71.989071 -185.771886) (xy 72.036198 -185.739805) (xy 72.087574 -185.715091)
			(xy 72.142054 -185.698295) (xy 72.198427 -185.689789) (xy 72.226932 -185.68924) (xy 72.254182 -185.689706)
			(xy 72.308127 -185.697466) (xy 72.360418 -185.712826) (xy 72.409991 -185.735471) (xy 72.455837 -185.76494)
			(xy 72.497022 -185.800635) (xy 72.532708 -185.841827) (xy 72.562168 -185.887679) (xy 72.584802 -185.937257)
			(xy 72.600151 -185.989551) (xy 72.6079 -186.043498) (xy 72.60844 -186.070748) (xy 72.607913 -186.099257)
			(xy 72.599431 -186.155641) (xy 72.582648 -186.210134) (xy 72.557938 -186.26152) (xy 72.525853 -186.308654)
			(xy 72.487107 -186.350486) (xy 72.442565 -186.386082) (xy 72.393219 -186.41465) (xy 72.366886 -186.425586)
			(xy 72.353665 -186.431321) (xy 72.330866 -186.448926) (xy 72.313886 -186.472193) (xy 72.304073 -186.499275)
			(xy 72.302208 -186.528019) (xy 72.308437 -186.556142) (xy 72.322267 -186.58141) (xy 72.332088 -186.591956)
			(xy 72.499982 -186.75985) (xy 73.05878 -186.75985) (xy 73.062851 -186.704228) (xy 73.074977 -186.649791)
			(xy 73.0949 -186.5977) (xy 73.122196 -186.549065) (xy 73.156282 -186.504922) (xy 73.196431 -186.466213)
			(xy 73.241789 -186.433762) (xy 73.291389 -186.408261) (xy 73.344173 -186.390254) (xy 73.399016 -186.380124)
			(xy 73.45475 -186.378087) (xy 73.510187 -186.384187) (xy 73.564144 -186.398293) (xy 73.615473 -186.420105)
			(xy 73.663079 -186.449159) (xy 73.705947 -186.484834) (xy 73.743164 -186.526371) (xy 73.773937 -186.572884)
			(xy 73.797609 -186.623381) (xy 73.813677 -186.676788) (xy 73.821797 -186.731964) (xy 73.822306 -186.75985)
			(xy 73.821797 -186.787736) (xy 73.813677 -186.842912) (xy 73.797609 -186.896319) (xy 73.773937 -186.946816)
			(xy 73.743164 -186.993329) (xy 73.705947 -187.034866) (xy 73.663079 -187.070541) (xy 73.615473 -187.099595)
			(xy 73.564144 -187.121407) (xy 73.510187 -187.135513) (xy 73.45475 -187.141613) (xy 73.399016 -187.139576)
			(xy 73.344173 -187.129446) (xy 73.291389 -187.111439) (xy 73.241789 -187.085938) (xy 73.196431 -187.053487)
			(xy 73.156282 -187.014778) (xy 73.122196 -186.970635) (xy 73.0949 -186.922) (xy 73.074977 -186.869909)
			(xy 73.062851 -186.815472) (xy 73.05878 -186.75985) (xy 72.499982 -186.75985) (xy 73.385172 -187.64504)
			(xy 73.420986 -187.61202) (xy 73.442235 -187.593183) (xy 73.489259 -187.561357) (xy 73.540478 -187.536845)
			(xy 73.594761 -187.520187) (xy 73.650913 -187.51175) (xy 73.679304 -187.511182) (xy 73.679558 -187.511182)
			(xy 73.706813 -187.511642) (xy 73.760769 -187.519394) (xy 73.813073 -187.534746) (xy 73.862659 -187.557386)
			(xy 73.908518 -187.586853) (xy 73.949717 -187.622547) (xy 73.985416 -187.66374) (xy 74.014889 -187.709595)
			(xy 74.037535 -187.759179) (xy 74.052895 -187.81148) (xy 74.060654 -187.865435) (xy 74.061066 -187.89269)
			(xy 74.061066 -187.892944) (xy 74.060547 -187.921338) (xy 74.052127 -187.9775) (xy 74.035466 -188.03179)
			(xy 74.010933 -188.083006) (xy 73.979071 -188.130014) (xy 73.960228 -188.151262) (xy 73.946766 -188.185552)
			(xy 73.947249 -188.195516) (xy 73.954829 -188.213947) (xy 73.961498 -188.221366) (xy 83.90128 -198.161148)
			(xy 86.42096 -198.161148) (xy 86.434492 -198.160689) (xy 86.460587 -198.153506) (xy 86.483875 -198.139713)
			(xy 86.502717 -198.120283) (xy 86.515787 -198.096582) (xy 86.522165 -198.070278) (xy 86.521403 -198.043223)
			(xy 86.513553 -198.017321) (xy 86.499169 -197.994393) (xy 86.48954 -197.984872) (xy 86.470491 -197.966739)
			(xy 86.437054 -197.926145) (xy 86.409505 -197.881346) (xy 86.388366 -197.83319) (xy 86.374038 -197.782588)
			(xy 86.366791 -197.730498) (xy 86.36635 -197.704202) (xy 86.36635 -197.703948) (xy 86.366836 -197.676697)
			(xy 86.374592 -197.622749) (xy 86.389947 -197.570454) (xy 86.412589 -197.520877) (xy 86.442055 -197.475027)
			(xy 86.477746 -197.433836) (xy 86.518937 -197.398145) (xy 86.564787 -197.368679) (xy 86.614364 -197.346037)
			(xy 86.666659 -197.330682) (xy 86.720607 -197.322926) (xy 86.775109 -197.322926) (xy 86.829057 -197.330682)
			(xy 86.881352 -197.346037) (xy 86.930929 -197.368679) (xy 86.976779 -197.398145) (xy 87.01797 -197.433836)
			(xy 87.053661 -197.475027) (xy 87.083127 -197.520877) (xy 87.105769 -197.570454) (xy 87.121124 -197.622749)
			(xy 87.12888 -197.676697) (xy 87.129366 -197.703948) (xy 87.129366 -197.704202) (xy 87.128931 -197.730501)
			(xy 87.121713 -197.7826) (xy 87.107399 -197.833212) (xy 87.086263 -197.881376) (xy 87.058705 -197.926176)
			(xy 87.02525 -197.966762) (xy 87.006176 -197.984872) (xy 86.996504 -197.994357) (xy 86.98211 -198.017296)
			(xy 86.974254 -198.043212) (xy 86.973491 -198.070282) (xy 86.979872 -198.0966) (xy 86.99295 -198.120313)
			(xy 87.011804 -198.139753) (xy 87.035106 -198.153551) (xy 87.061217 -198.160735) (xy 87.074756 -198.161148)
			(xy 93.32468 -198.161148) (xy 104.39908 -209.235548) (xy 104.39908 -213.284054) (xy 104.399625 -213.299084)
			(xy 104.408386 -213.327838) (xy 104.425134 -213.3528) (xy 104.44842 -213.371809) (xy 104.476229 -213.383221)
			(xy 104.506156 -213.386048) (xy 104.521 -213.383622) (xy 104.538526 -213.380286) (xy 104.574027 -213.376724)
			(xy 104.591866 -213.37651) (xy 104.618517 -213.376981) (xy 104.671226 -213.384921) (xy 104.722162 -213.400628)
			(xy 104.770187 -213.423752) (xy 104.81423 -213.453776) (xy 104.853306 -213.490029) (xy 104.886541 -213.531701)
			(xy 104.913194 -213.577862) (xy 104.932669 -213.62748) (xy 104.94453 -213.679446) (xy 104.948514 -213.7326)
			(xy 104.948513 -213.732618) (xy 105.175558 -213.732618) (xy 105.176056 -213.705969) (xy 105.183999 -213.653265)
			(xy 105.199709 -213.602335) (xy 105.222835 -213.554314) (xy 105.252859 -213.510277) (xy 105.289111 -213.471206)
			(xy 105.330782 -213.437975) (xy 105.37694 -213.411326) (xy 105.426554 -213.391854) (xy 105.478516 -213.379994)
			(xy 105.531666 -213.376011) (xy 105.584816 -213.379994) (xy 105.636778 -213.391854) (xy 105.686392 -213.411326)
			(xy 105.73255 -213.437975) (xy 105.774221 -213.471206) (xy 105.810473 -213.510277) (xy 105.840497 -213.554314)
			(xy 105.863623 -213.602335) (xy 105.879333 -213.653265) (xy 105.887276 -213.705969) (xy 105.887774 -213.732618)
			(xy 105.887252 -213.759267) (xy 106.115856 -213.759267) (xy 106.115856 -213.705969) (xy 106.123799 -213.653265)
			(xy 106.139509 -213.602335) (xy 106.162635 -213.554314) (xy 106.192659 -213.510277) (xy 106.228911 -213.471206)
			(xy 106.270582 -213.437975) (xy 106.31674 -213.411326) (xy 106.366354 -213.391854) (xy 106.418316 -213.379994)
			(xy 106.471466 -213.376011) (xy 106.524616 -213.379994) (xy 106.576578 -213.391854) (xy 106.626192 -213.411326)
			(xy 106.67235 -213.437975) (xy 106.714021 -213.471206) (xy 106.750273 -213.510277) (xy 106.780297 -213.554314)
			(xy 106.803423 -213.602335) (xy 106.819133 -213.653265) (xy 106.827076 -213.705969) (xy 106.827574 -213.732618)
			(xy 107.055158 -213.732618) (xy 107.055656 -213.705969) (xy 107.063599 -213.653265) (xy 107.079309 -213.602335)
			(xy 107.102435 -213.554314) (xy 107.132459 -213.510277) (xy 107.168711 -213.471206) (xy 107.210382 -213.437975)
			(xy 107.25654 -213.411326) (xy 107.306154 -213.391854) (xy 107.358116 -213.379994) (xy 107.411266 -213.376011)
			(xy 107.464416 -213.379994) (xy 107.516378 -213.391854) (xy 107.565992 -213.411326) (xy 107.61215 -213.437975)
			(xy 107.653821 -213.471206) (xy 107.690073 -213.510277) (xy 107.720097 -213.554314) (xy 107.743223 -213.602335)
			(xy 107.758933 -213.653265) (xy 107.766876 -213.705969) (xy 107.767374 -213.732618) (xy 107.766852 -213.759267)
			(xy 107.995456 -213.759267) (xy 107.995456 -213.705969) (xy 108.003399 -213.653265) (xy 108.019109 -213.602335)
			(xy 108.042235 -213.554314) (xy 108.072259 -213.510277) (xy 108.108511 -213.471206) (xy 108.150182 -213.437975)
			(xy 108.19634 -213.411326) (xy 108.245954 -213.391854) (xy 108.297916 -213.379994) (xy 108.351066 -213.376011)
			(xy 108.404216 -213.379994) (xy 108.456178 -213.391854) (xy 108.505792 -213.411326) (xy 108.55195 -213.437975)
			(xy 108.593621 -213.471206) (xy 108.629873 -213.510277) (xy 108.659897 -213.554314) (xy 108.683023 -213.602335)
			(xy 108.698733 -213.653265) (xy 108.706676 -213.705969) (xy 108.707174 -213.732618) (xy 108.706676 -213.759267)
			(xy 108.698733 -213.811971) (xy 108.683023 -213.862901) (xy 108.659897 -213.910922) (xy 108.629873 -213.954959)
			(xy 108.593621 -213.99403) (xy 108.55195 -214.027261) (xy 108.505792 -214.05391) (xy 108.456178 -214.073382)
			(xy 108.404216 -214.085242) (xy 108.351066 -214.089226) (xy 108.297916 -214.085242) (xy 108.245954 -214.073382)
			(xy 108.19634 -214.05391) (xy 108.150182 -214.027261) (xy 108.108511 -213.99403) (xy 108.072259 -213.954959)
			(xy 108.042235 -213.910922) (xy 108.019109 -213.862901) (xy 108.003399 -213.811971) (xy 107.995456 -213.759267)
			(xy 107.766852 -213.759267) (xy 107.766829 -213.760435) (xy 107.758187 -213.815393) (xy 107.741099 -213.868337)
			(xy 107.72902 -213.8934) (xy 107.717082 -213.916768) (xy 107.901486 -214.266272) (xy 107.927394 -214.269574)
			(xy 107.952743 -214.27343) (xy 108.002079 -214.287384) (xy 108.048905 -214.308268) (xy 108.092252 -214.335651)
			(xy 108.131225 -214.368966) (xy 108.165018 -214.407526) (xy 108.192933 -214.450532) (xy 108.214393 -214.497097)
			(xy 108.228954 -214.546258) (xy 108.236315 -214.596998) (xy 108.236766 -214.622634) (xy 108.236268 -214.649283)
			(xy 108.228325 -214.701987) (xy 108.212615 -214.752917) (xy 108.189489 -214.800938) (xy 108.159465 -214.844975)
			(xy 108.123213 -214.884046) (xy 108.081542 -214.917277) (xy 108.035384 -214.943926) (xy 107.98577 -214.963398)
			(xy 107.933808 -214.975258) (xy 107.880658 -214.979242) (xy 107.827508 -214.975258) (xy 107.775546 -214.963398)
			(xy 107.725932 -214.943926) (xy 107.679774 -214.917277) (xy 107.638103 -214.884046) (xy 107.601851 -214.844975)
			(xy 107.571827 -214.800938) (xy 107.548701 -214.752917) (xy 107.532991 -214.701987) (xy 107.525048 -214.649283)
			(xy 107.52455 -214.622634) (xy 107.525074 -214.594816) (xy 107.533725 -214.539858) (xy 107.55082 -214.486914)
			(xy 107.562904 -214.461852) (xy 107.574842 -214.438484) (xy 107.390438 -214.08898) (xy 107.36453 -214.085678)
			(xy 107.339176 -214.081849) (xy 107.289836 -214.067896) (xy 107.243007 -214.047011) (xy 107.199657 -214.019626)
			(xy 107.160683 -213.986308) (xy 107.126889 -213.947745) (xy 107.098976 -213.904734) (xy 107.077518 -213.858165)
			(xy 107.062961 -213.809) (xy 107.055606 -213.758255) (xy 107.055158 -213.732618) (xy 106.827574 -213.732618)
			(xy 106.827076 -213.759267) (xy 106.819133 -213.811971) (xy 106.803423 -213.862901) (xy 106.780297 -213.910922)
			(xy 106.750273 -213.954959) (xy 106.714021 -213.99403) (xy 106.67235 -214.027261) (xy 106.626192 -214.05391)
			(xy 106.576578 -214.073382) (xy 106.524616 -214.085242) (xy 106.471466 -214.089226) (xy 106.418316 -214.085242)
			(xy 106.366354 -214.073382) (xy 106.31674 -214.05391) (xy 106.270582 -214.027261) (xy 106.228911 -213.99403)
			(xy 106.192659 -213.954959) (xy 106.162635 -213.910922) (xy 106.139509 -213.862901) (xy 106.123799 -213.811971)
			(xy 106.115856 -213.759267) (xy 105.887252 -213.759267) (xy 105.887229 -213.760435) (xy 105.878587 -213.815393)
			(xy 105.861499 -213.868337) (xy 105.84942 -213.8934) (xy 105.837482 -213.916768) (xy 106.021886 -214.266272)
			(xy 106.047794 -214.269574) (xy 106.073143 -214.27343) (xy 106.122479 -214.287384) (xy 106.169305 -214.308268)
			(xy 106.212652 -214.335651) (xy 106.251625 -214.368966) (xy 106.285418 -214.407526) (xy 106.313333 -214.450532)
			(xy 106.334793 -214.497097) (xy 106.349354 -214.546258) (xy 106.356715 -214.596998) (xy 106.357166 -214.622634)
			(xy 106.356668 -214.649283) (xy 106.348725 -214.701987) (xy 106.333015 -214.752917) (xy 106.309889 -214.800938)
			(xy 106.279865 -214.844975) (xy 106.243613 -214.884046) (xy 106.201942 -214.917277) (xy 106.155784 -214.943926)
			(xy 106.10617 -214.963398) (xy 106.054208 -214.975258) (xy 106.001058 -214.979242) (xy 105.947908 -214.975258)
			(xy 105.895946 -214.963398) (xy 105.846332 -214.943926) (xy 105.800174 -214.917277) (xy 105.758503 -214.884046)
			(xy 105.722251 -214.844975) (xy 105.692227 -214.800938) (xy 105.669101 -214.752917) (xy 105.653391 -214.701987)
			(xy 105.645448 -214.649283) (xy 105.64495 -214.622634) (xy 105.645474 -214.594816) (xy 105.654125 -214.539858)
			(xy 105.67122 -214.486914) (xy 105.683304 -214.461852) (xy 105.695242 -214.438484) (xy 105.510838 -214.08898)
			(xy 105.48493 -214.085678) (xy 105.459576 -214.081849) (xy 105.410236 -214.067896) (xy 105.363407 -214.047011)
			(xy 105.320057 -214.019626) (xy 105.281083 -213.986308) (xy 105.247289 -213.947745) (xy 105.219376 -213.904734)
			(xy 105.197918 -213.858165) (xy 105.183361 -213.809) (xy 105.176006 -213.758255) (xy 105.175558 -213.732618)
			(xy 104.948513 -213.732618) (xy 104.94453 -213.785754) (xy 104.932669 -213.83772) (xy 104.913194 -213.887338)
			(xy 104.886541 -213.933499) (xy 104.853306 -213.975171) (xy 104.81423 -214.011424) (xy 104.770187 -214.041448)
			(xy 104.722162 -214.064572) (xy 104.671226 -214.080279) (xy 104.618517 -214.088219) (xy 104.591866 -214.088726)
			(xy 104.574027 -214.088508) (xy 104.538526 -214.084947) (xy 104.521 -214.081614) (xy 104.50616 -214.079138)
			(xy 104.476222 -214.081966) (xy 104.448404 -214.093385) (xy 104.425112 -214.112404) (xy 104.408363 -214.137379)
			(xy 104.399607 -214.166147) (xy 104.39908 -214.181182) (xy 104.39908 -214.399622) (xy 104.41548 -214.420811)
			(xy 104.442397 -214.467138) (xy 104.462068 -214.516976) (xy 104.47405 -214.569198) (xy 104.478072 -214.622627)
			(xy 104.474042 -214.676054) (xy 104.462053 -214.728275) (xy 104.442374 -214.77811) (xy 104.41545 -214.824433)
			(xy 104.39908 -214.845646) (xy 104.39908 -214.98814) (xy 104.399608 -215.003154) (xy 104.408326 -215.031888)
			(xy 104.425027 -215.056843) (xy 104.448266 -215.07586) (xy 104.476032 -215.087293) (xy 104.505923 -215.090155)
			(xy 104.520746 -215.087708) (xy 104.544622 -215.083644) (xy 104.56926 -215.080342) (xy 104.741726 -214.781638)
			(xy 104.732074 -214.758524) (xy 104.723559 -214.736892) (xy 104.711575 -214.691974) (xy 104.705536 -214.645879)
			(xy 104.70515 -214.622634) (xy 104.705648 -214.595985) (xy 104.713591 -214.543281) (xy 104.729301 -214.492351)
			(xy 104.752427 -214.44433) (xy 104.782451 -214.400293) (xy 104.818703 -214.361222) (xy 104.860374 -214.327991)
			(xy 104.906532 -214.301342) (xy 104.956146 -214.28187) (xy 105.008108 -214.27001) (xy 105.061258 -214.266027)
			(xy 105.114408 -214.27001) (xy 105.16637 -214.28187) (xy 105.215984 -214.301342) (xy 105.262142 -214.327991)
			(xy 105.303813 -214.361222) (xy 105.340065 -214.400293) (xy 105.370089 -214.44433) (xy 105.393215 -214.492351)
			(xy 105.408925 -214.543281) (xy 105.416868 -214.595985) (xy 105.417366 -214.622634) (xy 105.416918 -214.648261)
			(xy 105.409569 -214.698985) (xy 105.395026 -214.748133) (xy 105.373591 -214.794689) (xy 105.345705 -214.837693)
			(xy 105.311945 -214.876257) (xy 105.273007 -214.909586) (xy 105.229695 -214.93699) (xy 105.182902 -214.957905)
			(xy 105.133596 -214.971899) (xy 105.108248 -214.975694) (xy 105.08361 -214.978996) (xy 104.911144 -215.2777)
			(xy 104.920796 -215.300814) (xy 104.929313 -215.322446) (xy 104.941303 -215.367363) (xy 104.947348 -215.413459)
			(xy 104.94772 -215.436704) (xy 104.947197 -215.463353) (xy 105.175802 -215.463353) (xy 105.175802 -215.410055)
			(xy 105.183745 -215.357351) (xy 105.199455 -215.306421) (xy 105.222581 -215.2584) (xy 105.252605 -215.214363)
			(xy 105.288857 -215.175292) (xy 105.330528 -215.142061) (xy 105.376686 -215.115412) (xy 105.4263 -215.09594)
			(xy 105.478262 -215.08408) (xy 105.531412 -215.080097) (xy 105.584562 -215.08408) (xy 105.636524 -215.09594)
			(xy 105.686138 -215.115412) (xy 105.732296 -215.142061) (xy 105.773967 -215.175292) (xy 105.810219 -215.214363)
			(xy 105.840243 -215.2584) (xy 105.863369 -215.306421) (xy 105.879079 -215.357351) (xy 105.887022 -215.410055)
			(xy 105.88752 -215.436704) (xy 106.115104 -215.436704) (xy 106.115484 -215.411073) (xy 106.12282 -215.360338)
			(xy 106.137357 -215.31118) (xy 106.158793 -215.264615) (xy 106.186685 -215.221605) (xy 106.220457 -215.18304)
			(xy 106.25941 -215.149717) (xy 106.30274 -215.122324) (xy 106.34955 -215.101428) (xy 106.398873 -215.087461)
			(xy 106.424222 -215.083644) (xy 106.44886 -215.080342) (xy 106.621326 -214.781638) (xy 106.611674 -214.758524)
			(xy 106.603165 -214.736889) (xy 106.591176 -214.691973) (xy 106.585128 -214.645879) (xy 106.58475 -214.622634)
			(xy 106.585248 -214.595985) (xy 106.593191 -214.543281) (xy 106.608901 -214.492351) (xy 106.632027 -214.44433)
			(xy 106.662051 -214.400293) (xy 106.698303 -214.361222) (xy 106.739974 -214.327991) (xy 106.786132 -214.301342)
			(xy 106.835746 -214.28187) (xy 106.887708 -214.27001) (xy 106.940858 -214.266027) (xy 106.994008 -214.27001)
			(xy 107.04597 -214.28187) (xy 107.095584 -214.301342) (xy 107.141742 -214.327991) (xy 107.183413 -214.361222)
			(xy 107.219665 -214.400293) (xy 107.249689 -214.44433) (xy 107.272815 -214.492351) (xy 107.288525 -214.543281)
			(xy 107.296468 -214.595985) (xy 107.296966 -214.622634) (xy 107.296469 -214.648261) (xy 107.289143 -214.698988)
			(xy 107.274618 -214.74814) (xy 107.253194 -214.794701) (xy 107.225315 -214.837708) (xy 107.191557 -214.876273)
			(xy 107.152617 -214.909599) (xy 107.109301 -214.936995) (xy 107.062503 -214.957897) (xy 107.013192 -214.971872)
			(xy 106.987848 -214.975694) (xy 106.96321 -214.978996) (xy 106.790744 -215.2777) (xy 106.800396 -215.300814)
			(xy 106.808915 -215.322445) (xy 106.820901 -215.367363) (xy 106.826945 -215.413459) (xy 106.82732 -215.436704)
			(xy 106.826822 -215.463353) (xy 107.055402 -215.463353) (xy 107.055402 -215.410055) (xy 107.063345 -215.357351)
			(xy 107.079055 -215.306421) (xy 107.102181 -215.2584) (xy 107.132205 -215.214363) (xy 107.168457 -215.175292)
			(xy 107.210128 -215.142061) (xy 107.256286 -215.115412) (xy 107.3059 -215.09594) (xy 107.357862 -215.08408)
			(xy 107.411012 -215.080097) (xy 107.464162 -215.08408) (xy 107.516124 -215.09594) (xy 107.565738 -215.115412)
			(xy 107.611896 -215.142061) (xy 107.653567 -215.175292) (xy 107.689819 -215.214363) (xy 107.719843 -215.2584)
			(xy 107.742969 -215.306421) (xy 107.758679 -215.357351) (xy 107.766622 -215.410055) (xy 107.76712 -215.436704)
			(xy 107.994704 -215.436704) (xy 107.995084 -215.411073) (xy 108.00242 -215.360338) (xy 108.016957 -215.31118)
			(xy 108.038393 -215.264615) (xy 108.066285 -215.221605) (xy 108.100057 -215.18304) (xy 108.13901 -215.149717)
			(xy 108.18234 -215.122324) (xy 108.22915 -215.101428) (xy 108.278473 -215.087461) (xy 108.303822 -215.083644)
			(xy 108.32846 -215.080342) (xy 108.500926 -214.781638) (xy 108.491274 -214.758524) (xy 108.482765 -214.736889)
			(xy 108.470776 -214.691973) (xy 108.464728 -214.645879) (xy 108.46435 -214.622634) (xy 108.464848 -214.595985)
			(xy 108.472791 -214.543281) (xy 108.488501 -214.492351) (xy 108.511627 -214.44433) (xy 108.541651 -214.400293)
			(xy 108.577903 -214.361222) (xy 108.619574 -214.327991) (xy 108.665732 -214.301342) (xy 108.715346 -214.28187)
			(xy 108.767308 -214.27001) (xy 108.820458 -214.266027) (xy 108.873608 -214.27001) (xy 108.92557 -214.28187)
			(xy 108.975184 -214.301342) (xy 109.021342 -214.327991) (xy 109.063013 -214.361222) (xy 109.099265 -214.400293)
			(xy 109.129289 -214.44433) (xy 109.152415 -214.492351) (xy 109.168125 -214.543281) (xy 109.172616 -214.573083)
			(xy 109.404902 -214.573083) (xy 109.404902 -214.519785) (xy 109.412845 -214.467081) (xy 109.428555 -214.416151)
			(xy 109.451681 -214.36813) (xy 109.481705 -214.324093) (xy 109.517957 -214.285022) (xy 109.559628 -214.251791)
			(xy 109.605786 -214.225142) (xy 109.6554 -214.20567) (xy 109.707362 -214.19381) (xy 109.760512 -214.189827)
			(xy 109.813662 -214.19381) (xy 109.865624 -214.20567) (xy 109.915238 -214.225142) (xy 109.961396 -214.251791)
			(xy 110.003067 -214.285022) (xy 110.039319 -214.324093) (xy 110.069343 -214.36813) (xy 110.092469 -214.416151)
			(xy 110.108179 -214.467081) (xy 110.116122 -214.519785) (xy 110.11662 -214.546434) (xy 110.116122 -214.573083)
			(xy 110.108179 -214.625787) (xy 110.092469 -214.676717) (xy 110.069343 -214.724738) (xy 110.039319 -214.768775)
			(xy 110.003067 -214.807846) (xy 109.961396 -214.841077) (xy 109.915238 -214.867726) (xy 109.865624 -214.887198)
			(xy 109.813662 -214.899058) (xy 109.760512 -214.903042) (xy 109.707362 -214.899058) (xy 109.6554 -214.887198)
			(xy 109.605786 -214.867726) (xy 109.559628 -214.841077) (xy 109.517957 -214.807846) (xy 109.481705 -214.768775)
			(xy 109.451681 -214.724738) (xy 109.428555 -214.676717) (xy 109.412845 -214.625787) (xy 109.404902 -214.573083)
			(xy 109.172616 -214.573083) (xy 109.176068 -214.595985) (xy 109.176566 -214.622634) (xy 109.176069 -214.648261)
			(xy 109.168743 -214.698988) (xy 109.154218 -214.74814) (xy 109.132794 -214.794701) (xy 109.104915 -214.837708)
			(xy 109.071157 -214.876273) (xy 109.032217 -214.909599) (xy 108.988901 -214.936995) (xy 108.942103 -214.957897)
			(xy 108.892792 -214.971872) (xy 108.867448 -214.975694) (xy 108.84281 -214.978996) (xy 108.670344 -215.2777)
			(xy 108.679996 -215.300814) (xy 108.688515 -215.322445) (xy 108.700501 -215.367363) (xy 108.706545 -215.413459)
			(xy 108.70692 -215.4367) (xy 108.933972 -215.4367) (xy 108.937955 -215.383546) (xy 108.949817 -215.33158)
			(xy 108.969291 -215.281962) (xy 108.995943 -215.235801) (xy 109.029177 -215.194127) (xy 109.068251 -215.157873)
			(xy 109.112293 -215.127847) (xy 109.160318 -215.104721) (xy 109.211253 -215.089011) (xy 109.263961 -215.081068)
			(xy 109.290612 -215.080596) (xy 109.315626 -215.081031) (xy 109.365163 -215.088017) (xy 109.413236 -215.101864)
			(xy 109.458899 -215.1223) (xy 109.501254 -215.148923) (xy 109.539468 -215.181208) (xy 109.572791 -215.218523)
			(xy 109.58703 -215.239092) (xy 109.933994 -215.239092) (xy 109.948204 -215.218502) (xy 109.981537 -215.181195)
			(xy 110.01976 -215.148915) (xy 110.06212 -215.122296) (xy 110.107785 -215.10186) (xy 110.155859 -215.08801)
			(xy 110.205397 -215.081017) (xy 110.230412 -215.080596) (xy 110.257061 -215.081087) (xy 110.309764 -215.089032)
			(xy 110.360693 -215.104743) (xy 110.408713 -215.127869) (xy 110.452749 -215.157894) (xy 110.491819 -215.194147)
			(xy 110.525049 -215.235817) (xy 110.551697 -215.281975) (xy 110.571169 -215.331589) (xy 110.583029 -215.383551)
			(xy 110.587012 -215.4367) (xy 110.583029 -215.489849) (xy 110.571169 -215.541811) (xy 110.551697 -215.591425)
			(xy 110.525049 -215.637583) (xy 110.491819 -215.679253) (xy 110.452749 -215.715506) (xy 110.408713 -215.745531)
			(xy 110.360693 -215.768657) (xy 110.309764 -215.784368) (xy 110.257061 -215.792313) (xy 110.230412 -215.792812)
			(xy 110.205399 -215.792355) (xy 110.155863 -215.785372) (xy 110.107791 -215.771529) (xy 110.062128 -215.751097)
			(xy 110.019773 -215.724478) (xy 109.981557 -215.692195) (xy 109.948234 -215.654884) (xy 109.933994 -215.634316)
			(xy 109.58703 -215.634316) (xy 109.572808 -215.654897) (xy 109.539476 -215.692204) (xy 109.501255 -215.724484)
			(xy 109.458898 -215.751104) (xy 109.413234 -215.771541) (xy 109.365162 -215.785393) (xy 109.315626 -215.792389)
			(xy 109.290612 -215.792812) (xy 109.263961 -215.792332) (xy 109.211253 -215.784389) (xy 109.160318 -215.768679)
			(xy 109.112293 -215.745553) (xy 109.068251 -215.715527) (xy 109.029177 -215.679273) (xy 108.995943 -215.637599)
			(xy 108.969291 -215.591438) (xy 108.949817 -215.54182) (xy 108.937955 -215.489854) (xy 108.933972 -215.4367)
			(xy 108.70692 -215.4367) (xy 108.70692 -215.436704) (xy 108.706422 -215.463353) (xy 108.698479 -215.516057)
			(xy 108.682769 -215.566987) (xy 108.659643 -215.615008) (xy 108.629619 -215.659045) (xy 108.593367 -215.698116)
			(xy 108.551696 -215.731347) (xy 108.505538 -215.757996) (xy 108.455924 -215.777468) (xy 108.403962 -215.789328)
			(xy 108.350812 -215.793312) (xy 108.297662 -215.789328) (xy 108.2457 -215.777468) (xy 108.196086 -215.757996)
			(xy 108.149928 -215.731347) (xy 108.108257 -215.698116) (xy 108.072005 -215.659045) (xy 108.041981 -215.615008)
			(xy 108.018855 -215.566987) (xy 108.003145 -215.516057) (xy 107.995202 -215.463353) (xy 107.994704 -215.436704)
			(xy 107.76712 -215.436704) (xy 107.766622 -215.463353) (xy 107.758679 -215.516057) (xy 107.742969 -215.566987)
			(xy 107.719843 -215.615008) (xy 107.689819 -215.659045) (xy 107.653567 -215.698116) (xy 107.611896 -215.731347)
			(xy 107.565738 -215.757996) (xy 107.516124 -215.777468) (xy 107.464162 -215.789328) (xy 107.411012 -215.793312)
			(xy 107.357862 -215.789328) (xy 107.3059 -215.777468) (xy 107.256286 -215.757996) (xy 107.210128 -215.731347)
			(xy 107.168457 -215.698116) (xy 107.132205 -215.659045) (xy 107.102181 -215.615008) (xy 107.079055 -215.566987)
			(xy 107.063345 -215.516057) (xy 107.055402 -215.463353) (xy 106.826822 -215.463353) (xy 106.818879 -215.516057)
			(xy 106.803169 -215.566987) (xy 106.780043 -215.615008) (xy 106.750019 -215.659045) (xy 106.713767 -215.698116)
			(xy 106.672096 -215.731347) (xy 106.625938 -215.757996) (xy 106.576324 -215.777468) (xy 106.524362 -215.789328)
			(xy 106.471212 -215.793312) (xy 106.418062 -215.789328) (xy 106.3661 -215.777468) (xy 106.316486 -215.757996)
			(xy 106.270328 -215.731347) (xy 106.228657 -215.698116) (xy 106.192405 -215.659045) (xy 106.162381 -215.615008)
			(xy 106.139255 -215.566987) (xy 106.123545 -215.516057) (xy 106.115602 -215.463353) (xy 106.115104 -215.436704)
			(xy 105.88752 -215.436704) (xy 105.887022 -215.463353) (xy 105.879079 -215.516057) (xy 105.863369 -215.566987)
			(xy 105.840243 -215.615008) (xy 105.810219 -215.659045) (xy 105.773967 -215.698116) (xy 105.732296 -215.731347)
			(xy 105.686138 -215.757996) (xy 105.636524 -215.777468) (xy 105.584562 -215.789328) (xy 105.531412 -215.793312)
			(xy 105.478262 -215.789328) (xy 105.4263 -215.777468) (xy 105.376686 -215.757996) (xy 105.330528 -215.731347)
			(xy 105.288857 -215.698116) (xy 105.252605 -215.659045) (xy 105.222581 -215.615008) (xy 105.199455 -215.566987)
			(xy 105.183745 -215.516057) (xy 105.175802 -215.463353) (xy 104.947197 -215.463353) (xy 104.947171 -215.464687)
			(xy 104.938415 -215.519965) (xy 104.921121 -215.573192) (xy 104.895712 -215.623058) (xy 104.862816 -215.668337)
			(xy 104.823243 -215.707911) (xy 104.777965 -215.740808) (xy 104.728099 -215.766218) (xy 104.674872 -215.783513)
			(xy 104.619595 -215.79227) (xy 104.591612 -215.792812) (xy 104.573773 -215.792592) (xy 104.538274 -215.789025)
			(xy 104.520746 -215.7857) (xy 104.505928 -215.783263) (xy 104.47605 -215.786147) (xy 104.448301 -215.797589)
			(xy 104.425073 -215.816601) (xy 104.408373 -215.841542) (xy 104.399642 -215.87026) (xy 104.39908 -215.885268)
			(xy 104.39908 -216.026746) (xy 104.415584 -216.047987) (xy 104.442681 -216.094452) (xy 104.462487 -216.144461)
			(xy 104.474552 -216.19688) (xy 104.478603 -216.250516) (xy 104.476587 -216.277169) (xy 104.706156 -216.277169)
			(xy 104.706156 -216.223871) (xy 104.714099 -216.171167) (xy 104.729809 -216.120237) (xy 104.752935 -216.072216)
			(xy 104.782959 -216.028179) (xy 104.819211 -215.989108) (xy 104.860882 -215.955877) (xy 104.90704 -215.929228)
			(xy 104.956654 -215.909756) (xy 105.008616 -215.897896) (xy 105.061766 -215.893913) (xy 105.114916 -215.897896)
			(xy 105.166878 -215.909756) (xy 105.216492 -215.929228) (xy 105.26265 -215.955877) (xy 105.304321 -215.989108)
			(xy 105.340573 -216.028179) (xy 105.370597 -216.072216) (xy 105.393723 -216.120237) (xy 105.409433 -216.171167)
			(xy 105.417376 -216.223871) (xy 105.417874 -216.25052) (xy 105.417376 -216.277169) (xy 105.645956 -216.277169)
			(xy 105.645956 -216.223871) (xy 105.653899 -216.171167) (xy 105.669609 -216.120237) (xy 105.692735 -216.072216)
			(xy 105.722759 -216.028179) (xy 105.759011 -215.989108) (xy 105.800682 -215.955877) (xy 105.84684 -215.929228)
			(xy 105.896454 -215.909756) (xy 105.948416 -215.897896) (xy 106.001566 -215.893913) (xy 106.054716 -215.897896)
			(xy 106.106678 -215.909756) (xy 106.156292 -215.929228) (xy 106.20245 -215.955877) (xy 106.244121 -215.989108)
			(xy 106.280373 -216.028179) (xy 106.310397 -216.072216) (xy 106.333523 -216.120237) (xy 106.349233 -216.171167)
			(xy 106.357176 -216.223871) (xy 106.357674 -216.25052) (xy 106.357176 -216.277169) (xy 106.585756 -216.277169)
			(xy 106.585756 -216.223871) (xy 106.593699 -216.171167) (xy 106.609409 -216.120237) (xy 106.632535 -216.072216)
			(xy 106.662559 -216.028179) (xy 106.698811 -215.989108) (xy 106.740482 -215.955877) (xy 106.78664 -215.929228)
			(xy 106.836254 -215.909756) (xy 106.888216 -215.897896) (xy 106.941366 -215.893913) (xy 106.994516 -215.897896)
			(xy 107.046478 -215.909756) (xy 107.096092 -215.929228) (xy 107.14225 -215.955877) (xy 107.183921 -215.989108)
			(xy 107.220173 -216.028179) (xy 107.250197 -216.072216) (xy 107.273323 -216.120237) (xy 107.289033 -216.171167)
			(xy 107.296976 -216.223871) (xy 107.297474 -216.25052) (xy 107.296976 -216.277169) (xy 107.525556 -216.277169)
			(xy 107.525556 -216.223871) (xy 107.533499 -216.171167) (xy 107.549209 -216.120237) (xy 107.572335 -216.072216)
			(xy 107.602359 -216.028179) (xy 107.638611 -215.989108) (xy 107.680282 -215.955877) (xy 107.72644 -215.929228)
			(xy 107.776054 -215.909756) (xy 107.828016 -215.897896) (xy 107.881166 -215.893913) (xy 107.934316 -215.897896)
			(xy 107.986278 -215.909756) (xy 108.035892 -215.929228) (xy 108.08205 -215.955877) (xy 108.123721 -215.989108)
			(xy 108.159973 -216.028179) (xy 108.189997 -216.072216) (xy 108.213123 -216.120237) (xy 108.228833 -216.171167)
			(xy 108.236776 -216.223871) (xy 108.237274 -216.25052) (xy 108.236776 -216.277169) (xy 108.465356 -216.277169)
			(xy 108.465356 -216.223871) (xy 108.473299 -216.171167) (xy 108.489009 -216.120237) (xy 108.512135 -216.072216)
			(xy 108.542159 -216.028179) (xy 108.578411 -215.989108) (xy 108.620082 -215.955877) (xy 108.66624 -215.929228)
			(xy 108.715854 -215.909756) (xy 108.767816 -215.897896) (xy 108.820966 -215.893913) (xy 108.874116 -215.897896)
			(xy 108.926078 -215.909756) (xy 108.975692 -215.929228) (xy 109.02185 -215.955877) (xy 109.063521 -215.989108)
			(xy 109.099773 -216.028179) (xy 109.129797 -216.072216) (xy 109.152923 -216.120237) (xy 109.168633 -216.171167)
			(xy 109.176576 -216.223871) (xy 109.177074 -216.25052) (xy 109.176576 -216.277169) (xy 109.405156 -216.277169)
			(xy 109.405156 -216.223871) (xy 109.413099 -216.171167) (xy 109.428809 -216.120237) (xy 109.451935 -216.072216)
			(xy 109.481959 -216.028179) (xy 109.518211 -215.989108) (xy 109.559882 -215.955877) (xy 109.60604 -215.929228)
			(xy 109.655654 -215.909756) (xy 109.707616 -215.897896) (xy 109.760766 -215.893913) (xy 109.813916 -215.897896)
			(xy 109.865878 -215.909756) (xy 109.915492 -215.929228) (xy 109.96165 -215.955877) (xy 110.003321 -215.989108)
			(xy 110.039573 -216.028179) (xy 110.069597 -216.072216) (xy 110.092723 -216.120237) (xy 110.108433 -216.171167)
			(xy 110.116376 -216.223871) (xy 110.116874 -216.25052) (xy 110.116376 -216.277169) (xy 110.344956 -216.277169)
			(xy 110.344956 -216.223871) (xy 110.352899 -216.171167) (xy 110.368609 -216.120237) (xy 110.391735 -216.072216)
			(xy 110.421759 -216.028179) (xy 110.458011 -215.989108) (xy 110.499682 -215.955877) (xy 110.54584 -215.929228)
			(xy 110.595454 -215.909756) (xy 110.647416 -215.897896) (xy 110.700566 -215.893913) (xy 110.753716 -215.897896)
			(xy 110.805678 -215.909756) (xy 110.855292 -215.929228) (xy 110.90145 -215.955877) (xy 110.943121 -215.989108)
			(xy 110.979373 -216.028179) (xy 111.009397 -216.072216) (xy 111.032523 -216.120237) (xy 111.048233 -216.171167)
			(xy 111.056176 -216.223871) (xy 111.056674 -216.25052) (xy 111.056176 -216.277169) (xy 111.048233 -216.329873)
			(xy 111.032523 -216.380803) (xy 111.009397 -216.428824) (xy 110.979373 -216.472861) (xy 110.943121 -216.511932)
			(xy 110.90145 -216.545163) (xy 110.855292 -216.571812) (xy 110.805678 -216.591284) (xy 110.753716 -216.603144)
			(xy 110.700566 -216.607128) (xy 110.647416 -216.603144) (xy 110.595454 -216.591284) (xy 110.54584 -216.571812)
			(xy 110.499682 -216.545163) (xy 110.458011 -216.511932) (xy 110.421759 -216.472861) (xy 110.391735 -216.428824)
			(xy 110.368609 -216.380803) (xy 110.352899 -216.329873) (xy 110.344956 -216.277169) (xy 110.116376 -216.277169)
			(xy 110.108433 -216.329873) (xy 110.092723 -216.380803) (xy 110.069597 -216.428824) (xy 110.039573 -216.472861)
			(xy 110.003321 -216.511932) (xy 109.96165 -216.545163) (xy 109.915492 -216.571812) (xy 109.865878 -216.591284)
			(xy 109.813916 -216.603144) (xy 109.760766 -216.607128) (xy 109.707616 -216.603144) (xy 109.655654 -216.591284)
			(xy 109.60604 -216.571812) (xy 109.559882 -216.545163) (xy 109.518211 -216.511932) (xy 109.481959 -216.472861)
			(xy 109.451935 -216.428824) (xy 109.428809 -216.380803) (xy 109.413099 -216.329873) (xy 109.405156 -216.277169)
			(xy 109.176576 -216.277169) (xy 109.168633 -216.329873) (xy 109.152923 -216.380803) (xy 109.129797 -216.428824)
			(xy 109.099773 -216.472861) (xy 109.063521 -216.511932) (xy 109.02185 -216.545163) (xy 108.975692 -216.571812)
			(xy 108.926078 -216.591284) (xy 108.874116 -216.603144) (xy 108.820966 -216.607128) (xy 108.767816 -216.603144)
			(xy 108.715854 -216.591284) (xy 108.66624 -216.571812) (xy 108.620082 -216.545163) (xy 108.578411 -216.511932)
			(xy 108.542159 -216.472861) (xy 108.512135 -216.428824) (xy 108.489009 -216.380803) (xy 108.473299 -216.329873)
			(xy 108.465356 -216.277169) (xy 108.236776 -216.277169) (xy 108.228833 -216.329873) (xy 108.213123 -216.380803)
			(xy 108.189997 -216.428824) (xy 108.159973 -216.472861) (xy 108.123721 -216.511932) (xy 108.08205 -216.545163)
			(xy 108.035892 -216.571812) (xy 107.986278 -216.591284) (xy 107.934316 -216.603144) (xy 107.881166 -216.607128)
			(xy 107.828016 -216.603144) (xy 107.776054 -216.591284) (xy 107.72644 -216.571812) (xy 107.680282 -216.545163)
			(xy 107.638611 -216.511932) (xy 107.602359 -216.472861) (xy 107.572335 -216.428824) (xy 107.549209 -216.380803)
			(xy 107.533499 -216.329873) (xy 107.525556 -216.277169) (xy 107.296976 -216.277169) (xy 107.289033 -216.329873)
			(xy 107.273323 -216.380803) (xy 107.250197 -216.428824) (xy 107.220173 -216.472861) (xy 107.183921 -216.511932)
			(xy 107.14225 -216.545163) (xy 107.096092 -216.571812) (xy 107.046478 -216.591284) (xy 106.994516 -216.603144)
			(xy 106.941366 -216.607128) (xy 106.888216 -216.603144) (xy 106.836254 -216.591284) (xy 106.78664 -216.571812)
			(xy 106.740482 -216.545163) (xy 106.698811 -216.511932) (xy 106.662559 -216.472861) (xy 106.632535 -216.428824)
			(xy 106.609409 -216.380803) (xy 106.593699 -216.329873) (xy 106.585756 -216.277169) (xy 106.357176 -216.277169)
			(xy 106.349233 -216.329873) (xy 106.333523 -216.380803) (xy 106.310397 -216.428824) (xy 106.280373 -216.472861)
			(xy 106.244121 -216.511932) (xy 106.20245 -216.545163) (xy 106.156292 -216.571812) (xy 106.106678 -216.591284)
			(xy 106.054716 -216.603144) (xy 106.001566 -216.607128) (xy 105.948416 -216.603144) (xy 105.896454 -216.591284)
			(xy 105.84684 -216.571812) (xy 105.800682 -216.545163) (xy 105.759011 -216.511932) (xy 105.722759 -216.472861)
			(xy 105.692735 -216.428824) (xy 105.669609 -216.380803) (xy 105.653899 -216.329873) (xy 105.645956 -216.277169)
			(xy 105.417376 -216.277169) (xy 105.409433 -216.329873) (xy 105.393723 -216.380803) (xy 105.370597 -216.428824)
			(xy 105.340573 -216.472861) (xy 105.304321 -216.511932) (xy 105.26265 -216.545163) (xy 105.216492 -216.571812)
			(xy 105.166878 -216.591284) (xy 105.114916 -216.603144) (xy 105.061766 -216.607128) (xy 105.008616 -216.603144)
			(xy 104.956654 -216.591284) (xy 104.90704 -216.571812) (xy 104.860882 -216.545163) (xy 104.819211 -216.511932)
			(xy 104.782959 -216.472861) (xy 104.752935 -216.428824) (xy 104.729809 -216.380803) (xy 104.714099 -216.329873)
			(xy 104.706156 -216.277169) (xy 104.476587 -216.277169) (xy 104.474547 -216.304151) (xy 104.462477 -216.356568)
			(xy 104.442667 -216.406576) (xy 104.415567 -216.453039) (xy 104.39908 -216.474294) (xy 104.39908 -216.615772)
			(xy 104.399614 -216.63081) (xy 104.408361 -216.659586) (xy 104.425106 -216.684569) (xy 104.448399 -216.703596)
			(xy 104.476221 -216.715019) (xy 104.506164 -216.717848) (xy 104.521 -216.71534) (xy 104.538526 -216.712004)
			(xy 104.574027 -216.708444) (xy 104.591866 -216.708228) (xy 104.618516 -216.708699) (xy 104.671222 -216.716638)
			(xy 104.722155 -216.732345) (xy 104.770178 -216.755467) (xy 104.814219 -216.78549) (xy 104.853292 -216.821741)
			(xy 104.886526 -216.863412) (xy 104.913178 -216.90957) (xy 104.932652 -216.959185) (xy 104.944513 -217.011149)
			(xy 104.948496 -217.0643) (xy 104.944513 -217.117451) (xy 104.932652 -217.169415) (xy 104.913178 -217.21903)
			(xy 104.886526 -217.265188) (xy 104.853292 -217.306859) (xy 104.814219 -217.34311) (xy 104.770178 -217.373133)
			(xy 104.722155 -217.396255) (xy 104.671222 -217.411962) (xy 104.618516 -217.419901) (xy 104.591866 -217.420444)
			(xy 104.574027 -217.420226) (xy 104.538526 -217.416665) (xy 104.521 -217.413332) (xy 104.506161 -217.410856)
			(xy 104.476225 -217.413684) (xy 104.448408 -217.425102) (xy 104.425119 -217.444123) (xy 104.408373 -217.469098)
			(xy 104.399622 -217.497865) (xy 104.39908 -217.5129) (xy 104.39908 -217.654632) (xy 104.413963 -217.673722)
			(xy 104.438978 -217.715162) (xy 104.458151 -217.759609) (xy 104.471128 -217.806242) (xy 104.47767 -217.854203)
			(xy 104.478074 -217.878406) (xy 104.705658 -217.878406) (xy 104.706079 -217.852777) (xy 104.713414 -217.802046)
			(xy 104.727948 -217.752891) (xy 104.749381 -217.706328) (xy 104.777269 -217.66332) (xy 104.811035 -217.624755)
			(xy 104.849983 -217.591431) (xy 104.893307 -217.564037) (xy 104.940112 -217.543138) (xy 104.989429 -217.529166)
			(xy 105.014776 -217.525346) (xy 105.039414 -217.522044) (xy 105.21188 -217.22334) (xy 105.202228 -217.200226)
			(xy 105.193723 -217.17859) (xy 105.181731 -217.133674) (xy 105.175682 -217.08758) (xy 105.175304 -217.064336)
			(xy 105.175802 -217.037687) (xy 105.183745 -216.984983) (xy 105.199455 -216.934053) (xy 105.222581 -216.886032)
			(xy 105.252605 -216.841995) (xy 105.288857 -216.802924) (xy 105.330528 -216.769693) (xy 105.376686 -216.743044)
			(xy 105.4263 -216.723572) (xy 105.478262 -216.711712) (xy 105.531412 -216.707729) (xy 105.584562 -216.711712)
			(xy 105.636524 -216.723572) (xy 105.686138 -216.743044) (xy 105.732296 -216.769693) (xy 105.773967 -216.802924)
			(xy 105.810219 -216.841995) (xy 105.840243 -216.886032) (xy 105.863369 -216.934053) (xy 105.879079 -216.984983)
			(xy 105.887022 -217.037687) (xy 105.88752 -217.064336) (xy 105.887064 -217.089965) (xy 105.886917 -217.090985)
			(xy 106.115856 -217.090985) (xy 106.115856 -217.037687) (xy 106.123799 -216.984983) (xy 106.139509 -216.934053)
			(xy 106.162635 -216.886032) (xy 106.192659 -216.841995) (xy 106.228911 -216.802924) (xy 106.270582 -216.769693)
			(xy 106.31674 -216.743044) (xy 106.366354 -216.723572) (xy 106.418316 -216.711712) (xy 106.471466 -216.707729)
			(xy 106.524616 -216.711712) (xy 106.576578 -216.723572) (xy 106.626192 -216.743044) (xy 106.67235 -216.769693)
			(xy 106.714021 -216.802924) (xy 106.750273 -216.841995) (xy 106.780297 -216.886032) (xy 106.803423 -216.934053)
			(xy 106.819133 -216.984983) (xy 106.827076 -217.037687) (xy 106.827574 -217.064336) (xy 106.827076 -217.090985)
			(xy 106.819133 -217.143689) (xy 106.803423 -217.194619) (xy 106.780297 -217.24264) (xy 106.750273 -217.286677)
			(xy 106.714021 -217.325748) (xy 106.67235 -217.358979) (xy 106.626192 -217.385628) (xy 106.576578 -217.4051)
			(xy 106.524616 -217.41696) (xy 106.471466 -217.420944) (xy 106.418316 -217.41696) (xy 106.366354 -217.4051)
			(xy 106.31674 -217.385628) (xy 106.270582 -217.358979) (xy 106.228911 -217.325748) (xy 106.192659 -217.286677)
			(xy 106.162635 -217.24264) (xy 106.139509 -217.194619) (xy 106.123799 -217.143689) (xy 106.115856 -217.090985)
			(xy 105.886917 -217.090985) (xy 105.879737 -217.140695) (xy 105.865209 -217.18985) (xy 105.843782 -217.236414)
			(xy 105.815899 -217.279423) (xy 105.782135 -217.317989) (xy 105.74319 -217.351313) (xy 105.699868 -217.378708)
			(xy 105.653065 -217.399607) (xy 105.603748 -217.413577) (xy 105.578402 -217.417396) (xy 105.553764 -217.420698)
			(xy 105.381298 -217.719402) (xy 105.39095 -217.742516) (xy 105.399467 -217.764148) (xy 105.411454 -217.809066)
			(xy 105.417499 -217.855161) (xy 105.417874 -217.878406) (xy 105.645458 -217.878406) (xy 105.645956 -217.851757)
			(xy 105.653899 -217.799053) (xy 105.669609 -217.748123) (xy 105.692735 -217.700102) (xy 105.722759 -217.656065)
			(xy 105.759011 -217.616994) (xy 105.800682 -217.583763) (xy 105.84684 -217.557114) (xy 105.896454 -217.537642)
			(xy 105.948416 -217.525782) (xy 106.001566 -217.521799) (xy 106.054716 -217.525782) (xy 106.106678 -217.537642)
			(xy 106.156292 -217.557114) (xy 106.20245 -217.583763) (xy 106.244121 -217.616994) (xy 106.280373 -217.656065)
			(xy 106.310397 -217.700102) (xy 106.333523 -217.748123) (xy 106.349233 -217.799053) (xy 106.357176 -217.851757)
			(xy 106.357674 -217.878406) (xy 106.585258 -217.878406) (xy 106.585679 -217.852777) (xy 106.593014 -217.802046)
			(xy 106.607548 -217.752891) (xy 106.628981 -217.706328) (xy 106.656869 -217.66332) (xy 106.690635 -217.624755)
			(xy 106.729583 -217.591431) (xy 106.772907 -217.564037) (xy 106.819712 -217.543138) (xy 106.869029 -217.529166)
			(xy 106.894376 -217.525346) (xy 106.919014 -217.522044) (xy 107.09148 -217.22334) (xy 107.081828 -217.200226)
			(xy 107.073323 -217.17859) (xy 107.061331 -217.133674) (xy 107.055282 -217.08758) (xy 107.054904 -217.064336)
			(xy 107.055402 -217.037687) (xy 107.063345 -216.984983) (xy 107.079055 -216.934053) (xy 107.102181 -216.886032)
			(xy 107.132205 -216.841995) (xy 107.168457 -216.802924) (xy 107.210128 -216.769693) (xy 107.256286 -216.743044)
			(xy 107.3059 -216.723572) (xy 107.357862 -216.711712) (xy 107.411012 -216.707729) (xy 107.464162 -216.711712)
			(xy 107.516124 -216.723572) (xy 107.565738 -216.743044) (xy 107.611896 -216.769693) (xy 107.653567 -216.802924)
			(xy 107.689819 -216.841995) (xy 107.719843 -216.886032) (xy 107.742969 -216.934053) (xy 107.758679 -216.984983)
			(xy 107.766622 -217.037687) (xy 107.76712 -217.064336) (xy 107.766664 -217.089965) (xy 107.766517 -217.090985)
			(xy 107.995456 -217.090985) (xy 107.995456 -217.037687) (xy 108.003399 -216.984983) (xy 108.019109 -216.934053)
			(xy 108.042235 -216.886032) (xy 108.072259 -216.841995) (xy 108.108511 -216.802924) (xy 108.150182 -216.769693)
			(xy 108.19634 -216.743044) (xy 108.245954 -216.723572) (xy 108.297916 -216.711712) (xy 108.351066 -216.707729)
			(xy 108.404216 -216.711712) (xy 108.456178 -216.723572) (xy 108.505792 -216.743044) (xy 108.55195 -216.769693)
			(xy 108.593621 -216.802924) (xy 108.629873 -216.841995) (xy 108.659897 -216.886032) (xy 108.683023 -216.934053)
			(xy 108.698733 -216.984983) (xy 108.706676 -217.037687) (xy 108.707174 -217.064336) (xy 108.706676 -217.090985)
			(xy 108.698733 -217.143689) (xy 108.683023 -217.194619) (xy 108.659897 -217.24264) (xy 108.629873 -217.286677)
			(xy 108.593621 -217.325748) (xy 108.55195 -217.358979) (xy 108.505792 -217.385628) (xy 108.456178 -217.4051)
			(xy 108.404216 -217.41696) (xy 108.351066 -217.420944) (xy 108.297916 -217.41696) (xy 108.245954 -217.4051)
			(xy 108.19634 -217.385628) (xy 108.150182 -217.358979) (xy 108.108511 -217.325748) (xy 108.072259 -217.286677)
			(xy 108.042235 -217.24264) (xy 108.019109 -217.194619) (xy 108.003399 -217.143689) (xy 107.995456 -217.090985)
			(xy 107.766517 -217.090985) (xy 107.759337 -217.140695) (xy 107.744809 -217.18985) (xy 107.723382 -217.236414)
			(xy 107.695499 -217.279423) (xy 107.661735 -217.317989) (xy 107.62279 -217.351313) (xy 107.579468 -217.378708)
			(xy 107.532665 -217.399607) (xy 107.483348 -217.413577) (xy 107.458002 -217.417396) (xy 107.433364 -217.420698)
			(xy 107.260898 -217.719402) (xy 107.27055 -217.742516) (xy 107.279067 -217.764148) (xy 107.291054 -217.809066)
			(xy 107.297099 -217.855161) (xy 107.297474 -217.878406) (xy 107.525058 -217.878406) (xy 107.525556 -217.851757)
			(xy 107.533499 -217.799053) (xy 107.549209 -217.748123) (xy 107.572335 -217.700102) (xy 107.602359 -217.656065)
			(xy 107.638611 -217.616994) (xy 107.680282 -217.583763) (xy 107.72644 -217.557114) (xy 107.776054 -217.537642)
			(xy 107.828016 -217.525782) (xy 107.881166 -217.521799) (xy 107.934316 -217.525782) (xy 107.986278 -217.537642)
			(xy 108.035892 -217.557114) (xy 108.08205 -217.583763) (xy 108.123721 -217.616994) (xy 108.159973 -217.656065)
			(xy 108.189997 -217.700102) (xy 108.213123 -217.748123) (xy 108.228833 -217.799053) (xy 108.236776 -217.851757)
			(xy 108.237274 -217.878406) (xy 108.464858 -217.878406) (xy 108.465279 -217.852777) (xy 108.472614 -217.802046)
			(xy 108.487148 -217.752891) (xy 108.508581 -217.706328) (xy 108.536469 -217.66332) (xy 108.570235 -217.624755)
			(xy 108.609183 -217.591431) (xy 108.652507 -217.564037) (xy 108.699312 -217.543138) (xy 108.748629 -217.529166)
			(xy 108.773976 -217.525346) (xy 108.798614 -217.522044) (xy 108.97108 -217.22334) (xy 108.961428 -217.200226)
			(xy 108.952923 -217.17859) (xy 108.940931 -217.133674) (xy 108.934882 -217.08758) (xy 108.934504 -217.064336)
			(xy 108.935002 -217.037687) (xy 108.942945 -216.984983) (xy 108.958655 -216.934053) (xy 108.981781 -216.886032)
			(xy 109.011805 -216.841995) (xy 109.048057 -216.802924) (xy 109.089728 -216.769693) (xy 109.135886 -216.743044)
			(xy 109.1855 -216.723572) (xy 109.237462 -216.711712) (xy 109.290612 -216.707729) (xy 109.343762 -216.711712)
			(xy 109.395724 -216.723572) (xy 109.445338 -216.743044) (xy 109.491496 -216.769693) (xy 109.533167 -216.802924)
			(xy 109.569419 -216.841995) (xy 109.599443 -216.886032) (xy 109.622569 -216.934053) (xy 109.638279 -216.984983)
			(xy 109.646222 -217.037687) (xy 109.64672 -217.064336) (xy 109.646264 -217.089965) (xy 109.646117 -217.090985)
			(xy 109.875056 -217.090985) (xy 109.875056 -217.037687) (xy 109.882999 -216.984983) (xy 109.898709 -216.934053)
			(xy 109.921835 -216.886032) (xy 109.951859 -216.841995) (xy 109.988111 -216.802924) (xy 110.029782 -216.769693)
			(xy 110.07594 -216.743044) (xy 110.125554 -216.723572) (xy 110.177516 -216.711712) (xy 110.230666 -216.707729)
			(xy 110.283816 -216.711712) (xy 110.335778 -216.723572) (xy 110.385392 -216.743044) (xy 110.43155 -216.769693)
			(xy 110.473221 -216.802924) (xy 110.509473 -216.841995) (xy 110.539497 -216.886032) (xy 110.562623 -216.934053)
			(xy 110.578333 -216.984983) (xy 110.586276 -217.037687) (xy 110.586774 -217.064336) (xy 110.586276 -217.090985)
			(xy 110.578333 -217.143689) (xy 110.562623 -217.194619) (xy 110.539497 -217.24264) (xy 110.509473 -217.286677)
			(xy 110.473221 -217.325748) (xy 110.43155 -217.358979) (xy 110.385392 -217.385628) (xy 110.335778 -217.4051)
			(xy 110.283816 -217.41696) (xy 110.230666 -217.420944) (xy 110.177516 -217.41696) (xy 110.125554 -217.4051)
			(xy 110.07594 -217.385628) (xy 110.029782 -217.358979) (xy 109.988111 -217.325748) (xy 109.951859 -217.286677)
			(xy 109.921835 -217.24264) (xy 109.898709 -217.194619) (xy 109.882999 -217.143689) (xy 109.875056 -217.090985)
			(xy 109.646117 -217.090985) (xy 109.638937 -217.140695) (xy 109.624409 -217.18985) (xy 109.602982 -217.236414)
			(xy 109.575099 -217.279423) (xy 109.541335 -217.317989) (xy 109.50239 -217.351313) (xy 109.459068 -217.378708)
			(xy 109.412265 -217.399607) (xy 109.362948 -217.413577) (xy 109.337602 -217.417396) (xy 109.312964 -217.420698)
			(xy 109.140498 -217.719402) (xy 109.15015 -217.742516) (xy 109.158667 -217.764148) (xy 109.170654 -217.809066)
			(xy 109.176699 -217.855161) (xy 109.177074 -217.878406) (xy 109.404658 -217.878406) (xy 109.405156 -217.851757)
			(xy 109.413099 -217.799053) (xy 109.428809 -217.748123) (xy 109.451935 -217.700102) (xy 109.481959 -217.656065)
			(xy 109.518211 -217.616994) (xy 109.559882 -217.583763) (xy 109.60604 -217.557114) (xy 109.655654 -217.537642)
			(xy 109.707616 -217.525782) (xy 109.760766 -217.521799) (xy 109.813916 -217.525782) (xy 109.865878 -217.537642)
			(xy 109.915492 -217.557114) (xy 109.96165 -217.583763) (xy 110.003321 -217.616994) (xy 110.039573 -217.656065)
			(xy 110.069597 -217.700102) (xy 110.092723 -217.748123) (xy 110.108433 -217.799053) (xy 110.116376 -217.851757)
			(xy 110.116874 -217.878406) (xy 110.116497 -217.901609) (xy 110.110446 -217.94762) (xy 110.098461 -217.992452)
			(xy 110.08995 -218.014042) (xy 110.080552 -218.037156) (xy 110.253018 -218.33586) (xy 110.277656 -218.339162)
			(xy 110.302997 -218.342993) (xy 110.3523 -218.356986) (xy 110.39909 -218.377898) (xy 110.4424 -218.4053)
			(xy 110.481337 -218.438624) (xy 110.515098 -218.477184) (xy 110.542985 -218.520183) (xy 110.564422 -218.566734)
			(xy 110.578969 -218.615877) (xy 110.586323 -218.666597) (xy 110.586774 -218.692222) (xy 110.586276 -218.718871)
			(xy 110.578333 -218.771575) (xy 110.562623 -218.822505) (xy 110.539497 -218.870526) (xy 110.509473 -218.914563)
			(xy 110.473221 -218.953634) (xy 110.43155 -218.986865) (xy 110.385392 -219.013514) (xy 110.335778 -219.032986)
			(xy 110.283816 -219.044846) (xy 110.230666 -219.04883) (xy 110.177516 -219.044846) (xy 110.125554 -219.032986)
			(xy 110.07594 -219.013514) (xy 110.029782 -218.986865) (xy 109.988111 -218.953634) (xy 109.951859 -218.914563)
			(xy 109.921835 -218.870526) (xy 109.898709 -218.822505) (xy 109.882999 -218.771575) (xy 109.875056 -218.718871)
			(xy 109.874558 -218.692222) (xy 109.874937 -218.668977) (xy 109.88098 -218.622882) (xy 109.892966 -218.577964)
			(xy 109.901482 -218.556332) (xy 109.911134 -218.533218) (xy 109.738668 -218.234768) (xy 109.71403 -218.231466)
			(xy 109.688674 -218.227649) (xy 109.639333 -218.213695) (xy 109.592503 -218.192809) (xy 109.549153 -218.165423)
			(xy 109.510178 -218.132104) (xy 109.476385 -218.093539) (xy 109.448472 -218.050527) (xy 109.427015 -218.003956)
			(xy 109.412459 -217.95479) (xy 109.405105 -217.904044) (xy 109.404658 -217.878406) (xy 109.177074 -217.878406)
			(xy 109.176576 -217.905055) (xy 109.168633 -217.957759) (xy 109.152923 -218.008689) (xy 109.129797 -218.05671)
			(xy 109.099773 -218.100747) (xy 109.063521 -218.139818) (xy 109.02185 -218.173049) (xy 108.975692 -218.199698)
			(xy 108.926078 -218.21917) (xy 108.874116 -218.23103) (xy 108.820966 -218.235014) (xy 108.767816 -218.23103)
			(xy 108.715854 -218.21917) (xy 108.66624 -218.199698) (xy 108.620082 -218.173049) (xy 108.578411 -218.139818)
			(xy 108.542159 -218.100747) (xy 108.512135 -218.05671) (xy 108.489009 -218.008689) (xy 108.473299 -217.957759)
			(xy 108.465356 -217.905055) (xy 108.464858 -217.878406) (xy 108.237274 -217.878406) (xy 108.236909 -217.901651)
			(xy 108.230861 -217.947747) (xy 108.218869 -217.992664) (xy 108.21035 -218.014296) (xy 108.200698 -218.03741)
			(xy 108.373164 -218.33586) (xy 108.397802 -218.339162) (xy 108.423136 -218.343036) (xy 108.472439 -218.357021)
			(xy 108.519229 -218.377927) (xy 108.56254 -218.405322) (xy 108.601478 -218.438642) (xy 108.63524 -218.477197)
			(xy 108.663128 -218.520192) (xy 108.684567 -218.566741) (xy 108.699114 -218.615881) (xy 108.706469 -218.666598)
			(xy 108.70692 -218.692222) (xy 108.706422 -218.718871) (xy 108.935002 -218.718871) (xy 108.935002 -218.665573)
			(xy 108.942945 -218.612869) (xy 108.958655 -218.561939) (xy 108.981781 -218.513918) (xy 109.011805 -218.469881)
			(xy 109.048057 -218.43081) (xy 109.089728 -218.397579) (xy 109.135886 -218.37093) (xy 109.1855 -218.351458)
			(xy 109.237462 -218.339598) (xy 109.290612 -218.335615) (xy 109.343762 -218.339598) (xy 109.395724 -218.351458)
			(xy 109.445338 -218.37093) (xy 109.491496 -218.397579) (xy 109.533167 -218.43081) (xy 109.569419 -218.469881)
			(xy 109.599443 -218.513918) (xy 109.622569 -218.561939) (xy 109.638279 -218.612869) (xy 109.646222 -218.665573)
			(xy 109.64672 -218.692222) (xy 109.646222 -218.718871) (xy 109.638279 -218.771575) (xy 109.622569 -218.822505)
			(xy 109.599443 -218.870526) (xy 109.569419 -218.914563) (xy 109.533167 -218.953634) (xy 109.491496 -218.986865)
			(xy 109.445338 -219.013514) (xy 109.395724 -219.032986) (xy 109.343762 -219.044846) (xy 109.290612 -219.04883)
			(xy 109.237462 -219.044846) (xy 109.1855 -219.032986) (xy 109.135886 -219.013514) (xy 109.089728 -218.986865)
			(xy 109.048057 -218.953634) (xy 109.011805 -218.914563) (xy 108.981781 -218.870526) (xy 108.958655 -218.822505)
			(xy 108.942945 -218.771575) (xy 108.935002 -218.718871) (xy 108.706422 -218.718871) (xy 108.698479 -218.771575)
			(xy 108.682769 -218.822505) (xy 108.659643 -218.870526) (xy 108.629619 -218.914563) (xy 108.593367 -218.953634)
			(xy 108.551696 -218.986865) (xy 108.505538 -219.013514) (xy 108.455924 -219.032986) (xy 108.403962 -219.044846)
			(xy 108.350812 -219.04883) (xy 108.297662 -219.044846) (xy 108.2457 -219.032986) (xy 108.196086 -219.013514)
			(xy 108.149928 -218.986865) (xy 108.108257 -218.953634) (xy 108.072005 -218.914563) (xy 108.041981 -218.870526)
			(xy 108.018855 -218.822505) (xy 108.003145 -218.771575) (xy 107.995202 -218.718871) (xy 107.994704 -218.692222)
			(xy 107.99508 -218.668977) (xy 108.001124 -218.622882) (xy 108.013112 -218.577964) (xy 108.021628 -218.556332)
			(xy 108.03128 -218.533218) (xy 107.858814 -218.234768) (xy 107.834176 -218.231466) (xy 107.808827 -218.227679)
			(xy 107.759518 -218.213687) (xy 107.712724 -218.192773) (xy 107.66941 -218.165368) (xy 107.630471 -218.132039)
			(xy 107.59671 -218.093473) (xy 107.568825 -218.050468) (xy 107.547391 -218.003909) (xy 107.53285 -217.95476)
			(xy 107.525504 -217.904034) (xy 107.525058 -217.878406) (xy 107.297474 -217.878406) (xy 107.296976 -217.905055)
			(xy 107.289033 -217.957759) (xy 107.273323 -218.008689) (xy 107.250197 -218.05671) (xy 107.220173 -218.100747)
			(xy 107.183921 -218.139818) (xy 107.14225 -218.173049) (xy 107.096092 -218.199698) (xy 107.046478 -218.21917)
			(xy 106.994516 -218.23103) (xy 106.941366 -218.235014) (xy 106.888216 -218.23103) (xy 106.836254 -218.21917)
			(xy 106.78664 -218.199698) (xy 106.740482 -218.173049) (xy 106.698811 -218.139818) (xy 106.662559 -218.100747)
			(xy 106.632535 -218.05671) (xy 106.609409 -218.008689) (xy 106.593699 -217.957759) (xy 106.585756 -217.905055)
			(xy 106.585258 -217.878406) (xy 106.357674 -217.878406) (xy 106.357309 -217.901651) (xy 106.351261 -217.947747)
			(xy 106.339269 -217.992664) (xy 106.33075 -218.014296) (xy 106.321098 -218.03741) (xy 106.493564 -218.33586)
			(xy 106.518202 -218.339162) (xy 106.543536 -218.343036) (xy 106.592839 -218.357021) (xy 106.639629 -218.377927)
			(xy 106.68294 -218.405322) (xy 106.721878 -218.438642) (xy 106.75564 -218.477197) (xy 106.783528 -218.520192)
			(xy 106.804967 -218.566741) (xy 106.819514 -218.615881) (xy 106.826869 -218.666598) (xy 106.82732 -218.692222)
			(xy 106.826822 -218.718871) (xy 107.055402 -218.718871) (xy 107.055402 -218.665573) (xy 107.063345 -218.612869)
			(xy 107.079055 -218.561939) (xy 107.102181 -218.513918) (xy 107.132205 -218.469881) (xy 107.168457 -218.43081)
			(xy 107.210128 -218.397579) (xy 107.256286 -218.37093) (xy 107.3059 -218.351458) (xy 107.357862 -218.339598)
			(xy 107.411012 -218.335615) (xy 107.464162 -218.339598) (xy 107.516124 -218.351458) (xy 107.565738 -218.37093)
			(xy 107.611896 -218.397579) (xy 107.653567 -218.43081) (xy 107.689819 -218.469881) (xy 107.719843 -218.513918)
			(xy 107.742969 -218.561939) (xy 107.758679 -218.612869) (xy 107.766622 -218.665573) (xy 107.76712 -218.692222)
			(xy 107.766622 -218.718871) (xy 107.758679 -218.771575) (xy 107.742969 -218.822505) (xy 107.719843 -218.870526)
			(xy 107.689819 -218.914563) (xy 107.653567 -218.953634) (xy 107.611896 -218.986865) (xy 107.565738 -219.013514)
			(xy 107.516124 -219.032986) (xy 107.464162 -219.044846) (xy 107.411012 -219.04883) (xy 107.357862 -219.044846)
			(xy 107.3059 -219.032986) (xy 107.256286 -219.013514) (xy 107.210128 -218.986865) (xy 107.168457 -218.953634)
			(xy 107.132205 -218.914563) (xy 107.102181 -218.870526) (xy 107.079055 -218.822505) (xy 107.063345 -218.771575)
			(xy 107.055402 -218.718871) (xy 106.826822 -218.718871) (xy 106.818879 -218.771575) (xy 106.803169 -218.822505)
			(xy 106.780043 -218.870526) (xy 106.750019 -218.914563) (xy 106.713767 -218.953634) (xy 106.672096 -218.986865)
			(xy 106.625938 -219.013514) (xy 106.576324 -219.032986) (xy 106.524362 -219.044846) (xy 106.471212 -219.04883)
			(xy 106.418062 -219.044846) (xy 106.3661 -219.032986) (xy 106.316486 -219.013514) (xy 106.270328 -218.986865)
			(xy 106.228657 -218.953634) (xy 106.192405 -218.914563) (xy 106.162381 -218.870526) (xy 106.139255 -218.822505)
			(xy 106.123545 -218.771575) (xy 106.115602 -218.718871) (xy 106.115104 -218.692222) (xy 106.11548 -218.668977)
			(xy 106.121524 -218.622882) (xy 106.133512 -218.577964) (xy 106.142028 -218.556332) (xy 106.15168 -218.533218)
			(xy 105.979214 -218.234768) (xy 105.954576 -218.231466) (xy 105.929227 -218.227679) (xy 105.879918 -218.213687)
			(xy 105.833124 -218.192773) (xy 105.78981 -218.165368) (xy 105.750871 -218.132039) (xy 105.71711 -218.093473)
			(xy 105.689225 -218.050468) (xy 105.667791 -218.003909) (xy 105.65325 -217.95476) (xy 105.645904 -217.904034)
			(xy 105.645458 -217.878406) (xy 105.417874 -217.878406) (xy 105.417376 -217.905055) (xy 105.409433 -217.957759)
			(xy 105.393723 -218.008689) (xy 105.370597 -218.05671) (xy 105.340573 -218.100747) (xy 105.304321 -218.139818)
			(xy 105.26265 -218.173049) (xy 105.216492 -218.199698) (xy 105.166878 -218.21917) (xy 105.114916 -218.23103)
			(xy 105.061766 -218.235014) (xy 105.008616 -218.23103) (xy 104.956654 -218.21917) (xy 104.90704 -218.199698)
			(xy 104.860882 -218.173049) (xy 104.819211 -218.139818) (xy 104.782959 -218.100747) (xy 104.752935 -218.05671)
			(xy 104.729809 -218.008689) (xy 104.714099 -217.957759) (xy 104.706156 -217.905055) (xy 104.705658 -217.878406)
			(xy 104.478074 -217.878406) (xy 104.477698 -217.901651) (xy 104.471652 -217.947746) (xy 104.459663 -217.992663)
			(xy 104.45115 -218.014296) (xy 104.441498 -218.03741) (xy 104.613964 -218.33586) (xy 104.638602 -218.339162)
			(xy 104.663949 -218.342981) (xy 104.713269 -218.35695) (xy 104.760075 -218.377848) (xy 104.8034 -218.405242)
			(xy 104.842349 -218.438566) (xy 104.876116 -218.477131) (xy 104.904005 -218.52014) (xy 104.925437 -218.566704)
			(xy 104.93997 -218.61586) (xy 104.947303 -218.666592) (xy 104.94772 -218.692222) (xy 104.947195 -218.718871)
			(xy 105.175802 -218.718871) (xy 105.175802 -218.665573) (xy 105.183745 -218.612869) (xy 105.199455 -218.561939)
			(xy 105.222581 -218.513918) (xy 105.252605 -218.469881) (xy 105.288857 -218.43081) (xy 105.330528 -218.397579)
			(xy 105.376686 -218.37093) (xy 105.4263 -218.351458) (xy 105.478262 -218.339598) (xy 105.531412 -218.335615)
			(xy 105.584562 -218.339598) (xy 105.636524 -218.351458) (xy 105.686138 -218.37093) (xy 105.732296 -218.397579)
			(xy 105.773967 -218.43081) (xy 105.810219 -218.469881) (xy 105.840243 -218.513918) (xy 105.863369 -218.561939)
			(xy 105.879079 -218.612869) (xy 105.887022 -218.665573) (xy 105.88752 -218.692222) (xy 105.887022 -218.718871)
			(xy 105.879079 -218.771575) (xy 105.863369 -218.822505) (xy 105.840243 -218.870526) (xy 105.810219 -218.914563)
			(xy 105.773967 -218.953634) (xy 105.732296 -218.986865) (xy 105.686138 -219.013514) (xy 105.636524 -219.032986)
			(xy 105.584562 -219.044846) (xy 105.531412 -219.04883) (xy 105.478262 -219.044846) (xy 105.4263 -219.032986)
			(xy 105.376686 -219.013514) (xy 105.330528 -218.986865) (xy 105.288857 -218.953634) (xy 105.252605 -218.914563)
			(xy 105.222581 -218.870526) (xy 105.199455 -218.822505) (xy 105.183745 -218.771575) (xy 105.175802 -218.718871)
			(xy 104.947195 -218.718871) (xy 104.947169 -218.720204) (xy 104.938412 -218.77548) (xy 104.921115 -218.828704)
			(xy 104.895706 -218.878568) (xy 104.86281 -218.923844) (xy 104.823236 -218.963417) (xy 104.77796 -218.996312)
			(xy 104.728095 -219.021719) (xy 104.67487 -219.039014) (xy 104.619594 -219.04777) (xy 104.591612 -219.04833)
			(xy 104.573773 -219.04811) (xy 104.538274 -219.044543) (xy 104.520746 -219.041218) (xy 104.505928 -219.038781)
			(xy 104.476053 -219.041665) (xy 104.448305 -219.053107) (xy 104.425081 -219.07212) (xy 104.408384 -219.097061)
			(xy 104.399657 -219.125779) (xy 104.39908 -219.140786) (xy 104.39908 -219.282264) (xy 104.413966 -219.301353)
			(xy 104.43899 -219.342792) (xy 104.458171 -219.387237) (xy 104.471157 -219.433871) (xy 104.477708 -219.481834)
			(xy 104.478074 -219.506038) (xy 104.477536 -219.532687) (xy 104.706156 -219.532687) (xy 104.706156 -219.479389)
			(xy 104.714099 -219.426685) (xy 104.729809 -219.375755) (xy 104.752935 -219.327734) (xy 104.782959 -219.283697)
			(xy 104.819211 -219.244626) (xy 104.860882 -219.211395) (xy 104.90704 -219.184746) (xy 104.956654 -219.165274)
			(xy 105.008616 -219.153414) (xy 105.061766 -219.149431) (xy 105.114916 -219.153414) (xy 105.166878 -219.165274)
			(xy 105.216492 -219.184746) (xy 105.26265 -219.211395) (xy 105.304321 -219.244626) (xy 105.340573 -219.283697)
			(xy 105.370597 -219.327734) (xy 105.393723 -219.375755) (xy 105.409433 -219.426685) (xy 105.417376 -219.479389)
			(xy 105.417874 -219.506038) (xy 105.417376 -219.532687) (xy 105.645956 -219.532687) (xy 105.645956 -219.479389)
			(xy 105.653899 -219.426685) (xy 105.669609 -219.375755) (xy 105.692735 -219.327734) (xy 105.722759 -219.283697)
			(xy 105.759011 -219.244626) (xy 105.800682 -219.211395) (xy 105.84684 -219.184746) (xy 105.896454 -219.165274)
			(xy 105.948416 -219.153414) (xy 106.001566 -219.149431) (xy 106.054716 -219.153414) (xy 106.106678 -219.165274)
			(xy 106.156292 -219.184746) (xy 106.20245 -219.211395) (xy 106.244121 -219.244626) (xy 106.280373 -219.283697)
			(xy 106.310397 -219.327734) (xy 106.333523 -219.375755) (xy 106.349233 -219.426685) (xy 106.357176 -219.479389)
			(xy 106.357674 -219.506038) (xy 106.357176 -219.532687) (xy 106.585756 -219.532687) (xy 106.585756 -219.479389)
			(xy 106.593699 -219.426685) (xy 106.609409 -219.375755) (xy 106.632535 -219.327734) (xy 106.662559 -219.283697)
			(xy 106.698811 -219.244626) (xy 106.740482 -219.211395) (xy 106.78664 -219.184746) (xy 106.836254 -219.165274)
			(xy 106.888216 -219.153414) (xy 106.941366 -219.149431) (xy 106.994516 -219.153414) (xy 107.046478 -219.165274)
			(xy 107.096092 -219.184746) (xy 107.14225 -219.211395) (xy 107.183921 -219.244626) (xy 107.220173 -219.283697)
			(xy 107.250197 -219.327734) (xy 107.273323 -219.375755) (xy 107.289033 -219.426685) (xy 107.296976 -219.479389)
			(xy 107.297474 -219.506038) (xy 107.296976 -219.532687) (xy 107.525556 -219.532687) (xy 107.525556 -219.479389)
			(xy 107.533499 -219.426685) (xy 107.549209 -219.375755) (xy 107.572335 -219.327734) (xy 107.602359 -219.283697)
			(xy 107.638611 -219.244626) (xy 107.680282 -219.211395) (xy 107.72644 -219.184746) (xy 107.776054 -219.165274)
			(xy 107.828016 -219.153414) (xy 107.881166 -219.149431) (xy 107.934316 -219.153414) (xy 107.986278 -219.165274)
			(xy 108.035892 -219.184746) (xy 108.08205 -219.211395) (xy 108.123721 -219.244626) (xy 108.159973 -219.283697)
			(xy 108.189997 -219.327734) (xy 108.213123 -219.375755) (xy 108.228833 -219.426685) (xy 108.236776 -219.479389)
			(xy 108.237274 -219.506038) (xy 108.236776 -219.532687) (xy 108.465356 -219.532687) (xy 108.465356 -219.479389)
			(xy 108.473299 -219.426685) (xy 108.489009 -219.375755) (xy 108.512135 -219.327734) (xy 108.542159 -219.283697)
			(xy 108.578411 -219.244626) (xy 108.620082 -219.211395) (xy 108.66624 -219.184746) (xy 108.715854 -219.165274)
			(xy 108.767816 -219.153414) (xy 108.820966 -219.149431) (xy 108.874116 -219.153414) (xy 108.926078 -219.165274)
			(xy 108.975692 -219.184746) (xy 109.02185 -219.211395) (xy 109.063521 -219.244626) (xy 109.099773 -219.283697)
			(xy 109.129797 -219.327734) (xy 109.152923 -219.375755) (xy 109.168633 -219.426685) (xy 109.176576 -219.479389)
			(xy 109.177074 -219.506038) (xy 109.176576 -219.532687) (xy 109.405156 -219.532687) (xy 109.405156 -219.479389)
			(xy 109.413099 -219.426685) (xy 109.428809 -219.375755) (xy 109.451935 -219.327734) (xy 109.481959 -219.283697)
			(xy 109.518211 -219.244626) (xy 109.559882 -219.211395) (xy 109.60604 -219.184746) (xy 109.655654 -219.165274)
			(xy 109.707616 -219.153414) (xy 109.760766 -219.149431) (xy 109.813916 -219.153414) (xy 109.865878 -219.165274)
			(xy 109.915492 -219.184746) (xy 109.96165 -219.211395) (xy 110.003321 -219.244626) (xy 110.039573 -219.283697)
			(xy 110.069597 -219.327734) (xy 110.092723 -219.375755) (xy 110.108433 -219.426685) (xy 110.116376 -219.479389)
			(xy 110.116874 -219.506038) (xy 110.116376 -219.532687) (xy 110.344956 -219.532687) (xy 110.344956 -219.479389)
			(xy 110.352899 -219.426685) (xy 110.368609 -219.375755) (xy 110.391735 -219.327734) (xy 110.421759 -219.283697)
			(xy 110.458011 -219.244626) (xy 110.499682 -219.211395) (xy 110.54584 -219.184746) (xy 110.595454 -219.165274)
			(xy 110.647416 -219.153414) (xy 110.700566 -219.149431) (xy 110.753716 -219.153414) (xy 110.805678 -219.165274)
			(xy 110.855292 -219.184746) (xy 110.90145 -219.211395) (xy 110.943121 -219.244626) (xy 110.979373 -219.283697)
			(xy 111.009397 -219.327734) (xy 111.032523 -219.375755) (xy 111.048233 -219.426685) (xy 111.056176 -219.479389)
			(xy 111.056674 -219.506038) (xy 111.056176 -219.532687) (xy 111.048233 -219.585391) (xy 111.032523 -219.636321)
			(xy 111.009397 -219.684342) (xy 110.979373 -219.728379) (xy 110.943121 -219.76745) (xy 110.90145 -219.800681)
			(xy 110.855292 -219.82733) (xy 110.805678 -219.846802) (xy 110.753716 -219.858662) (xy 110.700566 -219.862646)
			(xy 110.647416 -219.858662) (xy 110.595454 -219.846802) (xy 110.54584 -219.82733) (xy 110.499682 -219.800681)
			(xy 110.458011 -219.76745) (xy 110.421759 -219.728379) (xy 110.391735 -219.684342) (xy 110.368609 -219.636321)
			(xy 110.352899 -219.585391) (xy 110.344956 -219.532687) (xy 110.116376 -219.532687) (xy 110.108433 -219.585391)
			(xy 110.092723 -219.636321) (xy 110.069597 -219.684342) (xy 110.039573 -219.728379) (xy 110.003321 -219.76745)
			(xy 109.96165 -219.800681) (xy 109.915492 -219.82733) (xy 109.865878 -219.846802) (xy 109.813916 -219.858662)
			(xy 109.760766 -219.862646) (xy 109.707616 -219.858662) (xy 109.655654 -219.846802) (xy 109.60604 -219.82733)
			(xy 109.559882 -219.800681) (xy 109.518211 -219.76745) (xy 109.481959 -219.728379) (xy 109.451935 -219.684342)
			(xy 109.428809 -219.636321) (xy 109.413099 -219.585391) (xy 109.405156 -219.532687) (xy 109.176576 -219.532687)
			(xy 109.168633 -219.585391) (xy 109.152923 -219.636321) (xy 109.129797 -219.684342) (xy 109.099773 -219.728379)
			(xy 109.063521 -219.76745) (xy 109.02185 -219.800681) (xy 108.975692 -219.82733) (xy 108.926078 -219.846802)
			(xy 108.874116 -219.858662) (xy 108.820966 -219.862646) (xy 108.767816 -219.858662) (xy 108.715854 -219.846802)
			(xy 108.66624 -219.82733) (xy 108.620082 -219.800681) (xy 108.578411 -219.76745) (xy 108.542159 -219.728379)
			(xy 108.512135 -219.684342) (xy 108.489009 -219.636321) (xy 108.473299 -219.585391) (xy 108.465356 -219.532687)
			(xy 108.236776 -219.532687) (xy 108.228833 -219.585391) (xy 108.213123 -219.636321) (xy 108.189997 -219.684342)
			(xy 108.159973 -219.728379) (xy 108.123721 -219.76745) (xy 108.08205 -219.800681) (xy 108.035892 -219.82733)
			(xy 107.986278 -219.846802) (xy 107.934316 -219.858662) (xy 107.881166 -219.862646) (xy 107.828016 -219.858662)
			(xy 107.776054 -219.846802) (xy 107.72644 -219.82733) (xy 107.680282 -219.800681) (xy 107.638611 -219.76745)
			(xy 107.602359 -219.728379) (xy 107.572335 -219.684342) (xy 107.549209 -219.636321) (xy 107.533499 -219.585391)
			(xy 107.525556 -219.532687) (xy 107.296976 -219.532687) (xy 107.289033 -219.585391) (xy 107.273323 -219.636321)
			(xy 107.250197 -219.684342) (xy 107.220173 -219.728379) (xy 107.183921 -219.76745) (xy 107.14225 -219.800681)
			(xy 107.096092 -219.82733) (xy 107.046478 -219.846802) (xy 106.994516 -219.858662) (xy 106.941366 -219.862646)
			(xy 106.888216 -219.858662) (xy 106.836254 -219.846802) (xy 106.78664 -219.82733) (xy 106.740482 -219.800681)
			(xy 106.698811 -219.76745) (xy 106.662559 -219.728379) (xy 106.632535 -219.684342) (xy 106.609409 -219.636321)
			(xy 106.593699 -219.585391) (xy 106.585756 -219.532687) (xy 106.357176 -219.532687) (xy 106.349233 -219.585391)
			(xy 106.333523 -219.636321) (xy 106.310397 -219.684342) (xy 106.280373 -219.728379) (xy 106.244121 -219.76745)
			(xy 106.20245 -219.800681) (xy 106.156292 -219.82733) (xy 106.106678 -219.846802) (xy 106.054716 -219.858662)
			(xy 106.001566 -219.862646) (xy 105.948416 -219.858662) (xy 105.896454 -219.846802) (xy 105.84684 -219.82733)
			(xy 105.800682 -219.800681) (xy 105.759011 -219.76745) (xy 105.722759 -219.728379) (xy 105.692735 -219.684342)
			(xy 105.669609 -219.636321) (xy 105.653899 -219.585391) (xy 105.645956 -219.532687) (xy 105.417376 -219.532687)
			(xy 105.409433 -219.585391) (xy 105.393723 -219.636321) (xy 105.370597 -219.684342) (xy 105.340573 -219.728379)
			(xy 105.304321 -219.76745) (xy 105.26265 -219.800681) (xy 105.216492 -219.82733) (xy 105.166878 -219.846802)
			(xy 105.114916 -219.858662) (xy 105.061766 -219.862646) (xy 105.008616 -219.858662) (xy 104.956654 -219.846802)
			(xy 104.90704 -219.82733) (xy 104.860882 -219.800681) (xy 104.819211 -219.76745) (xy 104.782959 -219.728379)
			(xy 104.752935 -219.684342) (xy 104.729809 -219.636321) (xy 104.714099 -219.585391) (xy 104.706156 -219.532687)
			(xy 104.477536 -219.532687) (xy 104.477482 -219.535369) (xy 104.467883 -219.59324) (xy 104.448932 -219.648757)
			(xy 104.421144 -219.700419) (xy 104.403652 -219.72397) (xy 104.432358 -219.761123) (xy 104.483196 -219.840064)
			(xy 104.526078 -219.923595) (xy 104.54386 -219.967048) (xy 104.555803 -219.965519) (xy 104.579826 -219.963867)
			(xy 104.591866 -219.963746) (xy 104.618522 -219.964217) (xy 104.67124 -219.972158) (xy 104.722185 -219.987868)
			(xy 104.770219 -220.010996) (xy 104.81427 -220.041026) (xy 104.853352 -220.077285) (xy 104.886594 -220.118965)
			(xy 104.913252 -220.165134) (xy 104.93273 -220.214761) (xy 104.944594 -220.266737) (xy 104.948575 -220.319854)
			(xy 105.175304 -220.319854) (xy 105.175802 -220.293205) (xy 105.183745 -220.240501) (xy 105.199455 -220.189571)
			(xy 105.222581 -220.14155) (xy 105.252605 -220.097513) (xy 105.288857 -220.058442) (xy 105.330528 -220.025211)
			(xy 105.376686 -219.998562) (xy 105.4263 -219.97909) (xy 105.478262 -219.96723) (xy 105.531412 -219.963247)
			(xy 105.584562 -219.96723) (xy 105.636524 -219.97909) (xy 105.686138 -219.998562) (xy 105.732296 -220.025211)
			(xy 105.773967 -220.058442) (xy 105.810219 -220.097513) (xy 105.840243 -220.14155) (xy 105.863369 -220.189571)
			(xy 105.879079 -220.240501) (xy 105.887022 -220.293205) (xy 105.88752 -220.319854) (xy 105.887123 -220.343057)
			(xy 105.88667 -220.346503) (xy 106.115856 -220.346503) (xy 106.115856 -220.293205) (xy 106.123799 -220.240501)
			(xy 106.139509 -220.189571) (xy 106.162635 -220.14155) (xy 106.192659 -220.097513) (xy 106.228911 -220.058442)
			(xy 106.270582 -220.025211) (xy 106.31674 -219.998562) (xy 106.366354 -219.97909) (xy 106.418316 -219.96723)
			(xy 106.471466 -219.963247) (xy 106.524616 -219.96723) (xy 106.576578 -219.97909) (xy 106.626192 -219.998562)
			(xy 106.67235 -220.025211) (xy 106.714021 -220.058442) (xy 106.750273 -220.097513) (xy 106.780297 -220.14155)
			(xy 106.803423 -220.189571) (xy 106.819133 -220.240501) (xy 106.827076 -220.293205) (xy 106.827574 -220.319854)
			(xy 107.054904 -220.319854) (xy 107.055402 -220.293205) (xy 107.063345 -220.240501) (xy 107.079055 -220.189571)
			(xy 107.102181 -220.14155) (xy 107.132205 -220.097513) (xy 107.168457 -220.058442) (xy 107.210128 -220.025211)
			(xy 107.256286 -219.998562) (xy 107.3059 -219.97909) (xy 107.357862 -219.96723) (xy 107.411012 -219.963247)
			(xy 107.464162 -219.96723) (xy 107.516124 -219.97909) (xy 107.565738 -219.998562) (xy 107.611896 -220.025211)
			(xy 107.653567 -220.058442) (xy 107.689819 -220.097513) (xy 107.719843 -220.14155) (xy 107.742969 -220.189571)
			(xy 107.758679 -220.240501) (xy 107.766622 -220.293205) (xy 107.76712 -220.319854) (xy 107.766723 -220.343057)
			(xy 107.76627 -220.346503) (xy 107.995456 -220.346503) (xy 107.995456 -220.293205) (xy 108.003399 -220.240501)
			(xy 108.019109 -220.189571) (xy 108.042235 -220.14155) (xy 108.072259 -220.097513) (xy 108.108511 -220.058442)
			(xy 108.150182 -220.025211) (xy 108.19634 -219.998562) (xy 108.245954 -219.97909) (xy 108.297916 -219.96723)
			(xy 108.351066 -219.963247) (xy 108.404216 -219.96723) (xy 108.456178 -219.97909) (xy 108.505792 -219.998562)
			(xy 108.55195 -220.025211) (xy 108.593621 -220.058442) (xy 108.629873 -220.097513) (xy 108.659897 -220.14155)
			(xy 108.683023 -220.189571) (xy 108.698733 -220.240501) (xy 108.706676 -220.293205) (xy 108.707174 -220.319854)
			(xy 108.934504 -220.319854) (xy 108.935002 -220.293205) (xy 108.942945 -220.240501) (xy 108.958655 -220.189571)
			(xy 108.981781 -220.14155) (xy 109.011805 -220.097513) (xy 109.048057 -220.058442) (xy 109.089728 -220.025211)
			(xy 109.135886 -219.998562) (xy 109.1855 -219.97909) (xy 109.237462 -219.96723) (xy 109.290612 -219.963247)
			(xy 109.343762 -219.96723) (xy 109.395724 -219.97909) (xy 109.445338 -219.998562) (xy 109.491496 -220.025211)
			(xy 109.533167 -220.058442) (xy 109.569419 -220.097513) (xy 109.599443 -220.14155) (xy 109.622569 -220.189571)
			(xy 109.638279 -220.240501) (xy 109.646222 -220.293205) (xy 109.64672 -220.319854) (xy 109.646323 -220.343057)
			(xy 109.64587 -220.346503) (xy 109.875056 -220.346503) (xy 109.875056 -220.293205) (xy 109.882999 -220.240501)
			(xy 109.898709 -220.189571) (xy 109.921835 -220.14155) (xy 109.951859 -220.097513) (xy 109.988111 -220.058442)
			(xy 110.029782 -220.025211) (xy 110.07594 -219.998562) (xy 110.125554 -219.97909) (xy 110.177516 -219.96723)
			(xy 110.230666 -219.963247) (xy 110.283816 -219.96723) (xy 110.335778 -219.97909) (xy 110.385392 -219.998562)
			(xy 110.43155 -220.025211) (xy 110.473221 -220.058442) (xy 110.509473 -220.097513) (xy 110.539497 -220.14155)
			(xy 110.562623 -220.189571) (xy 110.578333 -220.240501) (xy 110.586276 -220.293205) (xy 110.586774 -220.319854)
			(xy 110.586276 -220.346503) (xy 110.578333 -220.399207) (xy 110.562623 -220.450137) (xy 110.539497 -220.498158)
			(xy 110.509473 -220.542195) (xy 110.473221 -220.581266) (xy 110.43155 -220.614497) (xy 110.385392 -220.641146)
			(xy 110.335778 -220.660618) (xy 110.283816 -220.672478) (xy 110.230666 -220.676462) (xy 110.177516 -220.672478)
			(xy 110.125554 -220.660618) (xy 110.07594 -220.641146) (xy 110.029782 -220.614497) (xy 109.988111 -220.581266)
			(xy 109.951859 -220.542195) (xy 109.921835 -220.498158) (xy 109.898709 -220.450137) (xy 109.882999 -220.399207)
			(xy 109.875056 -220.346503) (xy 109.64587 -220.346503) (xy 109.64028 -220.389067) (xy 109.628303 -220.4339)
			(xy 109.619796 -220.45549) (xy 109.610398 -220.478604) (xy 109.783118 -220.777562) (xy 109.807756 -220.780864)
			(xy 109.833097 -220.784693) (xy 109.882401 -220.798686) (xy 109.929191 -220.819599) (xy 109.972501 -220.847)
			(xy 110.011438 -220.880325) (xy 110.045198 -220.918885) (xy 110.073085 -220.961884) (xy 110.094523 -221.008436)
			(xy 110.109069 -221.057579) (xy 110.116424 -221.108299) (xy 110.116874 -221.133924) (xy 110.116376 -221.160573)
			(xy 110.108433 -221.213277) (xy 110.092723 -221.264207) (xy 110.069597 -221.312228) (xy 110.039573 -221.356265)
			(xy 110.003321 -221.395336) (xy 109.96165 -221.428567) (xy 109.915492 -221.455216) (xy 109.865878 -221.474688)
			(xy 109.813916 -221.486548) (xy 109.760766 -221.490532) (xy 109.707616 -221.486548) (xy 109.655654 -221.474688)
			(xy 109.60604 -221.455216) (xy 109.559882 -221.428567) (xy 109.518211 -221.395336) (xy 109.481959 -221.356265)
			(xy 109.451935 -221.312228) (xy 109.428809 -221.264207) (xy 109.413099 -221.213277) (xy 109.405156 -221.160573)
			(xy 109.404658 -221.133924) (xy 109.405037 -221.110679) (xy 109.41108 -221.064584) (xy 109.423066 -221.019666)
			(xy 109.431582 -220.998034) (xy 109.441234 -220.97492) (xy 109.268768 -220.676216) (xy 109.243876 -220.672914)
			(xy 109.218521 -220.669093) (xy 109.169184 -220.655134) (xy 109.122357 -220.634246) (xy 109.07901 -220.606859)
			(xy 109.040037 -220.573539) (xy 109.006245 -220.534976) (xy 108.978331 -220.491966) (xy 108.956873 -220.445398)
			(xy 108.942314 -220.396234) (xy 108.934954 -220.345491) (xy 108.934504 -220.319854) (xy 108.707174 -220.319854)
			(xy 108.706676 -220.346503) (xy 108.698733 -220.399207) (xy 108.683023 -220.450137) (xy 108.659897 -220.498158)
			(xy 108.629873 -220.542195) (xy 108.593621 -220.581266) (xy 108.55195 -220.614497) (xy 108.505792 -220.641146)
			(xy 108.456178 -220.660618) (xy 108.404216 -220.672478) (xy 108.351066 -220.676462) (xy 108.297916 -220.672478)
			(xy 108.245954 -220.660618) (xy 108.19634 -220.641146) (xy 108.150182 -220.614497) (xy 108.108511 -220.581266)
			(xy 108.072259 -220.542195) (xy 108.042235 -220.498158) (xy 108.019109 -220.450137) (xy 108.003399 -220.399207)
			(xy 107.995456 -220.346503) (xy 107.76627 -220.346503) (xy 107.76068 -220.389067) (xy 107.748703 -220.4339)
			(xy 107.740196 -220.45549) (xy 107.730798 -220.478604) (xy 107.903518 -220.777562) (xy 107.928156 -220.780864)
			(xy 107.953497 -220.784693) (xy 108.002801 -220.798686) (xy 108.049591 -220.819599) (xy 108.092901 -220.847)
			(xy 108.131838 -220.880325) (xy 108.165598 -220.918885) (xy 108.193485 -220.961884) (xy 108.214923 -221.008436)
			(xy 108.229469 -221.057579) (xy 108.236824 -221.108299) (xy 108.237274 -221.133924) (xy 108.236776 -221.160573)
			(xy 108.228833 -221.213277) (xy 108.213123 -221.264207) (xy 108.189997 -221.312228) (xy 108.159973 -221.356265)
			(xy 108.123721 -221.395336) (xy 108.08205 -221.428567) (xy 108.035892 -221.455216) (xy 107.986278 -221.474688)
			(xy 107.934316 -221.486548) (xy 107.881166 -221.490532) (xy 107.828016 -221.486548) (xy 107.776054 -221.474688)
			(xy 107.72644 -221.455216) (xy 107.680282 -221.428567) (xy 107.638611 -221.395336) (xy 107.602359 -221.356265)
			(xy 107.572335 -221.312228) (xy 107.549209 -221.264207) (xy 107.533499 -221.213277) (xy 107.525556 -221.160573)
			(xy 107.525058 -221.133924) (xy 107.525437 -221.110679) (xy 107.53148 -221.064584) (xy 107.543466 -221.019666)
			(xy 107.551982 -220.998034) (xy 107.561634 -220.97492) (xy 107.389168 -220.676216) (xy 107.364276 -220.672914)
			(xy 107.338921 -220.669093) (xy 107.289584 -220.655134) (xy 107.242757 -220.634246) (xy 107.19941 -220.606859)
			(xy 107.160437 -220.573539) (xy 107.126645 -220.534976) (xy 107.098731 -220.491966) (xy 107.077273 -220.445398)
			(xy 107.062714 -220.396234) (xy 107.055354 -220.345491) (xy 107.054904 -220.319854) (xy 106.827574 -220.319854)
			(xy 106.827076 -220.346503) (xy 106.819133 -220.399207) (xy 106.803423 -220.450137) (xy 106.780297 -220.498158)
			(xy 106.750273 -220.542195) (xy 106.714021 -220.581266) (xy 106.67235 -220.614497) (xy 106.626192 -220.641146)
			(xy 106.576578 -220.660618) (xy 106.524616 -220.672478) (xy 106.471466 -220.676462) (xy 106.418316 -220.672478)
			(xy 106.366354 -220.660618) (xy 106.31674 -220.641146) (xy 106.270582 -220.614497) (xy 106.228911 -220.581266)
			(xy 106.192659 -220.542195) (xy 106.162635 -220.498158) (xy 106.139509 -220.450137) (xy 106.123799 -220.399207)
			(xy 106.115856 -220.346503) (xy 105.88667 -220.346503) (xy 105.88108 -220.389067) (xy 105.869103 -220.4339)
			(xy 105.860596 -220.45549) (xy 105.851198 -220.478604) (xy 106.023918 -220.777562) (xy 106.048556 -220.780864)
			(xy 106.073897 -220.784693) (xy 106.123201 -220.798686) (xy 106.169991 -220.819599) (xy 106.213301 -220.847)
			(xy 106.252238 -220.880325) (xy 106.285998 -220.918885) (xy 106.313885 -220.961884) (xy 106.335323 -221.008436)
			(xy 106.349869 -221.057579) (xy 106.357224 -221.108299) (xy 106.357674 -221.133924) (xy 106.357176 -221.160573)
			(xy 106.349233 -221.213277) (xy 106.333523 -221.264207) (xy 106.310397 -221.312228) (xy 106.280373 -221.356265)
			(xy 106.244121 -221.395336) (xy 106.20245 -221.428567) (xy 106.156292 -221.455216) (xy 106.106678 -221.474688)
			(xy 106.054716 -221.486548) (xy 106.001566 -221.490532) (xy 105.948416 -221.486548) (xy 105.896454 -221.474688)
			(xy 105.84684 -221.455216) (xy 105.800682 -221.428567) (xy 105.759011 -221.395336) (xy 105.722759 -221.356265)
			(xy 105.692735 -221.312228) (xy 105.669609 -221.264207) (xy 105.653899 -221.213277) (xy 105.645956 -221.160573)
			(xy 105.645458 -221.133924) (xy 105.645837 -221.110679) (xy 105.65188 -221.064584) (xy 105.663866 -221.019666)
			(xy 105.672382 -220.998034) (xy 105.682034 -220.97492) (xy 105.509568 -220.676216) (xy 105.484676 -220.672914)
			(xy 105.459321 -220.669093) (xy 105.409984 -220.655134) (xy 105.363157 -220.634246) (xy 105.31981 -220.606859)
			(xy 105.280837 -220.573539) (xy 105.247045 -220.534976) (xy 105.219131 -220.491966) (xy 105.197673 -220.445398)
			(xy 105.183114 -220.396234) (xy 105.175754 -220.345491) (xy 105.175304 -220.319854) (xy 104.948575 -220.319854)
			(xy 104.948578 -220.3199) (xy 104.944594 -220.373063) (xy 104.93273 -220.425039) (xy 104.913252 -220.474666)
			(xy 104.886594 -220.520835) (xy 104.853352 -220.562515) (xy 104.81427 -220.598774) (xy 104.770219 -220.628804)
			(xy 104.722185 -220.651932) (xy 104.67124 -220.667642) (xy 104.618522 -220.675583) (xy 104.591866 -220.675962)
			(xy 104.579826 -220.675857) (xy 104.555801 -220.674204) (xy 104.54386 -220.67266) (xy 104.530607 -220.705297)
			(xy 104.499967 -220.768733) (xy 104.482646 -220.799406) (xy 104.410764 -220.923612) (xy 104.426512 -220.949266)
			(xy 104.438743 -220.970238) (xy 104.458036 -221.01479) (xy 104.471099 -221.061549) (xy 104.47769 -221.109649)
			(xy 104.478074 -221.133924) (xy 104.477633 -221.159159) (xy 104.470505 -221.209123) (xy 104.456396 -221.25758)
			(xy 104.435587 -221.303561) (xy 104.408496 -221.346143) (xy 104.375664 -221.384475) (xy 104.337751 -221.417788)
			(xy 104.295515 -221.445416) (xy 104.272842 -221.456504) (xy 104.264714 -221.460314) (xy 103.95966 -221.765368)
			(xy 103.974646 -221.797626) (xy 103.985142 -221.821245) (xy 103.99996 -221.87076) (xy 104.007452 -221.921898)
			(xy 104.00792 -221.94774) (xy 104.235504 -221.94774) (xy 104.235917 -221.92211) (xy 104.243248 -221.871376)
			(xy 104.25778 -221.822219) (xy 104.279212 -221.775654) (xy 104.3071 -221.732644) (xy 104.340869 -221.694079)
			(xy 104.379819 -221.660755) (xy 104.423146 -221.633361) (xy 104.469953 -221.612465) (xy 104.519274 -221.598497)
			(xy 104.544622 -221.59468) (xy 104.56926 -221.591378) (xy 104.741726 -221.29242) (xy 104.732328 -221.269306)
			(xy 104.723874 -221.247794) (xy 104.712 -221.203123) (xy 104.706021 -221.157289) (xy 104.705658 -221.134178)
			(xy 104.705658 -221.133924) (xy 104.706156 -221.107275) (xy 104.714099 -221.054571) (xy 104.729809 -221.003641)
			(xy 104.752935 -220.95562) (xy 104.782959 -220.911583) (xy 104.819211 -220.872512) (xy 104.860882 -220.839281)
			(xy 104.90704 -220.812632) (xy 104.956654 -220.79316) (xy 105.008616 -220.7813) (xy 105.061766 -220.777317)
			(xy 105.114916 -220.7813) (xy 105.166878 -220.79316) (xy 105.216492 -220.812632) (xy 105.26265 -220.839281)
			(xy 105.304321 -220.872512) (xy 105.340573 -220.911583) (xy 105.370597 -220.95562) (xy 105.393723 -221.003641)
			(xy 105.409433 -221.054571) (xy 105.417376 -221.107275) (xy 105.417874 -221.133924) (xy 105.417477 -221.159576)
			(xy 105.410112 -221.210348) (xy 105.395537 -221.259539) (xy 105.374054 -221.306128) (xy 105.346109 -221.349153)
			(xy 105.312278 -221.387723) (xy 105.273264 -221.421038) (xy 105.229872 -221.448411) (xy 105.183002 -221.469274)
			(xy 105.133623 -221.483195) (xy 105.108248 -221.486984) (xy 105.083356 -221.490286) (xy 104.911144 -221.788736)
			(xy 104.920796 -221.81185) (xy 104.929325 -221.833477) (xy 104.941307 -221.878397) (xy 104.947347 -221.924494)
			(xy 104.94772 -221.94774) (xy 104.947222 -221.974389) (xy 105.175802 -221.974389) (xy 105.175802 -221.921091)
			(xy 105.183745 -221.868387) (xy 105.199455 -221.817457) (xy 105.222581 -221.769436) (xy 105.252605 -221.725399)
			(xy 105.288857 -221.686328) (xy 105.330528 -221.653097) (xy 105.376686 -221.626448) (xy 105.4263 -221.606976)
			(xy 105.478262 -221.595116) (xy 105.531412 -221.591133) (xy 105.584562 -221.595116) (xy 105.636524 -221.606976)
			(xy 105.686138 -221.626448) (xy 105.732296 -221.653097) (xy 105.773967 -221.686328) (xy 105.810219 -221.725399)
			(xy 105.840243 -221.769436) (xy 105.863369 -221.817457) (xy 105.879079 -221.868387) (xy 105.887022 -221.921091)
			(xy 105.88752 -221.94774) (xy 106.115104 -221.94774) (xy 106.115517 -221.92211) (xy 106.122848 -221.871376)
			(xy 106.13738 -221.822219) (xy 106.158812 -221.775654) (xy 106.1867 -221.732644) (xy 106.220469 -221.694079)
			(xy 106.259419 -221.660755) (xy 106.302746 -221.633361) (xy 106.349553 -221.612465) (xy 106.398874 -221.598497)
			(xy 106.424222 -221.59468) (xy 106.44886 -221.591378) (xy 106.621326 -221.29242) (xy 106.611928 -221.269306)
			(xy 106.603474 -221.247794) (xy 106.5916 -221.203123) (xy 106.585621 -221.157289) (xy 106.585258 -221.134178)
			(xy 106.585258 -221.133924) (xy 106.585756 -221.107275) (xy 106.593699 -221.054571) (xy 106.609409 -221.003641)
			(xy 106.632535 -220.95562) (xy 106.662559 -220.911583) (xy 106.698811 -220.872512) (xy 106.740482 -220.839281)
			(xy 106.78664 -220.812632) (xy 106.836254 -220.79316) (xy 106.888216 -220.7813) (xy 106.941366 -220.777317)
			(xy 106.994516 -220.7813) (xy 107.046478 -220.79316) (xy 107.096092 -220.812632) (xy 107.14225 -220.839281)
			(xy 107.183921 -220.872512) (xy 107.220173 -220.911583) (xy 107.250197 -220.95562) (xy 107.273323 -221.003641)
			(xy 107.289033 -221.054571) (xy 107.296976 -221.107275) (xy 107.297474 -221.133924) (xy 107.297077 -221.159576)
			(xy 107.289712 -221.210348) (xy 107.275137 -221.259539) (xy 107.253654 -221.306128) (xy 107.225709 -221.349153)
			(xy 107.191878 -221.387723) (xy 107.152864 -221.421038) (xy 107.109472 -221.448411) (xy 107.062602 -221.469274)
			(xy 107.013223 -221.483195) (xy 106.987848 -221.486984) (xy 106.962956 -221.490286) (xy 106.790744 -221.788736)
			(xy 106.800396 -221.81185) (xy 106.808925 -221.833477) (xy 106.820907 -221.878397) (xy 106.826947 -221.924494)
			(xy 106.82732 -221.94774) (xy 106.826822 -221.974389) (xy 107.055402 -221.974389) (xy 107.055402 -221.921091)
			(xy 107.063345 -221.868387) (xy 107.079055 -221.817457) (xy 107.102181 -221.769436) (xy 107.132205 -221.725399)
			(xy 107.168457 -221.686328) (xy 107.210128 -221.653097) (xy 107.256286 -221.626448) (xy 107.3059 -221.606976)
			(xy 107.357862 -221.595116) (xy 107.411012 -221.591133) (xy 107.464162 -221.595116) (xy 107.516124 -221.606976)
			(xy 107.565738 -221.626448) (xy 107.611896 -221.653097) (xy 107.653567 -221.686328) (xy 107.689819 -221.725399)
			(xy 107.719843 -221.769436) (xy 107.742969 -221.817457) (xy 107.758679 -221.868387) (xy 107.766622 -221.921091)
			(xy 107.76712 -221.94774) (xy 107.994704 -221.94774) (xy 107.995117 -221.92211) (xy 108.002448 -221.871376)
			(xy 108.01698 -221.822219) (xy 108.038412 -221.775654) (xy 108.0663 -221.732644) (xy 108.100069 -221.694079)
			(xy 108.139019 -221.660755) (xy 108.182346 -221.633361) (xy 108.229153 -221.612465) (xy 108.278474 -221.598497)
			(xy 108.303822 -221.59468) (xy 108.32846 -221.591378) (xy 108.500926 -221.29242) (xy 108.491528 -221.269306)
			(xy 108.483074 -221.247794) (xy 108.4712 -221.203123) (xy 108.465221 -221.157289) (xy 108.464858 -221.134178)
			(xy 108.464858 -221.133924) (xy 108.465356 -221.107275) (xy 108.473299 -221.054571) (xy 108.489009 -221.003641)
			(xy 108.512135 -220.95562) (xy 108.542159 -220.911583) (xy 108.578411 -220.872512) (xy 108.620082 -220.839281)
			(xy 108.66624 -220.812632) (xy 108.715854 -220.79316) (xy 108.767816 -220.7813) (xy 108.820966 -220.777317)
			(xy 108.874116 -220.7813) (xy 108.926078 -220.79316) (xy 108.975692 -220.812632) (xy 109.02185 -220.839281)
			(xy 109.063521 -220.872512) (xy 109.099773 -220.911583) (xy 109.129797 -220.95562) (xy 109.152923 -221.003641)
			(xy 109.168633 -221.054571) (xy 109.176576 -221.107275) (xy 109.177074 -221.133924) (xy 109.176677 -221.159576)
			(xy 109.169312 -221.210348) (xy 109.154737 -221.259539) (xy 109.133254 -221.306128) (xy 109.105309 -221.349153)
			(xy 109.071478 -221.387723) (xy 109.032464 -221.421038) (xy 108.989072 -221.448411) (xy 108.942202 -221.469274)
			(xy 108.892823 -221.483195) (xy 108.867448 -221.486984) (xy 108.842556 -221.490286) (xy 108.670344 -221.788736)
			(xy 108.679996 -221.81185) (xy 108.688525 -221.833477) (xy 108.700507 -221.878397) (xy 108.706547 -221.924494)
			(xy 108.70692 -221.94774) (xy 108.706422 -221.974389) (xy 108.935002 -221.974389) (xy 108.935002 -221.921091)
			(xy 108.942945 -221.868387) (xy 108.958655 -221.817457) (xy 108.981781 -221.769436) (xy 109.011805 -221.725399)
			(xy 109.048057 -221.686328) (xy 109.089728 -221.653097) (xy 109.135886 -221.626448) (xy 109.1855 -221.606976)
			(xy 109.237462 -221.595116) (xy 109.290612 -221.591133) (xy 109.343762 -221.595116) (xy 109.395724 -221.606976)
			(xy 109.445338 -221.626448) (xy 109.491496 -221.653097) (xy 109.533167 -221.686328) (xy 109.569419 -221.725399)
			(xy 109.599443 -221.769436) (xy 109.622569 -221.817457) (xy 109.638279 -221.868387) (xy 109.646222 -221.921091)
			(xy 109.64672 -221.94774) (xy 109.874558 -221.94774) (xy 109.875011 -221.922112) (xy 109.882341 -221.871382)
			(xy 109.896871 -221.822228) (xy 109.918299 -221.775665) (xy 109.946183 -221.732657) (xy 109.979946 -221.694092)
			(xy 110.018891 -221.660767) (xy 110.062213 -221.633372) (xy 110.109015 -221.612472) (xy 110.15833 -221.5985)
			(xy 110.183676 -221.59468) (xy 110.208314 -221.591378) (xy 110.38078 -221.292674) (xy 110.371382 -221.26956)
			(xy 110.362883 -221.247967) (xy 110.35091 -221.203133) (xy 110.344851 -221.157126) (xy 110.344458 -221.133924)
			(xy 110.344956 -221.107275) (xy 110.352899 -221.054571) (xy 110.368609 -221.003641) (xy 110.391735 -220.95562)
			(xy 110.421759 -220.911583) (xy 110.458011 -220.872512) (xy 110.499682 -220.839281) (xy 110.54584 -220.812632)
			(xy 110.595454 -220.79316) (xy 110.647416 -220.7813) (xy 110.700566 -220.777317) (xy 110.753716 -220.7813)
			(xy 110.805678 -220.79316) (xy 110.855292 -220.812632) (xy 110.90145 -220.839281) (xy 110.943121 -220.872512)
			(xy 110.979373 -220.911583) (xy 111.009397 -220.95562) (xy 111.032523 -221.003641) (xy 111.048233 -221.054571)
			(xy 111.056176 -221.107275) (xy 111.056674 -221.133924) (xy 111.056218 -221.159563) (xy 111.048873 -221.210312)
			(xy 111.034324 -221.259483) (xy 111.012872 -221.306058) (xy 110.984961 -221.349074) (xy 110.951168 -221.387641)
			(xy 110.912191 -221.420962) (xy 110.868838 -221.448347) (xy 110.822005 -221.469229) (xy 110.772661 -221.483178)
			(xy 110.747302 -221.486984) (xy 110.72241 -221.490286) (xy 110.550198 -221.788736) (xy 110.55985 -221.81185)
			(xy 110.568377 -221.833478) (xy 110.580361 -221.878398) (xy 110.586401 -221.924495) (xy 110.586774 -221.94774)
			(xy 110.586276 -221.974389) (xy 110.578333 -222.027093) (xy 110.562623 -222.078023) (xy 110.539497 -222.126044)
			(xy 110.509473 -222.170081) (xy 110.473221 -222.209152) (xy 110.43155 -222.242383) (xy 110.385392 -222.269032)
			(xy 110.335778 -222.288504) (xy 110.283816 -222.300364) (xy 110.230666 -222.304348) (xy 110.177516 -222.300364)
			(xy 110.125554 -222.288504) (xy 110.07594 -222.269032) (xy 110.029782 -222.242383) (xy 109.988111 -222.209152)
			(xy 109.951859 -222.170081) (xy 109.921835 -222.126044) (xy 109.898709 -222.078023) (xy 109.882999 -222.027093)
			(xy 109.875056 -221.974389) (xy 109.874558 -221.94774) (xy 109.64672 -221.94774) (xy 109.646222 -221.974389)
			(xy 109.638279 -222.027093) (xy 109.622569 -222.078023) (xy 109.599443 -222.126044) (xy 109.569419 -222.170081)
			(xy 109.533167 -222.209152) (xy 109.491496 -222.242383) (xy 109.445338 -222.269032) (xy 109.395724 -222.288504)
			(xy 109.343762 -222.300364) (xy 109.290612 -222.304348) (xy 109.237462 -222.300364) (xy 109.1855 -222.288504)
			(xy 109.135886 -222.269032) (xy 109.089728 -222.242383) (xy 109.048057 -222.209152) (xy 109.011805 -222.170081)
			(xy 108.981781 -222.126044) (xy 108.958655 -222.078023) (xy 108.942945 -222.027093) (xy 108.935002 -221.974389)
			(xy 108.706422 -221.974389) (xy 108.698479 -222.027093) (xy 108.682769 -222.078023) (xy 108.659643 -222.126044)
			(xy 108.629619 -222.170081) (xy 108.593367 -222.209152) (xy 108.551696 -222.242383) (xy 108.505538 -222.269032)
			(xy 108.455924 -222.288504) (xy 108.403962 -222.300364) (xy 108.350812 -222.304348) (xy 108.297662 -222.300364)
			(xy 108.2457 -222.288504) (xy 108.196086 -222.269032) (xy 108.149928 -222.242383) (xy 108.108257 -222.209152)
			(xy 108.072005 -222.170081) (xy 108.041981 -222.126044) (xy 108.018855 -222.078023) (xy 108.003145 -222.027093)
			(xy 107.995202 -221.974389) (xy 107.994704 -221.94774) (xy 107.76712 -221.94774) (xy 107.766622 -221.974389)
			(xy 107.758679 -222.027093) (xy 107.742969 -222.078023) (xy 107.719843 -222.126044) (xy 107.689819 -222.170081)
			(xy 107.653567 -222.209152) (xy 107.611896 -222.242383) (xy 107.565738 -222.269032) (xy 107.516124 -222.288504)
			(xy 107.464162 -222.300364) (xy 107.411012 -222.304348) (xy 107.357862 -222.300364) (xy 107.3059 -222.288504)
			(xy 107.256286 -222.269032) (xy 107.210128 -222.242383) (xy 107.168457 -222.209152) (xy 107.132205 -222.170081)
			(xy 107.102181 -222.126044) (xy 107.079055 -222.078023) (xy 107.063345 -222.027093) (xy 107.055402 -221.974389)
			(xy 106.826822 -221.974389) (xy 106.818879 -222.027093) (xy 106.803169 -222.078023) (xy 106.780043 -222.126044)
			(xy 106.750019 -222.170081) (xy 106.713767 -222.209152) (xy 106.672096 -222.242383) (xy 106.625938 -222.269032)
			(xy 106.576324 -222.288504) (xy 106.524362 -222.300364) (xy 106.471212 -222.304348) (xy 106.418062 -222.300364)
			(xy 106.3661 -222.288504) (xy 106.316486 -222.269032) (xy 106.270328 -222.242383) (xy 106.228657 -222.209152)
			(xy 106.192405 -222.170081) (xy 106.162381 -222.126044) (xy 106.139255 -222.078023) (xy 106.123545 -222.027093)
			(xy 106.115602 -221.974389) (xy 106.115104 -221.94774) (xy 105.88752 -221.94774) (xy 105.887022 -221.974389)
			(xy 105.879079 -222.027093) (xy 105.863369 -222.078023) (xy 105.840243 -222.126044) (xy 105.810219 -222.170081)
			(xy 105.773967 -222.209152) (xy 105.732296 -222.242383) (xy 105.686138 -222.269032) (xy 105.636524 -222.288504)
			(xy 105.584562 -222.300364) (xy 105.531412 -222.304348) (xy 105.478262 -222.300364) (xy 105.4263 -222.288504)
			(xy 105.376686 -222.269032) (xy 105.330528 -222.242383) (xy 105.288857 -222.209152) (xy 105.252605 -222.170081)
			(xy 105.222581 -222.126044) (xy 105.199455 -222.078023) (xy 105.183745 -222.027093) (xy 105.175802 -221.974389)
			(xy 104.947222 -221.974389) (xy 104.939279 -222.027093) (xy 104.923569 -222.078023) (xy 104.900443 -222.126044)
			(xy 104.870419 -222.170081) (xy 104.834167 -222.209152) (xy 104.792496 -222.242383) (xy 104.746338 -222.269032)
			(xy 104.696724 -222.288504) (xy 104.644762 -222.300364) (xy 104.591612 -222.304348) (xy 104.538462 -222.300364)
			(xy 104.4865 -222.288504) (xy 104.436886 -222.269032) (xy 104.390728 -222.242383) (xy 104.349057 -222.209152)
			(xy 104.312805 -222.170081) (xy 104.282781 -222.126044) (xy 104.259655 -222.078023) (xy 104.243945 -222.027093)
			(xy 104.236002 -221.974389) (xy 104.235504 -221.94774) (xy 104.00792 -221.94774) (xy 104.007368 -221.975721)
			(xy 103.998608 -222.030994) (xy 103.98131 -222.084217) (xy 103.9559 -222.134078) (xy 103.923004 -222.179352)
			(xy 103.88343 -222.218922) (xy 103.838155 -222.251815) (xy 103.788291 -222.277221) (xy 103.735067 -222.294515)
			(xy 103.679793 -222.30327) (xy 103.651812 -222.303848) (xy 103.639835 -222.303734) (xy 103.615939 -222.30208)
			(xy 103.60406 -222.300546) (xy 103.586273 -222.343997) (xy 103.543391 -222.427527) (xy 103.492552 -222.506467)
			(xy 103.463852 -222.543624) (xy 103.481315 -222.567194) (xy 103.509101 -222.618853) (xy 103.528055 -222.674363)
			(xy 103.537665 -222.732228) (xy 103.538274 -222.761556) (xy 103.537782 -222.788205) (xy 103.766356 -222.788205)
			(xy 103.766356 -222.734907) (xy 103.774299 -222.682203) (xy 103.790009 -222.631273) (xy 103.813135 -222.583252)
			(xy 103.843159 -222.539215) (xy 103.879411 -222.500144) (xy 103.921082 -222.466913) (xy 103.96724 -222.440264)
			(xy 104.016854 -222.420792) (xy 104.068816 -222.408932) (xy 104.121966 -222.404949) (xy 104.175116 -222.408932)
			(xy 104.227078 -222.420792) (xy 104.276692 -222.440264) (xy 104.32285 -222.466913) (xy 104.364521 -222.500144)
			(xy 104.400773 -222.539215) (xy 104.430797 -222.583252) (xy 104.453923 -222.631273) (xy 104.469633 -222.682203)
			(xy 104.477576 -222.734907) (xy 104.478074 -222.761556) (xy 104.477576 -222.788205) (xy 104.706156 -222.788205)
			(xy 104.706156 -222.734907) (xy 104.714099 -222.682203) (xy 104.729809 -222.631273) (xy 104.752935 -222.583252)
			(xy 104.782959 -222.539215) (xy 104.819211 -222.500144) (xy 104.860882 -222.466913) (xy 104.90704 -222.440264)
			(xy 104.956654 -222.420792) (xy 105.008616 -222.408932) (xy 105.061766 -222.404949) (xy 105.114916 -222.408932)
			(xy 105.166878 -222.420792) (xy 105.216492 -222.440264) (xy 105.26265 -222.466913) (xy 105.304321 -222.500144)
			(xy 105.340573 -222.539215) (xy 105.370597 -222.583252) (xy 105.393723 -222.631273) (xy 105.409433 -222.682203)
			(xy 105.417376 -222.734907) (xy 105.417874 -222.761556) (xy 105.417376 -222.788205) (xy 105.645956 -222.788205)
			(xy 105.645956 -222.734907) (xy 105.653899 -222.682203) (xy 105.669609 -222.631273) (xy 105.692735 -222.583252)
			(xy 105.722759 -222.539215) (xy 105.759011 -222.500144) (xy 105.800682 -222.466913) (xy 105.84684 -222.440264)
			(xy 105.896454 -222.420792) (xy 105.948416 -222.408932) (xy 106.001566 -222.404949) (xy 106.054716 -222.408932)
			(xy 106.106678 -222.420792) (xy 106.156292 -222.440264) (xy 106.20245 -222.466913) (xy 106.244121 -222.500144)
			(xy 106.280373 -222.539215) (xy 106.310397 -222.583252) (xy 106.333523 -222.631273) (xy 106.349233 -222.682203)
			(xy 106.357176 -222.734907) (xy 106.357674 -222.761556) (xy 106.357176 -222.788205) (xy 106.585756 -222.788205)
			(xy 106.585756 -222.734907) (xy 106.593699 -222.682203) (xy 106.609409 -222.631273) (xy 106.632535 -222.583252)
			(xy 106.662559 -222.539215) (xy 106.698811 -222.500144) (xy 106.740482 -222.466913) (xy 106.78664 -222.440264)
			(xy 106.836254 -222.420792) (xy 106.888216 -222.408932) (xy 106.941366 -222.404949) (xy 106.994516 -222.408932)
			(xy 107.046478 -222.420792) (xy 107.096092 -222.440264) (xy 107.14225 -222.466913) (xy 107.183921 -222.500144)
			(xy 107.220173 -222.539215) (xy 107.250197 -222.583252) (xy 107.273323 -222.631273) (xy 107.289033 -222.682203)
			(xy 107.296976 -222.734907) (xy 107.297474 -222.761556) (xy 107.296976 -222.788205) (xy 107.525556 -222.788205)
			(xy 107.525556 -222.734907) (xy 107.533499 -222.682203) (xy 107.549209 -222.631273) (xy 107.572335 -222.583252)
			(xy 107.602359 -222.539215) (xy 107.638611 -222.500144) (xy 107.680282 -222.466913) (xy 107.72644 -222.440264)
			(xy 107.776054 -222.420792) (xy 107.828016 -222.408932) (xy 107.881166 -222.404949) (xy 107.934316 -222.408932)
			(xy 107.986278 -222.420792) (xy 108.035892 -222.440264) (xy 108.08205 -222.466913) (xy 108.123721 -222.500144)
			(xy 108.159973 -222.539215) (xy 108.189997 -222.583252) (xy 108.213123 -222.631273) (xy 108.228833 -222.682203)
			(xy 108.236776 -222.734907) (xy 108.237274 -222.761556) (xy 108.236776 -222.788205) (xy 108.465356 -222.788205)
			(xy 108.465356 -222.734907) (xy 108.473299 -222.682203) (xy 108.489009 -222.631273) (xy 108.512135 -222.583252)
			(xy 108.542159 -222.539215) (xy 108.578411 -222.500144) (xy 108.620082 -222.466913) (xy 108.66624 -222.440264)
			(xy 108.715854 -222.420792) (xy 108.767816 -222.408932) (xy 108.820966 -222.404949) (xy 108.874116 -222.408932)
			(xy 108.926078 -222.420792) (xy 108.975692 -222.440264) (xy 109.02185 -222.466913) (xy 109.063521 -222.500144)
			(xy 109.099773 -222.539215) (xy 109.129797 -222.583252) (xy 109.152923 -222.631273) (xy 109.168633 -222.682203)
			(xy 109.176576 -222.734907) (xy 109.177074 -222.761556) (xy 109.176576 -222.788205) (xy 109.405156 -222.788205)
			(xy 109.405156 -222.734907) (xy 109.413099 -222.682203) (xy 109.428809 -222.631273) (xy 109.451935 -222.583252)
			(xy 109.481959 -222.539215) (xy 109.518211 -222.500144) (xy 109.559882 -222.466913) (xy 109.60604 -222.440264)
			(xy 109.655654 -222.420792) (xy 109.707616 -222.408932) (xy 109.760766 -222.404949) (xy 109.813916 -222.408932)
			(xy 109.865878 -222.420792) (xy 109.915492 -222.440264) (xy 109.96165 -222.466913) (xy 110.003321 -222.500144)
			(xy 110.039573 -222.539215) (xy 110.069597 -222.583252) (xy 110.092723 -222.631273) (xy 110.108433 -222.682203)
			(xy 110.116376 -222.734907) (xy 110.116874 -222.761556) (xy 110.116376 -222.788205) (xy 110.344956 -222.788205)
			(xy 110.344956 -222.734907) (xy 110.352899 -222.682203) (xy 110.368609 -222.631273) (xy 110.391735 -222.583252)
			(xy 110.421759 -222.539215) (xy 110.458011 -222.500144) (xy 110.499682 -222.466913) (xy 110.54584 -222.440264)
			(xy 110.595454 -222.420792) (xy 110.647416 -222.408932) (xy 110.700566 -222.404949) (xy 110.753716 -222.408932)
			(xy 110.805678 -222.420792) (xy 110.855292 -222.440264) (xy 110.90145 -222.466913) (xy 110.943121 -222.500144)
			(xy 110.979373 -222.539215) (xy 111.009397 -222.583252) (xy 111.032523 -222.631273) (xy 111.048233 -222.682203)
			(xy 111.056176 -222.734907) (xy 111.056674 -222.761556) (xy 111.056176 -222.788205) (xy 111.048233 -222.840909)
			(xy 111.032523 -222.891839) (xy 111.009397 -222.93986) (xy 110.979373 -222.983897) (xy 110.943121 -223.022968)
			(xy 110.90145 -223.056199) (xy 110.855292 -223.082848) (xy 110.805678 -223.10232) (xy 110.753716 -223.11418)
			(xy 110.700566 -223.118164) (xy 110.647416 -223.11418) (xy 110.595454 -223.10232) (xy 110.54584 -223.082848)
			(xy 110.499682 -223.056199) (xy 110.458011 -223.022968) (xy 110.421759 -222.983897) (xy 110.391735 -222.93986)
			(xy 110.368609 -222.891839) (xy 110.352899 -222.840909) (xy 110.344956 -222.788205) (xy 110.116376 -222.788205)
			(xy 110.108433 -222.840909) (xy 110.092723 -222.891839) (xy 110.069597 -222.93986) (xy 110.039573 -222.983897)
			(xy 110.003321 -223.022968) (xy 109.96165 -223.056199) (xy 109.915492 -223.082848) (xy 109.865878 -223.10232)
			(xy 109.813916 -223.11418) (xy 109.760766 -223.118164) (xy 109.707616 -223.11418) (xy 109.655654 -223.10232)
			(xy 109.60604 -223.082848) (xy 109.559882 -223.056199) (xy 109.518211 -223.022968) (xy 109.481959 -222.983897)
			(xy 109.451935 -222.93986) (xy 109.428809 -222.891839) (xy 109.413099 -222.840909) (xy 109.405156 -222.788205)
			(xy 109.176576 -222.788205) (xy 109.168633 -222.840909) (xy 109.152923 -222.891839) (xy 109.129797 -222.93986)
			(xy 109.099773 -222.983897) (xy 109.063521 -223.022968) (xy 109.02185 -223.056199) (xy 108.975692 -223.082848)
			(xy 108.926078 -223.10232) (xy 108.874116 -223.11418) (xy 108.820966 -223.118164) (xy 108.767816 -223.11418)
			(xy 108.715854 -223.10232) (xy 108.66624 -223.082848) (xy 108.620082 -223.056199) (xy 108.578411 -223.022968)
			(xy 108.542159 -222.983897) (xy 108.512135 -222.93986) (xy 108.489009 -222.891839) (xy 108.473299 -222.840909)
			(xy 108.465356 -222.788205) (xy 108.236776 -222.788205) (xy 108.228833 -222.840909) (xy 108.213123 -222.891839)
			(xy 108.189997 -222.93986) (xy 108.159973 -222.983897) (xy 108.123721 -223.022968) (xy 108.08205 -223.056199)
			(xy 108.035892 -223.082848) (xy 107.986278 -223.10232) (xy 107.934316 -223.11418) (xy 107.881166 -223.118164)
			(xy 107.828016 -223.11418) (xy 107.776054 -223.10232) (xy 107.72644 -223.082848) (xy 107.680282 -223.056199)
			(xy 107.638611 -223.022968) (xy 107.602359 -222.983897) (xy 107.572335 -222.93986) (xy 107.549209 -222.891839)
			(xy 107.533499 -222.840909) (xy 107.525556 -222.788205) (xy 107.296976 -222.788205) (xy 107.289033 -222.840909)
			(xy 107.273323 -222.891839) (xy 107.250197 -222.93986) (xy 107.220173 -222.983897) (xy 107.183921 -223.022968)
			(xy 107.14225 -223.056199) (xy 107.096092 -223.082848) (xy 107.046478 -223.10232) (xy 106.994516 -223.11418)
			(xy 106.941366 -223.118164) (xy 106.888216 -223.11418) (xy 106.836254 -223.10232) (xy 106.78664 -223.082848)
			(xy 106.740482 -223.056199) (xy 106.698811 -223.022968) (xy 106.662559 -222.983897) (xy 106.632535 -222.93986)
			(xy 106.609409 -222.891839) (xy 106.593699 -222.840909) (xy 106.585756 -222.788205) (xy 106.357176 -222.788205)
			(xy 106.349233 -222.840909) (xy 106.333523 -222.891839) (xy 106.310397 -222.93986) (xy 106.280373 -222.983897)
			(xy 106.244121 -223.022968) (xy 106.20245 -223.056199) (xy 106.156292 -223.082848) (xy 106.106678 -223.10232)
			(xy 106.054716 -223.11418) (xy 106.001566 -223.118164) (xy 105.948416 -223.11418) (xy 105.896454 -223.10232)
			(xy 105.84684 -223.082848) (xy 105.800682 -223.056199) (xy 105.759011 -223.022968) (xy 105.722759 -222.983897)
			(xy 105.692735 -222.93986) (xy 105.669609 -222.891839) (xy 105.653899 -222.840909) (xy 105.645956 -222.788205)
			(xy 105.417376 -222.788205) (xy 105.409433 -222.840909) (xy 105.393723 -222.891839) (xy 105.370597 -222.93986)
			(xy 105.340573 -222.983897) (xy 105.304321 -223.022968) (xy 105.26265 -223.056199) (xy 105.216492 -223.082848)
			(xy 105.166878 -223.10232) (xy 105.114916 -223.11418) (xy 105.061766 -223.118164) (xy 105.008616 -223.11418)
			(xy 104.956654 -223.10232) (xy 104.90704 -223.082848) (xy 104.860882 -223.056199) (xy 104.819211 -223.022968)
			(xy 104.782959 -222.983897) (xy 104.752935 -222.93986) (xy 104.729809 -222.891839) (xy 104.714099 -222.840909)
			(xy 104.706156 -222.788205) (xy 104.477576 -222.788205) (xy 104.469633 -222.840909) (xy 104.453923 -222.891839)
			(xy 104.430797 -222.93986) (xy 104.400773 -222.983897) (xy 104.364521 -223.022968) (xy 104.32285 -223.056199)
			(xy 104.276692 -223.082848) (xy 104.227078 -223.10232) (xy 104.175116 -223.11418) (xy 104.121966 -223.118164)
			(xy 104.068816 -223.11418) (xy 104.016854 -223.10232) (xy 103.96724 -223.082848) (xy 103.921082 -223.056199)
			(xy 103.879411 -223.022968) (xy 103.843159 -222.983897) (xy 103.813135 -222.93986) (xy 103.790009 -222.891839)
			(xy 103.774299 -222.840909) (xy 103.766356 -222.788205) (xy 103.537782 -222.788205) (xy 103.537757 -222.789543)
			(xy 103.529006 -222.844828) (xy 103.511714 -222.898063) (xy 103.486305 -222.947936) (xy 103.453407 -222.993221)
			(xy 103.413828 -223.0328) (xy 103.368545 -223.0657) (xy 103.318672 -223.09111) (xy 103.265437 -223.108404)
			(xy 103.210153 -223.117156) (xy 103.182166 -223.117664) (xy 103.155393 -223.117181) (xy 103.10245 -223.109167)
			(xy 103.051302 -223.093324) (xy 103.003098 -223.07001) (xy 102.958924 -223.039748) (xy 102.919773 -223.003219)
			(xy 102.902766 -222.982536) (xy 102.893531 -222.971602) (xy 102.870281 -222.954934) (xy 102.843314 -222.945383)
			(xy 102.814756 -222.943701) (xy 102.786855 -222.95002) (xy 102.761808 -222.963843) (xy 102.751382 -222.973646)
			(xy 102.677214 -223.047814) (xy 102.667401 -223.058424) (xy 102.653614 -223.083807) (xy 102.64748 -223.112034)
			(xy 102.649491 -223.14085) (xy 102.659485 -223.167952) (xy 102.676665 -223.191174) (xy 102.699656 -223.208661)
			(xy 102.726623 -223.219015) (xy 102.740968 -223.220788) (xy 102.76738 -223.223419) (xy 102.81906 -223.235509)
			(xy 102.868375 -223.255134) (xy 102.914231 -223.28186) (xy 102.955613 -223.315095) (xy 102.991605 -223.354103)
			(xy 103.021411 -223.398019) (xy 103.044369 -223.445873) (xy 103.059972 -223.496604) (xy 103.067874 -223.549088)
			(xy 103.068374 -223.575626) (xy 103.067876 -223.602275) (xy 103.059933 -223.654979) (xy 103.044223 -223.705909)
			(xy 103.021097 -223.75393) (xy 102.991073 -223.797967) (xy 102.954821 -223.837038) (xy 102.91315 -223.870269)
			(xy 102.866992 -223.896918) (xy 102.817378 -223.91639) (xy 102.765416 -223.92825) (xy 102.712266 -223.932234)
			(xy 102.659116 -223.92825) (xy 102.607154 -223.91639) (xy 102.55754 -223.896918) (xy 102.511382 -223.870269)
			(xy 102.469711 -223.837038) (xy 102.433459 -223.797967) (xy 102.403435 -223.75393) (xy 102.380309 -223.705909)
			(xy 102.364599 -223.654979) (xy 102.356656 -223.602275) (xy 102.356158 -223.575626) (xy 102.356732 -223.546176)
			(xy 102.366428 -223.488081) (xy 102.385561 -223.432376) (xy 102.399084 -223.406208) (xy 102.405756 -223.392732)
			(xy 102.411735 -223.363278) (xy 102.408886 -223.333359) (xy 102.397455 -223.305562) (xy 102.378431 -223.282295)
			(xy 102.35346 -223.265568) (xy 102.324704 -223.256831) (xy 102.309676 -223.256348) (xy 102.174802 -223.256348)
			(xy 102.159784 -223.256884) (xy 102.131048 -223.265621) (xy 102.106096 -223.28234) (xy 102.087086 -223.305594)
			(xy 102.075664 -223.333372) (xy 102.072816 -223.363272) (xy 102.078789 -223.392707) (xy 102.085394 -223.406208)
			(xy 102.098912 -223.432378) (xy 102.118051 -223.488082) (xy 102.127758 -223.546176) (xy 102.12832 -223.575626)
			(xy 102.127873 -223.601252) (xy 102.120524 -223.651975) (xy 102.105981 -223.701121) (xy 102.084546 -223.747676)
			(xy 102.056659 -223.790678) (xy 102.022898 -223.829239) (xy 101.983958 -223.862564) (xy 101.940645 -223.889964)
			(xy 101.893852 -223.910874) (xy 101.844545 -223.924862) (xy 101.819202 -223.928686) (xy 101.79431 -223.931988)
			(xy 101.622098 -224.230438) (xy 101.63175 -224.253552) (xy 101.640266 -224.275184) (xy 101.652252 -224.320102)
			(xy 101.658293 -224.366197) (xy 101.658674 -224.389442) (xy 101.886258 -224.389442) (xy 101.886756 -224.362793)
			(xy 101.894699 -224.310089) (xy 101.910409 -224.259159) (xy 101.933535 -224.211138) (xy 101.963559 -224.167101)
			(xy 101.999811 -224.12803) (xy 102.041482 -224.094799) (xy 102.08764 -224.06815) (xy 102.137254 -224.048678)
			(xy 102.189216 -224.036818) (xy 102.242366 -224.032835) (xy 102.295516 -224.036818) (xy 102.347478 -224.048678)
			(xy 102.397092 -224.06815) (xy 102.44325 -224.094799) (xy 102.484921 -224.12803) (xy 102.521173 -224.167101)
			(xy 102.551197 -224.211138) (xy 102.574323 -224.259159) (xy 102.590033 -224.310089) (xy 102.597976 -224.362793)
			(xy 102.598474 -224.389442) (xy 102.826058 -224.389442) (xy 102.826512 -224.363814) (xy 102.833843 -224.313084)
			(xy 102.848372 -224.26393) (xy 102.8698 -224.217367) (xy 102.897684 -224.174359) (xy 102.931447 -224.135794)
			(xy 102.970392 -224.102469) (xy 103.013713 -224.075074) (xy 103.060515 -224.054174) (xy 103.10983 -224.040202)
			(xy 103.135176 -224.036382) (xy 103.159814 -224.03308) (xy 103.332026 -223.734376) (xy 103.322628 -223.711516)
			(xy 103.31412 -223.689881) (xy 103.302129 -223.644965) (xy 103.296081 -223.598871) (xy 103.295704 -223.575626)
			(xy 103.296202 -223.548977) (xy 103.304145 -223.496273) (xy 103.319855 -223.445343) (xy 103.342981 -223.397322)
			(xy 103.373005 -223.353285) (xy 103.409257 -223.314214) (xy 103.450928 -223.280983) (xy 103.497086 -223.254334)
			(xy 103.5467 -223.234862) (xy 103.598662 -223.223002) (xy 103.651812 -223.219019) (xy 103.704962 -223.223002)
			(xy 103.756924 -223.234862) (xy 103.806538 -223.254334) (xy 103.852696 -223.280983) (xy 103.894367 -223.314214)
			(xy 103.930619 -223.353285) (xy 103.960643 -223.397322) (xy 103.983769 -223.445343) (xy 103.999479 -223.496273)
			(xy 104.007422 -223.548977) (xy 104.00792 -223.575626) (xy 104.007547 -223.601257) (xy 104.0074 -223.602275)
			(xy 104.236256 -223.602275) (xy 104.236256 -223.548977) (xy 104.244199 -223.496273) (xy 104.259909 -223.445343)
			(xy 104.283035 -223.397322) (xy 104.313059 -223.353285) (xy 104.349311 -223.314214) (xy 104.390982 -223.280983)
			(xy 104.43714 -223.254334) (xy 104.486754 -223.234862) (xy 104.538716 -223.223002) (xy 104.591866 -223.219019)
			(xy 104.645016 -223.223002) (xy 104.696978 -223.234862) (xy 104.746592 -223.254334) (xy 104.79275 -223.280983)
			(xy 104.834421 -223.314214) (xy 104.870673 -223.353285) (xy 104.900697 -223.397322) (xy 104.923823 -223.445343)
			(xy 104.939533 -223.496273) (xy 104.947476 -223.548977) (xy 104.947974 -223.575626) (xy 104.947476 -223.602275)
			(xy 104.939533 -223.654979) (xy 104.923823 -223.705909) (xy 104.900697 -223.75393) (xy 104.870673 -223.797967)
			(xy 104.834421 -223.837038) (xy 104.79275 -223.870269) (xy 104.746592 -223.896918) (xy 104.696978 -223.91639)
			(xy 104.645016 -223.92825) (xy 104.591866 -223.932234) (xy 104.538716 -223.92825) (xy 104.486754 -223.91639)
			(xy 104.43714 -223.896918) (xy 104.390982 -223.870269) (xy 104.349311 -223.837038) (xy 104.313059 -223.797967)
			(xy 104.283035 -223.75393) (xy 104.259909 -223.705909) (xy 104.244199 -223.654979) (xy 104.236256 -223.602275)
			(xy 104.0074 -223.602275) (xy 104.000207 -223.651991) (xy 103.985668 -223.701148) (xy 103.96423 -223.747712)
			(xy 103.936337 -223.790721) (xy 103.902564 -223.829285) (xy 103.863611 -223.862608) (xy 103.820282 -223.890002)
			(xy 103.773473 -223.910899) (xy 103.724151 -223.924868) (xy 103.698802 -223.928686) (xy 103.67391 -223.931988)
			(xy 103.501698 -224.230438) (xy 103.51135 -224.253552) (xy 103.519878 -224.27518) (xy 103.531861 -224.3201)
			(xy 103.537901 -224.366197) (xy 103.538274 -224.389442) (xy 103.765858 -224.389442) (xy 103.766356 -224.362793)
			(xy 103.774299 -224.310089) (xy 103.790009 -224.259159) (xy 103.813135 -224.211138) (xy 103.843159 -224.167101)
			(xy 103.879411 -224.12803) (xy 103.921082 -224.094799) (xy 103.96724 -224.06815) (xy 104.016854 -224.048678)
			(xy 104.068816 -224.036818) (xy 104.121966 -224.032835) (xy 104.175116 -224.036818) (xy 104.227078 -224.048678)
			(xy 104.276692 -224.06815) (xy 104.32285 -224.094799) (xy 104.364521 -224.12803) (xy 104.400773 -224.167101)
			(xy 104.430797 -224.211138) (xy 104.453923 -224.259159) (xy 104.469633 -224.310089) (xy 104.477576 -224.362793)
			(xy 104.478074 -224.389442) (xy 104.705658 -224.389442) (xy 104.706112 -224.363814) (xy 104.713443 -224.313084)
			(xy 104.727972 -224.26393) (xy 104.7494 -224.217367) (xy 104.777284 -224.174359) (xy 104.811047 -224.135794)
			(xy 104.849992 -224.102469) (xy 104.893313 -224.075074) (xy 104.940115 -224.054174) (xy 104.98943 -224.040202)
			(xy 105.014776 -224.036382) (xy 105.039414 -224.03308) (xy 105.211626 -223.734376) (xy 105.202228 -223.711516)
			(xy 105.19372 -223.689881) (xy 105.181729 -223.644965) (xy 105.175681 -223.598871) (xy 105.175304 -223.575626)
			(xy 105.175802 -223.548977) (xy 105.183745 -223.496273) (xy 105.199455 -223.445343) (xy 105.222581 -223.397322)
			(xy 105.252605 -223.353285) (xy 105.288857 -223.314214) (xy 105.330528 -223.280983) (xy 105.376686 -223.254334)
			(xy 105.4263 -223.234862) (xy 105.478262 -223.223002) (xy 105.531412 -223.219019) (xy 105.584562 -223.223002)
			(xy 105.636524 -223.234862) (xy 105.686138 -223.254334) (xy 105.732296 -223.280983) (xy 105.773967 -223.314214)
			(xy 105.810219 -223.353285) (xy 105.840243 -223.397322) (xy 105.863369 -223.445343) (xy 105.879079 -223.496273)
			(xy 105.887022 -223.548977) (xy 105.88752 -223.575626) (xy 105.887147 -223.601257) (xy 105.887 -223.602275)
			(xy 106.115856 -223.602275) (xy 106.115856 -223.548977) (xy 106.123799 -223.496273) (xy 106.139509 -223.445343)
			(xy 106.162635 -223.397322) (xy 106.192659 -223.353285) (xy 106.228911 -223.314214) (xy 106.270582 -223.280983)
			(xy 106.31674 -223.254334) (xy 106.366354 -223.234862) (xy 106.418316 -223.223002) (xy 106.471466 -223.219019)
			(xy 106.524616 -223.223002) (xy 106.576578 -223.234862) (xy 106.626192 -223.254334) (xy 106.67235 -223.280983)
			(xy 106.714021 -223.314214) (xy 106.750273 -223.353285) (xy 106.780297 -223.397322) (xy 106.803423 -223.445343)
			(xy 106.819133 -223.496273) (xy 106.827076 -223.548977) (xy 106.827574 -223.575626) (xy 106.827076 -223.602275)
			(xy 106.819133 -223.654979) (xy 106.803423 -223.705909) (xy 106.780297 -223.75393) (xy 106.750273 -223.797967)
			(xy 106.714021 -223.837038) (xy 106.67235 -223.870269) (xy 106.626192 -223.896918) (xy 106.576578 -223.91639)
			(xy 106.524616 -223.92825) (xy 106.471466 -223.932234) (xy 106.418316 -223.92825) (xy 106.366354 -223.91639)
			(xy 106.31674 -223.896918) (xy 106.270582 -223.870269) (xy 106.228911 -223.837038) (xy 106.192659 -223.797967)
			(xy 106.162635 -223.75393) (xy 106.139509 -223.705909) (xy 106.123799 -223.654979) (xy 106.115856 -223.602275)
			(xy 105.887 -223.602275) (xy 105.879807 -223.651991) (xy 105.865268 -223.701148) (xy 105.84383 -223.747712)
			(xy 105.815937 -223.790721) (xy 105.782164 -223.829285) (xy 105.743211 -223.862608) (xy 105.699882 -223.890002)
			(xy 105.653073 -223.910899) (xy 105.603751 -223.924868) (xy 105.578402 -223.928686) (xy 105.55351 -223.931988)
			(xy 105.381298 -224.230438) (xy 105.39095 -224.253552) (xy 105.399478 -224.27518) (xy 105.411461 -224.3201)
			(xy 105.417501 -224.366197) (xy 105.417874 -224.389442) (xy 105.645458 -224.389442) (xy 105.645956 -224.362793)
			(xy 105.653899 -224.310089) (xy 105.669609 -224.259159) (xy 105.692735 -224.211138) (xy 105.722759 -224.167101)
			(xy 105.759011 -224.12803) (xy 105.800682 -224.094799) (xy 105.84684 -224.06815) (xy 105.896454 -224.048678)
			(xy 105.948416 -224.036818) (xy 106.001566 -224.032835) (xy 106.054716 -224.036818) (xy 106.106678 -224.048678)
			(xy 106.156292 -224.06815) (xy 106.20245 -224.094799) (xy 106.244121 -224.12803) (xy 106.280373 -224.167101)
			(xy 106.310397 -224.211138) (xy 106.333523 -224.259159) (xy 106.349233 -224.310089) (xy 106.357176 -224.362793)
			(xy 106.357674 -224.389442) (xy 106.585258 -224.389442) (xy 106.585712 -224.363814) (xy 106.593043 -224.313084)
			(xy 106.607572 -224.26393) (xy 106.629 -224.217367) (xy 106.656884 -224.174359) (xy 106.690647 -224.135794)
			(xy 106.729592 -224.102469) (xy 106.772913 -224.075074) (xy 106.819715 -224.054174) (xy 106.86903 -224.040202)
			(xy 106.894376 -224.036382) (xy 106.919014 -224.03308) (xy 107.091226 -223.734376) (xy 107.081828 -223.711516)
			(xy 107.07332 -223.689881) (xy 107.061329 -223.644965) (xy 107.055281 -223.598871) (xy 107.054904 -223.575626)
			(xy 107.055402 -223.548977) (xy 107.063345 -223.496273) (xy 107.079055 -223.445343) (xy 107.102181 -223.397322)
			(xy 107.132205 -223.353285) (xy 107.168457 -223.314214) (xy 107.210128 -223.280983) (xy 107.256286 -223.254334)
			(xy 107.3059 -223.234862) (xy 107.357862 -223.223002) (xy 107.411012 -223.219019) (xy 107.464162 -223.223002)
			(xy 107.516124 -223.234862) (xy 107.565738 -223.254334) (xy 107.611896 -223.280983) (xy 107.653567 -223.314214)
			(xy 107.689819 -223.353285) (xy 107.719843 -223.397322) (xy 107.742969 -223.445343) (xy 107.758679 -223.496273)
			(xy 107.766622 -223.548977) (xy 107.76712 -223.575626) (xy 107.766747 -223.601257) (xy 107.7666 -223.602275)
			(xy 107.995456 -223.602275) (xy 107.995456 -223.548977) (xy 108.003399 -223.496273) (xy 108.019109 -223.445343)
			(xy 108.042235 -223.397322) (xy 108.072259 -223.353285) (xy 108.108511 -223.314214) (xy 108.150182 -223.280983)
			(xy 108.19634 -223.254334) (xy 108.245954 -223.234862) (xy 108.297916 -223.223002) (xy 108.351066 -223.219019)
			(xy 108.404216 -223.223002) (xy 108.456178 -223.234862) (xy 108.505792 -223.254334) (xy 108.55195 -223.280983)
			(xy 108.593621 -223.314214) (xy 108.629873 -223.353285) (xy 108.659897 -223.397322) (xy 108.683023 -223.445343)
			(xy 108.698733 -223.496273) (xy 108.706676 -223.548977) (xy 108.707174 -223.575626) (xy 108.706676 -223.602275)
			(xy 108.698733 -223.654979) (xy 108.683023 -223.705909) (xy 108.659897 -223.75393) (xy 108.629873 -223.797967)
			(xy 108.593621 -223.837038) (xy 108.55195 -223.870269) (xy 108.505792 -223.896918) (xy 108.456178 -223.91639)
			(xy 108.404216 -223.92825) (xy 108.351066 -223.932234) (xy 108.297916 -223.92825) (xy 108.245954 -223.91639)
			(xy 108.19634 -223.896918) (xy 108.150182 -223.870269) (xy 108.108511 -223.837038) (xy 108.072259 -223.797967)
			(xy 108.042235 -223.75393) (xy 108.019109 -223.705909) (xy 108.003399 -223.654979) (xy 107.995456 -223.602275)
			(xy 107.7666 -223.602275) (xy 107.759407 -223.651991) (xy 107.744868 -223.701148) (xy 107.72343 -223.747712)
			(xy 107.695537 -223.790721) (xy 107.661764 -223.829285) (xy 107.622811 -223.862608) (xy 107.579482 -223.890002)
			(xy 107.532673 -223.910899) (xy 107.483351 -223.924868) (xy 107.458002 -223.928686) (xy 107.43311 -223.931988)
			(xy 107.260898 -224.230438) (xy 107.27055 -224.253552) (xy 107.279078 -224.27518) (xy 107.291061 -224.3201)
			(xy 107.297101 -224.366197) (xy 107.297474 -224.389442) (xy 107.525058 -224.389442) (xy 107.525556 -224.362793)
			(xy 107.533499 -224.310089) (xy 107.549209 -224.259159) (xy 107.572335 -224.211138) (xy 107.602359 -224.167101)
			(xy 107.638611 -224.12803) (xy 107.680282 -224.094799) (xy 107.72644 -224.06815) (xy 107.776054 -224.048678)
			(xy 107.828016 -224.036818) (xy 107.881166 -224.032835) (xy 107.934316 -224.036818) (xy 107.986278 -224.048678)
			(xy 108.035892 -224.06815) (xy 108.08205 -224.094799) (xy 108.123721 -224.12803) (xy 108.159973 -224.167101)
			(xy 108.189997 -224.211138) (xy 108.213123 -224.259159) (xy 108.228833 -224.310089) (xy 108.236776 -224.362793)
			(xy 108.237274 -224.389442) (xy 108.464858 -224.389442) (xy 108.465312 -224.363814) (xy 108.472643 -224.313084)
			(xy 108.487172 -224.26393) (xy 108.5086 -224.217367) (xy 108.536484 -224.174359) (xy 108.570247 -224.135794)
			(xy 108.609192 -224.102469) (xy 108.652513 -224.075074) (xy 108.699315 -224.054174) (xy 108.74863 -224.040202)
			(xy 108.773976 -224.036382) (xy 108.798614 -224.03308) (xy 108.970826 -223.734376) (xy 108.961428 -223.711516)
			(xy 108.95292 -223.689881) (xy 108.940929 -223.644965) (xy 108.934881 -223.598871) (xy 108.934504 -223.575626)
			(xy 108.935002 -223.548977) (xy 108.942945 -223.496273) (xy 108.958655 -223.445343) (xy 108.981781 -223.397322)
			(xy 109.011805 -223.353285) (xy 109.048057 -223.314214) (xy 109.089728 -223.280983) (xy 109.135886 -223.254334)
			(xy 109.1855 -223.234862) (xy 109.237462 -223.223002) (xy 109.290612 -223.219019) (xy 109.343762 -223.223002)
			(xy 109.395724 -223.234862) (xy 109.445338 -223.254334) (xy 109.491496 -223.280983) (xy 109.533167 -223.314214)
			(xy 109.569419 -223.353285) (xy 109.599443 -223.397322) (xy 109.622569 -223.445343) (xy 109.638279 -223.496273)
			(xy 109.646222 -223.548977) (xy 109.64672 -223.575626) (xy 109.646347 -223.601257) (xy 109.6462 -223.602275)
			(xy 109.875056 -223.602275) (xy 109.875056 -223.548977) (xy 109.882999 -223.496273) (xy 109.898709 -223.445343)
			(xy 109.921835 -223.397322) (xy 109.951859 -223.353285) (xy 109.988111 -223.314214) (xy 110.029782 -223.280983)
			(xy 110.07594 -223.254334) (xy 110.125554 -223.234862) (xy 110.177516 -223.223002) (xy 110.230666 -223.219019)
			(xy 110.283816 -223.223002) (xy 110.335778 -223.234862) (xy 110.385392 -223.254334) (xy 110.43155 -223.280983)
			(xy 110.473221 -223.314214) (xy 110.509473 -223.353285) (xy 110.539497 -223.397322) (xy 110.562623 -223.445343)
			(xy 110.578333 -223.496273) (xy 110.586276 -223.548977) (xy 110.586774 -223.575626) (xy 110.586276 -223.602275)
			(xy 110.578333 -223.654979) (xy 110.562623 -223.705909) (xy 110.539497 -223.75393) (xy 110.509473 -223.797967)
			(xy 110.473221 -223.837038) (xy 110.43155 -223.870269) (xy 110.385392 -223.896918) (xy 110.335778 -223.91639)
			(xy 110.283816 -223.92825) (xy 110.230666 -223.932234) (xy 110.177516 -223.92825) (xy 110.125554 -223.91639)
			(xy 110.07594 -223.896918) (xy 110.029782 -223.870269) (xy 109.988111 -223.837038) (xy 109.951859 -223.797967)
			(xy 109.921835 -223.75393) (xy 109.898709 -223.705909) (xy 109.882999 -223.654979) (xy 109.875056 -223.602275)
			(xy 109.6462 -223.602275) (xy 109.639007 -223.651991) (xy 109.624468 -223.701148) (xy 109.60303 -223.747712)
			(xy 109.575137 -223.790721) (xy 109.541364 -223.829285) (xy 109.502411 -223.862608) (xy 109.459082 -223.890002)
			(xy 109.412273 -223.910899) (xy 109.362951 -223.924868) (xy 109.337602 -223.928686) (xy 109.31271 -223.931988)
			(xy 109.140498 -224.230438) (xy 109.15015 -224.253552) (xy 109.158678 -224.27518) (xy 109.170661 -224.3201)
			(xy 109.176701 -224.366197) (xy 109.177074 -224.389442) (xy 109.404658 -224.389442) (xy 109.405156 -224.362793)
			(xy 109.413099 -224.310089) (xy 109.428809 -224.259159) (xy 109.451935 -224.211138) (xy 109.481959 -224.167101)
			(xy 109.518211 -224.12803) (xy 109.559882 -224.094799) (xy 109.60604 -224.06815) (xy 109.655654 -224.048678)
			(xy 109.707616 -224.036818) (xy 109.760766 -224.032835) (xy 109.813916 -224.036818) (xy 109.865878 -224.048678)
			(xy 109.915492 -224.06815) (xy 109.96165 -224.094799) (xy 110.003321 -224.12803) (xy 110.039573 -224.167101)
			(xy 110.069597 -224.211138) (xy 110.092723 -224.259159) (xy 110.108433 -224.310089) (xy 110.116376 -224.362793)
			(xy 110.116874 -224.389442) (xy 110.116488 -224.412687) (xy 110.110449 -224.458782) (xy 110.098465 -224.5037)
			(xy 110.08995 -224.525332) (xy 110.080298 -224.548446) (xy 110.252764 -224.846896) (xy 110.277402 -224.850198)
			(xy 110.302742 -224.854037) (xy 110.352048 -224.868024) (xy 110.39884 -224.888933) (xy 110.442153 -224.916332)
			(xy 110.481092 -224.949655) (xy 110.514853 -224.988214) (xy 110.54274 -225.031214) (xy 110.564177 -225.077767)
			(xy 110.578721 -225.126911) (xy 110.586072 -225.177632) (xy 110.58652 -225.203258) (xy 110.586022 -225.229907)
			(xy 110.578079 -225.282611) (xy 110.562369 -225.333541) (xy 110.539243 -225.381562) (xy 110.509219 -225.425599)
			(xy 110.472967 -225.46467) (xy 110.431296 -225.497901) (xy 110.385138 -225.52455) (xy 110.335524 -225.544022)
			(xy 110.283562 -225.555882) (xy 110.230412 -225.559866) (xy 110.177262 -225.555882) (xy 110.1253 -225.544022)
			(xy 110.075686 -225.52455) (xy 110.029528 -225.497901) (xy 109.987857 -225.46467) (xy 109.951605 -225.425599)
			(xy 109.921581 -225.381562) (xy 109.898455 -225.333541) (xy 109.882745 -225.282611) (xy 109.874802 -225.229907)
			(xy 109.874304 -225.203258) (xy 109.874691 -225.180013) (xy 109.880731 -225.133918) (xy 109.892714 -225.089)
			(xy 109.901228 -225.067368) (xy 109.91088 -225.044254) (xy 109.738414 -224.745804) (xy 109.713776 -224.742502)
			(xy 109.688433 -224.73868) (xy 109.639127 -224.72469) (xy 109.592335 -224.703779) (xy 109.549023 -224.676378)
			(xy 109.510084 -224.643052) (xy 109.476323 -224.604491) (xy 109.448437 -224.56149) (xy 109.427 -224.514936)
			(xy 109.412457 -224.46579) (xy 109.405106 -224.415068) (xy 109.404658 -224.389442) (xy 109.177074 -224.389442)
			(xy 109.176576 -224.416091) (xy 109.168633 -224.468795) (xy 109.152923 -224.519725) (xy 109.129797 -224.567746)
			(xy 109.099773 -224.611783) (xy 109.063521 -224.650854) (xy 109.02185 -224.684085) (xy 108.975692 -224.710734)
			(xy 108.926078 -224.730206) (xy 108.874116 -224.742066) (xy 108.820966 -224.74605) (xy 108.767816 -224.742066)
			(xy 108.715854 -224.730206) (xy 108.66624 -224.710734) (xy 108.620082 -224.684085) (xy 108.578411 -224.650854)
			(xy 108.542159 -224.611783) (xy 108.512135 -224.567746) (xy 108.489009 -224.519725) (xy 108.473299 -224.468795)
			(xy 108.465356 -224.416091) (xy 108.464858 -224.389442) (xy 108.237274 -224.389442) (xy 108.236888 -224.412687)
			(xy 108.230849 -224.458782) (xy 108.218865 -224.5037) (xy 108.21035 -224.525332) (xy 108.200698 -224.548446)
			(xy 108.373164 -224.846896) (xy 108.397802 -224.850198) (xy 108.423142 -224.854037) (xy 108.472448 -224.868024)
			(xy 108.51924 -224.888933) (xy 108.562553 -224.916332) (xy 108.601492 -224.949655) (xy 108.635253 -224.988214)
			(xy 108.66314 -225.031214) (xy 108.684577 -225.077767) (xy 108.699121 -225.126911) (xy 108.706472 -225.177632)
			(xy 108.70692 -225.203258) (xy 108.706422 -225.229907) (xy 108.935002 -225.229907) (xy 108.935002 -225.176609)
			(xy 108.942945 -225.123905) (xy 108.958655 -225.072975) (xy 108.981781 -225.024954) (xy 109.011805 -224.980917)
			(xy 109.048057 -224.941846) (xy 109.089728 -224.908615) (xy 109.135886 -224.881966) (xy 109.1855 -224.862494)
			(xy 109.237462 -224.850634) (xy 109.290612 -224.846651) (xy 109.343762 -224.850634) (xy 109.395724 -224.862494)
			(xy 109.445338 -224.881966) (xy 109.491496 -224.908615) (xy 109.533167 -224.941846) (xy 109.569419 -224.980917)
			(xy 109.599443 -225.024954) (xy 109.622569 -225.072975) (xy 109.638279 -225.123905) (xy 109.646222 -225.176609)
			(xy 109.64672 -225.203258) (xy 109.646222 -225.229907) (xy 109.638279 -225.282611) (xy 109.622569 -225.333541)
			(xy 109.599443 -225.381562) (xy 109.569419 -225.425599) (xy 109.533167 -225.46467) (xy 109.491496 -225.497901)
			(xy 109.445338 -225.52455) (xy 109.395724 -225.544022) (xy 109.343762 -225.555882) (xy 109.290612 -225.559866)
			(xy 109.237462 -225.555882) (xy 109.1855 -225.544022) (xy 109.135886 -225.52455) (xy 109.089728 -225.497901)
			(xy 109.048057 -225.46467) (xy 109.011805 -225.425599) (xy 108.981781 -225.381562) (xy 108.958655 -225.333541)
			(xy 108.942945 -225.282611) (xy 108.935002 -225.229907) (xy 108.706422 -225.229907) (xy 108.698479 -225.282611)
			(xy 108.682769 -225.333541) (xy 108.659643 -225.381562) (xy 108.629619 -225.425599) (xy 108.593367 -225.46467)
			(xy 108.551696 -225.497901) (xy 108.505538 -225.52455) (xy 108.455924 -225.544022) (xy 108.403962 -225.555882)
			(xy 108.350812 -225.559866) (xy 108.297662 -225.555882) (xy 108.2457 -225.544022) (xy 108.196086 -225.52455)
			(xy 108.149928 -225.497901) (xy 108.108257 -225.46467) (xy 108.072005 -225.425599) (xy 108.041981 -225.381562)
			(xy 108.018855 -225.333541) (xy 108.003145 -225.282611) (xy 107.995202 -225.229907) (xy 107.994704 -225.203258)
			(xy 107.995091 -225.180013) (xy 108.001131 -225.133918) (xy 108.013114 -225.089) (xy 108.021628 -225.067368)
			(xy 108.03128 -225.044254) (xy 107.858814 -224.745804) (xy 107.834176 -224.742502) (xy 107.808833 -224.73868)
			(xy 107.759527 -224.72469) (xy 107.712735 -224.703779) (xy 107.669423 -224.676378) (xy 107.630484 -224.643052)
			(xy 107.596723 -224.604491) (xy 107.568837 -224.56149) (xy 107.5474 -224.514936) (xy 107.532857 -224.46579)
			(xy 107.525506 -224.415068) (xy 107.525058 -224.389442) (xy 107.297474 -224.389442) (xy 107.296976 -224.416091)
			(xy 107.289033 -224.468795) (xy 107.273323 -224.519725) (xy 107.250197 -224.567746) (xy 107.220173 -224.611783)
			(xy 107.183921 -224.650854) (xy 107.14225 -224.684085) (xy 107.096092 -224.710734) (xy 107.046478 -224.730206)
			(xy 106.994516 -224.742066) (xy 106.941366 -224.74605) (xy 106.888216 -224.742066) (xy 106.836254 -224.730206)
			(xy 106.78664 -224.710734) (xy 106.740482 -224.684085) (xy 106.698811 -224.650854) (xy 106.662559 -224.611783)
			(xy 106.632535 -224.567746) (xy 106.609409 -224.519725) (xy 106.593699 -224.468795) (xy 106.585756 -224.416091)
			(xy 106.585258 -224.389442) (xy 106.357674 -224.389442) (xy 106.357288 -224.412687) (xy 106.351249 -224.458782)
			(xy 106.339265 -224.5037) (xy 106.33075 -224.525332) (xy 106.321098 -224.548446) (xy 106.493564 -224.846896)
			(xy 106.518202 -224.850198) (xy 106.543542 -224.854037) (xy 106.592848 -224.868024) (xy 106.63964 -224.888933)
			(xy 106.682953 -224.916332) (xy 106.721892 -224.949655) (xy 106.755653 -224.988214) (xy 106.78354 -225.031214)
			(xy 106.804977 -225.077767) (xy 106.819521 -225.126911) (xy 106.826872 -225.177632) (xy 106.82732 -225.203258)
			(xy 106.826822 -225.229907) (xy 107.055402 -225.229907) (xy 107.055402 -225.176609) (xy 107.063345 -225.123905)
			(xy 107.079055 -225.072975) (xy 107.102181 -225.024954) (xy 107.132205 -224.980917) (xy 107.168457 -224.941846)
			(xy 107.210128 -224.908615) (xy 107.256286 -224.881966) (xy 107.3059 -224.862494) (xy 107.357862 -224.850634)
			(xy 107.411012 -224.846651) (xy 107.464162 -224.850634) (xy 107.516124 -224.862494) (xy 107.565738 -224.881966)
			(xy 107.611896 -224.908615) (xy 107.653567 -224.941846) (xy 107.689819 -224.980917) (xy 107.719843 -225.024954)
			(xy 107.742969 -225.072975) (xy 107.758679 -225.123905) (xy 107.766622 -225.176609) (xy 107.76712 -225.203258)
			(xy 107.766622 -225.229907) (xy 107.758679 -225.282611) (xy 107.742969 -225.333541) (xy 107.719843 -225.381562)
			(xy 107.689819 -225.425599) (xy 107.653567 -225.46467) (xy 107.611896 -225.497901) (xy 107.565738 -225.52455)
			(xy 107.516124 -225.544022) (xy 107.464162 -225.555882) (xy 107.411012 -225.559866) (xy 107.357862 -225.555882)
			(xy 107.3059 -225.544022) (xy 107.256286 -225.52455) (xy 107.210128 -225.497901) (xy 107.168457 -225.46467)
			(xy 107.132205 -225.425599) (xy 107.102181 -225.381562) (xy 107.079055 -225.333541) (xy 107.063345 -225.282611)
			(xy 107.055402 -225.229907) (xy 106.826822 -225.229907) (xy 106.818879 -225.282611) (xy 106.803169 -225.333541)
			(xy 106.780043 -225.381562) (xy 106.750019 -225.425599) (xy 106.713767 -225.46467) (xy 106.672096 -225.497901)
			(xy 106.625938 -225.52455) (xy 106.576324 -225.544022) (xy 106.524362 -225.555882) (xy 106.471212 -225.559866)
			(xy 106.418062 -225.555882) (xy 106.3661 -225.544022) (xy 106.316486 -225.52455) (xy 106.270328 -225.497901)
			(xy 106.228657 -225.46467) (xy 106.192405 -225.425599) (xy 106.162381 -225.381562) (xy 106.139255 -225.333541)
			(xy 106.123545 -225.282611) (xy 106.115602 -225.229907) (xy 106.115104 -225.203258) (xy 106.115491 -225.180013)
			(xy 106.121531 -225.133918) (xy 106.133514 -225.089) (xy 106.142028 -225.067368) (xy 106.15168 -225.044254)
			(xy 105.979214 -224.745804) (xy 105.954576 -224.742502) (xy 105.929233 -224.73868) (xy 105.879927 -224.72469)
			(xy 105.833135 -224.703779) (xy 105.789823 -224.676378) (xy 105.750884 -224.643052) (xy 105.717123 -224.604491)
			(xy 105.689237 -224.56149) (xy 105.6678 -224.514936) (xy 105.653257 -224.46579) (xy 105.645906 -224.415068)
			(xy 105.645458 -224.389442) (xy 105.417874 -224.389442) (xy 105.417376 -224.416091) (xy 105.409433 -224.468795)
			(xy 105.393723 -224.519725) (xy 105.370597 -224.567746) (xy 105.340573 -224.611783) (xy 105.304321 -224.650854)
			(xy 105.26265 -224.684085) (xy 105.216492 -224.710734) (xy 105.166878 -224.730206) (xy 105.114916 -224.742066)
			(xy 105.061766 -224.74605) (xy 105.008616 -224.742066) (xy 104.956654 -224.730206) (xy 104.90704 -224.710734)
			(xy 104.860882 -224.684085) (xy 104.819211 -224.650854) (xy 104.782959 -224.611783) (xy 104.752935 -224.567746)
			(xy 104.729809 -224.519725) (xy 104.714099 -224.468795) (xy 104.706156 -224.416091) (xy 104.705658 -224.389442)
			(xy 104.478074 -224.389442) (xy 104.477688 -224.412687) (xy 104.471649 -224.458782) (xy 104.459665 -224.5037)
			(xy 104.45115 -224.525332) (xy 104.441498 -224.548446) (xy 104.613964 -224.846896) (xy 104.638602 -224.850198)
			(xy 104.663942 -224.854037) (xy 104.713248 -224.868024) (xy 104.76004 -224.888933) (xy 104.803353 -224.916332)
			(xy 104.842292 -224.949655) (xy 104.876053 -224.988214) (xy 104.90394 -225.031214) (xy 104.925377 -225.077767)
			(xy 104.939921 -225.126911) (xy 104.947272 -225.177632) (xy 104.94772 -225.203258) (xy 104.947222 -225.229907)
			(xy 105.175802 -225.229907) (xy 105.175802 -225.176609) (xy 105.183745 -225.123905) (xy 105.199455 -225.072975)
			(xy 105.222581 -225.024954) (xy 105.252605 -224.980917) (xy 105.288857 -224.941846) (xy 105.330528 -224.908615)
			(xy 105.376686 -224.881966) (xy 105.4263 -224.862494) (xy 105.478262 -224.850634) (xy 105.531412 -224.846651)
			(xy 105.584562 -224.850634) (xy 105.636524 -224.862494) (xy 105.686138 -224.881966) (xy 105.732296 -224.908615)
			(xy 105.773967 -224.941846) (xy 105.810219 -224.980917) (xy 105.840243 -225.024954) (xy 105.863369 -225.072975)
			(xy 105.879079 -225.123905) (xy 105.887022 -225.176609) (xy 105.88752 -225.203258) (xy 105.887022 -225.229907)
			(xy 105.879079 -225.282611) (xy 105.863369 -225.333541) (xy 105.840243 -225.381562) (xy 105.810219 -225.425599)
			(xy 105.773967 -225.46467) (xy 105.732296 -225.497901) (xy 105.686138 -225.52455) (xy 105.636524 -225.544022)
			(xy 105.584562 -225.555882) (xy 105.531412 -225.559866) (xy 105.478262 -225.555882) (xy 105.4263 -225.544022)
			(xy 105.376686 -225.52455) (xy 105.330528 -225.497901) (xy 105.288857 -225.46467) (xy 105.252605 -225.425599)
			(xy 105.222581 -225.381562) (xy 105.199455 -225.333541) (xy 105.183745 -225.282611) (xy 105.175802 -225.229907)
			(xy 104.947222 -225.229907) (xy 104.939279 -225.282611) (xy 104.923569 -225.333541) (xy 104.900443 -225.381562)
			(xy 104.870419 -225.425599) (xy 104.834167 -225.46467) (xy 104.792496 -225.497901) (xy 104.746338 -225.52455)
			(xy 104.696724 -225.544022) (xy 104.644762 -225.555882) (xy 104.591612 -225.559866) (xy 104.538462 -225.555882)
			(xy 104.4865 -225.544022) (xy 104.436886 -225.52455) (xy 104.390728 -225.497901) (xy 104.349057 -225.46467)
			(xy 104.312805 -225.425599) (xy 104.282781 -225.381562) (xy 104.259655 -225.333541) (xy 104.243945 -225.282611)
			(xy 104.236002 -225.229907) (xy 104.235504 -225.203258) (xy 104.235891 -225.180013) (xy 104.241931 -225.133918)
			(xy 104.253914 -225.089) (xy 104.262428 -225.067368) (xy 104.27208 -225.044254) (xy 104.099614 -224.745804)
			(xy 104.074976 -224.742502) (xy 104.049633 -224.73868) (xy 104.000327 -224.72469) (xy 103.953535 -224.703779)
			(xy 103.910223 -224.676378) (xy 103.871284 -224.643052) (xy 103.837523 -224.604491) (xy 103.809637 -224.56149)
			(xy 103.7882 -224.514936) (xy 103.773657 -224.46579) (xy 103.766306 -224.415068) (xy 103.765858 -224.389442)
			(xy 103.538274 -224.389442) (xy 103.537776 -224.416091) (xy 103.529833 -224.468795) (xy 103.514123 -224.519725)
			(xy 103.490997 -224.567746) (xy 103.460973 -224.611783) (xy 103.424721 -224.650854) (xy 103.38305 -224.684085)
			(xy 103.336892 -224.710734) (xy 103.287278 -224.730206) (xy 103.235316 -224.742066) (xy 103.182166 -224.74605)
			(xy 103.129016 -224.742066) (xy 103.077054 -224.730206) (xy 103.02744 -224.710734) (xy 102.981282 -224.684085)
			(xy 102.939611 -224.650854) (xy 102.903359 -224.611783) (xy 102.873335 -224.567746) (xy 102.850209 -224.519725)
			(xy 102.834499 -224.468795) (xy 102.826556 -224.416091) (xy 102.826058 -224.389442) (xy 102.598474 -224.389442)
			(xy 102.598088 -224.412687) (xy 102.592049 -224.458782) (xy 102.580065 -224.5037) (xy 102.57155 -224.525332)
			(xy 102.561898 -224.548446) (xy 102.734364 -224.846896) (xy 102.759002 -224.850198) (xy 102.784342 -224.854037)
			(xy 102.833648 -224.868024) (xy 102.88044 -224.888933) (xy 102.923753 -224.916332) (xy 102.962692 -224.949655)
			(xy 102.996453 -224.988214) (xy 103.02434 -225.031214) (xy 103.045777 -225.077767) (xy 103.060321 -225.126911)
			(xy 103.067672 -225.177632) (xy 103.06812 -225.203258) (xy 103.067622 -225.229907) (xy 103.296202 -225.229907)
			(xy 103.296202 -225.176609) (xy 103.304145 -225.123905) (xy 103.319855 -225.072975) (xy 103.342981 -225.024954)
			(xy 103.373005 -224.980917) (xy 103.409257 -224.941846) (xy 103.450928 -224.908615) (xy 103.497086 -224.881966)
			(xy 103.5467 -224.862494) (xy 103.598662 -224.850634) (xy 103.651812 -224.846651) (xy 103.704962 -224.850634)
			(xy 103.756924 -224.862494) (xy 103.806538 -224.881966) (xy 103.852696 -224.908615) (xy 103.894367 -224.941846)
			(xy 103.930619 -224.980917) (xy 103.960643 -225.024954) (xy 103.983769 -225.072975) (xy 103.999479 -225.123905)
			(xy 104.007422 -225.176609) (xy 104.00792 -225.203258) (xy 104.007422 -225.229907) (xy 103.999479 -225.282611)
			(xy 103.983769 -225.333541) (xy 103.960643 -225.381562) (xy 103.930619 -225.425599) (xy 103.894367 -225.46467)
			(xy 103.852696 -225.497901) (xy 103.806538 -225.52455) (xy 103.756924 -225.544022) (xy 103.704962 -225.555882)
			(xy 103.651812 -225.559866) (xy 103.598662 -225.555882) (xy 103.5467 -225.544022) (xy 103.497086 -225.52455)
			(xy 103.450928 -225.497901) (xy 103.409257 -225.46467) (xy 103.373005 -225.425599) (xy 103.342981 -225.381562)
			(xy 103.319855 -225.333541) (xy 103.304145 -225.282611) (xy 103.296202 -225.229907) (xy 103.067622 -225.229907)
			(xy 103.059679 -225.282611) (xy 103.043969 -225.333541) (xy 103.020843 -225.381562) (xy 102.990819 -225.425599)
			(xy 102.954567 -225.46467) (xy 102.912896 -225.497901) (xy 102.866738 -225.52455) (xy 102.817124 -225.544022)
			(xy 102.765162 -225.555882) (xy 102.712012 -225.559866) (xy 102.658862 -225.555882) (xy 102.6069 -225.544022)
			(xy 102.557286 -225.52455) (xy 102.511128 -225.497901) (xy 102.469457 -225.46467) (xy 102.433205 -225.425599)
			(xy 102.403181 -225.381562) (xy 102.380055 -225.333541) (xy 102.364345 -225.282611) (xy 102.356402 -225.229907)
			(xy 102.355904 -225.203258) (xy 102.356291 -225.180013) (xy 102.362331 -225.133918) (xy 102.374314 -225.089)
			(xy 102.382828 -225.067368) (xy 102.39248 -225.044254) (xy 102.220014 -224.745804) (xy 102.195376 -224.742502)
			(xy 102.170033 -224.73868) (xy 102.120727 -224.72469) (xy 102.073935 -224.703779) (xy 102.030623 -224.676378)
			(xy 101.991684 -224.643052) (xy 101.957923 -224.604491) (xy 101.930037 -224.56149) (xy 101.9086 -224.514936)
			(xy 101.894057 -224.46579) (xy 101.886706 -224.415068) (xy 101.886258 -224.389442) (xy 101.658674 -224.389442)
			(xy 101.658176 -224.416091) (xy 101.650233 -224.468795) (xy 101.634523 -224.519725) (xy 101.611397 -224.567746)
			(xy 101.581373 -224.611783) (xy 101.545121 -224.650854) (xy 101.50345 -224.684085) (xy 101.457292 -224.710734)
			(xy 101.407678 -224.730206) (xy 101.355716 -224.742066) (xy 101.302566 -224.74605) (xy 101.249416 -224.742066)
			(xy 101.197454 -224.730206) (xy 101.14784 -224.710734) (xy 101.101682 -224.684085) (xy 101.060011 -224.650854)
			(xy 101.023759 -224.611783) (xy 100.993735 -224.567746) (xy 100.970609 -224.519725) (xy 100.954899 -224.468795)
			(xy 100.946956 -224.416091) (xy 100.946458 -224.389442) (xy 100.946907 -224.363817) (xy 100.95426 -224.313096)
			(xy 100.968805 -224.263953) (xy 100.990242 -224.217401) (xy 101.018129 -224.174401) (xy 101.05189 -224.135842)
			(xy 101.090828 -224.102518) (xy 101.13414 -224.075119) (xy 101.180931 -224.054208) (xy 101.230236 -224.040219)
			(xy 101.255576 -224.036382) (xy 101.280214 -224.03308) (xy 101.452426 -223.734376) (xy 101.443028 -223.711516)
			(xy 101.434508 -223.689885) (xy 101.422514 -223.644967) (xy 101.416464 -223.598872) (xy 101.416104 -223.575626)
			(xy 101.416678 -223.546176) (xy 101.426376 -223.488081) (xy 101.445511 -223.432377) (xy 101.45903 -223.406208)
			(xy 101.4657 -223.39273) (xy 101.471676 -223.363273) (xy 101.468826 -223.333351) (xy 101.457396 -223.305552)
			(xy 101.438374 -223.282279) (xy 101.413406 -223.265545) (xy 101.384651 -223.256797) (xy 101.369622 -223.256348)
			(xy 101.235256 -223.256348) (xy 101.220243 -223.25689) (xy 101.191519 -223.265635) (xy 101.16658 -223.282354)
			(xy 101.14758 -223.305604) (xy 101.136163 -223.333374) (xy 101.133315 -223.363265) (xy 101.139283 -223.392691)
			(xy 101.145848 -223.406208) (xy 101.159334 -223.432392) (xy 101.178467 -223.488091) (xy 101.188173 -223.546179)
			(xy 101.188774 -223.575626) (xy 101.188276 -223.602275) (xy 101.180333 -223.654979) (xy 101.164623 -223.705909)
			(xy 101.141497 -223.75393) (xy 101.111473 -223.797967) (xy 101.075221 -223.837038) (xy 101.03355 -223.870269)
			(xy 100.987392 -223.896918) (xy 100.937778 -223.91639) (xy 100.885816 -223.92825) (xy 100.832666 -223.932234)
			(xy 100.779516 -223.92825) (xy 100.727554 -223.91639) (xy 100.67794 -223.896918) (xy 100.631782 -223.870269)
			(xy 100.590111 -223.837038) (xy 100.553859 -223.797967) (xy 100.523835 -223.75393) (xy 100.500709 -223.705909)
			(xy 100.484999 -223.654979) (xy 100.477056 -223.602275) (xy 100.476558 -223.575626) (xy 100.477132 -223.546176)
			(xy 100.486828 -223.488081) (xy 100.505961 -223.432376) (xy 100.519484 -223.406208) (xy 100.526156 -223.392732)
			(xy 100.532135 -223.363278) (xy 100.529286 -223.333359) (xy 100.517855 -223.305562) (xy 100.498831 -223.282295)
			(xy 100.47386 -223.265568) (xy 100.445104 -223.256831) (xy 100.430076 -223.256348) (xy 100.295202 -223.256348)
			(xy 100.280184 -223.256884) (xy 100.251448 -223.265621) (xy 100.226496 -223.28234) (xy 100.207486 -223.305594)
			(xy 100.196064 -223.333372) (xy 100.193216 -223.363272) (xy 100.199189 -223.392707) (xy 100.205794 -223.406208)
			(xy 100.219312 -223.432378) (xy 100.238451 -223.488082) (xy 100.248158 -223.546176) (xy 100.24872 -223.575626)
			(xy 100.248273 -223.601252) (xy 100.240924 -223.651975) (xy 100.226381 -223.701121) (xy 100.204946 -223.747676)
			(xy 100.177059 -223.790678) (xy 100.143298 -223.829239) (xy 100.104358 -223.862564) (xy 100.061045 -223.889964)
			(xy 100.014252 -223.910874) (xy 99.964945 -223.924862) (xy 99.939602 -223.928686) (xy 99.91471 -223.931988)
			(xy 99.742498 -224.230438) (xy 99.75215 -224.253552) (xy 99.760666 -224.275184) (xy 99.772652 -224.320102)
			(xy 99.778693 -224.366197) (xy 99.779074 -224.389442) (xy 100.006658 -224.389442) (xy 100.007156 -224.362793)
			(xy 100.015099 -224.310089) (xy 100.030809 -224.259159) (xy 100.053935 -224.211138) (xy 100.083959 -224.167101)
			(xy 100.120211 -224.12803) (xy 100.161882 -224.094799) (xy 100.20804 -224.06815) (xy 100.257654 -224.048678)
			(xy 100.309616 -224.036818) (xy 100.362766 -224.032835) (xy 100.415916 -224.036818) (xy 100.467878 -224.048678)
			(xy 100.517492 -224.06815) (xy 100.56365 -224.094799) (xy 100.605321 -224.12803) (xy 100.641573 -224.167101)
			(xy 100.671597 -224.211138) (xy 100.694723 -224.259159) (xy 100.710433 -224.310089) (xy 100.718376 -224.362793)
			(xy 100.718874 -224.389442) (xy 100.718488 -224.412687) (xy 100.712449 -224.458782) (xy 100.700465 -224.5037)
			(xy 100.69195 -224.525332) (xy 100.682298 -224.548446) (xy 100.854764 -224.846896) (xy 100.879402 -224.850198)
			(xy 100.904742 -224.854037) (xy 100.954048 -224.868024) (xy 101.00084 -224.888933) (xy 101.044153 -224.916332)
			(xy 101.083092 -224.949655) (xy 101.116853 -224.988214) (xy 101.14474 -225.031214) (xy 101.166177 -225.077767)
			(xy 101.180721 -225.126911) (xy 101.188072 -225.177632) (xy 101.18852 -225.203258) (xy 101.188022 -225.229907)
			(xy 101.416602 -225.229907) (xy 101.416602 -225.176609) (xy 101.424545 -225.123905) (xy 101.440255 -225.072975)
			(xy 101.463381 -225.024954) (xy 101.493405 -224.980917) (xy 101.529657 -224.941846) (xy 101.571328 -224.908615)
			(xy 101.617486 -224.881966) (xy 101.6671 -224.862494) (xy 101.719062 -224.850634) (xy 101.772212 -224.846651)
			(xy 101.825362 -224.850634) (xy 101.877324 -224.862494) (xy 101.926938 -224.881966) (xy 101.973096 -224.908615)
			(xy 102.014767 -224.941846) (xy 102.051019 -224.980917) (xy 102.081043 -225.024954) (xy 102.104169 -225.072975)
			(xy 102.119879 -225.123905) (xy 102.127822 -225.176609) (xy 102.12832 -225.203258) (xy 102.127822 -225.229907)
			(xy 102.119879 -225.282611) (xy 102.104169 -225.333541) (xy 102.081043 -225.381562) (xy 102.051019 -225.425599)
			(xy 102.014767 -225.46467) (xy 101.973096 -225.497901) (xy 101.926938 -225.52455) (xy 101.877324 -225.544022)
			(xy 101.825362 -225.555882) (xy 101.772212 -225.559866) (xy 101.719062 -225.555882) (xy 101.6671 -225.544022)
			(xy 101.617486 -225.52455) (xy 101.571328 -225.497901) (xy 101.529657 -225.46467) (xy 101.493405 -225.425599)
			(xy 101.463381 -225.381562) (xy 101.440255 -225.333541) (xy 101.424545 -225.282611) (xy 101.416602 -225.229907)
			(xy 101.188022 -225.229907) (xy 101.180079 -225.282611) (xy 101.164369 -225.333541) (xy 101.141243 -225.381562)
			(xy 101.111219 -225.425599) (xy 101.074967 -225.46467) (xy 101.033296 -225.497901) (xy 100.987138 -225.52455)
			(xy 100.937524 -225.544022) (xy 100.885562 -225.555882) (xy 100.832412 -225.559866) (xy 100.779262 -225.555882)
			(xy 100.7273 -225.544022) (xy 100.677686 -225.52455) (xy 100.631528 -225.497901) (xy 100.589857 -225.46467)
			(xy 100.553605 -225.425599) (xy 100.523581 -225.381562) (xy 100.500455 -225.333541) (xy 100.484745 -225.282611)
			(xy 100.476802 -225.229907) (xy 100.476304 -225.203258) (xy 100.476691 -225.180013) (xy 100.482731 -225.133918)
			(xy 100.494714 -225.089) (xy 100.503228 -225.067368) (xy 100.51288 -225.044254) (xy 100.340414 -224.745804)
			(xy 100.315776 -224.742502) (xy 100.290433 -224.73868) (xy 100.241127 -224.72469) (xy 100.194335 -224.703779)
			(xy 100.151023 -224.676378) (xy 100.112084 -224.643052) (xy 100.078323 -224.604491) (xy 100.050437 -224.56149)
			(xy 100.029 -224.514936) (xy 100.014457 -224.46579) (xy 100.007106 -224.415068) (xy 100.006658 -224.389442)
			(xy 99.779074 -224.389442) (xy 99.778576 -224.416091) (xy 99.770633 -224.468795) (xy 99.754923 -224.519725)
			(xy 99.731797 -224.567746) (xy 99.701773 -224.611783) (xy 99.665521 -224.650854) (xy 99.62385 -224.684085)
			(xy 99.577692 -224.710734) (xy 99.528078 -224.730206) (xy 99.476116 -224.742066) (xy 99.422966 -224.74605)
			(xy 99.369816 -224.742066) (xy 99.317854 -224.730206) (xy 99.26824 -224.710734) (xy 99.222082 -224.684085)
			(xy 99.180411 -224.650854) (xy 99.144159 -224.611783) (xy 99.114135 -224.567746) (xy 99.091009 -224.519725)
			(xy 99.075299 -224.468795) (xy 99.067356 -224.416091) (xy 99.066858 -224.389442) (xy 99.067307 -224.363817)
			(xy 99.07466 -224.313096) (xy 99.089205 -224.263953) (xy 99.110642 -224.217401) (xy 99.138529 -224.174401)
			(xy 99.17229 -224.135842) (xy 99.211228 -224.102518) (xy 99.25454 -224.075119) (xy 99.301331 -224.054208)
			(xy 99.350636 -224.040219) (xy 99.375976 -224.036382) (xy 99.400614 -224.03308) (xy 99.572826 -223.734376)
			(xy 99.563428 -223.711516) (xy 99.554908 -223.689885) (xy 99.542914 -223.644967) (xy 99.536864 -223.598872)
			(xy 99.536504 -223.575626) (xy 99.537078 -223.546176) (xy 99.546776 -223.488081) (xy 99.565911 -223.432377)
			(xy 99.57943 -223.406208) (xy 99.5861 -223.39273) (xy 99.592076 -223.363273) (xy 99.589226 -223.333351)
			(xy 99.577796 -223.305552) (xy 99.558774 -223.282279) (xy 99.533806 -223.265545) (xy 99.505051 -223.256797)
			(xy 99.490022 -223.256348) (xy 99.355656 -223.256348) (xy 99.340643 -223.25689) (xy 99.311919 -223.265635)
			(xy 99.28698 -223.282354) (xy 99.26798 -223.305604) (xy 99.256563 -223.333374) (xy 99.253715 -223.363265)
			(xy 99.259683 -223.392691) (xy 99.266248 -223.406208) (xy 99.279734 -223.432392) (xy 99.298867 -223.488091)
			(xy 99.308573 -223.546179) (xy 99.309174 -223.575626) (xy 99.308676 -223.602275) (xy 99.300733 -223.654979)
			(xy 99.285023 -223.705909) (xy 99.261897 -223.75393) (xy 99.231873 -223.797967) (xy 99.195621 -223.837038)
			(xy 99.15395 -223.870269) (xy 99.107792 -223.896918) (xy 99.058178 -223.91639) (xy 99.006216 -223.92825)
			(xy 98.953066 -223.932234) (xy 98.899916 -223.92825) (xy 98.847954 -223.91639) (xy 98.79834 -223.896918)
			(xy 98.752182 -223.870269) (xy 98.710511 -223.837038) (xy 98.674259 -223.797967) (xy 98.644235 -223.75393)
			(xy 98.621109 -223.705909) (xy 98.605399 -223.654979) (xy 98.597456 -223.602275) (xy 98.596958 -223.575626)
			(xy 98.597532 -223.546176) (xy 98.607228 -223.488081) (xy 98.626361 -223.432376) (xy 98.639884 -223.406208)
			(xy 98.646556 -223.392732) (xy 98.652535 -223.363278) (xy 98.649686 -223.333359) (xy 98.638255 -223.305562)
			(xy 98.619231 -223.282295) (xy 98.59426 -223.265568) (xy 98.565504 -223.256831) (xy 98.550476 -223.256348)
			(xy 98.415602 -223.256348) (xy 98.400584 -223.256884) (xy 98.371848 -223.265621) (xy 98.346896 -223.28234)
			(xy 98.327886 -223.305594) (xy 98.316464 -223.333372) (xy 98.313616 -223.363272) (xy 98.319589 -223.392707)
			(xy 98.326194 -223.406208) (xy 98.339712 -223.432378) (xy 98.358851 -223.488082) (xy 98.368558 -223.546176)
			(xy 98.36912 -223.575626) (xy 98.368673 -223.601252) (xy 98.361324 -223.651975) (xy 98.346781 -223.701121)
			(xy 98.325346 -223.747676) (xy 98.297459 -223.790678) (xy 98.263698 -223.829239) (xy 98.224758 -223.862564)
			(xy 98.181445 -223.889964) (xy 98.134652 -223.910874) (xy 98.085345 -223.924862) (xy 98.060002 -223.928686)
			(xy 98.03511 -223.931988) (xy 97.862898 -224.230438) (xy 97.87255 -224.253552) (xy 97.881066 -224.275184)
			(xy 97.893052 -224.320102) (xy 97.899093 -224.366197) (xy 97.899474 -224.389442) (xy 98.127058 -224.389442)
			(xy 98.127556 -224.362793) (xy 98.135499 -224.310089) (xy 98.151209 -224.259159) (xy 98.174335 -224.211138)
			(xy 98.204359 -224.167101) (xy 98.240611 -224.12803) (xy 98.282282 -224.094799) (xy 98.32844 -224.06815)
			(xy 98.378054 -224.048678) (xy 98.430016 -224.036818) (xy 98.483166 -224.032835) (xy 98.536316 -224.036818)
			(xy 98.588278 -224.048678) (xy 98.637892 -224.06815) (xy 98.68405 -224.094799) (xy 98.725721 -224.12803)
			(xy 98.761973 -224.167101) (xy 98.791997 -224.211138) (xy 98.815123 -224.259159) (xy 98.830833 -224.310089)
			(xy 98.838776 -224.362793) (xy 98.839274 -224.389442) (xy 98.838888 -224.412687) (xy 98.832849 -224.458782)
			(xy 98.820865 -224.5037) (xy 98.81235 -224.525332) (xy 98.802698 -224.548446) (xy 98.975164 -224.846896)
			(xy 98.999802 -224.850198) (xy 99.025142 -224.854037) (xy 99.074448 -224.868024) (xy 99.12124 -224.888933)
			(xy 99.164553 -224.916332) (xy 99.203492 -224.949655) (xy 99.237253 -224.988214) (xy 99.26514 -225.031214)
			(xy 99.286577 -225.077767) (xy 99.301121 -225.126911) (xy 99.308472 -225.177632) (xy 99.30892 -225.203258)
			(xy 99.308422 -225.229907) (xy 99.537002 -225.229907) (xy 99.537002 -225.176609) (xy 99.544945 -225.123905)
			(xy 99.560655 -225.072975) (xy 99.583781 -225.024954) (xy 99.613805 -224.980917) (xy 99.650057 -224.941846)
			(xy 99.691728 -224.908615) (xy 99.737886 -224.881966) (xy 99.7875 -224.862494) (xy 99.839462 -224.850634)
			(xy 99.892612 -224.846651) (xy 99.945762 -224.850634) (xy 99.997724 -224.862494) (xy 100.047338 -224.881966)
			(xy 100.093496 -224.908615) (xy 100.135167 -224.941846) (xy 100.171419 -224.980917) (xy 100.201443 -225.024954)
			(xy 100.224569 -225.072975) (xy 100.240279 -225.123905) (xy 100.248222 -225.176609) (xy 100.24872 -225.203258)
			(xy 100.248222 -225.229907) (xy 100.240279 -225.282611) (xy 100.224569 -225.333541) (xy 100.201443 -225.381562)
			(xy 100.171419 -225.425599) (xy 100.135167 -225.46467) (xy 100.093496 -225.497901) (xy 100.047338 -225.52455)
			(xy 99.997724 -225.544022) (xy 99.945762 -225.555882) (xy 99.892612 -225.559866) (xy 99.839462 -225.555882)
			(xy 99.7875 -225.544022) (xy 99.737886 -225.52455) (xy 99.691728 -225.497901) (xy 99.650057 -225.46467)
			(xy 99.613805 -225.425599) (xy 99.583781 -225.381562) (xy 99.560655 -225.333541) (xy 99.544945 -225.282611)
			(xy 99.537002 -225.229907) (xy 99.308422 -225.229907) (xy 99.300479 -225.282611) (xy 99.284769 -225.333541)
			(xy 99.261643 -225.381562) (xy 99.231619 -225.425599) (xy 99.195367 -225.46467) (xy 99.153696 -225.497901)
			(xy 99.107538 -225.52455) (xy 99.057924 -225.544022) (xy 99.005962 -225.555882) (xy 98.952812 -225.559866)
			(xy 98.899662 -225.555882) (xy 98.8477 -225.544022) (xy 98.798086 -225.52455) (xy 98.751928 -225.497901)
			(xy 98.710257 -225.46467) (xy 98.674005 -225.425599) (xy 98.643981 -225.381562) (xy 98.620855 -225.333541)
			(xy 98.605145 -225.282611) (xy 98.597202 -225.229907) (xy 98.596704 -225.203258) (xy 98.597091 -225.180013)
			(xy 98.603131 -225.133918) (xy 98.615114 -225.089) (xy 98.623628 -225.067368) (xy 98.63328 -225.044254)
			(xy 98.460814 -224.745804) (xy 98.436176 -224.742502) (xy 98.410833 -224.73868) (xy 98.361527 -224.72469)
			(xy 98.314735 -224.703779) (xy 98.271423 -224.676378) (xy 98.232484 -224.643052) (xy 98.198723 -224.604491)
			(xy 98.170837 -224.56149) (xy 98.1494 -224.514936) (xy 98.134857 -224.46579) (xy 98.127506 -224.415068)
			(xy 98.127058 -224.389442) (xy 97.899474 -224.389442) (xy 97.898976 -224.416091) (xy 97.891033 -224.468795)
			(xy 97.875323 -224.519725) (xy 97.852197 -224.567746) (xy 97.822173 -224.611783) (xy 97.785921 -224.650854)
			(xy 97.74425 -224.684085) (xy 97.698092 -224.710734) (xy 97.648478 -224.730206) (xy 97.596516 -224.742066)
			(xy 97.543366 -224.74605) (xy 97.490216 -224.742066) (xy 97.438254 -224.730206) (xy 97.38864 -224.710734)
			(xy 97.342482 -224.684085) (xy 97.300811 -224.650854) (xy 97.264559 -224.611783) (xy 97.234535 -224.567746)
			(xy 97.211409 -224.519725) (xy 97.195699 -224.468795) (xy 97.187756 -224.416091) (xy 97.187258 -224.389442)
			(xy 97.187707 -224.363817) (xy 97.19506 -224.313096) (xy 97.209605 -224.263953) (xy 97.231042 -224.217401)
			(xy 97.258929 -224.174401) (xy 97.29269 -224.135842) (xy 97.331628 -224.102518) (xy 97.37494 -224.075119)
			(xy 97.421731 -224.054208) (xy 97.471036 -224.040219) (xy 97.496376 -224.036382) (xy 97.521014 -224.03308)
			(xy 97.693226 -223.734376) (xy 97.683828 -223.711516) (xy 97.675308 -223.689885) (xy 97.663314 -223.644967)
			(xy 97.657264 -223.598872) (xy 97.656904 -223.575626) (xy 97.657478 -223.546176) (xy 97.667176 -223.488081)
			(xy 97.686311 -223.432377) (xy 97.69983 -223.406208) (xy 97.7065 -223.39273) (xy 97.712476 -223.363273)
			(xy 97.709626 -223.333351) (xy 97.698196 -223.305552) (xy 97.679174 -223.282279) (xy 97.654206 -223.265545)
			(xy 97.625451 -223.256797) (xy 97.610422 -223.256348) (xy 97.476056 -223.256348) (xy 97.461043 -223.25689)
			(xy 97.432319 -223.265635) (xy 97.40738 -223.282354) (xy 97.38838 -223.305604) (xy 97.376963 -223.333374)
			(xy 97.374115 -223.363265) (xy 97.380083 -223.392691) (xy 97.386648 -223.406208) (xy 97.400134 -223.432392)
			(xy 97.419267 -223.488091) (xy 97.428973 -223.546179) (xy 97.429574 -223.575626) (xy 97.429076 -223.602275)
			(xy 97.421133 -223.654979) (xy 97.405423 -223.705909) (xy 97.382297 -223.75393) (xy 97.352273 -223.797967)
			(xy 97.316021 -223.837038) (xy 97.27435 -223.870269) (xy 97.228192 -223.896918) (xy 97.178578 -223.91639)
			(xy 97.126616 -223.92825) (xy 97.073466 -223.932234) (xy 97.020316 -223.92825) (xy 96.968354 -223.91639)
			(xy 96.91874 -223.896918) (xy 96.872582 -223.870269) (xy 96.830911 -223.837038) (xy 96.794659 -223.797967)
			(xy 96.764635 -223.75393) (xy 96.741509 -223.705909) (xy 96.725799 -223.654979) (xy 96.717856 -223.602275)
			(xy 96.717358 -223.575626) (xy 96.717932 -223.546176) (xy 96.727628 -223.488081) (xy 96.746761 -223.432376)
			(xy 96.760284 -223.406208) (xy 96.766956 -223.392732) (xy 96.772935 -223.363278) (xy 96.770086 -223.333359)
			(xy 96.758655 -223.305562) (xy 96.739631 -223.282295) (xy 96.71466 -223.265568) (xy 96.685904 -223.256831)
			(xy 96.670876 -223.256348) (xy 96.536002 -223.256348) (xy 96.520984 -223.256884) (xy 96.492248 -223.265621)
			(xy 96.467296 -223.28234) (xy 96.448286 -223.305594) (xy 96.436864 -223.333372) (xy 96.434016 -223.363272)
			(xy 96.439989 -223.392707) (xy 96.446594 -223.406208) (xy 96.460112 -223.432378) (xy 96.479251 -223.488082)
			(xy 96.488958 -223.546176) (xy 96.48952 -223.575626) (xy 96.489073 -223.601252) (xy 96.481724 -223.651975)
			(xy 96.467181 -223.701121) (xy 96.445746 -223.747676) (xy 96.417859 -223.790678) (xy 96.384098 -223.829239)
			(xy 96.345158 -223.862564) (xy 96.301845 -223.889964) (xy 96.255052 -223.910874) (xy 96.205745 -223.924862)
			(xy 96.180402 -223.928686) (xy 96.15551 -223.931988) (xy 95.983298 -224.230438) (xy 95.99295 -224.253552)
			(xy 96.001466 -224.275184) (xy 96.013452 -224.320102) (xy 96.019493 -224.366197) (xy 96.019874 -224.389442)
			(xy 96.247458 -224.389442) (xy 96.247956 -224.362793) (xy 96.255899 -224.310089) (xy 96.271609 -224.259159)
			(xy 96.294735 -224.211138) (xy 96.324759 -224.167101) (xy 96.361011 -224.12803) (xy 96.402682 -224.094799)
			(xy 96.44884 -224.06815) (xy 96.498454 -224.048678) (xy 96.550416 -224.036818) (xy 96.603566 -224.032835)
			(xy 96.656716 -224.036818) (xy 96.708678 -224.048678) (xy 96.758292 -224.06815) (xy 96.80445 -224.094799)
			(xy 96.846121 -224.12803) (xy 96.882373 -224.167101) (xy 96.912397 -224.211138) (xy 96.935523 -224.259159)
			(xy 96.951233 -224.310089) (xy 96.959176 -224.362793) (xy 96.959674 -224.389442) (xy 96.959288 -224.412687)
			(xy 96.953249 -224.458782) (xy 96.941265 -224.5037) (xy 96.93275 -224.525332) (xy 96.923098 -224.548446)
			(xy 97.095564 -224.846896) (xy 97.120202 -224.850198) (xy 97.145542 -224.854037) (xy 97.194848 -224.868024)
			(xy 97.24164 -224.888933) (xy 97.284953 -224.916332) (xy 97.323892 -224.949655) (xy 97.357653 -224.988214)
			(xy 97.38554 -225.031214) (xy 97.406977 -225.077767) (xy 97.421521 -225.126911) (xy 97.428872 -225.177632)
			(xy 97.42932 -225.203258) (xy 97.428822 -225.229907) (xy 97.657402 -225.229907) (xy 97.657402 -225.176609)
			(xy 97.665345 -225.123905) (xy 97.681055 -225.072975) (xy 97.704181 -225.024954) (xy 97.734205 -224.980917)
			(xy 97.770457 -224.941846) (xy 97.812128 -224.908615) (xy 97.858286 -224.881966) (xy 97.9079 -224.862494)
			(xy 97.959862 -224.850634) (xy 98.013012 -224.846651) (xy 98.066162 -224.850634) (xy 98.118124 -224.862494)
			(xy 98.167738 -224.881966) (xy 98.213896 -224.908615) (xy 98.255567 -224.941846) (xy 98.291819 -224.980917)
			(xy 98.321843 -225.024954) (xy 98.344969 -225.072975) (xy 98.360679 -225.123905) (xy 98.368622 -225.176609)
			(xy 98.36912 -225.203258) (xy 98.368622 -225.229907) (xy 98.360679 -225.282611) (xy 98.344969 -225.333541)
			(xy 98.321843 -225.381562) (xy 98.291819 -225.425599) (xy 98.255567 -225.46467) (xy 98.213896 -225.497901)
			(xy 98.167738 -225.52455) (xy 98.118124 -225.544022) (xy 98.066162 -225.555882) (xy 98.013012 -225.559866)
			(xy 97.959862 -225.555882) (xy 97.9079 -225.544022) (xy 97.858286 -225.52455) (xy 97.812128 -225.497901)
			(xy 97.770457 -225.46467) (xy 97.734205 -225.425599) (xy 97.704181 -225.381562) (xy 97.681055 -225.333541)
			(xy 97.665345 -225.282611) (xy 97.657402 -225.229907) (xy 97.428822 -225.229907) (xy 97.420879 -225.282611)
			(xy 97.405169 -225.333541) (xy 97.382043 -225.381562) (xy 97.352019 -225.425599) (xy 97.315767 -225.46467)
			(xy 97.274096 -225.497901) (xy 97.227938 -225.52455) (xy 97.178324 -225.544022) (xy 97.126362 -225.555882)
			(xy 97.073212 -225.559866) (xy 97.020062 -225.555882) (xy 96.9681 -225.544022) (xy 96.918486 -225.52455)
			(xy 96.872328 -225.497901) (xy 96.830657 -225.46467) (xy 96.794405 -225.425599) (xy 96.764381 -225.381562)
			(xy 96.741255 -225.333541) (xy 96.725545 -225.282611) (xy 96.717602 -225.229907) (xy 96.717104 -225.203258)
			(xy 96.717491 -225.180013) (xy 96.723531 -225.133918) (xy 96.735514 -225.089) (xy 96.744028 -225.067368)
			(xy 96.75368 -225.044254) (xy 96.581214 -224.745804) (xy 96.556576 -224.742502) (xy 96.531233 -224.73868)
			(xy 96.481927 -224.72469) (xy 96.435135 -224.703779) (xy 96.391823 -224.676378) (xy 96.352884 -224.643052)
			(xy 96.319123 -224.604491) (xy 96.291237 -224.56149) (xy 96.2698 -224.514936) (xy 96.255257 -224.46579)
			(xy 96.247906 -224.415068) (xy 96.247458 -224.389442) (xy 96.019874 -224.389442) (xy 96.019376 -224.416091)
			(xy 96.011433 -224.468795) (xy 95.995723 -224.519725) (xy 95.972597 -224.567746) (xy 95.942573 -224.611783)
			(xy 95.906321 -224.650854) (xy 95.86465 -224.684085) (xy 95.818492 -224.710734) (xy 95.768878 -224.730206)
			(xy 95.716916 -224.742066) (xy 95.663766 -224.74605) (xy 95.610616 -224.742066) (xy 95.558654 -224.730206)
			(xy 95.50904 -224.710734) (xy 95.462882 -224.684085) (xy 95.421211 -224.650854) (xy 95.384959 -224.611783)
			(xy 95.354935 -224.567746) (xy 95.331809 -224.519725) (xy 95.316099 -224.468795) (xy 95.308156 -224.416091)
			(xy 95.307658 -224.389442) (xy 95.308107 -224.363817) (xy 95.31546 -224.313096) (xy 95.330005 -224.263953)
			(xy 95.351442 -224.217401) (xy 95.379329 -224.174401) (xy 95.41309 -224.135842) (xy 95.452028 -224.102518)
			(xy 95.49534 -224.075119) (xy 95.542131 -224.054208) (xy 95.591436 -224.040219) (xy 95.616776 -224.036382)
			(xy 95.641414 -224.03308) (xy 95.813626 -223.734376) (xy 95.804228 -223.711516) (xy 95.795708 -223.689885)
			(xy 95.783714 -223.644967) (xy 95.777664 -223.598872) (xy 95.777304 -223.575626) (xy 95.777878 -223.546176)
			(xy 95.787576 -223.488081) (xy 95.806711 -223.432377) (xy 95.82023 -223.406208) (xy 95.8269 -223.39273)
			(xy 95.832876 -223.363273) (xy 95.830026 -223.333351) (xy 95.818596 -223.305552) (xy 95.799574 -223.282279)
			(xy 95.774606 -223.265545) (xy 95.745851 -223.256797) (xy 95.730822 -223.256348) (xy 95.596456 -223.256348)
			(xy 95.581443 -223.25689) (xy 95.552719 -223.265635) (xy 95.52778 -223.282354) (xy 95.50878 -223.305604)
			(xy 95.497363 -223.333374) (xy 95.494515 -223.363265) (xy 95.500483 -223.392691) (xy 95.507048 -223.406208)
			(xy 95.520534 -223.432392) (xy 95.539667 -223.488091) (xy 95.549373 -223.546179) (xy 95.549974 -223.575626)
			(xy 95.549476 -223.602275) (xy 95.541533 -223.654979) (xy 95.525823 -223.705909) (xy 95.502697 -223.75393)
			(xy 95.472673 -223.797967) (xy 95.436421 -223.837038) (xy 95.39475 -223.870269) (xy 95.348592 -223.896918)
			(xy 95.298978 -223.91639) (xy 95.247016 -223.92825) (xy 95.193866 -223.932234) (xy 95.140716 -223.92825)
			(xy 95.088754 -223.91639) (xy 95.03914 -223.896918) (xy 94.992982 -223.870269) (xy 94.951311 -223.837038)
			(xy 94.915059 -223.797967) (xy 94.885035 -223.75393) (xy 94.861909 -223.705909) (xy 94.846199 -223.654979)
			(xy 94.838256 -223.602275) (xy 94.837758 -223.575626) (xy 94.838332 -223.546176) (xy 94.848028 -223.488081)
			(xy 94.867161 -223.432376) (xy 94.880684 -223.406208) (xy 94.887356 -223.392732) (xy 94.893335 -223.363278)
			(xy 94.890486 -223.333359) (xy 94.879055 -223.305562) (xy 94.860031 -223.282295) (xy 94.83506 -223.265568)
			(xy 94.806304 -223.256831) (xy 94.791276 -223.256348) (xy 94.656402 -223.256348) (xy 94.641384 -223.256884)
			(xy 94.612648 -223.265621) (xy 94.587696 -223.28234) (xy 94.568686 -223.305594) (xy 94.557264 -223.333372)
			(xy 94.554416 -223.363272) (xy 94.560389 -223.392707) (xy 94.566994 -223.406208) (xy 94.580512 -223.432378)
			(xy 94.599651 -223.488082) (xy 94.609358 -223.546176) (xy 94.60992 -223.575626) (xy 94.609473 -223.601252)
			(xy 94.602124 -223.651975) (xy 94.587581 -223.701121) (xy 94.566146 -223.747676) (xy 94.538259 -223.790678)
			(xy 94.504498 -223.829239) (xy 94.465558 -223.862564) (xy 94.422245 -223.889964) (xy 94.375452 -223.910874)
			(xy 94.326145 -223.924862) (xy 94.300802 -223.928686) (xy 94.27591 -223.931988) (xy 94.103698 -224.230438)
			(xy 94.11335 -224.253552) (xy 94.121866 -224.275184) (xy 94.133852 -224.320102) (xy 94.139893 -224.366197)
			(xy 94.140274 -224.389442) (xy 94.367858 -224.389442) (xy 94.368356 -224.362793) (xy 94.376299 -224.310089)
			(xy 94.392009 -224.259159) (xy 94.415135 -224.211138) (xy 94.445159 -224.167101) (xy 94.481411 -224.12803)
			(xy 94.523082 -224.094799) (xy 94.56924 -224.06815) (xy 94.618854 -224.048678) (xy 94.670816 -224.036818)
			(xy 94.723966 -224.032835) (xy 94.777116 -224.036818) (xy 94.829078 -224.048678) (xy 94.878692 -224.06815)
			(xy 94.92485 -224.094799) (xy 94.966521 -224.12803) (xy 95.002773 -224.167101) (xy 95.032797 -224.211138)
			(xy 95.055923 -224.259159) (xy 95.071633 -224.310089) (xy 95.079576 -224.362793) (xy 95.080074 -224.389442)
			(xy 95.079688 -224.412687) (xy 95.073649 -224.458782) (xy 95.061665 -224.5037) (xy 95.05315 -224.525332)
			(xy 95.043498 -224.548446) (xy 95.215964 -224.846896) (xy 95.240602 -224.850198) (xy 95.265942 -224.854037)
			(xy 95.315248 -224.868024) (xy 95.36204 -224.888933) (xy 95.405353 -224.916332) (xy 95.444292 -224.949655)
			(xy 95.478053 -224.988214) (xy 95.50594 -225.031214) (xy 95.527377 -225.077767) (xy 95.541921 -225.126911)
			(xy 95.549272 -225.177632) (xy 95.54972 -225.203258) (xy 95.549222 -225.229907) (xy 95.777802 -225.229907)
			(xy 95.777802 -225.176609) (xy 95.785745 -225.123905) (xy 95.801455 -225.072975) (xy 95.824581 -225.024954)
			(xy 95.854605 -224.980917) (xy 95.890857 -224.941846) (xy 95.932528 -224.908615) (xy 95.978686 -224.881966)
			(xy 96.0283 -224.862494) (xy 96.080262 -224.850634) (xy 96.133412 -224.846651) (xy 96.186562 -224.850634)
			(xy 96.238524 -224.862494) (xy 96.288138 -224.881966) (xy 96.334296 -224.908615) (xy 96.375967 -224.941846)
			(xy 96.412219 -224.980917) (xy 96.442243 -225.024954) (xy 96.465369 -225.072975) (xy 96.481079 -225.123905)
			(xy 96.489022 -225.176609) (xy 96.48952 -225.203258) (xy 96.489022 -225.229907) (xy 96.481079 -225.282611)
			(xy 96.465369 -225.333541) (xy 96.442243 -225.381562) (xy 96.412219 -225.425599) (xy 96.375967 -225.46467)
			(xy 96.334296 -225.497901) (xy 96.288138 -225.52455) (xy 96.238524 -225.544022) (xy 96.186562 -225.555882)
			(xy 96.133412 -225.559866) (xy 96.080262 -225.555882) (xy 96.0283 -225.544022) (xy 95.978686 -225.52455)
			(xy 95.932528 -225.497901) (xy 95.890857 -225.46467) (xy 95.854605 -225.425599) (xy 95.824581 -225.381562)
			(xy 95.801455 -225.333541) (xy 95.785745 -225.282611) (xy 95.777802 -225.229907) (xy 95.549222 -225.229907)
			(xy 95.541279 -225.282611) (xy 95.525569 -225.333541) (xy 95.502443 -225.381562) (xy 95.472419 -225.425599)
			(xy 95.436167 -225.46467) (xy 95.394496 -225.497901) (xy 95.348338 -225.52455) (xy 95.298724 -225.544022)
			(xy 95.246762 -225.555882) (xy 95.193612 -225.559866) (xy 95.140462 -225.555882) (xy 95.0885 -225.544022)
			(xy 95.038886 -225.52455) (xy 94.992728 -225.497901) (xy 94.951057 -225.46467) (xy 94.914805 -225.425599)
			(xy 94.884781 -225.381562) (xy 94.861655 -225.333541) (xy 94.845945 -225.282611) (xy 94.838002 -225.229907)
			(xy 94.837504 -225.203258) (xy 94.837891 -225.180013) (xy 94.843931 -225.133918) (xy 94.855914 -225.089)
			(xy 94.864428 -225.067368) (xy 94.87408 -225.044254) (xy 94.701614 -224.745804) (xy 94.676976 -224.742502)
			(xy 94.651633 -224.73868) (xy 94.602327 -224.72469) (xy 94.555535 -224.703779) (xy 94.512223 -224.676378)
			(xy 94.473284 -224.643052) (xy 94.439523 -224.604491) (xy 94.411637 -224.56149) (xy 94.3902 -224.514936)
			(xy 94.375657 -224.46579) (xy 94.368306 -224.415068) (xy 94.367858 -224.389442) (xy 94.140274 -224.389442)
			(xy 94.139776 -224.416091) (xy 94.131833 -224.468795) (xy 94.116123 -224.519725) (xy 94.092997 -224.567746)
			(xy 94.062973 -224.611783) (xy 94.026721 -224.650854) (xy 93.98505 -224.684085) (xy 93.938892 -224.710734)
			(xy 93.889278 -224.730206) (xy 93.837316 -224.742066) (xy 93.784166 -224.74605) (xy 93.731016 -224.742066)
			(xy 93.679054 -224.730206) (xy 93.62944 -224.710734) (xy 93.583282 -224.684085) (xy 93.541611 -224.650854)
			(xy 93.505359 -224.611783) (xy 93.475335 -224.567746) (xy 93.452209 -224.519725) (xy 93.436499 -224.468795)
			(xy 93.428556 -224.416091) (xy 93.428058 -224.389442) (xy 93.428507 -224.363817) (xy 93.43586 -224.313096)
			(xy 93.450405 -224.263953) (xy 93.471842 -224.217401) (xy 93.499729 -224.174401) (xy 93.53349 -224.135842)
			(xy 93.572428 -224.102518) (xy 93.61574 -224.075119) (xy 93.662531 -224.054208) (xy 93.711836 -224.040219)
			(xy 93.737176 -224.036382) (xy 93.761814 -224.03308) (xy 93.934026 -223.734376) (xy 93.924628 -223.711516)
			(xy 93.916108 -223.689885) (xy 93.904114 -223.644967) (xy 93.898064 -223.598872) (xy 93.897704 -223.575626)
			(xy 93.898278 -223.546176) (xy 93.907976 -223.488081) (xy 93.927111 -223.432377) (xy 93.94063 -223.406208)
			(xy 93.9473 -223.39273) (xy 93.953276 -223.363273) (xy 93.950426 -223.333351) (xy 93.938996 -223.305552)
			(xy 93.919974 -223.282279) (xy 93.895006 -223.265545) (xy 93.866251 -223.256797) (xy 93.851222 -223.256348)
			(xy 93.716856 -223.256348) (xy 93.701843 -223.25689) (xy 93.673119 -223.265635) (xy 93.64818 -223.282354)
			(xy 93.62918 -223.305604) (xy 93.617763 -223.333374) (xy 93.614915 -223.363265) (xy 93.620883 -223.392691)
			(xy 93.627448 -223.406208) (xy 93.640934 -223.432392) (xy 93.660067 -223.488091) (xy 93.669773 -223.546179)
			(xy 93.670374 -223.575626) (xy 93.669876 -223.602275) (xy 93.661933 -223.654979) (xy 93.646223 -223.705909)
			(xy 93.623097 -223.75393) (xy 93.593073 -223.797967) (xy 93.556821 -223.837038) (xy 93.51515 -223.870269)
			(xy 93.468992 -223.896918) (xy 93.419378 -223.91639) (xy 93.367416 -223.92825) (xy 93.314266 -223.932234)
			(xy 93.261116 -223.92825) (xy 93.209154 -223.91639) (xy 93.15954 -223.896918) (xy 93.113382 -223.870269)
			(xy 93.071711 -223.837038) (xy 93.035459 -223.797967) (xy 93.005435 -223.75393) (xy 92.982309 -223.705909)
			(xy 92.966599 -223.654979) (xy 92.958656 -223.602275) (xy 92.958158 -223.575626) (xy 92.958732 -223.546176)
			(xy 92.968428 -223.488081) (xy 92.987561 -223.432376) (xy 93.001084 -223.406208) (xy 93.007756 -223.392732)
			(xy 93.013735 -223.363278) (xy 93.010886 -223.333359) (xy 92.999455 -223.305562) (xy 92.980431 -223.282295)
			(xy 92.95546 -223.265568) (xy 92.926704 -223.256831) (xy 92.911676 -223.256348) (xy 92.776802 -223.256348)
			(xy 92.761784 -223.256884) (xy 92.733048 -223.265621) (xy 92.708096 -223.28234) (xy 92.689086 -223.305594)
			(xy 92.677664 -223.333372) (xy 92.674816 -223.363272) (xy 92.680789 -223.392707) (xy 92.687394 -223.406208)
			(xy 92.700912 -223.432378) (xy 92.720051 -223.488082) (xy 92.729758 -223.546176) (xy 92.73032 -223.575626)
			(xy 92.729873 -223.601252) (xy 92.722524 -223.651975) (xy 92.707981 -223.701121) (xy 92.686546 -223.747676)
			(xy 92.658659 -223.790678) (xy 92.624898 -223.829239) (xy 92.585958 -223.862564) (xy 92.542645 -223.889964)
			(xy 92.495852 -223.910874) (xy 92.446545 -223.924862) (xy 92.421202 -223.928686) (xy 92.396564 -223.931988)
			(xy 92.224098 -224.230438) (xy 92.23375 -224.253552) (xy 92.242266 -224.275184) (xy 92.254252 -224.320102)
			(xy 92.260293 -224.366197) (xy 92.260674 -224.389442) (xy 92.488258 -224.389442) (xy 92.488756 -224.362793)
			(xy 92.496699 -224.310089) (xy 92.512409 -224.259159) (xy 92.535535 -224.211138) (xy 92.565559 -224.167101)
			(xy 92.601811 -224.12803) (xy 92.643482 -224.094799) (xy 92.68964 -224.06815) (xy 92.739254 -224.048678)
			(xy 92.791216 -224.036818) (xy 92.844366 -224.032835) (xy 92.897516 -224.036818) (xy 92.949478 -224.048678)
			(xy 92.999092 -224.06815) (xy 93.04525 -224.094799) (xy 93.086921 -224.12803) (xy 93.123173 -224.167101)
			(xy 93.153197 -224.211138) (xy 93.176323 -224.259159) (xy 93.192033 -224.310089) (xy 93.199976 -224.362793)
			(xy 93.200474 -224.389442) (xy 93.200088 -224.412687) (xy 93.194049 -224.458782) (xy 93.182065 -224.5037)
			(xy 93.17355 -224.525332) (xy 93.163898 -224.548446) (xy 93.336364 -224.846896) (xy 93.361002 -224.850198)
			(xy 93.386342 -224.854037) (xy 93.435648 -224.868024) (xy 93.48244 -224.888933) (xy 93.525753 -224.916332)
			(xy 93.564692 -224.949655) (xy 93.598453 -224.988214) (xy 93.62634 -225.031214) (xy 93.647777 -225.077767)
			(xy 93.662321 -225.126911) (xy 93.669672 -225.177632) (xy 93.67012 -225.203258) (xy 93.669622 -225.229907)
			(xy 93.898202 -225.229907) (xy 93.898202 -225.176609) (xy 93.906145 -225.123905) (xy 93.921855 -225.072975)
			(xy 93.944981 -225.024954) (xy 93.975005 -224.980917) (xy 94.011257 -224.941846) (xy 94.052928 -224.908615)
			(xy 94.099086 -224.881966) (xy 94.1487 -224.862494) (xy 94.200662 -224.850634) (xy 94.253812 -224.846651)
			(xy 94.306962 -224.850634) (xy 94.358924 -224.862494) (xy 94.408538 -224.881966) (xy 94.454696 -224.908615)
			(xy 94.496367 -224.941846) (xy 94.532619 -224.980917) (xy 94.562643 -225.024954) (xy 94.585769 -225.072975)
			(xy 94.601479 -225.123905) (xy 94.609422 -225.176609) (xy 94.60992 -225.203258) (xy 94.609422 -225.229907)
			(xy 94.601479 -225.282611) (xy 94.585769 -225.333541) (xy 94.562643 -225.381562) (xy 94.532619 -225.425599)
			(xy 94.496367 -225.46467) (xy 94.454696 -225.497901) (xy 94.408538 -225.52455) (xy 94.358924 -225.544022)
			(xy 94.306962 -225.555882) (xy 94.253812 -225.559866) (xy 94.200662 -225.555882) (xy 94.1487 -225.544022)
			(xy 94.099086 -225.52455) (xy 94.052928 -225.497901) (xy 94.011257 -225.46467) (xy 93.975005 -225.425599)
			(xy 93.944981 -225.381562) (xy 93.921855 -225.333541) (xy 93.906145 -225.282611) (xy 93.898202 -225.229907)
			(xy 93.669622 -225.229907) (xy 93.661679 -225.282611) (xy 93.645969 -225.333541) (xy 93.622843 -225.381562)
			(xy 93.592819 -225.425599) (xy 93.556567 -225.46467) (xy 93.514896 -225.497901) (xy 93.468738 -225.52455)
			(xy 93.419124 -225.544022) (xy 93.367162 -225.555882) (xy 93.314012 -225.559866) (xy 93.260862 -225.555882)
			(xy 93.2089 -225.544022) (xy 93.159286 -225.52455) (xy 93.113128 -225.497901) (xy 93.071457 -225.46467)
			(xy 93.035205 -225.425599) (xy 93.005181 -225.381562) (xy 92.982055 -225.333541) (xy 92.966345 -225.282611)
			(xy 92.958402 -225.229907) (xy 92.957904 -225.203258) (xy 92.958291 -225.180013) (xy 92.964331 -225.133918)
			(xy 92.976314 -225.089) (xy 92.984828 -225.067368) (xy 92.99448 -225.044254) (xy 92.822014 -224.745804)
			(xy 92.797376 -224.742502) (xy 92.772033 -224.73868) (xy 92.722727 -224.72469) (xy 92.675935 -224.703779)
			(xy 92.632623 -224.676378) (xy 92.593684 -224.643052) (xy 92.559923 -224.604491) (xy 92.532037 -224.56149)
			(xy 92.5106 -224.514936) (xy 92.496057 -224.46579) (xy 92.488706 -224.415068) (xy 92.488258 -224.389442)
			(xy 92.260674 -224.389442) (xy 92.260176 -224.416091) (xy 92.252233 -224.468795) (xy 92.236523 -224.519725)
			(xy 92.213397 -224.567746) (xy 92.183373 -224.611783) (xy 92.147121 -224.650854) (xy 92.10545 -224.684085)
			(xy 92.059292 -224.710734) (xy 92.009678 -224.730206) (xy 91.957716 -224.742066) (xy 91.904566 -224.74605)
			(xy 91.851416 -224.742066) (xy 91.799454 -224.730206) (xy 91.74984 -224.710734) (xy 91.703682 -224.684085)
			(xy 91.662011 -224.650854) (xy 91.625759 -224.611783) (xy 91.595735 -224.567746) (xy 91.572609 -224.519725)
			(xy 91.556899 -224.468795) (xy 91.548956 -224.416091) (xy 91.548458 -224.389442) (xy 91.548907 -224.363817)
			(xy 91.55626 -224.313096) (xy 91.570805 -224.263953) (xy 91.592242 -224.217401) (xy 91.620129 -224.174401)
			(xy 91.65389 -224.135842) (xy 91.692828 -224.102518) (xy 91.73614 -224.075119) (xy 91.782931 -224.054208)
			(xy 91.832236 -224.040219) (xy 91.857576 -224.036382) (xy 91.882214 -224.03308) (xy 92.054426 -223.734376)
			(xy 92.045028 -223.711262) (xy 92.036517 -223.689673) (xy 92.02453 -223.64484) (xy 92.018476 -223.598829)
			(xy 92.018104 -223.575626) (xy 92.018678 -223.546176) (xy 92.028376 -223.488081) (xy 92.047511 -223.432377)
			(xy 92.06103 -223.406208) (xy 92.0677 -223.39273) (xy 92.073676 -223.363273) (xy 92.070826 -223.333351)
			(xy 92.059396 -223.305552) (xy 92.040374 -223.282279) (xy 92.015406 -223.265545) (xy 91.986651 -223.256797)
			(xy 91.971622 -223.256348) (xy 91.837256 -223.256348) (xy 91.822243 -223.25689) (xy 91.793519 -223.265635)
			(xy 91.76858 -223.282354) (xy 91.74958 -223.305604) (xy 91.738163 -223.333374) (xy 91.735315 -223.363265)
			(xy 91.741283 -223.392691) (xy 91.747848 -223.406208) (xy 91.761334 -223.432392) (xy 91.780467 -223.488091)
			(xy 91.790173 -223.546179) (xy 91.790774 -223.575626) (xy 91.790276 -223.602275) (xy 91.782333 -223.654979)
			(xy 91.766623 -223.705909) (xy 91.743497 -223.75393) (xy 91.713473 -223.797967) (xy 91.677221 -223.837038)
			(xy 91.63555 -223.870269) (xy 91.589392 -223.896918) (xy 91.539778 -223.91639) (xy 91.487816 -223.92825)
			(xy 91.434666 -223.932234) (xy 91.381516 -223.92825) (xy 91.329554 -223.91639) (xy 91.27994 -223.896918)
			(xy 91.233782 -223.870269) (xy 91.192111 -223.837038) (xy 91.155859 -223.797967) (xy 91.125835 -223.75393)
			(xy 91.102709 -223.705909) (xy 91.086999 -223.654979) (xy 91.079056 -223.602275) (xy 91.078558 -223.575626)
			(xy 91.079132 -223.546176) (xy 91.088828 -223.488081) (xy 91.107961 -223.432376) (xy 91.121484 -223.406208)
			(xy 91.128156 -223.392732) (xy 91.134135 -223.363278) (xy 91.131286 -223.333359) (xy 91.119855 -223.305562)
			(xy 91.100831 -223.282295) (xy 91.07586 -223.265568) (xy 91.047104 -223.256831) (xy 91.032076 -223.256348)
			(xy 90.897202 -223.256348) (xy 90.882184 -223.256884) (xy 90.853448 -223.265621) (xy 90.828496 -223.28234)
			(xy 90.809486 -223.305594) (xy 90.798064 -223.333372) (xy 90.795216 -223.363272) (xy 90.801189 -223.392707)
			(xy 90.807794 -223.406208) (xy 90.821312 -223.432378) (xy 90.840451 -223.488082) (xy 90.850158 -223.546176)
			(xy 90.85072 -223.575626) (xy 90.850273 -223.601252) (xy 90.842924 -223.651975) (xy 90.828381 -223.701121)
			(xy 90.806946 -223.747676) (xy 90.779059 -223.790678) (xy 90.745298 -223.829239) (xy 90.706358 -223.862564)
			(xy 90.663045 -223.889964) (xy 90.616252 -223.910874) (xy 90.566945 -223.924862) (xy 90.541602 -223.928686)
			(xy 90.516964 -223.931988) (xy 90.344498 -224.230438) (xy 90.35415 -224.253552) (xy 90.362666 -224.275184)
			(xy 90.374652 -224.320102) (xy 90.380693 -224.366197) (xy 90.381074 -224.389442) (xy 90.608658 -224.389442)
			(xy 90.609156 -224.362793) (xy 90.617099 -224.310089) (xy 90.632809 -224.259159) (xy 90.655935 -224.211138)
			(xy 90.685959 -224.167101) (xy 90.722211 -224.12803) (xy 90.763882 -224.094799) (xy 90.81004 -224.06815)
			(xy 90.859654 -224.048678) (xy 90.911616 -224.036818) (xy 90.964766 -224.032835) (xy 91.017916 -224.036818)
			(xy 91.069878 -224.048678) (xy 91.119492 -224.06815) (xy 91.16565 -224.094799) (xy 91.207321 -224.12803)
			(xy 91.243573 -224.167101) (xy 91.273597 -224.211138) (xy 91.296723 -224.259159) (xy 91.312433 -224.310089)
			(xy 91.320376 -224.362793) (xy 91.320874 -224.389442) (xy 91.320488 -224.412687) (xy 91.314449 -224.458782)
			(xy 91.302465 -224.5037) (xy 91.29395 -224.525332) (xy 91.284298 -224.548446) (xy 91.456764 -224.846896)
			(xy 91.481402 -224.850198) (xy 91.506742 -224.854037) (xy 91.556048 -224.868024) (xy 91.60284 -224.888933)
			(xy 91.646153 -224.916332) (xy 91.685092 -224.949655) (xy 91.718853 -224.988214) (xy 91.74674 -225.031214)
			(xy 91.768177 -225.077767) (xy 91.782721 -225.126911) (xy 91.790072 -225.177632) (xy 91.79052 -225.203258)
			(xy 91.790022 -225.229907) (xy 92.018602 -225.229907) (xy 92.018602 -225.176609) (xy 92.026545 -225.123905)
			(xy 92.042255 -225.072975) (xy 92.065381 -225.024954) (xy 92.095405 -224.980917) (xy 92.131657 -224.941846)
			(xy 92.173328 -224.908615) (xy 92.219486 -224.881966) (xy 92.2691 -224.862494) (xy 92.321062 -224.850634)
			(xy 92.374212 -224.846651) (xy 92.427362 -224.850634) (xy 92.479324 -224.862494) (xy 92.528938 -224.881966)
			(xy 92.575096 -224.908615) (xy 92.616767 -224.941846) (xy 92.653019 -224.980917) (xy 92.683043 -225.024954)
			(xy 92.706169 -225.072975) (xy 92.721879 -225.123905) (xy 92.729822 -225.176609) (xy 92.73032 -225.203258)
			(xy 92.729822 -225.229907) (xy 92.721879 -225.282611) (xy 92.706169 -225.333541) (xy 92.683043 -225.381562)
			(xy 92.653019 -225.425599) (xy 92.616767 -225.46467) (xy 92.575096 -225.497901) (xy 92.528938 -225.52455)
			(xy 92.479324 -225.544022) (xy 92.427362 -225.555882) (xy 92.374212 -225.559866) (xy 92.321062 -225.555882)
			(xy 92.2691 -225.544022) (xy 92.219486 -225.52455) (xy 92.173328 -225.497901) (xy 92.131657 -225.46467)
			(xy 92.095405 -225.425599) (xy 92.065381 -225.381562) (xy 92.042255 -225.333541) (xy 92.026545 -225.282611)
			(xy 92.018602 -225.229907) (xy 91.790022 -225.229907) (xy 91.782079 -225.282611) (xy 91.766369 -225.333541)
			(xy 91.743243 -225.381562) (xy 91.713219 -225.425599) (xy 91.676967 -225.46467) (xy 91.635296 -225.497901)
			(xy 91.589138 -225.52455) (xy 91.539524 -225.544022) (xy 91.487562 -225.555882) (xy 91.434412 -225.559866)
			(xy 91.381262 -225.555882) (xy 91.3293 -225.544022) (xy 91.279686 -225.52455) (xy 91.233528 -225.497901)
			(xy 91.191857 -225.46467) (xy 91.155605 -225.425599) (xy 91.125581 -225.381562) (xy 91.102455 -225.333541)
			(xy 91.086745 -225.282611) (xy 91.078802 -225.229907) (xy 91.078304 -225.203258) (xy 91.078691 -225.180013)
			(xy 91.084731 -225.133918) (xy 91.096714 -225.089) (xy 91.105228 -225.067368) (xy 91.11488 -225.044254)
			(xy 90.942414 -224.745804) (xy 90.917776 -224.742502) (xy 90.892433 -224.73868) (xy 90.843127 -224.72469)
			(xy 90.796335 -224.703779) (xy 90.753023 -224.676378) (xy 90.714084 -224.643052) (xy 90.680323 -224.604491)
			(xy 90.652437 -224.56149) (xy 90.631 -224.514936) (xy 90.616457 -224.46579) (xy 90.609106 -224.415068)
			(xy 90.608658 -224.389442) (xy 90.381074 -224.389442) (xy 90.380576 -224.416091) (xy 90.372633 -224.468795)
			(xy 90.356923 -224.519725) (xy 90.333797 -224.567746) (xy 90.303773 -224.611783) (xy 90.267521 -224.650854)
			(xy 90.22585 -224.684085) (xy 90.179692 -224.710734) (xy 90.130078 -224.730206) (xy 90.078116 -224.742066)
			(xy 90.024966 -224.74605) (xy 89.971816 -224.742066) (xy 89.919854 -224.730206) (xy 89.87024 -224.710734)
			(xy 89.824082 -224.684085) (xy 89.782411 -224.650854) (xy 89.746159 -224.611783) (xy 89.716135 -224.567746)
			(xy 89.693009 -224.519725) (xy 89.677299 -224.468795) (xy 89.669356 -224.416091) (xy 89.668858 -224.389442)
			(xy 89.669307 -224.363817) (xy 89.67666 -224.313096) (xy 89.691205 -224.263953) (xy 89.712642 -224.217401)
			(xy 89.740529 -224.174401) (xy 89.77429 -224.135842) (xy 89.813228 -224.102518) (xy 89.85654 -224.075119)
			(xy 89.903331 -224.054208) (xy 89.952636 -224.040219) (xy 89.977976 -224.036382) (xy 90.002614 -224.03308)
			(xy 90.174826 -223.734376) (xy 90.165428 -223.711262) (xy 90.159474 -223.696355) (xy 90.149937 -223.665701)
			(xy 90.146378 -223.650048) (xy 90.14333 -223.635316) (xy 90.096594 -223.588834) (xy 89.420192 -224.265236)
			(xy 89.428066 -224.293684) (xy 89.434208 -224.317147) (xy 89.440833 -224.365192) (xy 89.441274 -224.389442)
			(xy 89.440722 -224.417422) (xy 89.431961 -224.472692) (xy 89.414663 -224.525911) (xy 89.389252 -224.575769)
			(xy 89.356354 -224.621038) (xy 89.31678 -224.660604) (xy 89.271504 -224.693492) (xy 89.221641 -224.718892)
			(xy 89.168418 -224.736179) (xy 89.113146 -224.744928) (xy 89.085166 -224.74555) (xy 89.074793 -224.745504)
			(xy 89.054079 -224.744362) (xy 89.043764 -224.743264) (xy 89.02951 -224.742103) (xy 89.001317 -224.746819)
			(xy 88.975535 -224.759165) (xy 88.954184 -224.778172) (xy 88.938937 -224.802352) (xy 88.930989 -224.82981)
			(xy 88.93048 -224.844102) (xy 88.93048 -225.037142) (xy 88.93556 -225.047556) (xy 88.946864 -225.071939)
			(xy 88.962825 -225.123258) (xy 88.9709 -225.176391) (xy 88.970906 -225.229907) (xy 89.199202 -225.229907)
			(xy 89.199202 -225.176609) (xy 89.207145 -225.123905) (xy 89.222855 -225.072975) (xy 89.245981 -225.024954)
			(xy 89.276005 -224.980917) (xy 89.312257 -224.941846) (xy 89.353928 -224.908615) (xy 89.400086 -224.881966)
			(xy 89.4497 -224.862494) (xy 89.501662 -224.850634) (xy 89.554812 -224.846651) (xy 89.607962 -224.850634)
			(xy 89.659924 -224.862494) (xy 89.709538 -224.881966) (xy 89.755696 -224.908615) (xy 89.797367 -224.941846)
			(xy 89.833619 -224.980917) (xy 89.863643 -225.024954) (xy 89.886769 -225.072975) (xy 89.902479 -225.123905)
			(xy 89.910422 -225.176609) (xy 89.91092 -225.203258) (xy 89.910422 -225.229907) (xy 90.139002 -225.229907)
			(xy 90.139002 -225.176609) (xy 90.146945 -225.123905) (xy 90.162655 -225.072975) (xy 90.185781 -225.024954)
			(xy 90.215805 -224.980917) (xy 90.252057 -224.941846) (xy 90.293728 -224.908615) (xy 90.339886 -224.881966)
			(xy 90.3895 -224.862494) (xy 90.441462 -224.850634) (xy 90.494612 -224.846651) (xy 90.547762 -224.850634)
			(xy 90.599724 -224.862494) (xy 90.649338 -224.881966) (xy 90.695496 -224.908615) (xy 90.737167 -224.941846)
			(xy 90.773419 -224.980917) (xy 90.803443 -225.024954) (xy 90.826569 -225.072975) (xy 90.842279 -225.123905)
			(xy 90.850222 -225.176609) (xy 90.85072 -225.203258) (xy 90.850222 -225.229907) (xy 90.842279 -225.282611)
			(xy 90.826569 -225.333541) (xy 90.803443 -225.381562) (xy 90.773419 -225.425599) (xy 90.737167 -225.46467)
			(xy 90.695496 -225.497901) (xy 90.649338 -225.52455) (xy 90.599724 -225.544022) (xy 90.547762 -225.555882)
			(xy 90.494612 -225.559866) (xy 90.441462 -225.555882) (xy 90.3895 -225.544022) (xy 90.339886 -225.52455)
			(xy 90.293728 -225.497901) (xy 90.252057 -225.46467) (xy 90.215805 -225.425599) (xy 90.185781 -225.381562)
			(xy 90.162655 -225.333541) (xy 90.146945 -225.282611) (xy 90.139002 -225.229907) (xy 89.910422 -225.229907)
			(xy 89.902479 -225.282611) (xy 89.886769 -225.333541) (xy 89.863643 -225.381562) (xy 89.833619 -225.425599)
			(xy 89.797367 -225.46467) (xy 89.755696 -225.497901) (xy 89.709538 -225.52455) (xy 89.659924 -225.544022)
			(xy 89.607962 -225.555882) (xy 89.554812 -225.559866) (xy 89.501662 -225.555882) (xy 89.4497 -225.544022)
			(xy 89.400086 -225.52455) (xy 89.353928 -225.497901) (xy 89.312257 -225.46467) (xy 89.276005 -225.425599)
			(xy 89.245981 -225.381562) (xy 89.222855 -225.333541) (xy 89.207145 -225.282611) (xy 89.199202 -225.229907)
			(xy 88.970906 -225.229907) (xy 88.970906 -225.230134) (xy 88.962842 -225.283269) (xy 88.946891 -225.33459)
			(xy 88.93556 -225.35896) (xy 88.93048 -225.369374) (xy 88.93048 -225.562668) (xy 88.930961 -225.576963)
			(xy 88.938891 -225.604431) (xy 88.954137 -225.628616) (xy 88.975498 -225.647617) (xy 89.001296 -225.659939)
			(xy 89.029501 -225.664613) (xy 89.043764 -225.663506) (xy 89.054078 -225.662403) (xy 89.074793 -225.66126)
			(xy 89.085166 -225.66122) (xy 89.111817 -225.661691) (xy 89.164523 -225.66963) (xy 89.215458 -225.685337)
			(xy 89.263482 -225.708461) (xy 89.307524 -225.738484) (xy 89.346598 -225.774736) (xy 89.379833 -225.816407)
			(xy 89.406485 -225.862567) (xy 89.425959 -225.912183) (xy 89.437821 -225.964148) (xy 89.441804 -226.0173)
			(xy 89.439805 -226.043977) (xy 89.669356 -226.043977) (xy 89.669356 -225.990679) (xy 89.677299 -225.937975)
			(xy 89.693009 -225.887045) (xy 89.716135 -225.839024) (xy 89.746159 -225.794987) (xy 89.782411 -225.755916)
			(xy 89.824082 -225.722685) (xy 89.87024 -225.696036) (xy 89.919854 -225.676564) (xy 89.971816 -225.664704)
			(xy 90.024966 -225.660721) (xy 90.078116 -225.664704) (xy 90.130078 -225.676564) (xy 90.179692 -225.696036)
			(xy 90.22585 -225.722685) (xy 90.267521 -225.755916) (xy 90.303773 -225.794987) (xy 90.333797 -225.839024)
			(xy 90.356923 -225.887045) (xy 90.372633 -225.937975) (xy 90.380576 -225.990679) (xy 90.381074 -226.017328)
			(xy 90.380576 -226.043977) (xy 90.608902 -226.043977) (xy 90.608902 -225.990679) (xy 90.616845 -225.937975)
			(xy 90.632555 -225.887045) (xy 90.655681 -225.839024) (xy 90.685705 -225.794987) (xy 90.721957 -225.755916)
			(xy 90.763628 -225.722685) (xy 90.809786 -225.696036) (xy 90.8594 -225.676564) (xy 90.911362 -225.664704)
			(xy 90.964512 -225.660721) (xy 91.017662 -225.664704) (xy 91.069624 -225.676564) (xy 91.119238 -225.696036)
			(xy 91.165396 -225.722685) (xy 91.207067 -225.755916) (xy 91.243319 -225.794987) (xy 91.273343 -225.839024)
			(xy 91.296469 -225.887045) (xy 91.312179 -225.937975) (xy 91.320122 -225.990679) (xy 91.32062 -226.017328)
			(xy 91.320122 -226.043977) (xy 91.548956 -226.043977) (xy 91.548956 -225.990679) (xy 91.556899 -225.937975)
			(xy 91.572609 -225.887045) (xy 91.595735 -225.839024) (xy 91.625759 -225.794987) (xy 91.662011 -225.755916)
			(xy 91.703682 -225.722685) (xy 91.74984 -225.696036) (xy 91.799454 -225.676564) (xy 91.851416 -225.664704)
			(xy 91.904566 -225.660721) (xy 91.957716 -225.664704) (xy 92.009678 -225.676564) (xy 92.059292 -225.696036)
			(xy 92.10545 -225.722685) (xy 92.147121 -225.755916) (xy 92.183373 -225.794987) (xy 92.213397 -225.839024)
			(xy 92.236523 -225.887045) (xy 92.252233 -225.937975) (xy 92.260176 -225.990679) (xy 92.260674 -226.017328)
			(xy 92.260176 -226.043977) (xy 92.488756 -226.043977) (xy 92.488756 -225.990679) (xy 92.496699 -225.937975)
			(xy 92.512409 -225.887045) (xy 92.535535 -225.839024) (xy 92.565559 -225.794987) (xy 92.601811 -225.755916)
			(xy 92.643482 -225.722685) (xy 92.68964 -225.696036) (xy 92.739254 -225.676564) (xy 92.791216 -225.664704)
			(xy 92.844366 -225.660721) (xy 92.897516 -225.664704) (xy 92.949478 -225.676564) (xy 92.999092 -225.696036)
			(xy 93.04525 -225.722685) (xy 93.086921 -225.755916) (xy 93.123173 -225.794987) (xy 93.153197 -225.839024)
			(xy 93.176323 -225.887045) (xy 93.192033 -225.937975) (xy 93.199976 -225.990679) (xy 93.200474 -226.017328)
			(xy 93.199976 -226.043977) (xy 93.428556 -226.043977) (xy 93.428556 -225.990679) (xy 93.436499 -225.937975)
			(xy 93.452209 -225.887045) (xy 93.475335 -225.839024) (xy 93.505359 -225.794987) (xy 93.541611 -225.755916)
			(xy 93.583282 -225.722685) (xy 93.62944 -225.696036) (xy 93.679054 -225.676564) (xy 93.731016 -225.664704)
			(xy 93.784166 -225.660721) (xy 93.837316 -225.664704) (xy 93.889278 -225.676564) (xy 93.938892 -225.696036)
			(xy 93.98505 -225.722685) (xy 94.026721 -225.755916) (xy 94.062973 -225.794987) (xy 94.092997 -225.839024)
			(xy 94.116123 -225.887045) (xy 94.131833 -225.937975) (xy 94.139776 -225.990679) (xy 94.140274 -226.017328)
			(xy 94.139776 -226.043977) (xy 94.368356 -226.043977) (xy 94.368356 -225.990679) (xy 94.376299 -225.937975)
			(xy 94.392009 -225.887045) (xy 94.415135 -225.839024) (xy 94.445159 -225.794987) (xy 94.481411 -225.755916)
			(xy 94.523082 -225.722685) (xy 94.56924 -225.696036) (xy 94.618854 -225.676564) (xy 94.670816 -225.664704)
			(xy 94.723966 -225.660721) (xy 94.777116 -225.664704) (xy 94.829078 -225.676564) (xy 94.878692 -225.696036)
			(xy 94.92485 -225.722685) (xy 94.966521 -225.755916) (xy 95.002773 -225.794987) (xy 95.032797 -225.839024)
			(xy 95.055923 -225.887045) (xy 95.071633 -225.937975) (xy 95.079576 -225.990679) (xy 95.080074 -226.017328)
			(xy 95.079576 -226.043977) (xy 95.308156 -226.043977) (xy 95.308156 -225.990679) (xy 95.316099 -225.937975)
			(xy 95.331809 -225.887045) (xy 95.354935 -225.839024) (xy 95.384959 -225.794987) (xy 95.421211 -225.755916)
			(xy 95.462882 -225.722685) (xy 95.50904 -225.696036) (xy 95.558654 -225.676564) (xy 95.610616 -225.664704)
			(xy 95.663766 -225.660721) (xy 95.716916 -225.664704) (xy 95.768878 -225.676564) (xy 95.818492 -225.696036)
			(xy 95.86465 -225.722685) (xy 95.906321 -225.755916) (xy 95.942573 -225.794987) (xy 95.972597 -225.839024)
			(xy 95.995723 -225.887045) (xy 96.011433 -225.937975) (xy 96.019376 -225.990679) (xy 96.019874 -226.017328)
			(xy 96.019376 -226.043977) (xy 96.247956 -226.043977) (xy 96.247956 -225.990679) (xy 96.255899 -225.937975)
			(xy 96.271609 -225.887045) (xy 96.294735 -225.839024) (xy 96.324759 -225.794987) (xy 96.361011 -225.755916)
			(xy 96.402682 -225.722685) (xy 96.44884 -225.696036) (xy 96.498454 -225.676564) (xy 96.550416 -225.664704)
			(xy 96.603566 -225.660721) (xy 96.656716 -225.664704) (xy 96.708678 -225.676564) (xy 96.758292 -225.696036)
			(xy 96.80445 -225.722685) (xy 96.846121 -225.755916) (xy 96.882373 -225.794987) (xy 96.912397 -225.839024)
			(xy 96.935523 -225.887045) (xy 96.951233 -225.937975) (xy 96.959176 -225.990679) (xy 96.959674 -226.017328)
			(xy 96.959176 -226.043977) (xy 97.187756 -226.043977) (xy 97.187756 -225.990679) (xy 97.195699 -225.937975)
			(xy 97.211409 -225.887045) (xy 97.234535 -225.839024) (xy 97.264559 -225.794987) (xy 97.300811 -225.755916)
			(xy 97.342482 -225.722685) (xy 97.38864 -225.696036) (xy 97.438254 -225.676564) (xy 97.490216 -225.664704)
			(xy 97.543366 -225.660721) (xy 97.596516 -225.664704) (xy 97.648478 -225.676564) (xy 97.698092 -225.696036)
			(xy 97.74425 -225.722685) (xy 97.785921 -225.755916) (xy 97.822173 -225.794987) (xy 97.852197 -225.839024)
			(xy 97.875323 -225.887045) (xy 97.891033 -225.937975) (xy 97.898976 -225.990679) (xy 97.899474 -226.017328)
			(xy 97.898976 -226.043977) (xy 98.127556 -226.043977) (xy 98.127556 -225.990679) (xy 98.135499 -225.937975)
			(xy 98.151209 -225.887045) (xy 98.174335 -225.839024) (xy 98.204359 -225.794987) (xy 98.240611 -225.755916)
			(xy 98.282282 -225.722685) (xy 98.32844 -225.696036) (xy 98.378054 -225.676564) (xy 98.430016 -225.664704)
			(xy 98.483166 -225.660721) (xy 98.536316 -225.664704) (xy 98.588278 -225.676564) (xy 98.637892 -225.696036)
			(xy 98.68405 -225.722685) (xy 98.725721 -225.755916) (xy 98.761973 -225.794987) (xy 98.791997 -225.839024)
			(xy 98.815123 -225.887045) (xy 98.830833 -225.937975) (xy 98.838776 -225.990679) (xy 98.839274 -226.017328)
			(xy 98.838776 -226.043977) (xy 99.067356 -226.043977) (xy 99.067356 -225.990679) (xy 99.075299 -225.937975)
			(xy 99.091009 -225.887045) (xy 99.114135 -225.839024) (xy 99.144159 -225.794987) (xy 99.180411 -225.755916)
			(xy 99.222082 -225.722685) (xy 99.26824 -225.696036) (xy 99.317854 -225.676564) (xy 99.369816 -225.664704)
			(xy 99.422966 -225.660721) (xy 99.476116 -225.664704) (xy 99.528078 -225.676564) (xy 99.577692 -225.696036)
			(xy 99.62385 -225.722685) (xy 99.665521 -225.755916) (xy 99.701773 -225.794987) (xy 99.731797 -225.839024)
			(xy 99.754923 -225.887045) (xy 99.770633 -225.937975) (xy 99.778576 -225.990679) (xy 99.779074 -226.017328)
			(xy 99.778576 -226.043977) (xy 100.007156 -226.043977) (xy 100.007156 -225.990679) (xy 100.015099 -225.937975)
			(xy 100.030809 -225.887045) (xy 100.053935 -225.839024) (xy 100.083959 -225.794987) (xy 100.120211 -225.755916)
			(xy 100.161882 -225.722685) (xy 100.20804 -225.696036) (xy 100.257654 -225.676564) (xy 100.309616 -225.664704)
			(xy 100.362766 -225.660721) (xy 100.415916 -225.664704) (xy 100.467878 -225.676564) (xy 100.517492 -225.696036)
			(xy 100.56365 -225.722685) (xy 100.605321 -225.755916) (xy 100.641573 -225.794987) (xy 100.671597 -225.839024)
			(xy 100.694723 -225.887045) (xy 100.710433 -225.937975) (xy 100.718376 -225.990679) (xy 100.718874 -226.017328)
			(xy 100.718376 -226.043977) (xy 100.946956 -226.043977) (xy 100.946956 -225.990679) (xy 100.954899 -225.937975)
			(xy 100.970609 -225.887045) (xy 100.993735 -225.839024) (xy 101.023759 -225.794987) (xy 101.060011 -225.755916)
			(xy 101.101682 -225.722685) (xy 101.14784 -225.696036) (xy 101.197454 -225.676564) (xy 101.249416 -225.664704)
			(xy 101.302566 -225.660721) (xy 101.355716 -225.664704) (xy 101.407678 -225.676564) (xy 101.457292 -225.696036)
			(xy 101.50345 -225.722685) (xy 101.545121 -225.755916) (xy 101.581373 -225.794987) (xy 101.611397 -225.839024)
			(xy 101.634523 -225.887045) (xy 101.650233 -225.937975) (xy 101.658176 -225.990679) (xy 101.658674 -226.017328)
			(xy 101.658176 -226.043977) (xy 101.886756 -226.043977) (xy 101.886756 -225.990679) (xy 101.894699 -225.937975)
			(xy 101.910409 -225.887045) (xy 101.933535 -225.839024) (xy 101.963559 -225.794987) (xy 101.999811 -225.755916)
			(xy 102.041482 -225.722685) (xy 102.08764 -225.696036) (xy 102.137254 -225.676564) (xy 102.189216 -225.664704)
			(xy 102.242366 -225.660721) (xy 102.295516 -225.664704) (xy 102.347478 -225.676564) (xy 102.397092 -225.696036)
			(xy 102.44325 -225.722685) (xy 102.484921 -225.755916) (xy 102.521173 -225.794987) (xy 102.551197 -225.839024)
			(xy 102.574323 -225.887045) (xy 102.590033 -225.937975) (xy 102.597976 -225.990679) (xy 102.598474 -226.017328)
			(xy 102.597976 -226.043977) (xy 102.826556 -226.043977) (xy 102.826556 -225.990679) (xy 102.834499 -225.937975)
			(xy 102.850209 -225.887045) (xy 102.873335 -225.839024) (xy 102.903359 -225.794987) (xy 102.939611 -225.755916)
			(xy 102.981282 -225.722685) (xy 103.02744 -225.696036) (xy 103.077054 -225.676564) (xy 103.129016 -225.664704)
			(xy 103.182166 -225.660721) (xy 103.235316 -225.664704) (xy 103.287278 -225.676564) (xy 103.336892 -225.696036)
			(xy 103.38305 -225.722685) (xy 103.424721 -225.755916) (xy 103.460973 -225.794987) (xy 103.490997 -225.839024)
			(xy 103.514123 -225.887045) (xy 103.529833 -225.937975) (xy 103.537776 -225.990679) (xy 103.538274 -226.017328)
			(xy 103.537776 -226.043977) (xy 103.766356 -226.043977) (xy 103.766356 -225.990679) (xy 103.774299 -225.937975)
			(xy 103.790009 -225.887045) (xy 103.813135 -225.839024) (xy 103.843159 -225.794987) (xy 103.879411 -225.755916)
			(xy 103.921082 -225.722685) (xy 103.96724 -225.696036) (xy 104.016854 -225.676564) (xy 104.068816 -225.664704)
			(xy 104.121966 -225.660721) (xy 104.175116 -225.664704) (xy 104.227078 -225.676564) (xy 104.276692 -225.696036)
			(xy 104.32285 -225.722685) (xy 104.364521 -225.755916) (xy 104.400773 -225.794987) (xy 104.430797 -225.839024)
			(xy 104.453923 -225.887045) (xy 104.469633 -225.937975) (xy 104.477576 -225.990679) (xy 104.478074 -226.017328)
			(xy 104.477576 -226.043977) (xy 104.706156 -226.043977) (xy 104.706156 -225.990679) (xy 104.714099 -225.937975)
			(xy 104.729809 -225.887045) (xy 104.752935 -225.839024) (xy 104.782959 -225.794987) (xy 104.819211 -225.755916)
			(xy 104.860882 -225.722685) (xy 104.90704 -225.696036) (xy 104.956654 -225.676564) (xy 105.008616 -225.664704)
			(xy 105.061766 -225.660721) (xy 105.114916 -225.664704) (xy 105.166878 -225.676564) (xy 105.216492 -225.696036)
			(xy 105.26265 -225.722685) (xy 105.304321 -225.755916) (xy 105.340573 -225.794987) (xy 105.370597 -225.839024)
			(xy 105.393723 -225.887045) (xy 105.409433 -225.937975) (xy 105.417376 -225.990679) (xy 105.417874 -226.017328)
			(xy 105.417376 -226.043977) (xy 105.645956 -226.043977) (xy 105.645956 -225.990679) (xy 105.653899 -225.937975)
			(xy 105.669609 -225.887045) (xy 105.692735 -225.839024) (xy 105.722759 -225.794987) (xy 105.759011 -225.755916)
			(xy 105.800682 -225.722685) (xy 105.84684 -225.696036) (xy 105.896454 -225.676564) (xy 105.948416 -225.664704)
			(xy 106.001566 -225.660721) (xy 106.054716 -225.664704) (xy 106.106678 -225.676564) (xy 106.156292 -225.696036)
			(xy 106.20245 -225.722685) (xy 106.244121 -225.755916) (xy 106.280373 -225.794987) (xy 106.310397 -225.839024)
			(xy 106.333523 -225.887045) (xy 106.349233 -225.937975) (xy 106.357176 -225.990679) (xy 106.357674 -226.017328)
			(xy 106.357176 -226.043977) (xy 106.585756 -226.043977) (xy 106.585756 -225.990679) (xy 106.593699 -225.937975)
			(xy 106.609409 -225.887045) (xy 106.632535 -225.839024) (xy 106.662559 -225.794987) (xy 106.698811 -225.755916)
			(xy 106.740482 -225.722685) (xy 106.78664 -225.696036) (xy 106.836254 -225.676564) (xy 106.888216 -225.664704)
			(xy 106.941366 -225.660721) (xy 106.994516 -225.664704) (xy 107.046478 -225.676564) (xy 107.096092 -225.696036)
			(xy 107.14225 -225.722685) (xy 107.183921 -225.755916) (xy 107.220173 -225.794987) (xy 107.250197 -225.839024)
			(xy 107.273323 -225.887045) (xy 107.289033 -225.937975) (xy 107.296976 -225.990679) (xy 107.297474 -226.017328)
			(xy 107.296976 -226.043977) (xy 107.525556 -226.043977) (xy 107.525556 -225.990679) (xy 107.533499 -225.937975)
			(xy 107.549209 -225.887045) (xy 107.572335 -225.839024) (xy 107.602359 -225.794987) (xy 107.638611 -225.755916)
			(xy 107.680282 -225.722685) (xy 107.72644 -225.696036) (xy 107.776054 -225.676564) (xy 107.828016 -225.664704)
			(xy 107.881166 -225.660721) (xy 107.934316 -225.664704) (xy 107.986278 -225.676564) (xy 108.035892 -225.696036)
			(xy 108.08205 -225.722685) (xy 108.123721 -225.755916) (xy 108.159973 -225.794987) (xy 108.189997 -225.839024)
			(xy 108.213123 -225.887045) (xy 108.228833 -225.937975) (xy 108.236776 -225.990679) (xy 108.237274 -226.017328)
			(xy 108.236776 -226.043977) (xy 108.465356 -226.043977) (xy 108.465356 -225.990679) (xy 108.473299 -225.937975)
			(xy 108.489009 -225.887045) (xy 108.512135 -225.839024) (xy 108.542159 -225.794987) (xy 108.578411 -225.755916)
			(xy 108.620082 -225.722685) (xy 108.66624 -225.696036) (xy 108.715854 -225.676564) (xy 108.767816 -225.664704)
			(xy 108.820966 -225.660721) (xy 108.874116 -225.664704) (xy 108.926078 -225.676564) (xy 108.975692 -225.696036)
			(xy 109.02185 -225.722685) (xy 109.063521 -225.755916) (xy 109.099773 -225.794987) (xy 109.129797 -225.839024)
			(xy 109.152923 -225.887045) (xy 109.168633 -225.937975) (xy 109.176576 -225.990679) (xy 109.177074 -226.017328)
			(xy 109.176576 -226.043977) (xy 109.405156 -226.043977) (xy 109.405156 -225.990679) (xy 109.413099 -225.937975)
			(xy 109.428809 -225.887045) (xy 109.451935 -225.839024) (xy 109.481959 -225.794987) (xy 109.518211 -225.755916)
			(xy 109.559882 -225.722685) (xy 109.60604 -225.696036) (xy 109.655654 -225.676564) (xy 109.707616 -225.664704)
			(xy 109.760766 -225.660721) (xy 109.813916 -225.664704) (xy 109.865878 -225.676564) (xy 109.915492 -225.696036)
			(xy 109.96165 -225.722685) (xy 110.003321 -225.755916) (xy 110.039573 -225.794987) (xy 110.069597 -225.839024)
			(xy 110.092723 -225.887045) (xy 110.108433 -225.937975) (xy 110.116376 -225.990679) (xy 110.116874 -226.017328)
			(xy 110.116376 -226.043977) (xy 110.344956 -226.043977) (xy 110.344956 -225.990679) (xy 110.352899 -225.937975)
			(xy 110.368609 -225.887045) (xy 110.391735 -225.839024) (xy 110.421759 -225.794987) (xy 110.458011 -225.755916)
			(xy 110.499682 -225.722685) (xy 110.54584 -225.696036) (xy 110.595454 -225.676564) (xy 110.647416 -225.664704)
			(xy 110.700566 -225.660721) (xy 110.753716 -225.664704) (xy 110.805678 -225.676564) (xy 110.855292 -225.696036)
			(xy 110.90145 -225.722685) (xy 110.943121 -225.755916) (xy 110.979373 -225.794987) (xy 111.009397 -225.839024)
			(xy 111.032523 -225.887045) (xy 111.048233 -225.937975) (xy 111.056176 -225.990679) (xy 111.056674 -226.017328)
			(xy 111.056176 -226.043977) (xy 111.048233 -226.096681) (xy 111.032523 -226.147611) (xy 111.009397 -226.195632)
			(xy 110.979373 -226.239669) (xy 110.943121 -226.27874) (xy 110.90145 -226.311971) (xy 110.855292 -226.33862)
			(xy 110.805678 -226.358092) (xy 110.753716 -226.369952) (xy 110.700566 -226.373936) (xy 110.647416 -226.369952)
			(xy 110.595454 -226.358092) (xy 110.54584 -226.33862) (xy 110.499682 -226.311971) (xy 110.458011 -226.27874)
			(xy 110.421759 -226.239669) (xy 110.391735 -226.195632) (xy 110.368609 -226.147611) (xy 110.352899 -226.096681)
			(xy 110.344956 -226.043977) (xy 110.116376 -226.043977) (xy 110.108433 -226.096681) (xy 110.092723 -226.147611)
			(xy 110.069597 -226.195632) (xy 110.039573 -226.239669) (xy 110.003321 -226.27874) (xy 109.96165 -226.311971)
			(xy 109.915492 -226.33862) (xy 109.865878 -226.358092) (xy 109.813916 -226.369952) (xy 109.760766 -226.373936)
			(xy 109.707616 -226.369952) (xy 109.655654 -226.358092) (xy 109.60604 -226.33862) (xy 109.559882 -226.311971)
			(xy 109.518211 -226.27874) (xy 109.481959 -226.239669) (xy 109.451935 -226.195632) (xy 109.428809 -226.147611)
			(xy 109.413099 -226.096681) (xy 109.405156 -226.043977) (xy 109.176576 -226.043977) (xy 109.168633 -226.096681)
			(xy 109.152923 -226.147611) (xy 109.129797 -226.195632) (xy 109.099773 -226.239669) (xy 109.063521 -226.27874)
			(xy 109.02185 -226.311971) (xy 108.975692 -226.33862) (xy 108.926078 -226.358092) (xy 108.874116 -226.369952)
			(xy 108.820966 -226.373936) (xy 108.767816 -226.369952) (xy 108.715854 -226.358092) (xy 108.66624 -226.33862)
			(xy 108.620082 -226.311971) (xy 108.578411 -226.27874) (xy 108.542159 -226.239669) (xy 108.512135 -226.195632)
			(xy 108.489009 -226.147611) (xy 108.473299 -226.096681) (xy 108.465356 -226.043977) (xy 108.236776 -226.043977)
			(xy 108.228833 -226.096681) (xy 108.213123 -226.147611) (xy 108.189997 -226.195632) (xy 108.159973 -226.239669)
			(xy 108.123721 -226.27874) (xy 108.08205 -226.311971) (xy 108.035892 -226.33862) (xy 107.986278 -226.358092)
			(xy 107.934316 -226.369952) (xy 107.881166 -226.373936) (xy 107.828016 -226.369952) (xy 107.776054 -226.358092)
			(xy 107.72644 -226.33862) (xy 107.680282 -226.311971) (xy 107.638611 -226.27874) (xy 107.602359 -226.239669)
			(xy 107.572335 -226.195632) (xy 107.549209 -226.147611) (xy 107.533499 -226.096681) (xy 107.525556 -226.043977)
			(xy 107.296976 -226.043977) (xy 107.289033 -226.096681) (xy 107.273323 -226.147611) (xy 107.250197 -226.195632)
			(xy 107.220173 -226.239669) (xy 107.183921 -226.27874) (xy 107.14225 -226.311971) (xy 107.096092 -226.33862)
			(xy 107.046478 -226.358092) (xy 106.994516 -226.369952) (xy 106.941366 -226.373936) (xy 106.888216 -226.369952)
			(xy 106.836254 -226.358092) (xy 106.78664 -226.33862) (xy 106.740482 -226.311971) (xy 106.698811 -226.27874)
			(xy 106.662559 -226.239669) (xy 106.632535 -226.195632) (xy 106.609409 -226.147611) (xy 106.593699 -226.096681)
			(xy 106.585756 -226.043977) (xy 106.357176 -226.043977) (xy 106.349233 -226.096681) (xy 106.333523 -226.147611)
			(xy 106.310397 -226.195632) (xy 106.280373 -226.239669) (xy 106.244121 -226.27874) (xy 106.20245 -226.311971)
			(xy 106.156292 -226.33862) (xy 106.106678 -226.358092) (xy 106.054716 -226.369952) (xy 106.001566 -226.373936)
			(xy 105.948416 -226.369952) (xy 105.896454 -226.358092) (xy 105.84684 -226.33862) (xy 105.800682 -226.311971)
			(xy 105.759011 -226.27874) (xy 105.722759 -226.239669) (xy 105.692735 -226.195632) (xy 105.669609 -226.147611)
			(xy 105.653899 -226.096681) (xy 105.645956 -226.043977) (xy 105.417376 -226.043977) (xy 105.409433 -226.096681)
			(xy 105.393723 -226.147611) (xy 105.370597 -226.195632) (xy 105.340573 -226.239669) (xy 105.304321 -226.27874)
			(xy 105.26265 -226.311971) (xy 105.216492 -226.33862) (xy 105.166878 -226.358092) (xy 105.114916 -226.369952)
			(xy 105.061766 -226.373936) (xy 105.008616 -226.369952) (xy 104.956654 -226.358092) (xy 104.90704 -226.33862)
			(xy 104.860882 -226.311971) (xy 104.819211 -226.27874) (xy 104.782959 -226.239669) (xy 104.752935 -226.195632)
			(xy 104.729809 -226.147611) (xy 104.714099 -226.096681) (xy 104.706156 -226.043977) (xy 104.477576 -226.043977)
			(xy 104.469633 -226.096681) (xy 104.453923 -226.147611) (xy 104.430797 -226.195632) (xy 104.400773 -226.239669)
			(xy 104.364521 -226.27874) (xy 104.32285 -226.311971) (xy 104.276692 -226.33862) (xy 104.227078 -226.358092)
			(xy 104.175116 -226.369952) (xy 104.121966 -226.373936) (xy 104.068816 -226.369952) (xy 104.016854 -226.358092)
			(xy 103.96724 -226.33862) (xy 103.921082 -226.311971) (xy 103.879411 -226.27874) (xy 103.843159 -226.239669)
			(xy 103.813135 -226.195632) (xy 103.790009 -226.147611) (xy 103.774299 -226.096681) (xy 103.766356 -226.043977)
			(xy 103.537776 -226.043977) (xy 103.529833 -226.096681) (xy 103.514123 -226.147611) (xy 103.490997 -226.195632)
			(xy 103.460973 -226.239669) (xy 103.424721 -226.27874) (xy 103.38305 -226.311971) (xy 103.336892 -226.33862)
			(xy 103.287278 -226.358092) (xy 103.235316 -226.369952) (xy 103.182166 -226.373936) (xy 103.129016 -226.369952)
			(xy 103.077054 -226.358092) (xy 103.02744 -226.33862) (xy 102.981282 -226.311971) (xy 102.939611 -226.27874)
			(xy 102.903359 -226.239669) (xy 102.873335 -226.195632) (xy 102.850209 -226.147611) (xy 102.834499 -226.096681)
			(xy 102.826556 -226.043977) (xy 102.597976 -226.043977) (xy 102.590033 -226.096681) (xy 102.574323 -226.147611)
			(xy 102.551197 -226.195632) (xy 102.521173 -226.239669) (xy 102.484921 -226.27874) (xy 102.44325 -226.311971)
			(xy 102.397092 -226.33862) (xy 102.347478 -226.358092) (xy 102.295516 -226.369952) (xy 102.242366 -226.373936)
			(xy 102.189216 -226.369952) (xy 102.137254 -226.358092) (xy 102.08764 -226.33862) (xy 102.041482 -226.311971)
			(xy 101.999811 -226.27874) (xy 101.963559 -226.239669) (xy 101.933535 -226.195632) (xy 101.910409 -226.147611)
			(xy 101.894699 -226.096681) (xy 101.886756 -226.043977) (xy 101.658176 -226.043977) (xy 101.650233 -226.096681)
			(xy 101.634523 -226.147611) (xy 101.611397 -226.195632) (xy 101.581373 -226.239669) (xy 101.545121 -226.27874)
			(xy 101.50345 -226.311971) (xy 101.457292 -226.33862) (xy 101.407678 -226.358092) (xy 101.355716 -226.369952)
			(xy 101.302566 -226.373936) (xy 101.249416 -226.369952) (xy 101.197454 -226.358092) (xy 101.14784 -226.33862)
			(xy 101.101682 -226.311971) (xy 101.060011 -226.27874) (xy 101.023759 -226.239669) (xy 100.993735 -226.195632)
			(xy 100.970609 -226.147611) (xy 100.954899 -226.096681) (xy 100.946956 -226.043977) (xy 100.718376 -226.043977)
			(xy 100.710433 -226.096681) (xy 100.694723 -226.147611) (xy 100.671597 -226.195632) (xy 100.641573 -226.239669)
			(xy 100.605321 -226.27874) (xy 100.56365 -226.311971) (xy 100.517492 -226.33862) (xy 100.467878 -226.358092)
			(xy 100.415916 -226.369952) (xy 100.362766 -226.373936) (xy 100.309616 -226.369952) (xy 100.257654 -226.358092)
			(xy 100.20804 -226.33862) (xy 100.161882 -226.311971) (xy 100.120211 -226.27874) (xy 100.083959 -226.239669)
			(xy 100.053935 -226.195632) (xy 100.030809 -226.147611) (xy 100.015099 -226.096681) (xy 100.007156 -226.043977)
			(xy 99.778576 -226.043977) (xy 99.770633 -226.096681) (xy 99.754923 -226.147611) (xy 99.731797 -226.195632)
			(xy 99.701773 -226.239669) (xy 99.665521 -226.27874) (xy 99.62385 -226.311971) (xy 99.577692 -226.33862)
			(xy 99.528078 -226.358092) (xy 99.476116 -226.369952) (xy 99.422966 -226.373936) (xy 99.369816 -226.369952)
			(xy 99.317854 -226.358092) (xy 99.26824 -226.33862) (xy 99.222082 -226.311971) (xy 99.180411 -226.27874)
			(xy 99.144159 -226.239669) (xy 99.114135 -226.195632) (xy 99.091009 -226.147611) (xy 99.075299 -226.096681)
			(xy 99.067356 -226.043977) (xy 98.838776 -226.043977) (xy 98.830833 -226.096681) (xy 98.815123 -226.147611)
			(xy 98.791997 -226.195632) (xy 98.761973 -226.239669) (xy 98.725721 -226.27874) (xy 98.68405 -226.311971)
			(xy 98.637892 -226.33862) (xy 98.588278 -226.358092) (xy 98.536316 -226.369952) (xy 98.483166 -226.373936)
			(xy 98.430016 -226.369952) (xy 98.378054 -226.358092) (xy 98.32844 -226.33862) (xy 98.282282 -226.311971)
			(xy 98.240611 -226.27874) (xy 98.204359 -226.239669) (xy 98.174335 -226.195632) (xy 98.151209 -226.147611)
			(xy 98.135499 -226.096681) (xy 98.127556 -226.043977) (xy 97.898976 -226.043977) (xy 97.891033 -226.096681)
			(xy 97.875323 -226.147611) (xy 97.852197 -226.195632) (xy 97.822173 -226.239669) (xy 97.785921 -226.27874)
			(xy 97.74425 -226.311971) (xy 97.698092 -226.33862) (xy 97.648478 -226.358092) (xy 97.596516 -226.369952)
			(xy 97.543366 -226.373936) (xy 97.490216 -226.369952) (xy 97.438254 -226.358092) (xy 97.38864 -226.33862)
			(xy 97.342482 -226.311971) (xy 97.300811 -226.27874) (xy 97.264559 -226.239669) (xy 97.234535 -226.195632)
			(xy 97.211409 -226.147611) (xy 97.195699 -226.096681) (xy 97.187756 -226.043977) (xy 96.959176 -226.043977)
			(xy 96.951233 -226.096681) (xy 96.935523 -226.147611) (xy 96.912397 -226.195632) (xy 96.882373 -226.239669)
			(xy 96.846121 -226.27874) (xy 96.80445 -226.311971) (xy 96.758292 -226.33862) (xy 96.708678 -226.358092)
			(xy 96.656716 -226.369952) (xy 96.603566 -226.373936) (xy 96.550416 -226.369952) (xy 96.498454 -226.358092)
			(xy 96.44884 -226.33862) (xy 96.402682 -226.311971) (xy 96.361011 -226.27874) (xy 96.324759 -226.239669)
			(xy 96.294735 -226.195632) (xy 96.271609 -226.147611) (xy 96.255899 -226.096681) (xy 96.247956 -226.043977)
			(xy 96.019376 -226.043977) (xy 96.011433 -226.096681) (xy 95.995723 -226.147611) (xy 95.972597 -226.195632)
			(xy 95.942573 -226.239669) (xy 95.906321 -226.27874) (xy 95.86465 -226.311971) (xy 95.818492 -226.33862)
			(xy 95.768878 -226.358092) (xy 95.716916 -226.369952) (xy 95.663766 -226.373936) (xy 95.610616 -226.369952)
			(xy 95.558654 -226.358092) (xy 95.50904 -226.33862) (xy 95.462882 -226.311971) (xy 95.421211 -226.27874)
			(xy 95.384959 -226.239669) (xy 95.354935 -226.195632) (xy 95.331809 -226.147611) (xy 95.316099 -226.096681)
			(xy 95.308156 -226.043977) (xy 95.079576 -226.043977) (xy 95.071633 -226.096681) (xy 95.055923 -226.147611)
			(xy 95.032797 -226.195632) (xy 95.002773 -226.239669) (xy 94.966521 -226.27874) (xy 94.92485 -226.311971)
			(xy 94.878692 -226.33862) (xy 94.829078 -226.358092) (xy 94.777116 -226.369952) (xy 94.723966 -226.373936)
			(xy 94.670816 -226.369952) (xy 94.618854 -226.358092) (xy 94.56924 -226.33862) (xy 94.523082 -226.311971)
			(xy 94.481411 -226.27874) (xy 94.445159 -226.239669) (xy 94.415135 -226.195632) (xy 94.392009 -226.147611)
			(xy 94.376299 -226.096681) (xy 94.368356 -226.043977) (xy 94.139776 -226.043977) (xy 94.131833 -226.096681)
			(xy 94.116123 -226.147611) (xy 94.092997 -226.195632) (xy 94.062973 -226.239669) (xy 94.026721 -226.27874)
			(xy 93.98505 -226.311971) (xy 93.938892 -226.33862) (xy 93.889278 -226.358092) (xy 93.837316 -226.369952)
			(xy 93.784166 -226.373936) (xy 93.731016 -226.369952) (xy 93.679054 -226.358092) (xy 93.62944 -226.33862)
			(xy 93.583282 -226.311971) (xy 93.541611 -226.27874) (xy 93.505359 -226.239669) (xy 93.475335 -226.195632)
			(xy 93.452209 -226.147611) (xy 93.436499 -226.096681) (xy 93.428556 -226.043977) (xy 93.199976 -226.043977)
			(xy 93.192033 -226.096681) (xy 93.176323 -226.147611) (xy 93.153197 -226.195632) (xy 93.123173 -226.239669)
			(xy 93.086921 -226.27874) (xy 93.04525 -226.311971) (xy 92.999092 -226.33862) (xy 92.949478 -226.358092)
			(xy 92.897516 -226.369952) (xy 92.844366 -226.373936) (xy 92.791216 -226.369952) (xy 92.739254 -226.358092)
			(xy 92.68964 -226.33862) (xy 92.643482 -226.311971) (xy 92.601811 -226.27874) (xy 92.565559 -226.239669)
			(xy 92.535535 -226.195632) (xy 92.512409 -226.147611) (xy 92.496699 -226.096681) (xy 92.488756 -226.043977)
			(xy 92.260176 -226.043977) (xy 92.252233 -226.096681) (xy 92.236523 -226.147611) (xy 92.213397 -226.195632)
			(xy 92.183373 -226.239669) (xy 92.147121 -226.27874) (xy 92.10545 -226.311971) (xy 92.059292 -226.33862)
			(xy 92.009678 -226.358092) (xy 91.957716 -226.369952) (xy 91.904566 -226.373936) (xy 91.851416 -226.369952)
			(xy 91.799454 -226.358092) (xy 91.74984 -226.33862) (xy 91.703682 -226.311971) (xy 91.662011 -226.27874)
			(xy 91.625759 -226.239669) (xy 91.595735 -226.195632) (xy 91.572609 -226.147611) (xy 91.556899 -226.096681)
			(xy 91.548956 -226.043977) (xy 91.320122 -226.043977) (xy 91.312179 -226.096681) (xy 91.296469 -226.147611)
			(xy 91.273343 -226.195632) (xy 91.243319 -226.239669) (xy 91.207067 -226.27874) (xy 91.165396 -226.311971)
			(xy 91.119238 -226.33862) (xy 91.069624 -226.358092) (xy 91.017662 -226.369952) (xy 90.964512 -226.373936)
			(xy 90.911362 -226.369952) (xy 90.8594 -226.358092) (xy 90.809786 -226.33862) (xy 90.763628 -226.311971)
			(xy 90.721957 -226.27874) (xy 90.685705 -226.239669) (xy 90.655681 -226.195632) (xy 90.632555 -226.147611)
			(xy 90.616845 -226.096681) (xy 90.608902 -226.043977) (xy 90.380576 -226.043977) (xy 90.372633 -226.096681)
			(xy 90.356923 -226.147611) (xy 90.333797 -226.195632) (xy 90.303773 -226.239669) (xy 90.267521 -226.27874)
			(xy 90.22585 -226.311971) (xy 90.179692 -226.33862) (xy 90.130078 -226.358092) (xy 90.078116 -226.369952)
			(xy 90.024966 -226.373936) (xy 89.971816 -226.369952) (xy 89.919854 -226.358092) (xy 89.87024 -226.33862)
			(xy 89.824082 -226.311971) (xy 89.782411 -226.27874) (xy 89.746159 -226.239669) (xy 89.716135 -226.195632)
			(xy 89.693009 -226.147611) (xy 89.677299 -226.096681) (xy 89.669356 -226.043977) (xy 89.439805 -226.043977)
			(xy 89.437821 -226.070452) (xy 89.425959 -226.122417) (xy 89.406485 -226.172033) (xy 89.379833 -226.218193)
			(xy 89.346598 -226.259864) (xy 89.307524 -226.296116) (xy 89.263482 -226.326139) (xy 89.215458 -226.349263)
			(xy 89.164523 -226.36497) (xy 89.111817 -226.372909) (xy 89.085166 -226.373436) (xy 89.074793 -226.37339)
			(xy 89.054079 -226.372248) (xy 89.043764 -226.37115) (xy 89.02951 -226.369989) (xy 89.001315 -226.374705)
			(xy 88.975531 -226.387051) (xy 88.954178 -226.406057) (xy 88.938929 -226.430237) (xy 88.930977 -226.457695)
			(xy 88.93048 -226.471988) (xy 88.93048 -226.665536) (xy 88.93556 -226.67595) (xy 88.946785 -226.700263)
			(xy 88.962626 -226.751417) (xy 88.970634 -226.804365) (xy 88.970628 -226.857793) (xy 89.199202 -226.857793)
			(xy 89.199202 -226.804495) (xy 89.207145 -226.751791) (xy 89.222855 -226.700861) (xy 89.245981 -226.65284)
			(xy 89.276005 -226.608803) (xy 89.312257 -226.569732) (xy 89.353928 -226.536501) (xy 89.400086 -226.509852)
			(xy 89.4497 -226.49038) (xy 89.501662 -226.47852) (xy 89.554812 -226.474537) (xy 89.607962 -226.47852)
			(xy 89.659924 -226.49038) (xy 89.709538 -226.509852) (xy 89.755696 -226.536501) (xy 89.797367 -226.569732)
			(xy 89.833619 -226.608803) (xy 89.863643 -226.65284) (xy 89.886769 -226.700861) (xy 89.902479 -226.751791)
			(xy 89.910422 -226.804495) (xy 89.91092 -226.831144) (xy 89.910422 -226.857793) (xy 90.139002 -226.857793)
			(xy 90.139002 -226.804495) (xy 90.146945 -226.751791) (xy 90.162655 -226.700861) (xy 90.185781 -226.65284)
			(xy 90.215805 -226.608803) (xy 90.252057 -226.569732) (xy 90.293728 -226.536501) (xy 90.339886 -226.509852)
			(xy 90.3895 -226.49038) (xy 90.441462 -226.47852) (xy 90.494612 -226.474537) (xy 90.547762 -226.47852)
			(xy 90.599724 -226.49038) (xy 90.649338 -226.509852) (xy 90.695496 -226.536501) (xy 90.737167 -226.569732)
			(xy 90.773419 -226.608803) (xy 90.803443 -226.65284) (xy 90.826569 -226.700861) (xy 90.842279 -226.751791)
			(xy 90.850222 -226.804495) (xy 90.85072 -226.831144) (xy 90.850222 -226.857793) (xy 91.079056 -226.857793)
			(xy 91.079056 -226.804495) (xy 91.086999 -226.751791) (xy 91.102709 -226.700861) (xy 91.125835 -226.65284)
			(xy 91.155859 -226.608803) (xy 91.192111 -226.569732) (xy 91.233782 -226.536501) (xy 91.27994 -226.509852)
			(xy 91.329554 -226.49038) (xy 91.381516 -226.47852) (xy 91.434666 -226.474537) (xy 91.487816 -226.47852)
			(xy 91.539778 -226.49038) (xy 91.589392 -226.509852) (xy 91.63555 -226.536501) (xy 91.677221 -226.569732)
			(xy 91.713473 -226.608803) (xy 91.743497 -226.65284) (xy 91.766623 -226.700861) (xy 91.782333 -226.751791)
			(xy 91.790276 -226.804495) (xy 91.790774 -226.831144) (xy 91.790276 -226.857793) (xy 92.018856 -226.857793)
			(xy 92.018856 -226.804495) (xy 92.026799 -226.751791) (xy 92.042509 -226.700861) (xy 92.065635 -226.65284)
			(xy 92.095659 -226.608803) (xy 92.131911 -226.569732) (xy 92.173582 -226.536501) (xy 92.21974 -226.509852)
			(xy 92.269354 -226.49038) (xy 92.321316 -226.47852) (xy 92.374466 -226.474537) (xy 92.427616 -226.47852)
			(xy 92.479578 -226.49038) (xy 92.529192 -226.509852) (xy 92.57535 -226.536501) (xy 92.617021 -226.569732)
			(xy 92.653273 -226.608803) (xy 92.683297 -226.65284) (xy 92.706423 -226.700861) (xy 92.722133 -226.751791)
			(xy 92.730076 -226.804495) (xy 92.730574 -226.831144) (xy 92.730076 -226.857793) (xy 92.958656 -226.857793)
			(xy 92.958656 -226.804495) (xy 92.966599 -226.751791) (xy 92.982309 -226.700861) (xy 93.005435 -226.65284)
			(xy 93.035459 -226.608803) (xy 93.071711 -226.569732) (xy 93.113382 -226.536501) (xy 93.15954 -226.509852)
			(xy 93.209154 -226.49038) (xy 93.261116 -226.47852) (xy 93.314266 -226.474537) (xy 93.367416 -226.47852)
			(xy 93.419378 -226.49038) (xy 93.468992 -226.509852) (xy 93.51515 -226.536501) (xy 93.556821 -226.569732)
			(xy 93.593073 -226.608803) (xy 93.623097 -226.65284) (xy 93.646223 -226.700861) (xy 93.661933 -226.751791)
			(xy 93.669876 -226.804495) (xy 93.670374 -226.831144) (xy 93.669876 -226.857793) (xy 93.898202 -226.857793)
			(xy 93.898202 -226.804495) (xy 93.906145 -226.751791) (xy 93.921855 -226.700861) (xy 93.944981 -226.65284)
			(xy 93.975005 -226.608803) (xy 94.011257 -226.569732) (xy 94.052928 -226.536501) (xy 94.099086 -226.509852)
			(xy 94.1487 -226.49038) (xy 94.200662 -226.47852) (xy 94.253812 -226.474537) (xy 94.306962 -226.47852)
			(xy 94.358924 -226.49038) (xy 94.408538 -226.509852) (xy 94.454696 -226.536501) (xy 94.496367 -226.569732)
			(xy 94.532619 -226.608803) (xy 94.562643 -226.65284) (xy 94.585769 -226.700861) (xy 94.601479 -226.751791)
			(xy 94.609422 -226.804495) (xy 94.60992 -226.831144) (xy 94.609422 -226.857793) (xy 94.838002 -226.857793)
			(xy 94.838002 -226.804495) (xy 94.845945 -226.751791) (xy 94.861655 -226.700861) (xy 94.884781 -226.65284)
			(xy 94.914805 -226.608803) (xy 94.951057 -226.569732) (xy 94.992728 -226.536501) (xy 95.038886 -226.509852)
			(xy 95.0885 -226.49038) (xy 95.140462 -226.47852) (xy 95.193612 -226.474537) (xy 95.246762 -226.47852)
			(xy 95.298724 -226.49038) (xy 95.348338 -226.509852) (xy 95.394496 -226.536501) (xy 95.436167 -226.569732)
			(xy 95.472419 -226.608803) (xy 95.502443 -226.65284) (xy 95.525569 -226.700861) (xy 95.541279 -226.751791)
			(xy 95.549222 -226.804495) (xy 95.54972 -226.831144) (xy 95.549222 -226.857793) (xy 95.778056 -226.857793)
			(xy 95.778056 -226.804495) (xy 95.785999 -226.751791) (xy 95.801709 -226.700861) (xy 95.824835 -226.65284)
			(xy 95.854859 -226.608803) (xy 95.891111 -226.569732) (xy 95.932782 -226.536501) (xy 95.97894 -226.509852)
			(xy 96.028554 -226.49038) (xy 96.080516 -226.47852) (xy 96.133666 -226.474537) (xy 96.186816 -226.47852)
			(xy 96.238778 -226.49038) (xy 96.288392 -226.509852) (xy 96.33455 -226.536501) (xy 96.376221 -226.569732)
			(xy 96.412473 -226.608803) (xy 96.442497 -226.65284) (xy 96.465623 -226.700861) (xy 96.481333 -226.751791)
			(xy 96.489276 -226.804495) (xy 96.489774 -226.831144) (xy 96.489276 -226.857793) (xy 96.717602 -226.857793)
			(xy 96.717602 -226.804495) (xy 96.725545 -226.751791) (xy 96.741255 -226.700861) (xy 96.764381 -226.65284)
			(xy 96.794405 -226.608803) (xy 96.830657 -226.569732) (xy 96.872328 -226.536501) (xy 96.918486 -226.509852)
			(xy 96.9681 -226.49038) (xy 97.020062 -226.47852) (xy 97.073212 -226.474537) (xy 97.126362 -226.47852)
			(xy 97.178324 -226.49038) (xy 97.227938 -226.509852) (xy 97.274096 -226.536501) (xy 97.315767 -226.569732)
			(xy 97.352019 -226.608803) (xy 97.382043 -226.65284) (xy 97.405169 -226.700861) (xy 97.420879 -226.751791)
			(xy 97.428822 -226.804495) (xy 97.42932 -226.831144) (xy 97.428822 -226.857793) (xy 97.657402 -226.857793)
			(xy 97.657402 -226.804495) (xy 97.665345 -226.751791) (xy 97.681055 -226.700861) (xy 97.704181 -226.65284)
			(xy 97.734205 -226.608803) (xy 97.770457 -226.569732) (xy 97.812128 -226.536501) (xy 97.858286 -226.509852)
			(xy 97.9079 -226.49038) (xy 97.959862 -226.47852) (xy 98.013012 -226.474537) (xy 98.066162 -226.47852)
			(xy 98.118124 -226.49038) (xy 98.167738 -226.509852) (xy 98.213896 -226.536501) (xy 98.255567 -226.569732)
			(xy 98.291819 -226.608803) (xy 98.321843 -226.65284) (xy 98.344969 -226.700861) (xy 98.360679 -226.751791)
			(xy 98.368622 -226.804495) (xy 98.36912 -226.831144) (xy 98.368622 -226.857793) (xy 98.597456 -226.857793)
			(xy 98.597456 -226.804495) (xy 98.605399 -226.751791) (xy 98.621109 -226.700861) (xy 98.644235 -226.65284)
			(xy 98.674259 -226.608803) (xy 98.710511 -226.569732) (xy 98.752182 -226.536501) (xy 98.79834 -226.509852)
			(xy 98.847954 -226.49038) (xy 98.899916 -226.47852) (xy 98.953066 -226.474537) (xy 99.006216 -226.47852)
			(xy 99.058178 -226.49038) (xy 99.107792 -226.509852) (xy 99.15395 -226.536501) (xy 99.195621 -226.569732)
			(xy 99.231873 -226.608803) (xy 99.261897 -226.65284) (xy 99.285023 -226.700861) (xy 99.300733 -226.751791)
			(xy 99.308676 -226.804495) (xy 99.309174 -226.831144) (xy 99.308676 -226.857793) (xy 99.537256 -226.857793)
			(xy 99.537256 -226.804495) (xy 99.545199 -226.751791) (xy 99.560909 -226.700861) (xy 99.584035 -226.65284)
			(xy 99.614059 -226.608803) (xy 99.650311 -226.569732) (xy 99.691982 -226.536501) (xy 99.73814 -226.509852)
			(xy 99.787754 -226.49038) (xy 99.839716 -226.47852) (xy 99.892866 -226.474537) (xy 99.946016 -226.47852)
			(xy 99.997978 -226.49038) (xy 100.047592 -226.509852) (xy 100.09375 -226.536501) (xy 100.135421 -226.569732)
			(xy 100.171673 -226.608803) (xy 100.201697 -226.65284) (xy 100.224823 -226.700861) (xy 100.240533 -226.751791)
			(xy 100.248476 -226.804495) (xy 100.248974 -226.831144) (xy 100.248476 -226.857793) (xy 100.477056 -226.857793)
			(xy 100.477056 -226.804495) (xy 100.484999 -226.751791) (xy 100.500709 -226.700861) (xy 100.523835 -226.65284)
			(xy 100.553859 -226.608803) (xy 100.590111 -226.569732) (xy 100.631782 -226.536501) (xy 100.67794 -226.509852)
			(xy 100.727554 -226.49038) (xy 100.779516 -226.47852) (xy 100.832666 -226.474537) (xy 100.885816 -226.47852)
			(xy 100.937778 -226.49038) (xy 100.987392 -226.509852) (xy 101.03355 -226.536501) (xy 101.075221 -226.569732)
			(xy 101.111473 -226.608803) (xy 101.141497 -226.65284) (xy 101.164623 -226.700861) (xy 101.180333 -226.751791)
			(xy 101.188276 -226.804495) (xy 101.188774 -226.831144) (xy 101.188276 -226.857793) (xy 101.416602 -226.857793)
			(xy 101.416602 -226.804495) (xy 101.424545 -226.751791) (xy 101.440255 -226.700861) (xy 101.463381 -226.65284)
			(xy 101.493405 -226.608803) (xy 101.529657 -226.569732) (xy 101.571328 -226.536501) (xy 101.617486 -226.509852)
			(xy 101.6671 -226.49038) (xy 101.719062 -226.47852) (xy 101.772212 -226.474537) (xy 101.825362 -226.47852)
			(xy 101.877324 -226.49038) (xy 101.926938 -226.509852) (xy 101.973096 -226.536501) (xy 102.014767 -226.569732)
			(xy 102.051019 -226.608803) (xy 102.081043 -226.65284) (xy 102.104169 -226.700861) (xy 102.119879 -226.751791)
			(xy 102.127822 -226.804495) (xy 102.12832 -226.831144) (xy 102.127822 -226.857793) (xy 102.356402 -226.857793)
			(xy 102.356402 -226.804495) (xy 102.364345 -226.751791) (xy 102.380055 -226.700861) (xy 102.403181 -226.65284)
			(xy 102.433205 -226.608803) (xy 102.469457 -226.569732) (xy 102.511128 -226.536501) (xy 102.557286 -226.509852)
			(xy 102.6069 -226.49038) (xy 102.658862 -226.47852) (xy 102.712012 -226.474537) (xy 102.765162 -226.47852)
			(xy 102.817124 -226.49038) (xy 102.866738 -226.509852) (xy 102.912896 -226.536501) (xy 102.954567 -226.569732)
			(xy 102.990819 -226.608803) (xy 103.020843 -226.65284) (xy 103.043969 -226.700861) (xy 103.059679 -226.751791)
			(xy 103.067622 -226.804495) (xy 103.06812 -226.831144) (xy 103.067622 -226.857793) (xy 103.296456 -226.857793)
			(xy 103.296456 -226.804495) (xy 103.304399 -226.751791) (xy 103.320109 -226.700861) (xy 103.343235 -226.65284)
			(xy 103.373259 -226.608803) (xy 103.409511 -226.569732) (xy 103.451182 -226.536501) (xy 103.49734 -226.509852)
			(xy 103.546954 -226.49038) (xy 103.598916 -226.47852) (xy 103.652066 -226.474537) (xy 103.705216 -226.47852)
			(xy 103.757178 -226.49038) (xy 103.806792 -226.509852) (xy 103.85295 -226.536501) (xy 103.894621 -226.569732)
			(xy 103.930873 -226.608803) (xy 103.960897 -226.65284) (xy 103.984023 -226.700861) (xy 103.999733 -226.751791)
			(xy 104.007676 -226.804495) (xy 104.008174 -226.831144) (xy 104.007676 -226.857793) (xy 104.236256 -226.857793)
			(xy 104.236256 -226.804495) (xy 104.244199 -226.751791) (xy 104.259909 -226.700861) (xy 104.283035 -226.65284)
			(xy 104.313059 -226.608803) (xy 104.349311 -226.569732) (xy 104.390982 -226.536501) (xy 104.43714 -226.509852)
			(xy 104.486754 -226.49038) (xy 104.538716 -226.47852) (xy 104.591866 -226.474537) (xy 104.645016 -226.47852)
			(xy 104.696978 -226.49038) (xy 104.746592 -226.509852) (xy 104.79275 -226.536501) (xy 104.834421 -226.569732)
			(xy 104.870673 -226.608803) (xy 104.900697 -226.65284) (xy 104.923823 -226.700861) (xy 104.939533 -226.751791)
			(xy 104.947476 -226.804495) (xy 104.947974 -226.831144) (xy 104.947476 -226.857793) (xy 105.175802 -226.857793)
			(xy 105.175802 -226.804495) (xy 105.183745 -226.751791) (xy 105.199455 -226.700861) (xy 105.222581 -226.65284)
			(xy 105.252605 -226.608803) (xy 105.288857 -226.569732) (xy 105.330528 -226.536501) (xy 105.376686 -226.509852)
			(xy 105.4263 -226.49038) (xy 105.478262 -226.47852) (xy 105.531412 -226.474537) (xy 105.584562 -226.47852)
			(xy 105.636524 -226.49038) (xy 105.686138 -226.509852) (xy 105.732296 -226.536501) (xy 105.773967 -226.569732)
			(xy 105.810219 -226.608803) (xy 105.840243 -226.65284) (xy 105.863369 -226.700861) (xy 105.879079 -226.751791)
			(xy 105.887022 -226.804495) (xy 105.88752 -226.831144) (xy 105.887022 -226.857793) (xy 106.115856 -226.857793)
			(xy 106.115856 -226.804495) (xy 106.123799 -226.751791) (xy 106.139509 -226.700861) (xy 106.162635 -226.65284)
			(xy 106.192659 -226.608803) (xy 106.228911 -226.569732) (xy 106.270582 -226.536501) (xy 106.31674 -226.509852)
			(xy 106.366354 -226.49038) (xy 106.418316 -226.47852) (xy 106.471466 -226.474537) (xy 106.524616 -226.47852)
			(xy 106.576578 -226.49038) (xy 106.626192 -226.509852) (xy 106.67235 -226.536501) (xy 106.714021 -226.569732)
			(xy 106.750273 -226.608803) (xy 106.780297 -226.65284) (xy 106.803423 -226.700861) (xy 106.819133 -226.751791)
			(xy 106.827076 -226.804495) (xy 106.827574 -226.831144) (xy 106.827076 -226.857793) (xy 107.055402 -226.857793)
			(xy 107.055402 -226.804495) (xy 107.063345 -226.751791) (xy 107.079055 -226.700861) (xy 107.102181 -226.65284)
			(xy 107.132205 -226.608803) (xy 107.168457 -226.569732) (xy 107.210128 -226.536501) (xy 107.256286 -226.509852)
			(xy 107.3059 -226.49038) (xy 107.357862 -226.47852) (xy 107.411012 -226.474537) (xy 107.464162 -226.47852)
			(xy 107.516124 -226.49038) (xy 107.565738 -226.509852) (xy 107.611896 -226.536501) (xy 107.653567 -226.569732)
			(xy 107.689819 -226.608803) (xy 107.719843 -226.65284) (xy 107.742969 -226.700861) (xy 107.758679 -226.751791)
			(xy 107.766622 -226.804495) (xy 107.76712 -226.831144) (xy 107.766622 -226.857793) (xy 107.995456 -226.857793)
			(xy 107.995456 -226.804495) (xy 108.003399 -226.751791) (xy 108.019109 -226.700861) (xy 108.042235 -226.65284)
			(xy 108.072259 -226.608803) (xy 108.108511 -226.569732) (xy 108.150182 -226.536501) (xy 108.19634 -226.509852)
			(xy 108.245954 -226.49038) (xy 108.297916 -226.47852) (xy 108.351066 -226.474537) (xy 108.404216 -226.47852)
			(xy 108.456178 -226.49038) (xy 108.505792 -226.509852) (xy 108.55195 -226.536501) (xy 108.593621 -226.569732)
			(xy 108.629873 -226.608803) (xy 108.659897 -226.65284) (xy 108.683023 -226.700861) (xy 108.698733 -226.751791)
			(xy 108.706676 -226.804495) (xy 108.707174 -226.831144) (xy 108.706676 -226.857793) (xy 108.935002 -226.857793)
			(xy 108.935002 -226.804495) (xy 108.942945 -226.751791) (xy 108.958655 -226.700861) (xy 108.981781 -226.65284)
			(xy 109.011805 -226.608803) (xy 109.048057 -226.569732) (xy 109.089728 -226.536501) (xy 109.135886 -226.509852)
			(xy 109.1855 -226.49038) (xy 109.237462 -226.47852) (xy 109.290612 -226.474537) (xy 109.343762 -226.47852)
			(xy 109.395724 -226.49038) (xy 109.445338 -226.509852) (xy 109.491496 -226.536501) (xy 109.533167 -226.569732)
			(xy 109.569419 -226.608803) (xy 109.599443 -226.65284) (xy 109.622569 -226.700861) (xy 109.638279 -226.751791)
			(xy 109.646222 -226.804495) (xy 109.64672 -226.831144) (xy 109.646222 -226.857793) (xy 109.875056 -226.857793)
			(xy 109.875056 -226.804495) (xy 109.882999 -226.751791) (xy 109.898709 -226.700861) (xy 109.921835 -226.65284)
			(xy 109.951859 -226.608803) (xy 109.988111 -226.569732) (xy 110.029782 -226.536501) (xy 110.07594 -226.509852)
			(xy 110.125554 -226.49038) (xy 110.177516 -226.47852) (xy 110.230666 -226.474537) (xy 110.283816 -226.47852)
			(xy 110.335778 -226.49038) (xy 110.385392 -226.509852) (xy 110.43155 -226.536501) (xy 110.473221 -226.569732)
			(xy 110.509473 -226.608803) (xy 110.539497 -226.65284) (xy 110.562623 -226.700861) (xy 110.578333 -226.751791)
			(xy 110.586276 -226.804495) (xy 110.586774 -226.831144) (xy 110.586276 -226.857793) (xy 110.578333 -226.910497)
			(xy 110.562623 -226.961427) (xy 110.539497 -227.009448) (xy 110.509473 -227.053485) (xy 110.473221 -227.092556)
			(xy 110.43155 -227.125787) (xy 110.385392 -227.152436) (xy 110.335778 -227.171908) (xy 110.283816 -227.183768)
			(xy 110.230666 -227.187752) (xy 110.177516 -227.183768) (xy 110.125554 -227.171908) (xy 110.07594 -227.152436)
			(xy 110.029782 -227.125787) (xy 109.988111 -227.092556) (xy 109.951859 -227.053485) (xy 109.921835 -227.009448)
			(xy 109.898709 -226.961427) (xy 109.882999 -226.910497) (xy 109.875056 -226.857793) (xy 109.646222 -226.857793)
			(xy 109.638279 -226.910497) (xy 109.622569 -226.961427) (xy 109.599443 -227.009448) (xy 109.569419 -227.053485)
			(xy 109.533167 -227.092556) (xy 109.491496 -227.125787) (xy 109.445338 -227.152436) (xy 109.395724 -227.171908)
			(xy 109.343762 -227.183768) (xy 109.290612 -227.187752) (xy 109.237462 -227.183768) (xy 109.1855 -227.171908)
			(xy 109.135886 -227.152436) (xy 109.089728 -227.125787) (xy 109.048057 -227.092556) (xy 109.011805 -227.053485)
			(xy 108.981781 -227.009448) (xy 108.958655 -226.961427) (xy 108.942945 -226.910497) (xy 108.935002 -226.857793)
			(xy 108.706676 -226.857793) (xy 108.698733 -226.910497) (xy 108.683023 -226.961427) (xy 108.659897 -227.009448)
			(xy 108.629873 -227.053485) (xy 108.593621 -227.092556) (xy 108.55195 -227.125787) (xy 108.505792 -227.152436)
			(xy 108.456178 -227.171908) (xy 108.404216 -227.183768) (xy 108.351066 -227.187752) (xy 108.297916 -227.183768)
			(xy 108.245954 -227.171908) (xy 108.19634 -227.152436) (xy 108.150182 -227.125787) (xy 108.108511 -227.092556)
			(xy 108.072259 -227.053485) (xy 108.042235 -227.009448) (xy 108.019109 -226.961427) (xy 108.003399 -226.910497)
			(xy 107.995456 -226.857793) (xy 107.766622 -226.857793) (xy 107.758679 -226.910497) (xy 107.742969 -226.961427)
			(xy 107.719843 -227.009448) (xy 107.689819 -227.053485) (xy 107.653567 -227.092556) (xy 107.611896 -227.125787)
			(xy 107.565738 -227.152436) (xy 107.516124 -227.171908) (xy 107.464162 -227.183768) (xy 107.411012 -227.187752)
			(xy 107.357862 -227.183768) (xy 107.3059 -227.171908) (xy 107.256286 -227.152436) (xy 107.210128 -227.125787)
			(xy 107.168457 -227.092556) (xy 107.132205 -227.053485) (xy 107.102181 -227.009448) (xy 107.079055 -226.961427)
			(xy 107.063345 -226.910497) (xy 107.055402 -226.857793) (xy 106.827076 -226.857793) (xy 106.819133 -226.910497)
			(xy 106.803423 -226.961427) (xy 106.780297 -227.009448) (xy 106.750273 -227.053485) (xy 106.714021 -227.092556)
			(xy 106.67235 -227.125787) (xy 106.626192 -227.152436) (xy 106.576578 -227.171908) (xy 106.524616 -227.183768)
			(xy 106.471466 -227.187752) (xy 106.418316 -227.183768) (xy 106.366354 -227.171908) (xy 106.31674 -227.152436)
			(xy 106.270582 -227.125787) (xy 106.228911 -227.092556) (xy 106.192659 -227.053485) (xy 106.162635 -227.009448)
			(xy 106.139509 -226.961427) (xy 106.123799 -226.910497) (xy 106.115856 -226.857793) (xy 105.887022 -226.857793)
			(xy 105.879079 -226.910497) (xy 105.863369 -226.961427) (xy 105.840243 -227.009448) (xy 105.810219 -227.053485)
			(xy 105.773967 -227.092556) (xy 105.732296 -227.125787) (xy 105.686138 -227.152436) (xy 105.636524 -227.171908)
			(xy 105.584562 -227.183768) (xy 105.531412 -227.187752) (xy 105.478262 -227.183768) (xy 105.4263 -227.171908)
			(xy 105.376686 -227.152436) (xy 105.330528 -227.125787) (xy 105.288857 -227.092556) (xy 105.252605 -227.053485)
			(xy 105.222581 -227.009448) (xy 105.199455 -226.961427) (xy 105.183745 -226.910497) (xy 105.175802 -226.857793)
			(xy 104.947476 -226.857793) (xy 104.939533 -226.910497) (xy 104.923823 -226.961427) (xy 104.900697 -227.009448)
			(xy 104.870673 -227.053485) (xy 104.834421 -227.092556) (xy 104.79275 -227.125787) (xy 104.746592 -227.152436)
			(xy 104.696978 -227.171908) (xy 104.645016 -227.183768) (xy 104.591866 -227.187752) (xy 104.538716 -227.183768)
			(xy 104.486754 -227.171908) (xy 104.43714 -227.152436) (xy 104.390982 -227.125787) (xy 104.349311 -227.092556)
			(xy 104.313059 -227.053485) (xy 104.283035 -227.009448) (xy 104.259909 -226.961427) (xy 104.244199 -226.910497)
			(xy 104.236256 -226.857793) (xy 104.007676 -226.857793) (xy 103.999733 -226.910497) (xy 103.984023 -226.961427)
			(xy 103.960897 -227.009448) (xy 103.930873 -227.053485) (xy 103.894621 -227.092556) (xy 103.85295 -227.125787)
			(xy 103.806792 -227.152436) (xy 103.757178 -227.171908) (xy 103.705216 -227.183768) (xy 103.652066 -227.187752)
			(xy 103.598916 -227.183768) (xy 103.546954 -227.171908) (xy 103.49734 -227.152436) (xy 103.451182 -227.125787)
			(xy 103.409511 -227.092556) (xy 103.373259 -227.053485) (xy 103.343235 -227.009448) (xy 103.320109 -226.961427)
			(xy 103.304399 -226.910497) (xy 103.296456 -226.857793) (xy 103.067622 -226.857793) (xy 103.059679 -226.910497)
			(xy 103.043969 -226.961427) (xy 103.020843 -227.009448) (xy 102.990819 -227.053485) (xy 102.954567 -227.092556)
			(xy 102.912896 -227.125787) (xy 102.866738 -227.152436) (xy 102.817124 -227.171908) (xy 102.765162 -227.183768)
			(xy 102.712012 -227.187752) (xy 102.658862 -227.183768) (xy 102.6069 -227.171908) (xy 102.557286 -227.152436)
			(xy 102.511128 -227.125787) (xy 102.469457 -227.092556) (xy 102.433205 -227.053485) (xy 102.403181 -227.009448)
			(xy 102.380055 -226.961427) (xy 102.364345 -226.910497) (xy 102.356402 -226.857793) (xy 102.127822 -226.857793)
			(xy 102.119879 -226.910497) (xy 102.104169 -226.961427) (xy 102.081043 -227.009448) (xy 102.051019 -227.053485)
			(xy 102.014767 -227.092556) (xy 101.973096 -227.125787) (xy 101.926938 -227.152436) (xy 101.877324 -227.171908)
			(xy 101.825362 -227.183768) (xy 101.772212 -227.187752) (xy 101.719062 -227.183768) (xy 101.6671 -227.171908)
			(xy 101.617486 -227.152436) (xy 101.571328 -227.125787) (xy 101.529657 -227.092556) (xy 101.493405 -227.053485)
			(xy 101.463381 -227.009448) (xy 101.440255 -226.961427) (xy 101.424545 -226.910497) (xy 101.416602 -226.857793)
			(xy 101.188276 -226.857793) (xy 101.180333 -226.910497) (xy 101.164623 -226.961427) (xy 101.141497 -227.009448)
			(xy 101.111473 -227.053485) (xy 101.075221 -227.092556) (xy 101.03355 -227.125787) (xy 100.987392 -227.152436)
			(xy 100.937778 -227.171908) (xy 100.885816 -227.183768) (xy 100.832666 -227.187752) (xy 100.779516 -227.183768)
			(xy 100.727554 -227.171908) (xy 100.67794 -227.152436) (xy 100.631782 -227.125787) (xy 100.590111 -227.092556)
			(xy 100.553859 -227.053485) (xy 100.523835 -227.009448) (xy 100.500709 -226.961427) (xy 100.484999 -226.910497)
			(xy 100.477056 -226.857793) (xy 100.248476 -226.857793) (xy 100.240533 -226.910497) (xy 100.224823 -226.961427)
			(xy 100.201697 -227.009448) (xy 100.171673 -227.053485) (xy 100.135421 -227.092556) (xy 100.09375 -227.125787)
			(xy 100.047592 -227.152436) (xy 99.997978 -227.171908) (xy 99.946016 -227.183768) (xy 99.892866 -227.187752)
			(xy 99.839716 -227.183768) (xy 99.787754 -227.171908) (xy 99.73814 -227.152436) (xy 99.691982 -227.125787)
			(xy 99.650311 -227.092556) (xy 99.614059 -227.053485) (xy 99.584035 -227.009448) (xy 99.560909 -226.961427)
			(xy 99.545199 -226.910497) (xy 99.537256 -226.857793) (xy 99.308676 -226.857793) (xy 99.300733 -226.910497)
			(xy 99.285023 -226.961427) (xy 99.261897 -227.009448) (xy 99.231873 -227.053485) (xy 99.195621 -227.092556)
			(xy 99.15395 -227.125787) (xy 99.107792 -227.152436) (xy 99.058178 -227.171908) (xy 99.006216 -227.183768)
			(xy 98.953066 -227.187752) (xy 98.899916 -227.183768) (xy 98.847954 -227.171908) (xy 98.79834 -227.152436)
			(xy 98.752182 -227.125787) (xy 98.710511 -227.092556) (xy 98.674259 -227.053485) (xy 98.644235 -227.009448)
			(xy 98.621109 -226.961427) (xy 98.605399 -226.910497) (xy 98.597456 -226.857793) (xy 98.368622 -226.857793)
			(xy 98.360679 -226.910497) (xy 98.344969 -226.961427) (xy 98.321843 -227.009448) (xy 98.291819 -227.053485)
			(xy 98.255567 -227.092556) (xy 98.213896 -227.125787) (xy 98.167738 -227.152436) (xy 98.118124 -227.171908)
			(xy 98.066162 -227.183768) (xy 98.013012 -227.187752) (xy 97.959862 -227.183768) (xy 97.9079 -227.171908)
			(xy 97.858286 -227.152436) (xy 97.812128 -227.125787) (xy 97.770457 -227.092556) (xy 97.734205 -227.053485)
			(xy 97.704181 -227.009448) (xy 97.681055 -226.961427) (xy 97.665345 -226.910497) (xy 97.657402 -226.857793)
			(xy 97.428822 -226.857793) (xy 97.420879 -226.910497) (xy 97.405169 -226.961427) (xy 97.382043 -227.009448)
			(xy 97.352019 -227.053485) (xy 97.315767 -227.092556) (xy 97.274096 -227.125787) (xy 97.227938 -227.152436)
			(xy 97.178324 -227.171908) (xy 97.126362 -227.183768) (xy 97.073212 -227.187752) (xy 97.020062 -227.183768)
			(xy 96.9681 -227.171908) (xy 96.918486 -227.152436) (xy 96.872328 -227.125787) (xy 96.830657 -227.092556)
			(xy 96.794405 -227.053485) (xy 96.764381 -227.009448) (xy 96.741255 -226.961427) (xy 96.725545 -226.910497)
			(xy 96.717602 -226.857793) (xy 96.489276 -226.857793) (xy 96.481333 -226.910497) (xy 96.465623 -226.961427)
			(xy 96.442497 -227.009448) (xy 96.412473 -227.053485) (xy 96.376221 -227.092556) (xy 96.33455 -227.125787)
			(xy 96.288392 -227.152436) (xy 96.238778 -227.171908) (xy 96.186816 -227.183768) (xy 96.133666 -227.187752)
			(xy 96.080516 -227.183768) (xy 96.028554 -227.171908) (xy 95.97894 -227.152436) (xy 95.932782 -227.125787)
			(xy 95.891111 -227.092556) (xy 95.854859 -227.053485) (xy 95.824835 -227.009448) (xy 95.801709 -226.961427)
			(xy 95.785999 -226.910497) (xy 95.778056 -226.857793) (xy 95.549222 -226.857793) (xy 95.541279 -226.910497)
			(xy 95.525569 -226.961427) (xy 95.502443 -227.009448) (xy 95.472419 -227.053485) (xy 95.436167 -227.092556)
			(xy 95.394496 -227.125787) (xy 95.348338 -227.152436) (xy 95.298724 -227.171908) (xy 95.246762 -227.183768)
			(xy 95.193612 -227.187752) (xy 95.140462 -227.183768) (xy 95.0885 -227.171908) (xy 95.038886 -227.152436)
			(xy 94.992728 -227.125787) (xy 94.951057 -227.092556) (xy 94.914805 -227.053485) (xy 94.884781 -227.009448)
			(xy 94.861655 -226.961427) (xy 94.845945 -226.910497) (xy 94.838002 -226.857793) (xy 94.609422 -226.857793)
			(xy 94.601479 -226.910497) (xy 94.585769 -226.961427) (xy 94.562643 -227.009448) (xy 94.532619 -227.053485)
			(xy 94.496367 -227.092556) (xy 94.454696 -227.125787) (xy 94.408538 -227.152436) (xy 94.358924 -227.171908)
			(xy 94.306962 -227.183768) (xy 94.253812 -227.187752) (xy 94.200662 -227.183768) (xy 94.1487 -227.171908)
			(xy 94.099086 -227.152436) (xy 94.052928 -227.125787) (xy 94.011257 -227.092556) (xy 93.975005 -227.053485)
			(xy 93.944981 -227.009448) (xy 93.921855 -226.961427) (xy 93.906145 -226.910497) (xy 93.898202 -226.857793)
			(xy 93.669876 -226.857793) (xy 93.661933 -226.910497) (xy 93.646223 -226.961427) (xy 93.623097 -227.009448)
			(xy 93.593073 -227.053485) (xy 93.556821 -227.092556) (xy 93.51515 -227.125787) (xy 93.468992 -227.152436)
			(xy 93.419378 -227.171908) (xy 93.367416 -227.183768) (xy 93.314266 -227.187752) (xy 93.261116 -227.183768)
			(xy 93.209154 -227.171908) (xy 93.15954 -227.152436) (xy 93.113382 -227.125787) (xy 93.071711 -227.092556)
			(xy 93.035459 -227.053485) (xy 93.005435 -227.009448) (xy 92.982309 -226.961427) (xy 92.966599 -226.910497)
			(xy 92.958656 -226.857793) (xy 92.730076 -226.857793) (xy 92.722133 -226.910497) (xy 92.706423 -226.961427)
			(xy 92.683297 -227.009448) (xy 92.653273 -227.053485) (xy 92.617021 -227.092556) (xy 92.57535 -227.125787)
			(xy 92.529192 -227.152436) (xy 92.479578 -227.171908) (xy 92.427616 -227.183768) (xy 92.374466 -227.187752)
			(xy 92.321316 -227.183768) (xy 92.269354 -227.171908) (xy 92.21974 -227.152436) (xy 92.173582 -227.125787)
			(xy 92.131911 -227.092556) (xy 92.095659 -227.053485) (xy 92.065635 -227.009448) (xy 92.042509 -226.961427)
			(xy 92.026799 -226.910497) (xy 92.018856 -226.857793) (xy 91.790276 -226.857793) (xy 91.782333 -226.910497)
			(xy 91.766623 -226.961427) (xy 91.743497 -227.009448) (xy 91.713473 -227.053485) (xy 91.677221 -227.092556)
			(xy 91.63555 -227.125787) (xy 91.589392 -227.152436) (xy 91.539778 -227.171908) (xy 91.487816 -227.183768)
			(xy 91.434666 -227.187752) (xy 91.381516 -227.183768) (xy 91.329554 -227.171908) (xy 91.27994 -227.152436)
			(xy 91.233782 -227.125787) (xy 91.192111 -227.092556) (xy 91.155859 -227.053485) (xy 91.125835 -227.009448)
			(xy 91.102709 -226.961427) (xy 91.086999 -226.910497) (xy 91.079056 -226.857793) (xy 90.850222 -226.857793)
			(xy 90.842279 -226.910497) (xy 90.826569 -226.961427) (xy 90.803443 -227.009448) (xy 90.773419 -227.053485)
			(xy 90.737167 -227.092556) (xy 90.695496 -227.125787) (xy 90.649338 -227.152436) (xy 90.599724 -227.171908)
			(xy 90.547762 -227.183768) (xy 90.494612 -227.187752) (xy 90.441462 -227.183768) (xy 90.3895 -227.171908)
			(xy 90.339886 -227.152436) (xy 90.293728 -227.125787) (xy 90.252057 -227.092556) (xy 90.215805 -227.053485)
			(xy 90.185781 -227.009448) (xy 90.162655 -226.961427) (xy 90.146945 -226.910497) (xy 90.139002 -226.857793)
			(xy 89.910422 -226.857793) (xy 89.902479 -226.910497) (xy 89.886769 -226.961427) (xy 89.863643 -227.009448)
			(xy 89.833619 -227.053485) (xy 89.797367 -227.092556) (xy 89.755696 -227.125787) (xy 89.709538 -227.152436)
			(xy 89.659924 -227.171908) (xy 89.607962 -227.183768) (xy 89.554812 -227.187752) (xy 89.501662 -227.183768)
			(xy 89.4497 -227.171908) (xy 89.400086 -227.152436) (xy 89.353928 -227.125787) (xy 89.312257 -227.092556)
			(xy 89.276005 -227.053485) (xy 89.245981 -227.009448) (xy 89.222855 -226.961427) (xy 89.207145 -226.910497)
			(xy 89.199202 -226.857793) (xy 88.970628 -226.857793) (xy 88.970628 -226.857915) (xy 88.962609 -226.910861)
			(xy 88.946756 -226.962011) (xy 88.93556 -226.986338) (xy 88.93048 -226.996752) (xy 88.93048 -227.1903)
			(xy 88.930953 -227.204602) (xy 88.938871 -227.232086) (xy 88.954113 -227.256288) (xy 88.975478 -227.275304)
			(xy 89.001285 -227.287636) (xy 89.029503 -227.292313) (xy 89.043764 -227.291138) (xy 89.054078 -227.290034)
			(xy 89.074793 -227.28889) (xy 89.085166 -227.288852) (xy 89.111822 -227.289323) (xy 89.164539 -227.297264)
			(xy 89.215483 -227.312974) (xy 89.263516 -227.336102) (xy 89.307566 -227.36613) (xy 89.346648 -227.40239)
			(xy 89.379889 -227.444069) (xy 89.406546 -227.490237) (xy 89.426024 -227.539863) (xy 89.437888 -227.591838)
			(xy 89.441872 -227.645) (xy 89.439878 -227.671609) (xy 89.669356 -227.671609) (xy 89.669356 -227.618311)
			(xy 89.677299 -227.565607) (xy 89.693009 -227.514677) (xy 89.716135 -227.466656) (xy 89.746159 -227.422619)
			(xy 89.782411 -227.383548) (xy 89.824082 -227.350317) (xy 89.87024 -227.323668) (xy 89.919854 -227.304196)
			(xy 89.971816 -227.292336) (xy 90.024966 -227.288353) (xy 90.078116 -227.292336) (xy 90.130078 -227.304196)
			(xy 90.179692 -227.323668) (xy 90.22585 -227.350317) (xy 90.267521 -227.383548) (xy 90.303773 -227.422619)
			(xy 90.333797 -227.466656) (xy 90.356923 -227.514677) (xy 90.372633 -227.565607) (xy 90.380576 -227.618311)
			(xy 90.381074 -227.64496) (xy 90.380576 -227.671609) (xy 90.609156 -227.671609) (xy 90.609156 -227.618311)
			(xy 90.617099 -227.565607) (xy 90.632809 -227.514677) (xy 90.655935 -227.466656) (xy 90.685959 -227.422619)
			(xy 90.722211 -227.383548) (xy 90.763882 -227.350317) (xy 90.81004 -227.323668) (xy 90.859654 -227.304196)
			(xy 90.911616 -227.292336) (xy 90.964766 -227.288353) (xy 91.017916 -227.292336) (xy 91.069878 -227.304196)
			(xy 91.119492 -227.323668) (xy 91.16565 -227.350317) (xy 91.207321 -227.383548) (xy 91.243573 -227.422619)
			(xy 91.273597 -227.466656) (xy 91.296723 -227.514677) (xy 91.312433 -227.565607) (xy 91.320376 -227.618311)
			(xy 91.320874 -227.64496) (xy 91.320376 -227.671609) (xy 91.548702 -227.671609) (xy 91.548702 -227.618311)
			(xy 91.556645 -227.565607) (xy 91.572355 -227.514677) (xy 91.595481 -227.466656) (xy 91.625505 -227.422619)
			(xy 91.661757 -227.383548) (xy 91.703428 -227.350317) (xy 91.749586 -227.323668) (xy 91.7992 -227.304196)
			(xy 91.851162 -227.292336) (xy 91.904312 -227.288353) (xy 91.957462 -227.292336) (xy 92.009424 -227.304196)
			(xy 92.059038 -227.323668) (xy 92.105196 -227.350317) (xy 92.146867 -227.383548) (xy 92.183119 -227.422619)
			(xy 92.213143 -227.466656) (xy 92.236269 -227.514677) (xy 92.251979 -227.565607) (xy 92.259922 -227.618311)
			(xy 92.26042 -227.64496) (xy 92.259922 -227.671609) (xy 92.488756 -227.671609) (xy 92.488756 -227.618311)
			(xy 92.496699 -227.565607) (xy 92.512409 -227.514677) (xy 92.535535 -227.466656) (xy 92.565559 -227.422619)
			(xy 92.601811 -227.383548) (xy 92.643482 -227.350317) (xy 92.68964 -227.323668) (xy 92.739254 -227.304196)
			(xy 92.791216 -227.292336) (xy 92.844366 -227.288353) (xy 92.897516 -227.292336) (xy 92.949478 -227.304196)
			(xy 92.999092 -227.323668) (xy 93.04525 -227.350317) (xy 93.086921 -227.383548) (xy 93.123173 -227.422619)
			(xy 93.153197 -227.466656) (xy 93.176323 -227.514677) (xy 93.192033 -227.565607) (xy 93.199976 -227.618311)
			(xy 93.200474 -227.64496) (xy 93.199976 -227.671609) (xy 93.428556 -227.671609) (xy 93.428556 -227.618311)
			(xy 93.436499 -227.565607) (xy 93.452209 -227.514677) (xy 93.475335 -227.466656) (xy 93.505359 -227.422619)
			(xy 93.541611 -227.383548) (xy 93.583282 -227.350317) (xy 93.62944 -227.323668) (xy 93.679054 -227.304196)
			(xy 93.731016 -227.292336) (xy 93.784166 -227.288353) (xy 93.837316 -227.292336) (xy 93.889278 -227.304196)
			(xy 93.938892 -227.323668) (xy 93.98505 -227.350317) (xy 94.026721 -227.383548) (xy 94.062973 -227.422619)
			(xy 94.092997 -227.466656) (xy 94.116123 -227.514677) (xy 94.131833 -227.565607) (xy 94.139776 -227.618311)
			(xy 94.140274 -227.64496) (xy 94.139776 -227.671609) (xy 94.368356 -227.671609) (xy 94.368356 -227.618311)
			(xy 94.376299 -227.565607) (xy 94.392009 -227.514677) (xy 94.415135 -227.466656) (xy 94.445159 -227.422619)
			(xy 94.481411 -227.383548) (xy 94.523082 -227.350317) (xy 94.56924 -227.323668) (xy 94.618854 -227.304196)
			(xy 94.670816 -227.292336) (xy 94.723966 -227.288353) (xy 94.777116 -227.292336) (xy 94.829078 -227.304196)
			(xy 94.878692 -227.323668) (xy 94.92485 -227.350317) (xy 94.966521 -227.383548) (xy 95.002773 -227.422619)
			(xy 95.032797 -227.466656) (xy 95.055923 -227.514677) (xy 95.071633 -227.565607) (xy 95.079576 -227.618311)
			(xy 95.080074 -227.64496) (xy 95.079576 -227.671609) (xy 95.308156 -227.671609) (xy 95.308156 -227.618311)
			(xy 95.316099 -227.565607) (xy 95.331809 -227.514677) (xy 95.354935 -227.466656) (xy 95.384959 -227.422619)
			(xy 95.421211 -227.383548) (xy 95.462882 -227.350317) (xy 95.50904 -227.323668) (xy 95.558654 -227.304196)
			(xy 95.610616 -227.292336) (xy 95.663766 -227.288353) (xy 95.716916 -227.292336) (xy 95.768878 -227.304196)
			(xy 95.818492 -227.323668) (xy 95.86465 -227.350317) (xy 95.906321 -227.383548) (xy 95.942573 -227.422619)
			(xy 95.972597 -227.466656) (xy 95.995723 -227.514677) (xy 96.011433 -227.565607) (xy 96.019376 -227.618311)
			(xy 96.019874 -227.64496) (xy 96.019376 -227.671609) (xy 96.247956 -227.671609) (xy 96.247956 -227.618311)
			(xy 96.255899 -227.565607) (xy 96.271609 -227.514677) (xy 96.294735 -227.466656) (xy 96.324759 -227.422619)
			(xy 96.361011 -227.383548) (xy 96.402682 -227.350317) (xy 96.44884 -227.323668) (xy 96.498454 -227.304196)
			(xy 96.550416 -227.292336) (xy 96.603566 -227.288353) (xy 96.656716 -227.292336) (xy 96.708678 -227.304196)
			(xy 96.758292 -227.323668) (xy 96.80445 -227.350317) (xy 96.846121 -227.383548) (xy 96.882373 -227.422619)
			(xy 96.912397 -227.466656) (xy 96.935523 -227.514677) (xy 96.951233 -227.565607) (xy 96.959176 -227.618311)
			(xy 96.959674 -227.64496) (xy 96.959176 -227.671609) (xy 97.187756 -227.671609) (xy 97.187756 -227.618311)
			(xy 97.195699 -227.565607) (xy 97.211409 -227.514677) (xy 97.234535 -227.466656) (xy 97.264559 -227.422619)
			(xy 97.300811 -227.383548) (xy 97.342482 -227.350317) (xy 97.38864 -227.323668) (xy 97.438254 -227.304196)
			(xy 97.490216 -227.292336) (xy 97.543366 -227.288353) (xy 97.596516 -227.292336) (xy 97.648478 -227.304196)
			(xy 97.698092 -227.323668) (xy 97.74425 -227.350317) (xy 97.785921 -227.383548) (xy 97.822173 -227.422619)
			(xy 97.852197 -227.466656) (xy 97.875323 -227.514677) (xy 97.891033 -227.565607) (xy 97.898976 -227.618311)
			(xy 97.899474 -227.64496) (xy 97.898976 -227.671609) (xy 98.127556 -227.671609) (xy 98.127556 -227.618311)
			(xy 98.135499 -227.565607) (xy 98.151209 -227.514677) (xy 98.174335 -227.466656) (xy 98.204359 -227.422619)
			(xy 98.240611 -227.383548) (xy 98.282282 -227.350317) (xy 98.32844 -227.323668) (xy 98.378054 -227.304196)
			(xy 98.430016 -227.292336) (xy 98.483166 -227.288353) (xy 98.536316 -227.292336) (xy 98.588278 -227.304196)
			(xy 98.637892 -227.323668) (xy 98.68405 -227.350317) (xy 98.725721 -227.383548) (xy 98.761973 -227.422619)
			(xy 98.791997 -227.466656) (xy 98.815123 -227.514677) (xy 98.830833 -227.565607) (xy 98.838776 -227.618311)
			(xy 98.839274 -227.64496) (xy 98.838776 -227.671609) (xy 99.067102 -227.671609) (xy 99.067102 -227.618311)
			(xy 99.075045 -227.565607) (xy 99.090755 -227.514677) (xy 99.113881 -227.466656) (xy 99.143905 -227.422619)
			(xy 99.180157 -227.383548) (xy 99.221828 -227.350317) (xy 99.267986 -227.323668) (xy 99.3176 -227.304196)
			(xy 99.369562 -227.292336) (xy 99.422712 -227.288353) (xy 99.475862 -227.292336) (xy 99.527824 -227.304196)
			(xy 99.577438 -227.323668) (xy 99.623596 -227.350317) (xy 99.665267 -227.383548) (xy 99.701519 -227.422619)
			(xy 99.731543 -227.466656) (xy 99.754669 -227.514677) (xy 99.770379 -227.565607) (xy 99.778322 -227.618311)
			(xy 99.77882 -227.64496) (xy 99.778322 -227.671609) (xy 100.007156 -227.671609) (xy 100.007156 -227.618311)
			(xy 100.015099 -227.565607) (xy 100.030809 -227.514677) (xy 100.053935 -227.466656) (xy 100.083959 -227.422619)
			(xy 100.120211 -227.383548) (xy 100.161882 -227.350317) (xy 100.20804 -227.323668) (xy 100.257654 -227.304196)
			(xy 100.309616 -227.292336) (xy 100.362766 -227.288353) (xy 100.415916 -227.292336) (xy 100.467878 -227.304196)
			(xy 100.517492 -227.323668) (xy 100.56365 -227.350317) (xy 100.605321 -227.383548) (xy 100.641573 -227.422619)
			(xy 100.671597 -227.466656) (xy 100.694723 -227.514677) (xy 100.710433 -227.565607) (xy 100.718376 -227.618311)
			(xy 100.718874 -227.64496) (xy 100.718376 -227.671609) (xy 100.946956 -227.671609) (xy 100.946956 -227.618311)
			(xy 100.954899 -227.565607) (xy 100.970609 -227.514677) (xy 100.993735 -227.466656) (xy 101.023759 -227.422619)
			(xy 101.060011 -227.383548) (xy 101.101682 -227.350317) (xy 101.14784 -227.323668) (xy 101.197454 -227.304196)
			(xy 101.249416 -227.292336) (xy 101.302566 -227.288353) (xy 101.355716 -227.292336) (xy 101.407678 -227.304196)
			(xy 101.457292 -227.323668) (xy 101.50345 -227.350317) (xy 101.545121 -227.383548) (xy 101.581373 -227.422619)
			(xy 101.611397 -227.466656) (xy 101.634523 -227.514677) (xy 101.650233 -227.565607) (xy 101.658176 -227.618311)
			(xy 101.658674 -227.64496) (xy 101.658176 -227.671609) (xy 101.886756 -227.671609) (xy 101.886756 -227.618311)
			(xy 101.894699 -227.565607) (xy 101.910409 -227.514677) (xy 101.933535 -227.466656) (xy 101.963559 -227.422619)
			(xy 101.999811 -227.383548) (xy 102.041482 -227.350317) (xy 102.08764 -227.323668) (xy 102.137254 -227.304196)
			(xy 102.189216 -227.292336) (xy 102.242366 -227.288353) (xy 102.295516 -227.292336) (xy 102.347478 -227.304196)
			(xy 102.397092 -227.323668) (xy 102.44325 -227.350317) (xy 102.484921 -227.383548) (xy 102.521173 -227.422619)
			(xy 102.551197 -227.466656) (xy 102.574323 -227.514677) (xy 102.590033 -227.565607) (xy 102.597976 -227.618311)
			(xy 102.598474 -227.64496) (xy 102.597976 -227.671609) (xy 102.826556 -227.671609) (xy 102.826556 -227.618311)
			(xy 102.834499 -227.565607) (xy 102.850209 -227.514677) (xy 102.873335 -227.466656) (xy 102.903359 -227.422619)
			(xy 102.939611 -227.383548) (xy 102.981282 -227.350317) (xy 103.02744 -227.323668) (xy 103.077054 -227.304196)
			(xy 103.129016 -227.292336) (xy 103.182166 -227.288353) (xy 103.235316 -227.292336) (xy 103.287278 -227.304196)
			(xy 103.336892 -227.323668) (xy 103.38305 -227.350317) (xy 103.424721 -227.383548) (xy 103.460973 -227.422619)
			(xy 103.490997 -227.466656) (xy 103.514123 -227.514677) (xy 103.529833 -227.565607) (xy 103.537776 -227.618311)
			(xy 103.538274 -227.64496) (xy 103.537776 -227.671609) (xy 103.766356 -227.671609) (xy 103.766356 -227.618311)
			(xy 103.774299 -227.565607) (xy 103.790009 -227.514677) (xy 103.813135 -227.466656) (xy 103.843159 -227.422619)
			(xy 103.879411 -227.383548) (xy 103.921082 -227.350317) (xy 103.96724 -227.323668) (xy 104.016854 -227.304196)
			(xy 104.068816 -227.292336) (xy 104.121966 -227.288353) (xy 104.175116 -227.292336) (xy 104.227078 -227.304196)
			(xy 104.276692 -227.323668) (xy 104.32285 -227.350317) (xy 104.364521 -227.383548) (xy 104.400773 -227.422619)
			(xy 104.430797 -227.466656) (xy 104.453923 -227.514677) (xy 104.469633 -227.565607) (xy 104.477576 -227.618311)
			(xy 104.478074 -227.64496) (xy 104.477576 -227.671609) (xy 104.706156 -227.671609) (xy 104.706156 -227.618311)
			(xy 104.714099 -227.565607) (xy 104.729809 -227.514677) (xy 104.752935 -227.466656) (xy 104.782959 -227.422619)
			(xy 104.819211 -227.383548) (xy 104.860882 -227.350317) (xy 104.90704 -227.323668) (xy 104.956654 -227.304196)
			(xy 105.008616 -227.292336) (xy 105.061766 -227.288353) (xy 105.114916 -227.292336) (xy 105.166878 -227.304196)
			(xy 105.216492 -227.323668) (xy 105.26265 -227.350317) (xy 105.304321 -227.383548) (xy 105.340573 -227.422619)
			(xy 105.370597 -227.466656) (xy 105.393723 -227.514677) (xy 105.409433 -227.565607) (xy 105.417376 -227.618311)
			(xy 105.417874 -227.64496) (xy 105.417376 -227.671609) (xy 105.645956 -227.671609) (xy 105.645956 -227.618311)
			(xy 105.653899 -227.565607) (xy 105.669609 -227.514677) (xy 105.692735 -227.466656) (xy 105.722759 -227.422619)
			(xy 105.759011 -227.383548) (xy 105.800682 -227.350317) (xy 105.84684 -227.323668) (xy 105.896454 -227.304196)
			(xy 105.948416 -227.292336) (xy 106.001566 -227.288353) (xy 106.054716 -227.292336) (xy 106.106678 -227.304196)
			(xy 106.156292 -227.323668) (xy 106.20245 -227.350317) (xy 106.244121 -227.383548) (xy 106.280373 -227.422619)
			(xy 106.310397 -227.466656) (xy 106.333523 -227.514677) (xy 106.349233 -227.565607) (xy 106.357176 -227.618311)
			(xy 106.357674 -227.64496) (xy 106.357176 -227.671609) (xy 106.585756 -227.671609) (xy 106.585756 -227.618311)
			(xy 106.593699 -227.565607) (xy 106.609409 -227.514677) (xy 106.632535 -227.466656) (xy 106.662559 -227.422619)
			(xy 106.698811 -227.383548) (xy 106.740482 -227.350317) (xy 106.78664 -227.323668) (xy 106.836254 -227.304196)
			(xy 106.888216 -227.292336) (xy 106.941366 -227.288353) (xy 106.994516 -227.292336) (xy 107.046478 -227.304196)
			(xy 107.096092 -227.323668) (xy 107.14225 -227.350317) (xy 107.183921 -227.383548) (xy 107.220173 -227.422619)
			(xy 107.250197 -227.466656) (xy 107.273323 -227.514677) (xy 107.289033 -227.565607) (xy 107.296976 -227.618311)
			(xy 107.297474 -227.64496) (xy 107.296976 -227.671609) (xy 107.525556 -227.671609) (xy 107.525556 -227.618311)
			(xy 107.533499 -227.565607) (xy 107.549209 -227.514677) (xy 107.572335 -227.466656) (xy 107.602359 -227.422619)
			(xy 107.638611 -227.383548) (xy 107.680282 -227.350317) (xy 107.72644 -227.323668) (xy 107.776054 -227.304196)
			(xy 107.828016 -227.292336) (xy 107.881166 -227.288353) (xy 107.934316 -227.292336) (xy 107.986278 -227.304196)
			(xy 108.035892 -227.323668) (xy 108.08205 -227.350317) (xy 108.123721 -227.383548) (xy 108.159973 -227.422619)
			(xy 108.189997 -227.466656) (xy 108.213123 -227.514677) (xy 108.228833 -227.565607) (xy 108.236776 -227.618311)
			(xy 108.237274 -227.64496) (xy 108.236776 -227.671609) (xy 108.465356 -227.671609) (xy 108.465356 -227.618311)
			(xy 108.473299 -227.565607) (xy 108.489009 -227.514677) (xy 108.512135 -227.466656) (xy 108.542159 -227.422619)
			(xy 108.578411 -227.383548) (xy 108.620082 -227.350317) (xy 108.66624 -227.323668) (xy 108.715854 -227.304196)
			(xy 108.767816 -227.292336) (xy 108.820966 -227.288353) (xy 108.874116 -227.292336) (xy 108.926078 -227.304196)
			(xy 108.975692 -227.323668) (xy 109.02185 -227.350317) (xy 109.063521 -227.383548) (xy 109.099773 -227.422619)
			(xy 109.129797 -227.466656) (xy 109.152923 -227.514677) (xy 109.168633 -227.565607) (xy 109.176576 -227.618311)
			(xy 109.177074 -227.64496) (xy 109.176576 -227.671609) (xy 109.405156 -227.671609) (xy 109.405156 -227.618311)
			(xy 109.413099 -227.565607) (xy 109.428809 -227.514677) (xy 109.451935 -227.466656) (xy 109.481959 -227.422619)
			(xy 109.518211 -227.383548) (xy 109.559882 -227.350317) (xy 109.60604 -227.323668) (xy 109.655654 -227.304196)
			(xy 109.707616 -227.292336) (xy 109.760766 -227.288353) (xy 109.813916 -227.292336) (xy 109.865878 -227.304196)
			(xy 109.915492 -227.323668) (xy 109.96165 -227.350317) (xy 110.003321 -227.383548) (xy 110.039573 -227.422619)
			(xy 110.069597 -227.466656) (xy 110.092723 -227.514677) (xy 110.108433 -227.565607) (xy 110.116376 -227.618311)
			(xy 110.116874 -227.64496) (xy 110.116376 -227.671609) (xy 110.344956 -227.671609) (xy 110.344956 -227.618311)
			(xy 110.352899 -227.565607) (xy 110.368609 -227.514677) (xy 110.391735 -227.466656) (xy 110.421759 -227.422619)
			(xy 110.458011 -227.383548) (xy 110.499682 -227.350317) (xy 110.54584 -227.323668) (xy 110.595454 -227.304196)
			(xy 110.647416 -227.292336) (xy 110.700566 -227.288353) (xy 110.753716 -227.292336) (xy 110.805678 -227.304196)
			(xy 110.855292 -227.323668) (xy 110.90145 -227.350317) (xy 110.943121 -227.383548) (xy 110.979373 -227.422619)
			(xy 111.009397 -227.466656) (xy 111.032523 -227.514677) (xy 111.048233 -227.565607) (xy 111.056176 -227.618311)
			(xy 111.056674 -227.64496) (xy 111.056176 -227.671609) (xy 111.048233 -227.724313) (xy 111.032523 -227.775243)
			(xy 111.009397 -227.823264) (xy 110.979373 -227.867301) (xy 110.943121 -227.906372) (xy 110.90145 -227.939603)
			(xy 110.855292 -227.966252) (xy 110.805678 -227.985724) (xy 110.753716 -227.997584) (xy 110.700566 -228.001568)
			(xy 110.647416 -227.997584) (xy 110.595454 -227.985724) (xy 110.54584 -227.966252) (xy 110.499682 -227.939603)
			(xy 110.458011 -227.906372) (xy 110.421759 -227.867301) (xy 110.391735 -227.823264) (xy 110.368609 -227.775243)
			(xy 110.352899 -227.724313) (xy 110.344956 -227.671609) (xy 110.116376 -227.671609) (xy 110.108433 -227.724313)
			(xy 110.092723 -227.775243) (xy 110.069597 -227.823264) (xy 110.039573 -227.867301) (xy 110.003321 -227.906372)
			(xy 109.96165 -227.939603) (xy 109.915492 -227.966252) (xy 109.865878 -227.985724) (xy 109.813916 -227.997584)
			(xy 109.760766 -228.001568) (xy 109.707616 -227.997584) (xy 109.655654 -227.985724) (xy 109.60604 -227.966252)
			(xy 109.559882 -227.939603) (xy 109.518211 -227.906372) (xy 109.481959 -227.867301) (xy 109.451935 -227.823264)
			(xy 109.428809 -227.775243) (xy 109.413099 -227.724313) (xy 109.405156 -227.671609) (xy 109.176576 -227.671609)
			(xy 109.168633 -227.724313) (xy 109.152923 -227.775243) (xy 109.129797 -227.823264) (xy 109.099773 -227.867301)
			(xy 109.063521 -227.906372) (xy 109.02185 -227.939603) (xy 108.975692 -227.966252) (xy 108.926078 -227.985724)
			(xy 108.874116 -227.997584) (xy 108.820966 -228.001568) (xy 108.767816 -227.997584) (xy 108.715854 -227.985724)
			(xy 108.66624 -227.966252) (xy 108.620082 -227.939603) (xy 108.578411 -227.906372) (xy 108.542159 -227.867301)
			(xy 108.512135 -227.823264) (xy 108.489009 -227.775243) (xy 108.473299 -227.724313) (xy 108.465356 -227.671609)
			(xy 108.236776 -227.671609) (xy 108.228833 -227.724313) (xy 108.213123 -227.775243) (xy 108.189997 -227.823264)
			(xy 108.159973 -227.867301) (xy 108.123721 -227.906372) (xy 108.08205 -227.939603) (xy 108.035892 -227.966252)
			(xy 107.986278 -227.985724) (xy 107.934316 -227.997584) (xy 107.881166 -228.001568) (xy 107.828016 -227.997584)
			(xy 107.776054 -227.985724) (xy 107.72644 -227.966252) (xy 107.680282 -227.939603) (xy 107.638611 -227.906372)
			(xy 107.602359 -227.867301) (xy 107.572335 -227.823264) (xy 107.549209 -227.775243) (xy 107.533499 -227.724313)
			(xy 107.525556 -227.671609) (xy 107.296976 -227.671609) (xy 107.289033 -227.724313) (xy 107.273323 -227.775243)
			(xy 107.250197 -227.823264) (xy 107.220173 -227.867301) (xy 107.183921 -227.906372) (xy 107.14225 -227.939603)
			(xy 107.096092 -227.966252) (xy 107.046478 -227.985724) (xy 106.994516 -227.997584) (xy 106.941366 -228.001568)
			(xy 106.888216 -227.997584) (xy 106.836254 -227.985724) (xy 106.78664 -227.966252) (xy 106.740482 -227.939603)
			(xy 106.698811 -227.906372) (xy 106.662559 -227.867301) (xy 106.632535 -227.823264) (xy 106.609409 -227.775243)
			(xy 106.593699 -227.724313) (xy 106.585756 -227.671609) (xy 106.357176 -227.671609) (xy 106.349233 -227.724313)
			(xy 106.333523 -227.775243) (xy 106.310397 -227.823264) (xy 106.280373 -227.867301) (xy 106.244121 -227.906372)
			(xy 106.20245 -227.939603) (xy 106.156292 -227.966252) (xy 106.106678 -227.985724) (xy 106.054716 -227.997584)
			(xy 106.001566 -228.001568) (xy 105.948416 -227.997584) (xy 105.896454 -227.985724) (xy 105.84684 -227.966252)
			(xy 105.800682 -227.939603) (xy 105.759011 -227.906372) (xy 105.722759 -227.867301) (xy 105.692735 -227.823264)
			(xy 105.669609 -227.775243) (xy 105.653899 -227.724313) (xy 105.645956 -227.671609) (xy 105.417376 -227.671609)
			(xy 105.409433 -227.724313) (xy 105.393723 -227.775243) (xy 105.370597 -227.823264) (xy 105.340573 -227.867301)
			(xy 105.304321 -227.906372) (xy 105.26265 -227.939603) (xy 105.216492 -227.966252) (xy 105.166878 -227.985724)
			(xy 105.114916 -227.997584) (xy 105.061766 -228.001568) (xy 105.008616 -227.997584) (xy 104.956654 -227.985724)
			(xy 104.90704 -227.966252) (xy 104.860882 -227.939603) (xy 104.819211 -227.906372) (xy 104.782959 -227.867301)
			(xy 104.752935 -227.823264) (xy 104.729809 -227.775243) (xy 104.714099 -227.724313) (xy 104.706156 -227.671609)
			(xy 104.477576 -227.671609) (xy 104.469633 -227.724313) (xy 104.453923 -227.775243) (xy 104.430797 -227.823264)
			(xy 104.400773 -227.867301) (xy 104.364521 -227.906372) (xy 104.32285 -227.939603) (xy 104.276692 -227.966252)
			(xy 104.227078 -227.985724) (xy 104.175116 -227.997584) (xy 104.121966 -228.001568) (xy 104.068816 -227.997584)
			(xy 104.016854 -227.985724) (xy 103.96724 -227.966252) (xy 103.921082 -227.939603) (xy 103.879411 -227.906372)
			(xy 103.843159 -227.867301) (xy 103.813135 -227.823264) (xy 103.790009 -227.775243) (xy 103.774299 -227.724313)
			(xy 103.766356 -227.671609) (xy 103.537776 -227.671609) (xy 103.529833 -227.724313) (xy 103.514123 -227.775243)
			(xy 103.490997 -227.823264) (xy 103.460973 -227.867301) (xy 103.424721 -227.906372) (xy 103.38305 -227.939603)
			(xy 103.336892 -227.966252) (xy 103.287278 -227.985724) (xy 103.235316 -227.997584) (xy 103.182166 -228.001568)
			(xy 103.129016 -227.997584) (xy 103.077054 -227.985724) (xy 103.02744 -227.966252) (xy 102.981282 -227.939603)
			(xy 102.939611 -227.906372) (xy 102.903359 -227.867301) (xy 102.873335 -227.823264) (xy 102.850209 -227.775243)
			(xy 102.834499 -227.724313) (xy 102.826556 -227.671609) (xy 102.597976 -227.671609) (xy 102.590033 -227.724313)
			(xy 102.574323 -227.775243) (xy 102.551197 -227.823264) (xy 102.521173 -227.867301) (xy 102.484921 -227.906372)
			(xy 102.44325 -227.939603) (xy 102.397092 -227.966252) (xy 102.347478 -227.985724) (xy 102.295516 -227.997584)
			(xy 102.242366 -228.001568) (xy 102.189216 -227.997584) (xy 102.137254 -227.985724) (xy 102.08764 -227.966252)
			(xy 102.041482 -227.939603) (xy 101.999811 -227.906372) (xy 101.963559 -227.867301) (xy 101.933535 -227.823264)
			(xy 101.910409 -227.775243) (xy 101.894699 -227.724313) (xy 101.886756 -227.671609) (xy 101.658176 -227.671609)
			(xy 101.650233 -227.724313) (xy 101.634523 -227.775243) (xy 101.611397 -227.823264) (xy 101.581373 -227.867301)
			(xy 101.545121 -227.906372) (xy 101.50345 -227.939603) (xy 101.457292 -227.966252) (xy 101.407678 -227.985724)
			(xy 101.355716 -227.997584) (xy 101.302566 -228.001568) (xy 101.249416 -227.997584) (xy 101.197454 -227.985724)
			(xy 101.14784 -227.966252) (xy 101.101682 -227.939603) (xy 101.060011 -227.906372) (xy 101.023759 -227.867301)
			(xy 100.993735 -227.823264) (xy 100.970609 -227.775243) (xy 100.954899 -227.724313) (xy 100.946956 -227.671609)
			(xy 100.718376 -227.671609) (xy 100.710433 -227.724313) (xy 100.694723 -227.775243) (xy 100.671597 -227.823264)
			(xy 100.641573 -227.867301) (xy 100.605321 -227.906372) (xy 100.56365 -227.939603) (xy 100.517492 -227.966252)
			(xy 100.467878 -227.985724) (xy 100.415916 -227.997584) (xy 100.362766 -228.001568) (xy 100.309616 -227.997584)
			(xy 100.257654 -227.985724) (xy 100.20804 -227.966252) (xy 100.161882 -227.939603) (xy 100.120211 -227.906372)
			(xy 100.083959 -227.867301) (xy 100.053935 -227.823264) (xy 100.030809 -227.775243) (xy 100.015099 -227.724313)
			(xy 100.007156 -227.671609) (xy 99.778322 -227.671609) (xy 99.770379 -227.724313) (xy 99.754669 -227.775243)
			(xy 99.731543 -227.823264) (xy 99.701519 -227.867301) (xy 99.665267 -227.906372) (xy 99.623596 -227.939603)
			(xy 99.577438 -227.966252) (xy 99.527824 -227.985724) (xy 99.475862 -227.997584) (xy 99.422712 -228.001568)
			(xy 99.369562 -227.997584) (xy 99.3176 -227.985724) (xy 99.267986 -227.966252) (xy 99.221828 -227.939603)
			(xy 99.180157 -227.906372) (xy 99.143905 -227.867301) (xy 99.113881 -227.823264) (xy 99.090755 -227.775243)
			(xy 99.075045 -227.724313) (xy 99.067102 -227.671609) (xy 98.838776 -227.671609) (xy 98.830833 -227.724313)
			(xy 98.815123 -227.775243) (xy 98.791997 -227.823264) (xy 98.761973 -227.867301) (xy 98.725721 -227.906372)
			(xy 98.68405 -227.939603) (xy 98.637892 -227.966252) (xy 98.588278 -227.985724) (xy 98.536316 -227.997584)
			(xy 98.483166 -228.001568) (xy 98.430016 -227.997584) (xy 98.378054 -227.985724) (xy 98.32844 -227.966252)
			(xy 98.282282 -227.939603) (xy 98.240611 -227.906372) (xy 98.204359 -227.867301) (xy 98.174335 -227.823264)
			(xy 98.151209 -227.775243) (xy 98.135499 -227.724313) (xy 98.127556 -227.671609) (xy 97.898976 -227.671609)
			(xy 97.891033 -227.724313) (xy 97.875323 -227.775243) (xy 97.852197 -227.823264) (xy 97.822173 -227.867301)
			(xy 97.785921 -227.906372) (xy 97.74425 -227.939603) (xy 97.698092 -227.966252) (xy 97.648478 -227.985724)
			(xy 97.596516 -227.997584) (xy 97.543366 -228.001568) (xy 97.490216 -227.997584) (xy 97.438254 -227.985724)
			(xy 97.38864 -227.966252) (xy 97.342482 -227.939603) (xy 97.300811 -227.906372) (xy 97.264559 -227.867301)
			(xy 97.234535 -227.823264) (xy 97.211409 -227.775243) (xy 97.195699 -227.724313) (xy 97.187756 -227.671609)
			(xy 96.959176 -227.671609) (xy 96.951233 -227.724313) (xy 96.935523 -227.775243) (xy 96.912397 -227.823264)
			(xy 96.882373 -227.867301) (xy 96.846121 -227.906372) (xy 96.80445 -227.939603) (xy 96.758292 -227.966252)
			(xy 96.708678 -227.985724) (xy 96.656716 -227.997584) (xy 96.603566 -228.001568) (xy 96.550416 -227.997584)
			(xy 96.498454 -227.985724) (xy 96.44884 -227.966252) (xy 96.402682 -227.939603) (xy 96.361011 -227.906372)
			(xy 96.324759 -227.867301) (xy 96.294735 -227.823264) (xy 96.271609 -227.775243) (xy 96.255899 -227.724313)
			(xy 96.247956 -227.671609) (xy 96.019376 -227.671609) (xy 96.011433 -227.724313) (xy 95.995723 -227.775243)
			(xy 95.972597 -227.823264) (xy 95.942573 -227.867301) (xy 95.906321 -227.906372) (xy 95.86465 -227.939603)
			(xy 95.818492 -227.966252) (xy 95.768878 -227.985724) (xy 95.716916 -227.997584) (xy 95.663766 -228.001568)
			(xy 95.610616 -227.997584) (xy 95.558654 -227.985724) (xy 95.50904 -227.966252) (xy 95.462882 -227.939603)
			(xy 95.421211 -227.906372) (xy 95.384959 -227.867301) (xy 95.354935 -227.823264) (xy 95.331809 -227.775243)
			(xy 95.316099 -227.724313) (xy 95.308156 -227.671609) (xy 95.079576 -227.671609) (xy 95.071633 -227.724313)
			(xy 95.055923 -227.775243) (xy 95.032797 -227.823264) (xy 95.002773 -227.867301) (xy 94.966521 -227.906372)
			(xy 94.92485 -227.939603) (xy 94.878692 -227.966252) (xy 94.829078 -227.985724) (xy 94.777116 -227.997584)
			(xy 94.723966 -228.001568) (xy 94.670816 -227.997584) (xy 94.618854 -227.985724) (xy 94.56924 -227.966252)
			(xy 94.523082 -227.939603) (xy 94.481411 -227.906372) (xy 94.445159 -227.867301) (xy 94.415135 -227.823264)
			(xy 94.392009 -227.775243) (xy 94.376299 -227.724313) (xy 94.368356 -227.671609) (xy 94.139776 -227.671609)
			(xy 94.131833 -227.724313) (xy 94.116123 -227.775243) (xy 94.092997 -227.823264) (xy 94.062973 -227.867301)
			(xy 94.026721 -227.906372) (xy 93.98505 -227.939603) (xy 93.938892 -227.966252) (xy 93.889278 -227.985724)
			(xy 93.837316 -227.997584) (xy 93.784166 -228.001568) (xy 93.731016 -227.997584) (xy 93.679054 -227.985724)
			(xy 93.62944 -227.966252) (xy 93.583282 -227.939603) (xy 93.541611 -227.906372) (xy 93.505359 -227.867301)
			(xy 93.475335 -227.823264) (xy 93.452209 -227.775243) (xy 93.436499 -227.724313) (xy 93.428556 -227.671609)
			(xy 93.199976 -227.671609) (xy 93.192033 -227.724313) (xy 93.176323 -227.775243) (xy 93.153197 -227.823264)
			(xy 93.123173 -227.867301) (xy 93.086921 -227.906372) (xy 93.04525 -227.939603) (xy 92.999092 -227.966252)
			(xy 92.949478 -227.985724) (xy 92.897516 -227.997584) (xy 92.844366 -228.001568) (xy 92.791216 -227.997584)
			(xy 92.739254 -227.985724) (xy 92.68964 -227.966252) (xy 92.643482 -227.939603) (xy 92.601811 -227.906372)
			(xy 92.565559 -227.867301) (xy 92.535535 -227.823264) (xy 92.512409 -227.775243) (xy 92.496699 -227.724313)
			(xy 92.488756 -227.671609) (xy 92.259922 -227.671609) (xy 92.251979 -227.724313) (xy 92.236269 -227.775243)
			(xy 92.213143 -227.823264) (xy 92.183119 -227.867301) (xy 92.146867 -227.906372) (xy 92.105196 -227.939603)
			(xy 92.059038 -227.966252) (xy 92.009424 -227.985724) (xy 91.957462 -227.997584) (xy 91.904312 -228.001568)
			(xy 91.851162 -227.997584) (xy 91.7992 -227.985724) (xy 91.749586 -227.966252) (xy 91.703428 -227.939603)
			(xy 91.661757 -227.906372) (xy 91.625505 -227.867301) (xy 91.595481 -227.823264) (xy 91.572355 -227.775243)
			(xy 91.556645 -227.724313) (xy 91.548702 -227.671609) (xy 91.320376 -227.671609) (xy 91.312433 -227.724313)
			(xy 91.296723 -227.775243) (xy 91.273597 -227.823264) (xy 91.243573 -227.867301) (xy 91.207321 -227.906372)
			(xy 91.16565 -227.939603) (xy 91.119492 -227.966252) (xy 91.069878 -227.985724) (xy 91.017916 -227.997584)
			(xy 90.964766 -228.001568) (xy 90.911616 -227.997584) (xy 90.859654 -227.985724) (xy 90.81004 -227.966252)
			(xy 90.763882 -227.939603) (xy 90.722211 -227.906372) (xy 90.685959 -227.867301) (xy 90.655935 -227.823264)
			(xy 90.632809 -227.775243) (xy 90.617099 -227.724313) (xy 90.609156 -227.671609) (xy 90.380576 -227.671609)
			(xy 90.372633 -227.724313) (xy 90.356923 -227.775243) (xy 90.333797 -227.823264) (xy 90.303773 -227.867301)
			(xy 90.267521 -227.906372) (xy 90.22585 -227.939603) (xy 90.179692 -227.966252) (xy 90.130078 -227.985724)
			(xy 90.078116 -227.997584) (xy 90.024966 -228.001568) (xy 89.971816 -227.997584) (xy 89.919854 -227.985724)
			(xy 89.87024 -227.966252) (xy 89.824082 -227.939603) (xy 89.782411 -227.906372) (xy 89.746159 -227.867301)
			(xy 89.716135 -227.823264) (xy 89.693009 -227.775243) (xy 89.677299 -227.724313) (xy 89.669356 -227.671609)
			(xy 89.439878 -227.671609) (xy 89.437888 -227.698162) (xy 89.426024 -227.750137) (xy 89.406546 -227.799763)
			(xy 89.379889 -227.845931) (xy 89.346648 -227.88761) (xy 89.307566 -227.92387) (xy 89.263516 -227.953898)
			(xy 89.215483 -227.977026) (xy 89.164539 -227.992736) (xy 89.111822 -228.000677) (xy 89.085166 -228.001068)
			(xy 89.074793 -228.001022) (xy 89.054079 -227.99988) (xy 89.043764 -227.998782) (xy 89.029507 -227.997621)
			(xy 89.001305 -228.002337) (xy 88.975513 -228.014681) (xy 88.95415 -228.033685) (xy 88.938887 -228.057864)
			(xy 88.930918 -228.085324) (xy 88.93048 -228.09962) (xy 88.93048 -228.293422) (xy 88.93556 -228.303836)
			(xy 88.946786 -228.328149) (xy 88.962629 -228.379303) (xy 88.970639 -228.432251) (xy 88.970635 -228.485679)
			(xy 89.199202 -228.485679) (xy 89.199202 -228.432381) (xy 89.207145 -228.379677) (xy 89.222855 -228.328747)
			(xy 89.245981 -228.280726) (xy 89.276005 -228.236689) (xy 89.312257 -228.197618) (xy 89.353928 -228.164387)
			(xy 89.400086 -228.137738) (xy 89.4497 -228.118266) (xy 89.501662 -228.106406) (xy 89.554812 -228.102423)
			(xy 89.607962 -228.106406) (xy 89.659924 -228.118266) (xy 89.709538 -228.137738) (xy 89.755696 -228.164387)
			(xy 89.797367 -228.197618) (xy 89.833619 -228.236689) (xy 89.863643 -228.280726) (xy 89.886769 -228.328747)
			(xy 89.902479 -228.379677) (xy 89.910422 -228.432381) (xy 89.91092 -228.45903) (xy 89.910422 -228.485679)
			(xy 90.139002 -228.485679) (xy 90.139002 -228.432381) (xy 90.146945 -228.379677) (xy 90.162655 -228.328747)
			(xy 90.185781 -228.280726) (xy 90.215805 -228.236689) (xy 90.252057 -228.197618) (xy 90.293728 -228.164387)
			(xy 90.339886 -228.137738) (xy 90.3895 -228.118266) (xy 90.441462 -228.106406) (xy 90.494612 -228.102423)
			(xy 90.547762 -228.106406) (xy 90.599724 -228.118266) (xy 90.649338 -228.137738) (xy 90.695496 -228.164387)
			(xy 90.737167 -228.197618) (xy 90.773419 -228.236689) (xy 90.803443 -228.280726) (xy 90.826569 -228.328747)
			(xy 90.842279 -228.379677) (xy 90.850222 -228.432381) (xy 90.85072 -228.45903) (xy 90.850222 -228.485679)
			(xy 91.079056 -228.485679) (xy 91.079056 -228.432381) (xy 91.086999 -228.379677) (xy 91.102709 -228.328747)
			(xy 91.125835 -228.280726) (xy 91.155859 -228.236689) (xy 91.192111 -228.197618) (xy 91.233782 -228.164387)
			(xy 91.27994 -228.137738) (xy 91.329554 -228.118266) (xy 91.381516 -228.106406) (xy 91.434666 -228.102423)
			(xy 91.487816 -228.106406) (xy 91.539778 -228.118266) (xy 91.589392 -228.137738) (xy 91.63555 -228.164387)
			(xy 91.677221 -228.197618) (xy 91.713473 -228.236689) (xy 91.743497 -228.280726) (xy 91.766623 -228.328747)
			(xy 91.782333 -228.379677) (xy 91.790276 -228.432381) (xy 91.790774 -228.45903) (xy 91.790276 -228.485679)
			(xy 92.018602 -228.485679) (xy 92.018602 -228.432381) (xy 92.026545 -228.379677) (xy 92.042255 -228.328747)
			(xy 92.065381 -228.280726) (xy 92.095405 -228.236689) (xy 92.131657 -228.197618) (xy 92.173328 -228.164387)
			(xy 92.219486 -228.137738) (xy 92.2691 -228.118266) (xy 92.321062 -228.106406) (xy 92.374212 -228.102423)
			(xy 92.427362 -228.106406) (xy 92.479324 -228.118266) (xy 92.528938 -228.137738) (xy 92.575096 -228.164387)
			(xy 92.616767 -228.197618) (xy 92.653019 -228.236689) (xy 92.683043 -228.280726) (xy 92.706169 -228.328747)
			(xy 92.721879 -228.379677) (xy 92.729822 -228.432381) (xy 92.73032 -228.45903) (xy 92.729822 -228.485679)
			(xy 92.958402 -228.485679) (xy 92.958402 -228.432381) (xy 92.966345 -228.379677) (xy 92.982055 -228.328747)
			(xy 93.005181 -228.280726) (xy 93.035205 -228.236689) (xy 93.071457 -228.197618) (xy 93.113128 -228.164387)
			(xy 93.159286 -228.137738) (xy 93.2089 -228.118266) (xy 93.260862 -228.106406) (xy 93.314012 -228.102423)
			(xy 93.367162 -228.106406) (xy 93.419124 -228.118266) (xy 93.468738 -228.137738) (xy 93.514896 -228.164387)
			(xy 93.556567 -228.197618) (xy 93.592819 -228.236689) (xy 93.622843 -228.280726) (xy 93.645969 -228.328747)
			(xy 93.661679 -228.379677) (xy 93.669622 -228.432381) (xy 93.67012 -228.45903) (xy 93.669622 -228.485679)
			(xy 93.898202 -228.485679) (xy 93.898202 -228.432381) (xy 93.906145 -228.379677) (xy 93.921855 -228.328747)
			(xy 93.944981 -228.280726) (xy 93.975005 -228.236689) (xy 94.011257 -228.197618) (xy 94.052928 -228.164387)
			(xy 94.099086 -228.137738) (xy 94.1487 -228.118266) (xy 94.200662 -228.106406) (xy 94.253812 -228.102423)
			(xy 94.306962 -228.106406) (xy 94.358924 -228.118266) (xy 94.408538 -228.137738) (xy 94.454696 -228.164387)
			(xy 94.496367 -228.197618) (xy 94.532619 -228.236689) (xy 94.562643 -228.280726) (xy 94.585769 -228.328747)
			(xy 94.601479 -228.379677) (xy 94.609422 -228.432381) (xy 94.60992 -228.45903) (xy 94.609422 -228.485679)
			(xy 94.838002 -228.485679) (xy 94.838002 -228.432381) (xy 94.845945 -228.379677) (xy 94.861655 -228.328747)
			(xy 94.884781 -228.280726) (xy 94.914805 -228.236689) (xy 94.951057 -228.197618) (xy 94.992728 -228.164387)
			(xy 95.038886 -228.137738) (xy 95.0885 -228.118266) (xy 95.140462 -228.106406) (xy 95.193612 -228.102423)
			(xy 95.246762 -228.106406) (xy 95.298724 -228.118266) (xy 95.348338 -228.137738) (xy 95.394496 -228.164387)
			(xy 95.436167 -228.197618) (xy 95.472419 -228.236689) (xy 95.502443 -228.280726) (xy 95.525569 -228.328747)
			(xy 95.541279 -228.379677) (xy 95.549222 -228.432381) (xy 95.54972 -228.45903) (xy 95.549222 -228.485679)
			(xy 95.777802 -228.485679) (xy 95.777802 -228.432381) (xy 95.785745 -228.379677) (xy 95.801455 -228.328747)
			(xy 95.824581 -228.280726) (xy 95.854605 -228.236689) (xy 95.890857 -228.197618) (xy 95.932528 -228.164387)
			(xy 95.978686 -228.137738) (xy 96.0283 -228.118266) (xy 96.080262 -228.106406) (xy 96.133412 -228.102423)
			(xy 96.186562 -228.106406) (xy 96.238524 -228.118266) (xy 96.288138 -228.137738) (xy 96.334296 -228.164387)
			(xy 96.375967 -228.197618) (xy 96.412219 -228.236689) (xy 96.442243 -228.280726) (xy 96.465369 -228.328747)
			(xy 96.481079 -228.379677) (xy 96.489022 -228.432381) (xy 96.48952 -228.45903) (xy 96.489022 -228.485679)
			(xy 96.717602 -228.485679) (xy 96.717602 -228.432381) (xy 96.725545 -228.379677) (xy 96.741255 -228.328747)
			(xy 96.764381 -228.280726) (xy 96.794405 -228.236689) (xy 96.830657 -228.197618) (xy 96.872328 -228.164387)
			(xy 96.918486 -228.137738) (xy 96.9681 -228.118266) (xy 97.020062 -228.106406) (xy 97.073212 -228.102423)
			(xy 97.126362 -228.106406) (xy 97.178324 -228.118266) (xy 97.227938 -228.137738) (xy 97.274096 -228.164387)
			(xy 97.315767 -228.197618) (xy 97.352019 -228.236689) (xy 97.382043 -228.280726) (xy 97.405169 -228.328747)
			(xy 97.420879 -228.379677) (xy 97.428822 -228.432381) (xy 97.42932 -228.45903) (xy 97.428822 -228.485679)
			(xy 97.657656 -228.485679) (xy 97.657656 -228.432381) (xy 97.665599 -228.379677) (xy 97.681309 -228.328747)
			(xy 97.704435 -228.280726) (xy 97.734459 -228.236689) (xy 97.770711 -228.197618) (xy 97.812382 -228.164387)
			(xy 97.85854 -228.137738) (xy 97.908154 -228.118266) (xy 97.960116 -228.106406) (xy 98.013266 -228.102423)
			(xy 98.066416 -228.106406) (xy 98.118378 -228.118266) (xy 98.167992 -228.137738) (xy 98.21415 -228.164387)
			(xy 98.255821 -228.197618) (xy 98.292073 -228.236689) (xy 98.322097 -228.280726) (xy 98.345223 -228.328747)
			(xy 98.360933 -228.379677) (xy 98.368876 -228.432381) (xy 98.369374 -228.45903) (xy 98.368876 -228.485679)
			(xy 98.597202 -228.485679) (xy 98.597202 -228.432381) (xy 98.605145 -228.379677) (xy 98.620855 -228.328747)
			(xy 98.643981 -228.280726) (xy 98.674005 -228.236689) (xy 98.710257 -228.197618) (xy 98.751928 -228.164387)
			(xy 98.798086 -228.137738) (xy 98.8477 -228.118266) (xy 98.899662 -228.106406) (xy 98.952812 -228.102423)
			(xy 99.005962 -228.106406) (xy 99.057924 -228.118266) (xy 99.107538 -228.137738) (xy 99.153696 -228.164387)
			(xy 99.195367 -228.197618) (xy 99.231619 -228.236689) (xy 99.261643 -228.280726) (xy 99.284769 -228.328747)
			(xy 99.300479 -228.379677) (xy 99.308422 -228.432381) (xy 99.30892 -228.45903) (xy 99.308422 -228.485679)
			(xy 99.537002 -228.485679) (xy 99.537002 -228.432381) (xy 99.544945 -228.379677) (xy 99.560655 -228.328747)
			(xy 99.583781 -228.280726) (xy 99.613805 -228.236689) (xy 99.650057 -228.197618) (xy 99.691728 -228.164387)
			(xy 99.737886 -228.137738) (xy 99.7875 -228.118266) (xy 99.839462 -228.106406) (xy 99.892612 -228.102423)
			(xy 99.945762 -228.106406) (xy 99.997724 -228.118266) (xy 100.047338 -228.137738) (xy 100.093496 -228.164387)
			(xy 100.135167 -228.197618) (xy 100.171419 -228.236689) (xy 100.201443 -228.280726) (xy 100.224569 -228.328747)
			(xy 100.240279 -228.379677) (xy 100.248222 -228.432381) (xy 100.24872 -228.45903) (xy 100.248222 -228.485679)
			(xy 100.476802 -228.485679) (xy 100.476802 -228.432381) (xy 100.484745 -228.379677) (xy 100.500455 -228.328747)
			(xy 100.523581 -228.280726) (xy 100.553605 -228.236689) (xy 100.589857 -228.197618) (xy 100.631528 -228.164387)
			(xy 100.677686 -228.137738) (xy 100.7273 -228.118266) (xy 100.779262 -228.106406) (xy 100.832412 -228.102423)
			(xy 100.885562 -228.106406) (xy 100.937524 -228.118266) (xy 100.987138 -228.137738) (xy 101.033296 -228.164387)
			(xy 101.074967 -228.197618) (xy 101.111219 -228.236689) (xy 101.141243 -228.280726) (xy 101.164369 -228.328747)
			(xy 101.180079 -228.379677) (xy 101.188022 -228.432381) (xy 101.18852 -228.45903) (xy 101.188022 -228.485679)
			(xy 101.416602 -228.485679) (xy 101.416602 -228.432381) (xy 101.424545 -228.379677) (xy 101.440255 -228.328747)
			(xy 101.463381 -228.280726) (xy 101.493405 -228.236689) (xy 101.529657 -228.197618) (xy 101.571328 -228.164387)
			(xy 101.617486 -228.137738) (xy 101.6671 -228.118266) (xy 101.719062 -228.106406) (xy 101.772212 -228.102423)
			(xy 101.825362 -228.106406) (xy 101.877324 -228.118266) (xy 101.926938 -228.137738) (xy 101.973096 -228.164387)
			(xy 102.014767 -228.197618) (xy 102.051019 -228.236689) (xy 102.081043 -228.280726) (xy 102.104169 -228.328747)
			(xy 102.119879 -228.379677) (xy 102.127822 -228.432381) (xy 102.12832 -228.45903) (xy 102.127822 -228.485679)
			(xy 102.356402 -228.485679) (xy 102.356402 -228.432381) (xy 102.364345 -228.379677) (xy 102.380055 -228.328747)
			(xy 102.403181 -228.280726) (xy 102.433205 -228.236689) (xy 102.469457 -228.197618) (xy 102.511128 -228.164387)
			(xy 102.557286 -228.137738) (xy 102.6069 -228.118266) (xy 102.658862 -228.106406) (xy 102.712012 -228.102423)
			(xy 102.765162 -228.106406) (xy 102.817124 -228.118266) (xy 102.866738 -228.137738) (xy 102.912896 -228.164387)
			(xy 102.954567 -228.197618) (xy 102.990819 -228.236689) (xy 103.020843 -228.280726) (xy 103.043969 -228.328747)
			(xy 103.059679 -228.379677) (xy 103.067622 -228.432381) (xy 103.06812 -228.45903) (xy 103.067622 -228.485679)
			(xy 103.296202 -228.485679) (xy 103.296202 -228.432381) (xy 103.304145 -228.379677) (xy 103.319855 -228.328747)
			(xy 103.342981 -228.280726) (xy 103.373005 -228.236689) (xy 103.409257 -228.197618) (xy 103.450928 -228.164387)
			(xy 103.497086 -228.137738) (xy 103.5467 -228.118266) (xy 103.598662 -228.106406) (xy 103.651812 -228.102423)
			(xy 103.704962 -228.106406) (xy 103.756924 -228.118266) (xy 103.806538 -228.137738) (xy 103.852696 -228.164387)
			(xy 103.894367 -228.197618) (xy 103.930619 -228.236689) (xy 103.960643 -228.280726) (xy 103.983769 -228.328747)
			(xy 103.999479 -228.379677) (xy 104.007422 -228.432381) (xy 104.00792 -228.45903) (xy 104.007422 -228.485679)
			(xy 104.236002 -228.485679) (xy 104.236002 -228.432381) (xy 104.243945 -228.379677) (xy 104.259655 -228.328747)
			(xy 104.282781 -228.280726) (xy 104.312805 -228.236689) (xy 104.349057 -228.197618) (xy 104.390728 -228.164387)
			(xy 104.436886 -228.137738) (xy 104.4865 -228.118266) (xy 104.538462 -228.106406) (xy 104.591612 -228.102423)
			(xy 104.644762 -228.106406) (xy 104.696724 -228.118266) (xy 104.746338 -228.137738) (xy 104.792496 -228.164387)
			(xy 104.834167 -228.197618) (xy 104.870419 -228.236689) (xy 104.900443 -228.280726) (xy 104.923569 -228.328747)
			(xy 104.939279 -228.379677) (xy 104.947222 -228.432381) (xy 104.94772 -228.45903) (xy 104.947222 -228.485679)
			(xy 105.175802 -228.485679) (xy 105.175802 -228.432381) (xy 105.183745 -228.379677) (xy 105.199455 -228.328747)
			(xy 105.222581 -228.280726) (xy 105.252605 -228.236689) (xy 105.288857 -228.197618) (xy 105.330528 -228.164387)
			(xy 105.376686 -228.137738) (xy 105.4263 -228.118266) (xy 105.478262 -228.106406) (xy 105.531412 -228.102423)
			(xy 105.584562 -228.106406) (xy 105.636524 -228.118266) (xy 105.686138 -228.137738) (xy 105.732296 -228.164387)
			(xy 105.773967 -228.197618) (xy 105.810219 -228.236689) (xy 105.840243 -228.280726) (xy 105.863369 -228.328747)
			(xy 105.879079 -228.379677) (xy 105.887022 -228.432381) (xy 105.88752 -228.45903) (xy 105.887022 -228.485679)
			(xy 106.115602 -228.485679) (xy 106.115602 -228.432381) (xy 106.123545 -228.379677) (xy 106.139255 -228.328747)
			(xy 106.162381 -228.280726) (xy 106.192405 -228.236689) (xy 106.228657 -228.197618) (xy 106.270328 -228.164387)
			(xy 106.316486 -228.137738) (xy 106.3661 -228.118266) (xy 106.418062 -228.106406) (xy 106.471212 -228.102423)
			(xy 106.524362 -228.106406) (xy 106.576324 -228.118266) (xy 106.625938 -228.137738) (xy 106.672096 -228.164387)
			(xy 106.713767 -228.197618) (xy 106.750019 -228.236689) (xy 106.780043 -228.280726) (xy 106.803169 -228.328747)
			(xy 106.818879 -228.379677) (xy 106.826822 -228.432381) (xy 106.82732 -228.45903) (xy 106.826822 -228.485679)
			(xy 107.055402 -228.485679) (xy 107.055402 -228.432381) (xy 107.063345 -228.379677) (xy 107.079055 -228.328747)
			(xy 107.102181 -228.280726) (xy 107.132205 -228.236689) (xy 107.168457 -228.197618) (xy 107.210128 -228.164387)
			(xy 107.256286 -228.137738) (xy 107.3059 -228.118266) (xy 107.357862 -228.106406) (xy 107.411012 -228.102423)
			(xy 107.464162 -228.106406) (xy 107.516124 -228.118266) (xy 107.565738 -228.137738) (xy 107.611896 -228.164387)
			(xy 107.653567 -228.197618) (xy 107.689819 -228.236689) (xy 107.719843 -228.280726) (xy 107.742969 -228.328747)
			(xy 107.758679 -228.379677) (xy 107.766622 -228.432381) (xy 107.76712 -228.45903) (xy 107.766622 -228.485679)
			(xy 107.995202 -228.485679) (xy 107.995202 -228.432381) (xy 108.003145 -228.379677) (xy 108.018855 -228.328747)
			(xy 108.041981 -228.280726) (xy 108.072005 -228.236689) (xy 108.108257 -228.197618) (xy 108.149928 -228.164387)
			(xy 108.196086 -228.137738) (xy 108.2457 -228.118266) (xy 108.297662 -228.106406) (xy 108.350812 -228.102423)
			(xy 108.403962 -228.106406) (xy 108.455924 -228.118266) (xy 108.505538 -228.137738) (xy 108.551696 -228.164387)
			(xy 108.593367 -228.197618) (xy 108.629619 -228.236689) (xy 108.659643 -228.280726) (xy 108.682769 -228.328747)
			(xy 108.698479 -228.379677) (xy 108.706422 -228.432381) (xy 108.70692 -228.45903) (xy 108.706422 -228.485679)
			(xy 108.935002 -228.485679) (xy 108.935002 -228.432381) (xy 108.942945 -228.379677) (xy 108.958655 -228.328747)
			(xy 108.981781 -228.280726) (xy 109.011805 -228.236689) (xy 109.048057 -228.197618) (xy 109.089728 -228.164387)
			(xy 109.135886 -228.137738) (xy 109.1855 -228.118266) (xy 109.237462 -228.106406) (xy 109.290612 -228.102423)
			(xy 109.343762 -228.106406) (xy 109.395724 -228.118266) (xy 109.445338 -228.137738) (xy 109.491496 -228.164387)
			(xy 109.533167 -228.197618) (xy 109.569419 -228.236689) (xy 109.599443 -228.280726) (xy 109.622569 -228.328747)
			(xy 109.638279 -228.379677) (xy 109.646222 -228.432381) (xy 109.64672 -228.45903) (xy 109.646222 -228.485679)
			(xy 109.874802 -228.485679) (xy 109.874802 -228.432381) (xy 109.882745 -228.379677) (xy 109.898455 -228.328747)
			(xy 109.921581 -228.280726) (xy 109.951605 -228.236689) (xy 109.987857 -228.197618) (xy 110.029528 -228.164387)
			(xy 110.075686 -228.137738) (xy 110.1253 -228.118266) (xy 110.177262 -228.106406) (xy 110.230412 -228.102423)
			(xy 110.283562 -228.106406) (xy 110.335524 -228.118266) (xy 110.385138 -228.137738) (xy 110.431296 -228.164387)
			(xy 110.472967 -228.197618) (xy 110.509219 -228.236689) (xy 110.539243 -228.280726) (xy 110.562369 -228.328747)
			(xy 110.578079 -228.379677) (xy 110.586022 -228.432381) (xy 110.58652 -228.45903) (xy 110.586022 -228.485679)
			(xy 110.578079 -228.538383) (xy 110.562369 -228.589313) (xy 110.539243 -228.637334) (xy 110.509219 -228.681371)
			(xy 110.472967 -228.720442) (xy 110.431296 -228.753673) (xy 110.385138 -228.780322) (xy 110.335524 -228.799794)
			(xy 110.283562 -228.811654) (xy 110.230412 -228.815638) (xy 110.177262 -228.811654) (xy 110.1253 -228.799794)
			(xy 110.075686 -228.780322) (xy 110.029528 -228.753673) (xy 109.987857 -228.720442) (xy 109.951605 -228.681371)
			(xy 109.921581 -228.637334) (xy 109.898455 -228.589313) (xy 109.882745 -228.538383) (xy 109.874802 -228.485679)
			(xy 109.646222 -228.485679) (xy 109.638279 -228.538383) (xy 109.622569 -228.589313) (xy 109.599443 -228.637334)
			(xy 109.569419 -228.681371) (xy 109.533167 -228.720442) (xy 109.491496 -228.753673) (xy 109.445338 -228.780322)
			(xy 109.395724 -228.799794) (xy 109.343762 -228.811654) (xy 109.290612 -228.815638) (xy 109.237462 -228.811654)
			(xy 109.1855 -228.799794) (xy 109.135886 -228.780322) (xy 109.089728 -228.753673) (xy 109.048057 -228.720442)
			(xy 109.011805 -228.681371) (xy 108.981781 -228.637334) (xy 108.958655 -228.589313) (xy 108.942945 -228.538383)
			(xy 108.935002 -228.485679) (xy 108.706422 -228.485679) (xy 108.698479 -228.538383) (xy 108.682769 -228.589313)
			(xy 108.659643 -228.637334) (xy 108.629619 -228.681371) (xy 108.593367 -228.720442) (xy 108.551696 -228.753673)
			(xy 108.505538 -228.780322) (xy 108.455924 -228.799794) (xy 108.403962 -228.811654) (xy 108.350812 -228.815638)
			(xy 108.297662 -228.811654) (xy 108.2457 -228.799794) (xy 108.196086 -228.780322) (xy 108.149928 -228.753673)
			(xy 108.108257 -228.720442) (xy 108.072005 -228.681371) (xy 108.041981 -228.637334) (xy 108.018855 -228.589313)
			(xy 108.003145 -228.538383) (xy 107.995202 -228.485679) (xy 107.766622 -228.485679) (xy 107.758679 -228.538383)
			(xy 107.742969 -228.589313) (xy 107.719843 -228.637334) (xy 107.689819 -228.681371) (xy 107.653567 -228.720442)
			(xy 107.611896 -228.753673) (xy 107.565738 -228.780322) (xy 107.516124 -228.799794) (xy 107.464162 -228.811654)
			(xy 107.411012 -228.815638) (xy 107.357862 -228.811654) (xy 107.3059 -228.799794) (xy 107.256286 -228.780322)
			(xy 107.210128 -228.753673) (xy 107.168457 -228.720442) (xy 107.132205 -228.681371) (xy 107.102181 -228.637334)
			(xy 107.079055 -228.589313) (xy 107.063345 -228.538383) (xy 107.055402 -228.485679) (xy 106.826822 -228.485679)
			(xy 106.818879 -228.538383) (xy 106.803169 -228.589313) (xy 106.780043 -228.637334) (xy 106.750019 -228.681371)
			(xy 106.713767 -228.720442) (xy 106.672096 -228.753673) (xy 106.625938 -228.780322) (xy 106.576324 -228.799794)
			(xy 106.524362 -228.811654) (xy 106.471212 -228.815638) (xy 106.418062 -228.811654) (xy 106.3661 -228.799794)
			(xy 106.316486 -228.780322) (xy 106.270328 -228.753673) (xy 106.228657 -228.720442) (xy 106.192405 -228.681371)
			(xy 106.162381 -228.637334) (xy 106.139255 -228.589313) (xy 106.123545 -228.538383) (xy 106.115602 -228.485679)
			(xy 105.887022 -228.485679) (xy 105.879079 -228.538383) (xy 105.863369 -228.589313) (xy 105.840243 -228.637334)
			(xy 105.810219 -228.681371) (xy 105.773967 -228.720442) (xy 105.732296 -228.753673) (xy 105.686138 -228.780322)
			(xy 105.636524 -228.799794) (xy 105.584562 -228.811654) (xy 105.531412 -228.815638) (xy 105.478262 -228.811654)
			(xy 105.4263 -228.799794) (xy 105.376686 -228.780322) (xy 105.330528 -228.753673) (xy 105.288857 -228.720442)
			(xy 105.252605 -228.681371) (xy 105.222581 -228.637334) (xy 105.199455 -228.589313) (xy 105.183745 -228.538383)
			(xy 105.175802 -228.485679) (xy 104.947222 -228.485679) (xy 104.939279 -228.538383) (xy 104.923569 -228.589313)
			(xy 104.900443 -228.637334) (xy 104.870419 -228.681371) (xy 104.834167 -228.720442) (xy 104.792496 -228.753673)
			(xy 104.746338 -228.780322) (xy 104.696724 -228.799794) (xy 104.644762 -228.811654) (xy 104.591612 -228.815638)
			(xy 104.538462 -228.811654) (xy 104.4865 -228.799794) (xy 104.436886 -228.780322) (xy 104.390728 -228.753673)
			(xy 104.349057 -228.720442) (xy 104.312805 -228.681371) (xy 104.282781 -228.637334) (xy 104.259655 -228.589313)
			(xy 104.243945 -228.538383) (xy 104.236002 -228.485679) (xy 104.007422 -228.485679) (xy 103.999479 -228.538383)
			(xy 103.983769 -228.589313) (xy 103.960643 -228.637334) (xy 103.930619 -228.681371) (xy 103.894367 -228.720442)
			(xy 103.852696 -228.753673) (xy 103.806538 -228.780322) (xy 103.756924 -228.799794) (xy 103.704962 -228.811654)
			(xy 103.651812 -228.815638) (xy 103.598662 -228.811654) (xy 103.5467 -228.799794) (xy 103.497086 -228.780322)
			(xy 103.450928 -228.753673) (xy 103.409257 -228.720442) (xy 103.373005 -228.681371) (xy 103.342981 -228.637334)
			(xy 103.319855 -228.589313) (xy 103.304145 -228.538383) (xy 103.296202 -228.485679) (xy 103.067622 -228.485679)
			(xy 103.059679 -228.538383) (xy 103.043969 -228.589313) (xy 103.020843 -228.637334) (xy 102.990819 -228.681371)
			(xy 102.954567 -228.720442) (xy 102.912896 -228.753673) (xy 102.866738 -228.780322) (xy 102.817124 -228.799794)
			(xy 102.765162 -228.811654) (xy 102.712012 -228.815638) (xy 102.658862 -228.811654) (xy 102.6069 -228.799794)
			(xy 102.557286 -228.780322) (xy 102.511128 -228.753673) (xy 102.469457 -228.720442) (xy 102.433205 -228.681371)
			(xy 102.403181 -228.637334) (xy 102.380055 -228.589313) (xy 102.364345 -228.538383) (xy 102.356402 -228.485679)
			(xy 102.127822 -228.485679) (xy 102.119879 -228.538383) (xy 102.104169 -228.589313) (xy 102.081043 -228.637334)
			(xy 102.051019 -228.681371) (xy 102.014767 -228.720442) (xy 101.973096 -228.753673) (xy 101.926938 -228.780322)
			(xy 101.877324 -228.799794) (xy 101.825362 -228.811654) (xy 101.772212 -228.815638) (xy 101.719062 -228.811654)
			(xy 101.6671 -228.799794) (xy 101.617486 -228.780322) (xy 101.571328 -228.753673) (xy 101.529657 -228.720442)
			(xy 101.493405 -228.681371) (xy 101.463381 -228.637334) (xy 101.440255 -228.589313) (xy 101.424545 -228.538383)
			(xy 101.416602 -228.485679) (xy 101.188022 -228.485679) (xy 101.180079 -228.538383) (xy 101.164369 -228.589313)
			(xy 101.141243 -228.637334) (xy 101.111219 -228.681371) (xy 101.074967 -228.720442) (xy 101.033296 -228.753673)
			(xy 100.987138 -228.780322) (xy 100.937524 -228.799794) (xy 100.885562 -228.811654) (xy 100.832412 -228.815638)
			(xy 100.779262 -228.811654) (xy 100.7273 -228.799794) (xy 100.677686 -228.780322) (xy 100.631528 -228.753673)
			(xy 100.589857 -228.720442) (xy 100.553605 -228.681371) (xy 100.523581 -228.637334) (xy 100.500455 -228.589313)
			(xy 100.484745 -228.538383) (xy 100.476802 -228.485679) (xy 100.248222 -228.485679) (xy 100.240279 -228.538383)
			(xy 100.224569 -228.589313) (xy 100.201443 -228.637334) (xy 100.171419 -228.681371) (xy 100.135167 -228.720442)
			(xy 100.093496 -228.753673) (xy 100.047338 -228.780322) (xy 99.997724 -228.799794) (xy 99.945762 -228.811654)
			(xy 99.892612 -228.815638) (xy 99.839462 -228.811654) (xy 99.7875 -228.799794) (xy 99.737886 -228.780322)
			(xy 99.691728 -228.753673) (xy 99.650057 -228.720442) (xy 99.613805 -228.681371) (xy 99.583781 -228.637334)
			(xy 99.560655 -228.589313) (xy 99.544945 -228.538383) (xy 99.537002 -228.485679) (xy 99.308422 -228.485679)
			(xy 99.300479 -228.538383) (xy 99.284769 -228.589313) (xy 99.261643 -228.637334) (xy 99.231619 -228.681371)
			(xy 99.195367 -228.720442) (xy 99.153696 -228.753673) (xy 99.107538 -228.780322) (xy 99.057924 -228.799794)
			(xy 99.005962 -228.811654) (xy 98.952812 -228.815638) (xy 98.899662 -228.811654) (xy 98.8477 -228.799794)
			(xy 98.798086 -228.780322) (xy 98.751928 -228.753673) (xy 98.710257 -228.720442) (xy 98.674005 -228.681371)
			(xy 98.643981 -228.637334) (xy 98.620855 -228.589313) (xy 98.605145 -228.538383) (xy 98.597202 -228.485679)
			(xy 98.368876 -228.485679) (xy 98.360933 -228.538383) (xy 98.345223 -228.589313) (xy 98.322097 -228.637334)
			(xy 98.292073 -228.681371) (xy 98.255821 -228.720442) (xy 98.21415 -228.753673) (xy 98.167992 -228.780322)
			(xy 98.118378 -228.799794) (xy 98.066416 -228.811654) (xy 98.013266 -228.815638) (xy 97.960116 -228.811654)
			(xy 97.908154 -228.799794) (xy 97.85854 -228.780322) (xy 97.812382 -228.753673) (xy 97.770711 -228.720442)
			(xy 97.734459 -228.681371) (xy 97.704435 -228.637334) (xy 97.681309 -228.589313) (xy 97.665599 -228.538383)
			(xy 97.657656 -228.485679) (xy 97.428822 -228.485679) (xy 97.420879 -228.538383) (xy 97.405169 -228.589313)
			(xy 97.382043 -228.637334) (xy 97.352019 -228.681371) (xy 97.315767 -228.720442) (xy 97.274096 -228.753673)
			(xy 97.227938 -228.780322) (xy 97.178324 -228.799794) (xy 97.126362 -228.811654) (xy 97.073212 -228.815638)
			(xy 97.020062 -228.811654) (xy 96.9681 -228.799794) (xy 96.918486 -228.780322) (xy 96.872328 -228.753673)
			(xy 96.830657 -228.720442) (xy 96.794405 -228.681371) (xy 96.764381 -228.637334) (xy 96.741255 -228.589313)
			(xy 96.725545 -228.538383) (xy 96.717602 -228.485679) (xy 96.489022 -228.485679) (xy 96.481079 -228.538383)
			(xy 96.465369 -228.589313) (xy 96.442243 -228.637334) (xy 96.412219 -228.681371) (xy 96.375967 -228.720442)
			(xy 96.334296 -228.753673) (xy 96.288138 -228.780322) (xy 96.238524 -228.799794) (xy 96.186562 -228.811654)
			(xy 96.133412 -228.815638) (xy 96.080262 -228.811654) (xy 96.0283 -228.799794) (xy 95.978686 -228.780322)
			(xy 95.932528 -228.753673) (xy 95.890857 -228.720442) (xy 95.854605 -228.681371) (xy 95.824581 -228.637334)
			(xy 95.801455 -228.589313) (xy 95.785745 -228.538383) (xy 95.777802 -228.485679) (xy 95.549222 -228.485679)
			(xy 95.541279 -228.538383) (xy 95.525569 -228.589313) (xy 95.502443 -228.637334) (xy 95.472419 -228.681371)
			(xy 95.436167 -228.720442) (xy 95.394496 -228.753673) (xy 95.348338 -228.780322) (xy 95.298724 -228.799794)
			(xy 95.246762 -228.811654) (xy 95.193612 -228.815638) (xy 95.140462 -228.811654) (xy 95.0885 -228.799794)
			(xy 95.038886 -228.780322) (xy 94.992728 -228.753673) (xy 94.951057 -228.720442) (xy 94.914805 -228.681371)
			(xy 94.884781 -228.637334) (xy 94.861655 -228.589313) (xy 94.845945 -228.538383) (xy 94.838002 -228.485679)
			(xy 94.609422 -228.485679) (xy 94.601479 -228.538383) (xy 94.585769 -228.589313) (xy 94.562643 -228.637334)
			(xy 94.532619 -228.681371) (xy 94.496367 -228.720442) (xy 94.454696 -228.753673) (xy 94.408538 -228.780322)
			(xy 94.358924 -228.799794) (xy 94.306962 -228.811654) (xy 94.253812 -228.815638) (xy 94.200662 -228.811654)
			(xy 94.1487 -228.799794) (xy 94.099086 -228.780322) (xy 94.052928 -228.753673) (xy 94.011257 -228.720442)
			(xy 93.975005 -228.681371) (xy 93.944981 -228.637334) (xy 93.921855 -228.589313) (xy 93.906145 -228.538383)
			(xy 93.898202 -228.485679) (xy 93.669622 -228.485679) (xy 93.661679 -228.538383) (xy 93.645969 -228.589313)
			(xy 93.622843 -228.637334) (xy 93.592819 -228.681371) (xy 93.556567 -228.720442) (xy 93.514896 -228.753673)
			(xy 93.468738 -228.780322) (xy 93.419124 -228.799794) (xy 93.367162 -228.811654) (xy 93.314012 -228.815638)
			(xy 93.260862 -228.811654) (xy 93.2089 -228.799794) (xy 93.159286 -228.780322) (xy 93.113128 -228.753673)
			(xy 93.071457 -228.720442) (xy 93.035205 -228.681371) (xy 93.005181 -228.637334) (xy 92.982055 -228.589313)
			(xy 92.966345 -228.538383) (xy 92.958402 -228.485679) (xy 92.729822 -228.485679) (xy 92.721879 -228.538383)
			(xy 92.706169 -228.589313) (xy 92.683043 -228.637334) (xy 92.653019 -228.681371) (xy 92.616767 -228.720442)
			(xy 92.575096 -228.753673) (xy 92.528938 -228.780322) (xy 92.479324 -228.799794) (xy 92.427362 -228.811654)
			(xy 92.374212 -228.815638) (xy 92.321062 -228.811654) (xy 92.2691 -228.799794) (xy 92.219486 -228.780322)
			(xy 92.173328 -228.753673) (xy 92.131657 -228.720442) (xy 92.095405 -228.681371) (xy 92.065381 -228.637334)
			(xy 92.042255 -228.589313) (xy 92.026545 -228.538383) (xy 92.018602 -228.485679) (xy 91.790276 -228.485679)
			(xy 91.782333 -228.538383) (xy 91.766623 -228.589313) (xy 91.743497 -228.637334) (xy 91.713473 -228.681371)
			(xy 91.677221 -228.720442) (xy 91.63555 -228.753673) (xy 91.589392 -228.780322) (xy 91.539778 -228.799794)
			(xy 91.487816 -228.811654) (xy 91.434666 -228.815638) (xy 91.381516 -228.811654) (xy 91.329554 -228.799794)
			(xy 91.27994 -228.780322) (xy 91.233782 -228.753673) (xy 91.192111 -228.720442) (xy 91.155859 -228.681371)
			(xy 91.125835 -228.637334) (xy 91.102709 -228.589313) (xy 91.086999 -228.538383) (xy 91.079056 -228.485679)
			(xy 90.850222 -228.485679) (xy 90.842279 -228.538383) (xy 90.826569 -228.589313) (xy 90.803443 -228.637334)
			(xy 90.773419 -228.681371) (xy 90.737167 -228.720442) (xy 90.695496 -228.753673) (xy 90.649338 -228.780322)
			(xy 90.599724 -228.799794) (xy 90.547762 -228.811654) (xy 90.494612 -228.815638) (xy 90.441462 -228.811654)
			(xy 90.3895 -228.799794) (xy 90.339886 -228.780322) (xy 90.293728 -228.753673) (xy 90.252057 -228.720442)
			(xy 90.215805 -228.681371) (xy 90.185781 -228.637334) (xy 90.162655 -228.589313) (xy 90.146945 -228.538383)
			(xy 90.139002 -228.485679) (xy 89.910422 -228.485679) (xy 89.902479 -228.538383) (xy 89.886769 -228.589313)
			(xy 89.863643 -228.637334) (xy 89.833619 -228.681371) (xy 89.797367 -228.720442) (xy 89.755696 -228.753673)
			(xy 89.709538 -228.780322) (xy 89.659924 -228.799794) (xy 89.607962 -228.811654) (xy 89.554812 -228.815638)
			(xy 89.501662 -228.811654) (xy 89.4497 -228.799794) (xy 89.400086 -228.780322) (xy 89.353928 -228.753673)
			(xy 89.312257 -228.720442) (xy 89.276005 -228.681371) (xy 89.245981 -228.637334) (xy 89.222855 -228.589313)
			(xy 89.207145 -228.538383) (xy 89.199202 -228.485679) (xy 88.970635 -228.485679) (xy 88.970635 -228.485802)
			(xy 88.962617 -228.53875) (xy 88.946767 -228.589901) (xy 88.93556 -228.614224) (xy 88.93048 -228.624638)
			(xy 88.93048 -228.818186) (xy 88.930964 -228.832479) (xy 88.938897 -228.859942) (xy 88.954143 -228.884123)
			(xy 88.975504 -228.903121) (xy 89.001299 -228.91544) (xy 89.0295 -228.920113) (xy 89.043764 -228.919024)
			(xy 89.054078 -228.91792) (xy 89.074793 -228.916776) (xy 89.085166 -228.916738) (xy 89.111815 -228.917209)
			(xy 89.164519 -228.925148) (xy 89.215451 -228.940854) (xy 89.263473 -228.963976) (xy 89.307513 -228.993998)
			(xy 89.346585 -229.030248) (xy 89.379818 -229.071917) (xy 89.406469 -229.118074) (xy 89.425942 -229.167688)
			(xy 89.437803 -229.21965) (xy 89.441786 -229.2728) (xy 89.439786 -229.299495) (xy 89.669356 -229.299495)
			(xy 89.669356 -229.246197) (xy 89.677299 -229.193493) (xy 89.693009 -229.142563) (xy 89.716135 -229.094542)
			(xy 89.746159 -229.050505) (xy 89.782411 -229.011434) (xy 89.824082 -228.978203) (xy 89.87024 -228.951554)
			(xy 89.919854 -228.932082) (xy 89.971816 -228.920222) (xy 90.024966 -228.916239) (xy 90.078116 -228.920222)
			(xy 90.130078 -228.932082) (xy 90.179692 -228.951554) (xy 90.22585 -228.978203) (xy 90.267521 -229.011434)
			(xy 90.303773 -229.050505) (xy 90.333797 -229.094542) (xy 90.356923 -229.142563) (xy 90.372633 -229.193493)
			(xy 90.380576 -229.246197) (xy 90.381074 -229.272846) (xy 90.380576 -229.299495) (xy 90.609156 -229.299495)
			(xy 90.609156 -229.246197) (xy 90.617099 -229.193493) (xy 90.632809 -229.142563) (xy 90.655935 -229.094542)
			(xy 90.685959 -229.050505) (xy 90.722211 -229.011434) (xy 90.763882 -228.978203) (xy 90.81004 -228.951554)
			(xy 90.859654 -228.932082) (xy 90.911616 -228.920222) (xy 90.964766 -228.916239) (xy 91.017916 -228.920222)
			(xy 91.069878 -228.932082) (xy 91.119492 -228.951554) (xy 91.16565 -228.978203) (xy 91.207321 -229.011434)
			(xy 91.243573 -229.050505) (xy 91.273597 -229.094542) (xy 91.296723 -229.142563) (xy 91.312433 -229.193493)
			(xy 91.320376 -229.246197) (xy 91.320874 -229.272846) (xy 91.320376 -229.299495) (xy 91.548956 -229.299495)
			(xy 91.548956 -229.246197) (xy 91.556899 -229.193493) (xy 91.572609 -229.142563) (xy 91.595735 -229.094542)
			(xy 91.625759 -229.050505) (xy 91.662011 -229.011434) (xy 91.703682 -228.978203) (xy 91.74984 -228.951554)
			(xy 91.799454 -228.932082) (xy 91.851416 -228.920222) (xy 91.904566 -228.916239) (xy 91.957716 -228.920222)
			(xy 92.009678 -228.932082) (xy 92.059292 -228.951554) (xy 92.10545 -228.978203) (xy 92.147121 -229.011434)
			(xy 92.183373 -229.050505) (xy 92.213397 -229.094542) (xy 92.236523 -229.142563) (xy 92.252233 -229.193493)
			(xy 92.260176 -229.246197) (xy 92.260674 -229.272846) (xy 92.260176 -229.299495) (xy 92.488756 -229.299495)
			(xy 92.488756 -229.246197) (xy 92.496699 -229.193493) (xy 92.512409 -229.142563) (xy 92.535535 -229.094542)
			(xy 92.565559 -229.050505) (xy 92.601811 -229.011434) (xy 92.643482 -228.978203) (xy 92.68964 -228.951554)
			(xy 92.739254 -228.932082) (xy 92.791216 -228.920222) (xy 92.844366 -228.916239) (xy 92.897516 -228.920222)
			(xy 92.949478 -228.932082) (xy 92.999092 -228.951554) (xy 93.04525 -228.978203) (xy 93.086921 -229.011434)
			(xy 93.123173 -229.050505) (xy 93.153197 -229.094542) (xy 93.176323 -229.142563) (xy 93.192033 -229.193493)
			(xy 93.199976 -229.246197) (xy 93.200474 -229.272846) (xy 93.199976 -229.299495) (xy 93.428556 -229.299495)
			(xy 93.428556 -229.246197) (xy 93.436499 -229.193493) (xy 93.452209 -229.142563) (xy 93.475335 -229.094542)
			(xy 93.505359 -229.050505) (xy 93.541611 -229.011434) (xy 93.583282 -228.978203) (xy 93.62944 -228.951554)
			(xy 93.679054 -228.932082) (xy 93.731016 -228.920222) (xy 93.784166 -228.916239) (xy 93.837316 -228.920222)
			(xy 93.889278 -228.932082) (xy 93.938892 -228.951554) (xy 93.98505 -228.978203) (xy 94.026721 -229.011434)
			(xy 94.062973 -229.050505) (xy 94.092997 -229.094542) (xy 94.116123 -229.142563) (xy 94.131833 -229.193493)
			(xy 94.139776 -229.246197) (xy 94.140274 -229.272846) (xy 94.139776 -229.299495) (xy 94.368102 -229.299495)
			(xy 94.368102 -229.246197) (xy 94.376045 -229.193493) (xy 94.391755 -229.142563) (xy 94.414881 -229.094542)
			(xy 94.444905 -229.050505) (xy 94.481157 -229.011434) (xy 94.522828 -228.978203) (xy 94.568986 -228.951554)
			(xy 94.6186 -228.932082) (xy 94.670562 -228.920222) (xy 94.723712 -228.916239) (xy 94.776862 -228.920222)
			(xy 94.828824 -228.932082) (xy 94.878438 -228.951554) (xy 94.924596 -228.978203) (xy 94.966267 -229.011434)
			(xy 95.002519 -229.050505) (xy 95.032543 -229.094542) (xy 95.055669 -229.142563) (xy 95.071379 -229.193493)
			(xy 95.079322 -229.246197) (xy 95.07982 -229.272846) (xy 95.079322 -229.299495) (xy 95.308156 -229.299495)
			(xy 95.308156 -229.246197) (xy 95.316099 -229.193493) (xy 95.331809 -229.142563) (xy 95.354935 -229.094542)
			(xy 95.384959 -229.050505) (xy 95.421211 -229.011434) (xy 95.462882 -228.978203) (xy 95.50904 -228.951554)
			(xy 95.558654 -228.932082) (xy 95.610616 -228.920222) (xy 95.663766 -228.916239) (xy 95.716916 -228.920222)
			(xy 95.768878 -228.932082) (xy 95.818492 -228.951554) (xy 95.86465 -228.978203) (xy 95.906321 -229.011434)
			(xy 95.942573 -229.050505) (xy 95.972597 -229.094542) (xy 95.995723 -229.142563) (xy 96.011433 -229.193493)
			(xy 96.019376 -229.246197) (xy 96.019874 -229.272846) (xy 96.019376 -229.299495) (xy 96.247956 -229.299495)
			(xy 96.247956 -229.246197) (xy 96.255899 -229.193493) (xy 96.271609 -229.142563) (xy 96.294735 -229.094542)
			(xy 96.324759 -229.050505) (xy 96.361011 -229.011434) (xy 96.402682 -228.978203) (xy 96.44884 -228.951554)
			(xy 96.498454 -228.932082) (xy 96.550416 -228.920222) (xy 96.603566 -228.916239) (xy 96.656716 -228.920222)
			(xy 96.708678 -228.932082) (xy 96.758292 -228.951554) (xy 96.80445 -228.978203) (xy 96.846121 -229.011434)
			(xy 96.882373 -229.050505) (xy 96.912397 -229.094542) (xy 96.935523 -229.142563) (xy 96.951233 -229.193493)
			(xy 96.959176 -229.246197) (xy 96.959674 -229.272846) (xy 96.959176 -229.299495) (xy 97.187756 -229.299495)
			(xy 97.187756 -229.246197) (xy 97.195699 -229.193493) (xy 97.211409 -229.142563) (xy 97.234535 -229.094542)
			(xy 97.264559 -229.050505) (xy 97.300811 -229.011434) (xy 97.342482 -228.978203) (xy 97.38864 -228.951554)
			(xy 97.438254 -228.932082) (xy 97.490216 -228.920222) (xy 97.543366 -228.916239) (xy 97.596516 -228.920222)
			(xy 97.648478 -228.932082) (xy 97.698092 -228.951554) (xy 97.74425 -228.978203) (xy 97.785921 -229.011434)
			(xy 97.822173 -229.050505) (xy 97.852197 -229.094542) (xy 97.875323 -229.142563) (xy 97.891033 -229.193493)
			(xy 97.898976 -229.246197) (xy 97.899474 -229.272846) (xy 97.898976 -229.299495) (xy 98.127556 -229.299495)
			(xy 98.127556 -229.246197) (xy 98.135499 -229.193493) (xy 98.151209 -229.142563) (xy 98.174335 -229.094542)
			(xy 98.204359 -229.050505) (xy 98.240611 -229.011434) (xy 98.282282 -228.978203) (xy 98.32844 -228.951554)
			(xy 98.378054 -228.932082) (xy 98.430016 -228.920222) (xy 98.483166 -228.916239) (xy 98.536316 -228.920222)
			(xy 98.588278 -228.932082) (xy 98.637892 -228.951554) (xy 98.68405 -228.978203) (xy 98.725721 -229.011434)
			(xy 98.761973 -229.050505) (xy 98.791997 -229.094542) (xy 98.815123 -229.142563) (xy 98.830833 -229.193493)
			(xy 98.838776 -229.246197) (xy 98.839274 -229.272846) (xy 98.838776 -229.299495) (xy 99.067356 -229.299495)
			(xy 99.067356 -229.246197) (xy 99.075299 -229.193493) (xy 99.091009 -229.142563) (xy 99.114135 -229.094542)
			(xy 99.144159 -229.050505) (xy 99.180411 -229.011434) (xy 99.222082 -228.978203) (xy 99.26824 -228.951554)
			(xy 99.317854 -228.932082) (xy 99.369816 -228.920222) (xy 99.422966 -228.916239) (xy 99.476116 -228.920222)
			(xy 99.528078 -228.932082) (xy 99.577692 -228.951554) (xy 99.62385 -228.978203) (xy 99.665521 -229.011434)
			(xy 99.701773 -229.050505) (xy 99.731797 -229.094542) (xy 99.754923 -229.142563) (xy 99.770633 -229.193493)
			(xy 99.778576 -229.246197) (xy 99.779074 -229.272846) (xy 99.778576 -229.299495) (xy 100.007156 -229.299495)
			(xy 100.007156 -229.246197) (xy 100.015099 -229.193493) (xy 100.030809 -229.142563) (xy 100.053935 -229.094542)
			(xy 100.083959 -229.050505) (xy 100.120211 -229.011434) (xy 100.161882 -228.978203) (xy 100.20804 -228.951554)
			(xy 100.257654 -228.932082) (xy 100.309616 -228.920222) (xy 100.362766 -228.916239) (xy 100.415916 -228.920222)
			(xy 100.467878 -228.932082) (xy 100.517492 -228.951554) (xy 100.56365 -228.978203) (xy 100.605321 -229.011434)
			(xy 100.641573 -229.050505) (xy 100.671597 -229.094542) (xy 100.694723 -229.142563) (xy 100.710433 -229.193493)
			(xy 100.718376 -229.246197) (xy 100.718874 -229.272846) (xy 100.718376 -229.299495) (xy 100.946702 -229.299495)
			(xy 100.946702 -229.246197) (xy 100.954645 -229.193493) (xy 100.970355 -229.142563) (xy 100.993481 -229.094542)
			(xy 101.023505 -229.050505) (xy 101.059757 -229.011434) (xy 101.101428 -228.978203) (xy 101.147586 -228.951554)
			(xy 101.1972 -228.932082) (xy 101.249162 -228.920222) (xy 101.302312 -228.916239) (xy 101.355462 -228.920222)
			(xy 101.407424 -228.932082) (xy 101.457038 -228.951554) (xy 101.503196 -228.978203) (xy 101.544867 -229.011434)
			(xy 101.581119 -229.050505) (xy 101.611143 -229.094542) (xy 101.634269 -229.142563) (xy 101.649979 -229.193493)
			(xy 101.657922 -229.246197) (xy 101.65842 -229.272846) (xy 101.657922 -229.299495) (xy 101.886756 -229.299495)
			(xy 101.886756 -229.246197) (xy 101.894699 -229.193493) (xy 101.910409 -229.142563) (xy 101.933535 -229.094542)
			(xy 101.963559 -229.050505) (xy 101.999811 -229.011434) (xy 102.041482 -228.978203) (xy 102.08764 -228.951554)
			(xy 102.137254 -228.932082) (xy 102.189216 -228.920222) (xy 102.242366 -228.916239) (xy 102.295516 -228.920222)
			(xy 102.347478 -228.932082) (xy 102.397092 -228.951554) (xy 102.44325 -228.978203) (xy 102.484921 -229.011434)
			(xy 102.521173 -229.050505) (xy 102.551197 -229.094542) (xy 102.574323 -229.142563) (xy 102.590033 -229.193493)
			(xy 102.597976 -229.246197) (xy 102.598474 -229.272846) (xy 102.597976 -229.299495) (xy 102.826556 -229.299495)
			(xy 102.826556 -229.246197) (xy 102.834499 -229.193493) (xy 102.850209 -229.142563) (xy 102.873335 -229.094542)
			(xy 102.903359 -229.050505) (xy 102.939611 -229.011434) (xy 102.981282 -228.978203) (xy 103.02744 -228.951554)
			(xy 103.077054 -228.932082) (xy 103.129016 -228.920222) (xy 103.182166 -228.916239) (xy 103.235316 -228.920222)
			(xy 103.287278 -228.932082) (xy 103.336892 -228.951554) (xy 103.38305 -228.978203) (xy 103.424721 -229.011434)
			(xy 103.460973 -229.050505) (xy 103.490997 -229.094542) (xy 103.514123 -229.142563) (xy 103.529833 -229.193493)
			(xy 103.537776 -229.246197) (xy 103.538274 -229.272846) (xy 103.537776 -229.299495) (xy 103.766356 -229.299495)
			(xy 103.766356 -229.246197) (xy 103.774299 -229.193493) (xy 103.790009 -229.142563) (xy 103.813135 -229.094542)
			(xy 103.843159 -229.050505) (xy 103.879411 -229.011434) (xy 103.921082 -228.978203) (xy 103.96724 -228.951554)
			(xy 104.016854 -228.932082) (xy 104.068816 -228.920222) (xy 104.121966 -228.916239) (xy 104.175116 -228.920222)
			(xy 104.227078 -228.932082) (xy 104.276692 -228.951554) (xy 104.32285 -228.978203) (xy 104.364521 -229.011434)
			(xy 104.400773 -229.050505) (xy 104.430797 -229.094542) (xy 104.453923 -229.142563) (xy 104.469633 -229.193493)
			(xy 104.477576 -229.246197) (xy 104.478074 -229.272846) (xy 104.477576 -229.299495) (xy 104.706156 -229.299495)
			(xy 104.706156 -229.246197) (xy 104.714099 -229.193493) (xy 104.729809 -229.142563) (xy 104.752935 -229.094542)
			(xy 104.782959 -229.050505) (xy 104.819211 -229.011434) (xy 104.860882 -228.978203) (xy 104.90704 -228.951554)
			(xy 104.956654 -228.932082) (xy 105.008616 -228.920222) (xy 105.061766 -228.916239) (xy 105.114916 -228.920222)
			(xy 105.166878 -228.932082) (xy 105.216492 -228.951554) (xy 105.26265 -228.978203) (xy 105.304321 -229.011434)
			(xy 105.340573 -229.050505) (xy 105.370597 -229.094542) (xy 105.393723 -229.142563) (xy 105.409433 -229.193493)
			(xy 105.417376 -229.246197) (xy 105.417874 -229.272846) (xy 105.417376 -229.299495) (xy 105.645956 -229.299495)
			(xy 105.645956 -229.246197) (xy 105.653899 -229.193493) (xy 105.669609 -229.142563) (xy 105.692735 -229.094542)
			(xy 105.722759 -229.050505) (xy 105.759011 -229.011434) (xy 105.800682 -228.978203) (xy 105.84684 -228.951554)
			(xy 105.896454 -228.932082) (xy 105.948416 -228.920222) (xy 106.001566 -228.916239) (xy 106.054716 -228.920222)
			(xy 106.106678 -228.932082) (xy 106.156292 -228.951554) (xy 106.20245 -228.978203) (xy 106.244121 -229.011434)
			(xy 106.280373 -229.050505) (xy 106.310397 -229.094542) (xy 106.333523 -229.142563) (xy 106.349233 -229.193493)
			(xy 106.357176 -229.246197) (xy 106.357674 -229.272846) (xy 106.357176 -229.299495) (xy 106.585756 -229.299495)
			(xy 106.585756 -229.246197) (xy 106.593699 -229.193493) (xy 106.609409 -229.142563) (xy 106.632535 -229.094542)
			(xy 106.662559 -229.050505) (xy 106.698811 -229.011434) (xy 106.740482 -228.978203) (xy 106.78664 -228.951554)
			(xy 106.836254 -228.932082) (xy 106.888216 -228.920222) (xy 106.941366 -228.916239) (xy 106.994516 -228.920222)
			(xy 107.046478 -228.932082) (xy 107.096092 -228.951554) (xy 107.14225 -228.978203) (xy 107.183921 -229.011434)
			(xy 107.220173 -229.050505) (xy 107.250197 -229.094542) (xy 107.273323 -229.142563) (xy 107.289033 -229.193493)
			(xy 107.296976 -229.246197) (xy 107.297474 -229.272846) (xy 107.296976 -229.299495) (xy 107.525556 -229.299495)
			(xy 107.525556 -229.246197) (xy 107.533499 -229.193493) (xy 107.549209 -229.142563) (xy 107.572335 -229.094542)
			(xy 107.602359 -229.050505) (xy 107.638611 -229.011434) (xy 107.680282 -228.978203) (xy 107.72644 -228.951554)
			(xy 107.776054 -228.932082) (xy 107.828016 -228.920222) (xy 107.881166 -228.916239) (xy 107.934316 -228.920222)
			(xy 107.986278 -228.932082) (xy 108.035892 -228.951554) (xy 108.08205 -228.978203) (xy 108.123721 -229.011434)
			(xy 108.159973 -229.050505) (xy 108.189997 -229.094542) (xy 108.213123 -229.142563) (xy 108.228833 -229.193493)
			(xy 108.236776 -229.246197) (xy 108.237274 -229.272846) (xy 108.236776 -229.299495) (xy 108.465356 -229.299495)
			(xy 108.465356 -229.246197) (xy 108.473299 -229.193493) (xy 108.489009 -229.142563) (xy 108.512135 -229.094542)
			(xy 108.542159 -229.050505) (xy 108.578411 -229.011434) (xy 108.620082 -228.978203) (xy 108.66624 -228.951554)
			(xy 108.715854 -228.932082) (xy 108.767816 -228.920222) (xy 108.820966 -228.916239) (xy 108.874116 -228.920222)
			(xy 108.926078 -228.932082) (xy 108.975692 -228.951554) (xy 109.02185 -228.978203) (xy 109.063521 -229.011434)
			(xy 109.099773 -229.050505) (xy 109.129797 -229.094542) (xy 109.152923 -229.142563) (xy 109.168633 -229.193493)
			(xy 109.176576 -229.246197) (xy 109.177074 -229.272846) (xy 109.176576 -229.299495) (xy 109.405156 -229.299495)
			(xy 109.405156 -229.246197) (xy 109.413099 -229.193493) (xy 109.428809 -229.142563) (xy 109.451935 -229.094542)
			(xy 109.481959 -229.050505) (xy 109.518211 -229.011434) (xy 109.559882 -228.978203) (xy 109.60604 -228.951554)
			(xy 109.655654 -228.932082) (xy 109.707616 -228.920222) (xy 109.760766 -228.916239) (xy 109.813916 -228.920222)
			(xy 109.865878 -228.932082) (xy 109.915492 -228.951554) (xy 109.96165 -228.978203) (xy 110.003321 -229.011434)
			(xy 110.039573 -229.050505) (xy 110.069597 -229.094542) (xy 110.092723 -229.142563) (xy 110.108433 -229.193493)
			(xy 110.116376 -229.246197) (xy 110.116874 -229.272846) (xy 110.116376 -229.299495) (xy 110.344956 -229.299495)
			(xy 110.344956 -229.246197) (xy 110.352899 -229.193493) (xy 110.368609 -229.142563) (xy 110.391735 -229.094542)
			(xy 110.421759 -229.050505) (xy 110.458011 -229.011434) (xy 110.499682 -228.978203) (xy 110.54584 -228.951554)
			(xy 110.595454 -228.932082) (xy 110.647416 -228.920222) (xy 110.700566 -228.916239) (xy 110.753716 -228.920222)
			(xy 110.805678 -228.932082) (xy 110.855292 -228.951554) (xy 110.90145 -228.978203) (xy 110.943121 -229.011434)
			(xy 110.979373 -229.050505) (xy 111.009397 -229.094542) (xy 111.032523 -229.142563) (xy 111.048233 -229.193493)
			(xy 111.056176 -229.246197) (xy 111.056674 -229.272846) (xy 111.056176 -229.299495) (xy 111.048233 -229.352199)
			(xy 111.032523 -229.403129) (xy 111.009397 -229.45115) (xy 110.979373 -229.495187) (xy 110.943121 -229.534258)
			(xy 110.90145 -229.567489) (xy 110.855292 -229.594138) (xy 110.805678 -229.61361) (xy 110.753716 -229.62547)
			(xy 110.700566 -229.629454) (xy 110.647416 -229.62547) (xy 110.595454 -229.61361) (xy 110.54584 -229.594138)
			(xy 110.499682 -229.567489) (xy 110.458011 -229.534258) (xy 110.421759 -229.495187) (xy 110.391735 -229.45115)
			(xy 110.368609 -229.403129) (xy 110.352899 -229.352199) (xy 110.344956 -229.299495) (xy 110.116376 -229.299495)
			(xy 110.108433 -229.352199) (xy 110.092723 -229.403129) (xy 110.069597 -229.45115) (xy 110.039573 -229.495187)
			(xy 110.003321 -229.534258) (xy 109.96165 -229.567489) (xy 109.915492 -229.594138) (xy 109.865878 -229.61361)
			(xy 109.813916 -229.62547) (xy 109.760766 -229.629454) (xy 109.707616 -229.62547) (xy 109.655654 -229.61361)
			(xy 109.60604 -229.594138) (xy 109.559882 -229.567489) (xy 109.518211 -229.534258) (xy 109.481959 -229.495187)
			(xy 109.451935 -229.45115) (xy 109.428809 -229.403129) (xy 109.413099 -229.352199) (xy 109.405156 -229.299495)
			(xy 109.176576 -229.299495) (xy 109.168633 -229.352199) (xy 109.152923 -229.403129) (xy 109.129797 -229.45115)
			(xy 109.099773 -229.495187) (xy 109.063521 -229.534258) (xy 109.02185 -229.567489) (xy 108.975692 -229.594138)
			(xy 108.926078 -229.61361) (xy 108.874116 -229.62547) (xy 108.820966 -229.629454) (xy 108.767816 -229.62547)
			(xy 108.715854 -229.61361) (xy 108.66624 -229.594138) (xy 108.620082 -229.567489) (xy 108.578411 -229.534258)
			(xy 108.542159 -229.495187) (xy 108.512135 -229.45115) (xy 108.489009 -229.403129) (xy 108.473299 -229.352199)
			(xy 108.465356 -229.299495) (xy 108.236776 -229.299495) (xy 108.228833 -229.352199) (xy 108.213123 -229.403129)
			(xy 108.189997 -229.45115) (xy 108.159973 -229.495187) (xy 108.123721 -229.534258) (xy 108.08205 -229.567489)
			(xy 108.035892 -229.594138) (xy 107.986278 -229.61361) (xy 107.934316 -229.62547) (xy 107.881166 -229.629454)
			(xy 107.828016 -229.62547) (xy 107.776054 -229.61361) (xy 107.72644 -229.594138) (xy 107.680282 -229.567489)
			(xy 107.638611 -229.534258) (xy 107.602359 -229.495187) (xy 107.572335 -229.45115) (xy 107.549209 -229.403129)
			(xy 107.533499 -229.352199) (xy 107.525556 -229.299495) (xy 107.296976 -229.299495) (xy 107.289033 -229.352199)
			(xy 107.273323 -229.403129) (xy 107.250197 -229.45115) (xy 107.220173 -229.495187) (xy 107.183921 -229.534258)
			(xy 107.14225 -229.567489) (xy 107.096092 -229.594138) (xy 107.046478 -229.61361) (xy 106.994516 -229.62547)
			(xy 106.941366 -229.629454) (xy 106.888216 -229.62547) (xy 106.836254 -229.61361) (xy 106.78664 -229.594138)
			(xy 106.740482 -229.567489) (xy 106.698811 -229.534258) (xy 106.662559 -229.495187) (xy 106.632535 -229.45115)
			(xy 106.609409 -229.403129) (xy 106.593699 -229.352199) (xy 106.585756 -229.299495) (xy 106.357176 -229.299495)
			(xy 106.349233 -229.352199) (xy 106.333523 -229.403129) (xy 106.310397 -229.45115) (xy 106.280373 -229.495187)
			(xy 106.244121 -229.534258) (xy 106.20245 -229.567489) (xy 106.156292 -229.594138) (xy 106.106678 -229.61361)
			(xy 106.054716 -229.62547) (xy 106.001566 -229.629454) (xy 105.948416 -229.62547) (xy 105.896454 -229.61361)
			(xy 105.84684 -229.594138) (xy 105.800682 -229.567489) (xy 105.759011 -229.534258) (xy 105.722759 -229.495187)
			(xy 105.692735 -229.45115) (xy 105.669609 -229.403129) (xy 105.653899 -229.352199) (xy 105.645956 -229.299495)
			(xy 105.417376 -229.299495) (xy 105.409433 -229.352199) (xy 105.393723 -229.403129) (xy 105.370597 -229.45115)
			(xy 105.340573 -229.495187) (xy 105.304321 -229.534258) (xy 105.26265 -229.567489) (xy 105.216492 -229.594138)
			(xy 105.166878 -229.61361) (xy 105.114916 -229.62547) (xy 105.061766 -229.629454) (xy 105.008616 -229.62547)
			(xy 104.956654 -229.61361) (xy 104.90704 -229.594138) (xy 104.860882 -229.567489) (xy 104.819211 -229.534258)
			(xy 104.782959 -229.495187) (xy 104.752935 -229.45115) (xy 104.729809 -229.403129) (xy 104.714099 -229.352199)
			(xy 104.706156 -229.299495) (xy 104.477576 -229.299495) (xy 104.469633 -229.352199) (xy 104.453923 -229.403129)
			(xy 104.430797 -229.45115) (xy 104.400773 -229.495187) (xy 104.364521 -229.534258) (xy 104.32285 -229.567489)
			(xy 104.276692 -229.594138) (xy 104.227078 -229.61361) (xy 104.175116 -229.62547) (xy 104.121966 -229.629454)
			(xy 104.068816 -229.62547) (xy 104.016854 -229.61361) (xy 103.96724 -229.594138) (xy 103.921082 -229.567489)
			(xy 103.879411 -229.534258) (xy 103.843159 -229.495187) (xy 103.813135 -229.45115) (xy 103.790009 -229.403129)
			(xy 103.774299 -229.352199) (xy 103.766356 -229.299495) (xy 103.537776 -229.299495) (xy 103.529833 -229.352199)
			(xy 103.514123 -229.403129) (xy 103.490997 -229.45115) (xy 103.460973 -229.495187) (xy 103.424721 -229.534258)
			(xy 103.38305 -229.567489) (xy 103.336892 -229.594138) (xy 103.287278 -229.61361) (xy 103.235316 -229.62547)
			(xy 103.182166 -229.629454) (xy 103.129016 -229.62547) (xy 103.077054 -229.61361) (xy 103.02744 -229.594138)
			(xy 102.981282 -229.567489) (xy 102.939611 -229.534258) (xy 102.903359 -229.495187) (xy 102.873335 -229.45115)
			(xy 102.850209 -229.403129) (xy 102.834499 -229.352199) (xy 102.826556 -229.299495) (xy 102.597976 -229.299495)
			(xy 102.590033 -229.352199) (xy 102.574323 -229.403129) (xy 102.551197 -229.45115) (xy 102.521173 -229.495187)
			(xy 102.484921 -229.534258) (xy 102.44325 -229.567489) (xy 102.397092 -229.594138) (xy 102.347478 -229.61361)
			(xy 102.295516 -229.62547) (xy 102.242366 -229.629454) (xy 102.189216 -229.62547) (xy 102.137254 -229.61361)
			(xy 102.08764 -229.594138) (xy 102.041482 -229.567489) (xy 101.999811 -229.534258) (xy 101.963559 -229.495187)
			(xy 101.933535 -229.45115) (xy 101.910409 -229.403129) (xy 101.894699 -229.352199) (xy 101.886756 -229.299495)
			(xy 101.657922 -229.299495) (xy 101.649979 -229.352199) (xy 101.634269 -229.403129) (xy 101.611143 -229.45115)
			(xy 101.581119 -229.495187) (xy 101.544867 -229.534258) (xy 101.503196 -229.567489) (xy 101.457038 -229.594138)
			(xy 101.407424 -229.61361) (xy 101.355462 -229.62547) (xy 101.302312 -229.629454) (xy 101.249162 -229.62547)
			(xy 101.1972 -229.61361) (xy 101.147586 -229.594138) (xy 101.101428 -229.567489) (xy 101.059757 -229.534258)
			(xy 101.023505 -229.495187) (xy 100.993481 -229.45115) (xy 100.970355 -229.403129) (xy 100.954645 -229.352199)
			(xy 100.946702 -229.299495) (xy 100.718376 -229.299495) (xy 100.710433 -229.352199) (xy 100.694723 -229.403129)
			(xy 100.671597 -229.45115) (xy 100.641573 -229.495187) (xy 100.605321 -229.534258) (xy 100.56365 -229.567489)
			(xy 100.517492 -229.594138) (xy 100.467878 -229.61361) (xy 100.415916 -229.62547) (xy 100.362766 -229.629454)
			(xy 100.309616 -229.62547) (xy 100.257654 -229.61361) (xy 100.20804 -229.594138) (xy 100.161882 -229.567489)
			(xy 100.120211 -229.534258) (xy 100.083959 -229.495187) (xy 100.053935 -229.45115) (xy 100.030809 -229.403129)
			(xy 100.015099 -229.352199) (xy 100.007156 -229.299495) (xy 99.778576 -229.299495) (xy 99.770633 -229.352199)
			(xy 99.754923 -229.403129) (xy 99.731797 -229.45115) (xy 99.701773 -229.495187) (xy 99.665521 -229.534258)
			(xy 99.62385 -229.567489) (xy 99.577692 -229.594138) (xy 99.528078 -229.61361) (xy 99.476116 -229.62547)
			(xy 99.422966 -229.629454) (xy 99.369816 -229.62547) (xy 99.317854 -229.61361) (xy 99.26824 -229.594138)
			(xy 99.222082 -229.567489) (xy 99.180411 -229.534258) (xy 99.144159 -229.495187) (xy 99.114135 -229.45115)
			(xy 99.091009 -229.403129) (xy 99.075299 -229.352199) (xy 99.067356 -229.299495) (xy 98.838776 -229.299495)
			(xy 98.830833 -229.352199) (xy 98.815123 -229.403129) (xy 98.791997 -229.45115) (xy 98.761973 -229.495187)
			(xy 98.725721 -229.534258) (xy 98.68405 -229.567489) (xy 98.637892 -229.594138) (xy 98.588278 -229.61361)
			(xy 98.536316 -229.62547) (xy 98.483166 -229.629454) (xy 98.430016 -229.62547) (xy 98.378054 -229.61361)
			(xy 98.32844 -229.594138) (xy 98.282282 -229.567489) (xy 98.240611 -229.534258) (xy 98.204359 -229.495187)
			(xy 98.174335 -229.45115) (xy 98.151209 -229.403129) (xy 98.135499 -229.352199) (xy 98.127556 -229.299495)
			(xy 97.898976 -229.299495) (xy 97.891033 -229.352199) (xy 97.875323 -229.403129) (xy 97.852197 -229.45115)
			(xy 97.822173 -229.495187) (xy 97.785921 -229.534258) (xy 97.74425 -229.567489) (xy 97.698092 -229.594138)
			(xy 97.648478 -229.61361) (xy 97.596516 -229.62547) (xy 97.543366 -229.629454) (xy 97.490216 -229.62547)
			(xy 97.438254 -229.61361) (xy 97.38864 -229.594138) (xy 97.342482 -229.567489) (xy 97.300811 -229.534258)
			(xy 97.264559 -229.495187) (xy 97.234535 -229.45115) (xy 97.211409 -229.403129) (xy 97.195699 -229.352199)
			(xy 97.187756 -229.299495) (xy 96.959176 -229.299495) (xy 96.951233 -229.352199) (xy 96.935523 -229.403129)
			(xy 96.912397 -229.45115) (xy 96.882373 -229.495187) (xy 96.846121 -229.534258) (xy 96.80445 -229.567489)
			(xy 96.758292 -229.594138) (xy 96.708678 -229.61361) (xy 96.656716 -229.62547) (xy 96.603566 -229.629454)
			(xy 96.550416 -229.62547) (xy 96.498454 -229.61361) (xy 96.44884 -229.594138) (xy 96.402682 -229.567489)
			(xy 96.361011 -229.534258) (xy 96.324759 -229.495187) (xy 96.294735 -229.45115) (xy 96.271609 -229.403129)
			(xy 96.255899 -229.352199) (xy 96.247956 -229.299495) (xy 96.019376 -229.299495) (xy 96.011433 -229.352199)
			(xy 95.995723 -229.403129) (xy 95.972597 -229.45115) (xy 95.942573 -229.495187) (xy 95.906321 -229.534258)
			(xy 95.86465 -229.567489) (xy 95.818492 -229.594138) (xy 95.768878 -229.61361) (xy 95.716916 -229.62547)
			(xy 95.663766 -229.629454) (xy 95.610616 -229.62547) (xy 95.558654 -229.61361) (xy 95.50904 -229.594138)
			(xy 95.462882 -229.567489) (xy 95.421211 -229.534258) (xy 95.384959 -229.495187) (xy 95.354935 -229.45115)
			(xy 95.331809 -229.403129) (xy 95.316099 -229.352199) (xy 95.308156 -229.299495) (xy 95.079322 -229.299495)
			(xy 95.071379 -229.352199) (xy 95.055669 -229.403129) (xy 95.032543 -229.45115) (xy 95.002519 -229.495187)
			(xy 94.966267 -229.534258) (xy 94.924596 -229.567489) (xy 94.878438 -229.594138) (xy 94.828824 -229.61361)
			(xy 94.776862 -229.62547) (xy 94.723712 -229.629454) (xy 94.670562 -229.62547) (xy 94.6186 -229.61361)
			(xy 94.568986 -229.594138) (xy 94.522828 -229.567489) (xy 94.481157 -229.534258) (xy 94.444905 -229.495187)
			(xy 94.414881 -229.45115) (xy 94.391755 -229.403129) (xy 94.376045 -229.352199) (xy 94.368102 -229.299495)
			(xy 94.139776 -229.299495) (xy 94.131833 -229.352199) (xy 94.116123 -229.403129) (xy 94.092997 -229.45115)
			(xy 94.062973 -229.495187) (xy 94.026721 -229.534258) (xy 93.98505 -229.567489) (xy 93.938892 -229.594138)
			(xy 93.889278 -229.61361) (xy 93.837316 -229.62547) (xy 93.784166 -229.629454) (xy 93.731016 -229.62547)
			(xy 93.679054 -229.61361) (xy 93.62944 -229.594138) (xy 93.583282 -229.567489) (xy 93.541611 -229.534258)
			(xy 93.505359 -229.495187) (xy 93.475335 -229.45115) (xy 93.452209 -229.403129) (xy 93.436499 -229.352199)
			(xy 93.428556 -229.299495) (xy 93.199976 -229.299495) (xy 93.192033 -229.352199) (xy 93.176323 -229.403129)
			(xy 93.153197 -229.45115) (xy 93.123173 -229.495187) (xy 93.086921 -229.534258) (xy 93.04525 -229.567489)
			(xy 92.999092 -229.594138) (xy 92.949478 -229.61361) (xy 92.897516 -229.62547) (xy 92.844366 -229.629454)
			(xy 92.791216 -229.62547) (xy 92.739254 -229.61361) (xy 92.68964 -229.594138) (xy 92.643482 -229.567489)
			(xy 92.601811 -229.534258) (xy 92.565559 -229.495187) (xy 92.535535 -229.45115) (xy 92.512409 -229.403129)
			(xy 92.496699 -229.352199) (xy 92.488756 -229.299495) (xy 92.260176 -229.299495) (xy 92.252233 -229.352199)
			(xy 92.236523 -229.403129) (xy 92.213397 -229.45115) (xy 92.183373 -229.495187) (xy 92.147121 -229.534258)
			(xy 92.10545 -229.567489) (xy 92.059292 -229.594138) (xy 92.009678 -229.61361) (xy 91.957716 -229.62547)
			(xy 91.904566 -229.629454) (xy 91.851416 -229.62547) (xy 91.799454 -229.61361) (xy 91.74984 -229.594138)
			(xy 91.703682 -229.567489) (xy 91.662011 -229.534258) (xy 91.625759 -229.495187) (xy 91.595735 -229.45115)
			(xy 91.572609 -229.403129) (xy 91.556899 -229.352199) (xy 91.548956 -229.299495) (xy 91.320376 -229.299495)
			(xy 91.312433 -229.352199) (xy 91.296723 -229.403129) (xy 91.273597 -229.45115) (xy 91.243573 -229.495187)
			(xy 91.207321 -229.534258) (xy 91.16565 -229.567489) (xy 91.119492 -229.594138) (xy 91.069878 -229.61361)
			(xy 91.017916 -229.62547) (xy 90.964766 -229.629454) (xy 90.911616 -229.62547) (xy 90.859654 -229.61361)
			(xy 90.81004 -229.594138) (xy 90.763882 -229.567489) (xy 90.722211 -229.534258) (xy 90.685959 -229.495187)
			(xy 90.655935 -229.45115) (xy 90.632809 -229.403129) (xy 90.617099 -229.352199) (xy 90.609156 -229.299495)
			(xy 90.380576 -229.299495) (xy 90.372633 -229.352199) (xy 90.356923 -229.403129) (xy 90.333797 -229.45115)
			(xy 90.303773 -229.495187) (xy 90.267521 -229.534258) (xy 90.22585 -229.567489) (xy 90.179692 -229.594138)
			(xy 90.130078 -229.61361) (xy 90.078116 -229.62547) (xy 90.024966 -229.629454) (xy 89.971816 -229.62547)
			(xy 89.919854 -229.61361) (xy 89.87024 -229.594138) (xy 89.824082 -229.567489) (xy 89.782411 -229.534258)
			(xy 89.746159 -229.495187) (xy 89.716135 -229.45115) (xy 89.693009 -229.403129) (xy 89.677299 -229.352199)
			(xy 89.669356 -229.299495) (xy 89.439786 -229.299495) (xy 89.437803 -229.32595) (xy 89.425942 -229.377912)
			(xy 89.406469 -229.427526) (xy 89.379818 -229.473683) (xy 89.346585 -229.515352) (xy 89.307513 -229.551602)
			(xy 89.263473 -229.581624) (xy 89.215451 -229.604746) (xy 89.164519 -229.620452) (xy 89.111815 -229.628391)
			(xy 89.085166 -229.628954) (xy 89.074793 -229.628908) (xy 89.054079 -229.627766) (xy 89.043764 -229.626668)
			(xy 89.029511 -229.625507) (xy 89.001317 -229.630223) (xy 88.975536 -229.642569) (xy 88.954186 -229.661576)
			(xy 88.93894 -229.685756) (xy 88.930992 -229.713214) (xy 88.93048 -229.727506) (xy 88.93048 -229.921054)
			(xy 88.93556 -229.931468) (xy 88.946791 -229.955781) (xy 88.962645 -230.006937) (xy 88.970664 -230.059888)
			(xy 88.970669 -230.113311) (xy 89.199202 -230.113311) (xy 89.199202 -230.060013) (xy 89.207145 -230.007309)
			(xy 89.222855 -229.956379) (xy 89.245981 -229.908358) (xy 89.276005 -229.864321) (xy 89.312257 -229.82525)
			(xy 89.353928 -229.792019) (xy 89.400086 -229.76537) (xy 89.4497 -229.745898) (xy 89.501662 -229.734038)
			(xy 89.554812 -229.730055) (xy 89.607962 -229.734038) (xy 89.659924 -229.745898) (xy 89.709538 -229.76537)
			(xy 89.755696 -229.792019) (xy 89.797367 -229.82525) (xy 89.833619 -229.864321) (xy 89.863643 -229.908358)
			(xy 89.886769 -229.956379) (xy 89.902479 -230.007309) (xy 89.910422 -230.060013) (xy 89.91092 -230.086662)
			(xy 89.910422 -230.113311) (xy 90.139002 -230.113311) (xy 90.139002 -230.060013) (xy 90.146945 -230.007309)
			(xy 90.162655 -229.956379) (xy 90.185781 -229.908358) (xy 90.215805 -229.864321) (xy 90.252057 -229.82525)
			(xy 90.293728 -229.792019) (xy 90.339886 -229.76537) (xy 90.3895 -229.745898) (xy 90.441462 -229.734038)
			(xy 90.494612 -229.730055) (xy 90.547762 -229.734038) (xy 90.599724 -229.745898) (xy 90.649338 -229.76537)
			(xy 90.695496 -229.792019) (xy 90.737167 -229.82525) (xy 90.773419 -229.864321) (xy 90.803443 -229.908358)
			(xy 90.826569 -229.956379) (xy 90.842279 -230.007309) (xy 90.850222 -230.060013) (xy 90.85072 -230.086662)
			(xy 90.850222 -230.113311) (xy 91.078802 -230.113311) (xy 91.078802 -230.060013) (xy 91.086745 -230.007309)
			(xy 91.102455 -229.956379) (xy 91.125581 -229.908358) (xy 91.155605 -229.864321) (xy 91.191857 -229.82525)
			(xy 91.233528 -229.792019) (xy 91.279686 -229.76537) (xy 91.3293 -229.745898) (xy 91.381262 -229.734038)
			(xy 91.434412 -229.730055) (xy 91.487562 -229.734038) (xy 91.539524 -229.745898) (xy 91.589138 -229.76537)
			(xy 91.635296 -229.792019) (xy 91.676967 -229.82525) (xy 91.713219 -229.864321) (xy 91.743243 -229.908358)
			(xy 91.766369 -229.956379) (xy 91.782079 -230.007309) (xy 91.790022 -230.060013) (xy 91.79052 -230.086662)
			(xy 91.790022 -230.113311) (xy 92.018602 -230.113311) (xy 92.018602 -230.060013) (xy 92.026545 -230.007309)
			(xy 92.042255 -229.956379) (xy 92.065381 -229.908358) (xy 92.095405 -229.864321) (xy 92.131657 -229.82525)
			(xy 92.173328 -229.792019) (xy 92.219486 -229.76537) (xy 92.2691 -229.745898) (xy 92.321062 -229.734038)
			(xy 92.374212 -229.730055) (xy 92.427362 -229.734038) (xy 92.479324 -229.745898) (xy 92.528938 -229.76537)
			(xy 92.575096 -229.792019) (xy 92.616767 -229.82525) (xy 92.653019 -229.864321) (xy 92.683043 -229.908358)
			(xy 92.706169 -229.956379) (xy 92.721879 -230.007309) (xy 92.729822 -230.060013) (xy 92.73032 -230.086662)
			(xy 92.729822 -230.113311) (xy 92.958402 -230.113311) (xy 92.958402 -230.060013) (xy 92.966345 -230.007309)
			(xy 92.982055 -229.956379) (xy 93.005181 -229.908358) (xy 93.035205 -229.864321) (xy 93.071457 -229.82525)
			(xy 93.113128 -229.792019) (xy 93.159286 -229.76537) (xy 93.2089 -229.745898) (xy 93.260862 -229.734038)
			(xy 93.314012 -229.730055) (xy 93.367162 -229.734038) (xy 93.419124 -229.745898) (xy 93.468738 -229.76537)
			(xy 93.514896 -229.792019) (xy 93.556567 -229.82525) (xy 93.592819 -229.864321) (xy 93.622843 -229.908358)
			(xy 93.645969 -229.956379) (xy 93.661679 -230.007309) (xy 93.669622 -230.060013) (xy 93.67012 -230.086662)
			(xy 93.669622 -230.113311) (xy 93.898202 -230.113311) (xy 93.898202 -230.060013) (xy 93.906145 -230.007309)
			(xy 93.921855 -229.956379) (xy 93.944981 -229.908358) (xy 93.975005 -229.864321) (xy 94.011257 -229.82525)
			(xy 94.052928 -229.792019) (xy 94.099086 -229.76537) (xy 94.1487 -229.745898) (xy 94.200662 -229.734038)
			(xy 94.253812 -229.730055) (xy 94.306962 -229.734038) (xy 94.358924 -229.745898) (xy 94.408538 -229.76537)
			(xy 94.454696 -229.792019) (xy 94.496367 -229.82525) (xy 94.532619 -229.864321) (xy 94.562643 -229.908358)
			(xy 94.585769 -229.956379) (xy 94.601479 -230.007309) (xy 94.609422 -230.060013) (xy 94.60992 -230.086662)
			(xy 94.609422 -230.113311) (xy 94.838002 -230.113311) (xy 94.838002 -230.060013) (xy 94.845945 -230.007309)
			(xy 94.861655 -229.956379) (xy 94.884781 -229.908358) (xy 94.914805 -229.864321) (xy 94.951057 -229.82525)
			(xy 94.992728 -229.792019) (xy 95.038886 -229.76537) (xy 95.0885 -229.745898) (xy 95.140462 -229.734038)
			(xy 95.193612 -229.730055) (xy 95.246762 -229.734038) (xy 95.298724 -229.745898) (xy 95.348338 -229.76537)
			(xy 95.394496 -229.792019) (xy 95.436167 -229.82525) (xy 95.472419 -229.864321) (xy 95.502443 -229.908358)
			(xy 95.525569 -229.956379) (xy 95.541279 -230.007309) (xy 95.549222 -230.060013) (xy 95.54972 -230.086662)
			(xy 95.549222 -230.113311) (xy 95.777802 -230.113311) (xy 95.777802 -230.060013) (xy 95.785745 -230.007309)
			(xy 95.801455 -229.956379) (xy 95.824581 -229.908358) (xy 95.854605 -229.864321) (xy 95.890857 -229.82525)
			(xy 95.932528 -229.792019) (xy 95.978686 -229.76537) (xy 96.0283 -229.745898) (xy 96.080262 -229.734038)
			(xy 96.133412 -229.730055) (xy 96.186562 -229.734038) (xy 96.238524 -229.745898) (xy 96.288138 -229.76537)
			(xy 96.334296 -229.792019) (xy 96.375967 -229.82525) (xy 96.412219 -229.864321) (xy 96.442243 -229.908358)
			(xy 96.465369 -229.956379) (xy 96.481079 -230.007309) (xy 96.489022 -230.060013) (xy 96.48952 -230.086662)
			(xy 96.489022 -230.113311) (xy 96.717856 -230.113311) (xy 96.717856 -230.060013) (xy 96.725799 -230.007309)
			(xy 96.741509 -229.956379) (xy 96.764635 -229.908358) (xy 96.794659 -229.864321) (xy 96.830911 -229.82525)
			(xy 96.872582 -229.792019) (xy 96.91874 -229.76537) (xy 96.968354 -229.745898) (xy 97.020316 -229.734038)
			(xy 97.073466 -229.730055) (xy 97.126616 -229.734038) (xy 97.178578 -229.745898) (xy 97.228192 -229.76537)
			(xy 97.27435 -229.792019) (xy 97.316021 -229.82525) (xy 97.352273 -229.864321) (xy 97.382297 -229.908358)
			(xy 97.405423 -229.956379) (xy 97.421133 -230.007309) (xy 97.429076 -230.060013) (xy 97.429574 -230.086662)
			(xy 97.429076 -230.113311) (xy 97.657402 -230.113311) (xy 97.657402 -230.060013) (xy 97.665345 -230.007309)
			(xy 97.681055 -229.956379) (xy 97.704181 -229.908358) (xy 97.734205 -229.864321) (xy 97.770457 -229.82525)
			(xy 97.812128 -229.792019) (xy 97.858286 -229.76537) (xy 97.9079 -229.745898) (xy 97.959862 -229.734038)
			(xy 98.013012 -229.730055) (xy 98.066162 -229.734038) (xy 98.118124 -229.745898) (xy 98.167738 -229.76537)
			(xy 98.213896 -229.792019) (xy 98.255567 -229.82525) (xy 98.291819 -229.864321) (xy 98.321843 -229.908358)
			(xy 98.344969 -229.956379) (xy 98.360679 -230.007309) (xy 98.368622 -230.060013) (xy 98.36912 -230.086662)
			(xy 98.368622 -230.113311) (xy 98.597202 -230.113311) (xy 98.597202 -230.060013) (xy 98.605145 -230.007309)
			(xy 98.620855 -229.956379) (xy 98.643981 -229.908358) (xy 98.674005 -229.864321) (xy 98.710257 -229.82525)
			(xy 98.751928 -229.792019) (xy 98.798086 -229.76537) (xy 98.8477 -229.745898) (xy 98.899662 -229.734038)
			(xy 98.952812 -229.730055) (xy 99.005962 -229.734038) (xy 99.057924 -229.745898) (xy 99.107538 -229.76537)
			(xy 99.153696 -229.792019) (xy 99.195367 -229.82525) (xy 99.231619 -229.864321) (xy 99.261643 -229.908358)
			(xy 99.284769 -229.956379) (xy 99.300479 -230.007309) (xy 99.308422 -230.060013) (xy 99.30892 -230.086662)
			(xy 99.308422 -230.113311) (xy 99.537002 -230.113311) (xy 99.537002 -230.060013) (xy 99.544945 -230.007309)
			(xy 99.560655 -229.956379) (xy 99.583781 -229.908358) (xy 99.613805 -229.864321) (xy 99.650057 -229.82525)
			(xy 99.691728 -229.792019) (xy 99.737886 -229.76537) (xy 99.7875 -229.745898) (xy 99.839462 -229.734038)
			(xy 99.892612 -229.730055) (xy 99.945762 -229.734038) (xy 99.997724 -229.745898) (xy 100.047338 -229.76537)
			(xy 100.093496 -229.792019) (xy 100.135167 -229.82525) (xy 100.171419 -229.864321) (xy 100.201443 -229.908358)
			(xy 100.224569 -229.956379) (xy 100.240279 -230.007309) (xy 100.248222 -230.060013) (xy 100.24872 -230.086662)
			(xy 100.248222 -230.113311) (xy 100.476802 -230.113311) (xy 100.476802 -230.060013) (xy 100.484745 -230.007309)
			(xy 100.500455 -229.956379) (xy 100.523581 -229.908358) (xy 100.553605 -229.864321) (xy 100.589857 -229.82525)
			(xy 100.631528 -229.792019) (xy 100.677686 -229.76537) (xy 100.7273 -229.745898) (xy 100.779262 -229.734038)
			(xy 100.832412 -229.730055) (xy 100.885562 -229.734038) (xy 100.937524 -229.745898) (xy 100.987138 -229.76537)
			(xy 101.033296 -229.792019) (xy 101.074967 -229.82525) (xy 101.111219 -229.864321) (xy 101.141243 -229.908358)
			(xy 101.164369 -229.956379) (xy 101.180079 -230.007309) (xy 101.188022 -230.060013) (xy 101.18852 -230.086662)
			(xy 101.188022 -230.113311) (xy 101.416602 -230.113311) (xy 101.416602 -230.060013) (xy 101.424545 -230.007309)
			(xy 101.440255 -229.956379) (xy 101.463381 -229.908358) (xy 101.493405 -229.864321) (xy 101.529657 -229.82525)
			(xy 101.571328 -229.792019) (xy 101.617486 -229.76537) (xy 101.6671 -229.745898) (xy 101.719062 -229.734038)
			(xy 101.772212 -229.730055) (xy 101.825362 -229.734038) (xy 101.877324 -229.745898) (xy 101.926938 -229.76537)
			(xy 101.973096 -229.792019) (xy 102.014767 -229.82525) (xy 102.051019 -229.864321) (xy 102.081043 -229.908358)
			(xy 102.104169 -229.956379) (xy 102.119879 -230.007309) (xy 102.127822 -230.060013) (xy 102.12832 -230.086662)
			(xy 102.127822 -230.113311) (xy 102.356402 -230.113311) (xy 102.356402 -230.060013) (xy 102.364345 -230.007309)
			(xy 102.380055 -229.956379) (xy 102.403181 -229.908358) (xy 102.433205 -229.864321) (xy 102.469457 -229.82525)
			(xy 102.511128 -229.792019) (xy 102.557286 -229.76537) (xy 102.6069 -229.745898) (xy 102.658862 -229.734038)
			(xy 102.712012 -229.730055) (xy 102.765162 -229.734038) (xy 102.817124 -229.745898) (xy 102.866738 -229.76537)
			(xy 102.912896 -229.792019) (xy 102.954567 -229.82525) (xy 102.990819 -229.864321) (xy 103.020843 -229.908358)
			(xy 103.043969 -229.956379) (xy 103.059679 -230.007309) (xy 103.067622 -230.060013) (xy 103.06812 -230.086662)
			(xy 103.067622 -230.113311) (xy 103.296202 -230.113311) (xy 103.296202 -230.060013) (xy 103.304145 -230.007309)
			(xy 103.319855 -229.956379) (xy 103.342981 -229.908358) (xy 103.373005 -229.864321) (xy 103.409257 -229.82525)
			(xy 103.450928 -229.792019) (xy 103.497086 -229.76537) (xy 103.5467 -229.745898) (xy 103.598662 -229.734038)
			(xy 103.651812 -229.730055) (xy 103.704962 -229.734038) (xy 103.756924 -229.745898) (xy 103.806538 -229.76537)
			(xy 103.852696 -229.792019) (xy 103.894367 -229.82525) (xy 103.930619 -229.864321) (xy 103.960643 -229.908358)
			(xy 103.983769 -229.956379) (xy 103.999479 -230.007309) (xy 104.007422 -230.060013) (xy 104.00792 -230.086662)
			(xy 104.007422 -230.113311) (xy 104.236002 -230.113311) (xy 104.236002 -230.060013) (xy 104.243945 -230.007309)
			(xy 104.259655 -229.956379) (xy 104.282781 -229.908358) (xy 104.312805 -229.864321) (xy 104.349057 -229.82525)
			(xy 104.390728 -229.792019) (xy 104.436886 -229.76537) (xy 104.4865 -229.745898) (xy 104.538462 -229.734038)
			(xy 104.591612 -229.730055) (xy 104.644762 -229.734038) (xy 104.696724 -229.745898) (xy 104.746338 -229.76537)
			(xy 104.792496 -229.792019) (xy 104.834167 -229.82525) (xy 104.870419 -229.864321) (xy 104.900443 -229.908358)
			(xy 104.923569 -229.956379) (xy 104.939279 -230.007309) (xy 104.947222 -230.060013) (xy 104.94772 -230.086662)
			(xy 104.947222 -230.113311) (xy 105.175802 -230.113311) (xy 105.175802 -230.060013) (xy 105.183745 -230.007309)
			(xy 105.199455 -229.956379) (xy 105.222581 -229.908358) (xy 105.252605 -229.864321) (xy 105.288857 -229.82525)
			(xy 105.330528 -229.792019) (xy 105.376686 -229.76537) (xy 105.4263 -229.745898) (xy 105.478262 -229.734038)
			(xy 105.531412 -229.730055) (xy 105.584562 -229.734038) (xy 105.636524 -229.745898) (xy 105.686138 -229.76537)
			(xy 105.732296 -229.792019) (xy 105.773967 -229.82525) (xy 105.810219 -229.864321) (xy 105.840243 -229.908358)
			(xy 105.863369 -229.956379) (xy 105.879079 -230.007309) (xy 105.887022 -230.060013) (xy 105.88752 -230.086662)
			(xy 105.887022 -230.113311) (xy 106.115856 -230.113311) (xy 106.115856 -230.060013) (xy 106.123799 -230.007309)
			(xy 106.139509 -229.956379) (xy 106.162635 -229.908358) (xy 106.192659 -229.864321) (xy 106.228911 -229.82525)
			(xy 106.270582 -229.792019) (xy 106.31674 -229.76537) (xy 106.366354 -229.745898) (xy 106.418316 -229.734038)
			(xy 106.471466 -229.730055) (xy 106.524616 -229.734038) (xy 106.576578 -229.745898) (xy 106.626192 -229.76537)
			(xy 106.67235 -229.792019) (xy 106.714021 -229.82525) (xy 106.750273 -229.864321) (xy 106.780297 -229.908358)
			(xy 106.803423 -229.956379) (xy 106.819133 -230.007309) (xy 106.827076 -230.060013) (xy 106.827574 -230.086662)
			(xy 106.827076 -230.113311) (xy 107.055402 -230.113311) (xy 107.055402 -230.060013) (xy 107.063345 -230.007309)
			(xy 107.079055 -229.956379) (xy 107.102181 -229.908358) (xy 107.132205 -229.864321) (xy 107.168457 -229.82525)
			(xy 107.210128 -229.792019) (xy 107.256286 -229.76537) (xy 107.3059 -229.745898) (xy 107.357862 -229.734038)
			(xy 107.411012 -229.730055) (xy 107.464162 -229.734038) (xy 107.516124 -229.745898) (xy 107.565738 -229.76537)
			(xy 107.611896 -229.792019) (xy 107.653567 -229.82525) (xy 107.689819 -229.864321) (xy 107.719843 -229.908358)
			(xy 107.742969 -229.956379) (xy 107.758679 -230.007309) (xy 107.766622 -230.060013) (xy 107.76712 -230.086662)
			(xy 107.766622 -230.113311) (xy 107.995202 -230.113311) (xy 107.995202 -230.060013) (xy 108.003145 -230.007309)
			(xy 108.018855 -229.956379) (xy 108.041981 -229.908358) (xy 108.072005 -229.864321) (xy 108.108257 -229.82525)
			(xy 108.149928 -229.792019) (xy 108.196086 -229.76537) (xy 108.2457 -229.745898) (xy 108.297662 -229.734038)
			(xy 108.350812 -229.730055) (xy 108.403962 -229.734038) (xy 108.455924 -229.745898) (xy 108.505538 -229.76537)
			(xy 108.551696 -229.792019) (xy 108.593367 -229.82525) (xy 108.629619 -229.864321) (xy 108.659643 -229.908358)
			(xy 108.682769 -229.956379) (xy 108.698479 -230.007309) (xy 108.706422 -230.060013) (xy 108.70692 -230.086662)
			(xy 108.706422 -230.113311) (xy 108.935002 -230.113311) (xy 108.935002 -230.060013) (xy 108.942945 -230.007309)
			(xy 108.958655 -229.956379) (xy 108.981781 -229.908358) (xy 109.011805 -229.864321) (xy 109.048057 -229.82525)
			(xy 109.089728 -229.792019) (xy 109.135886 -229.76537) (xy 109.1855 -229.745898) (xy 109.237462 -229.734038)
			(xy 109.290612 -229.730055) (xy 109.343762 -229.734038) (xy 109.395724 -229.745898) (xy 109.445338 -229.76537)
			(xy 109.491496 -229.792019) (xy 109.533167 -229.82525) (xy 109.569419 -229.864321) (xy 109.599443 -229.908358)
			(xy 109.622569 -229.956379) (xy 109.638279 -230.007309) (xy 109.646222 -230.060013) (xy 109.64672 -230.086662)
			(xy 109.646222 -230.113311) (xy 109.874802 -230.113311) (xy 109.874802 -230.060013) (xy 109.882745 -230.007309)
			(xy 109.898455 -229.956379) (xy 109.921581 -229.908358) (xy 109.951605 -229.864321) (xy 109.987857 -229.82525)
			(xy 110.029528 -229.792019) (xy 110.075686 -229.76537) (xy 110.1253 -229.745898) (xy 110.177262 -229.734038)
			(xy 110.230412 -229.730055) (xy 110.283562 -229.734038) (xy 110.335524 -229.745898) (xy 110.385138 -229.76537)
			(xy 110.431296 -229.792019) (xy 110.472967 -229.82525) (xy 110.509219 -229.864321) (xy 110.539243 -229.908358)
			(xy 110.562369 -229.956379) (xy 110.578079 -230.007309) (xy 110.586022 -230.060013) (xy 110.58652 -230.086662)
			(xy 110.586022 -230.113311) (xy 110.578079 -230.166015) (xy 110.562369 -230.216945) (xy 110.539243 -230.264966)
			(xy 110.509219 -230.309003) (xy 110.472967 -230.348074) (xy 110.431296 -230.381305) (xy 110.385138 -230.407954)
			(xy 110.335524 -230.427426) (xy 110.283562 -230.439286) (xy 110.230412 -230.44327) (xy 110.177262 -230.439286)
			(xy 110.1253 -230.427426) (xy 110.075686 -230.407954) (xy 110.029528 -230.381305) (xy 109.987857 -230.348074)
			(xy 109.951605 -230.309003) (xy 109.921581 -230.264966) (xy 109.898455 -230.216945) (xy 109.882745 -230.166015)
			(xy 109.874802 -230.113311) (xy 109.646222 -230.113311) (xy 109.638279 -230.166015) (xy 109.622569 -230.216945)
			(xy 109.599443 -230.264966) (xy 109.569419 -230.309003) (xy 109.533167 -230.348074) (xy 109.491496 -230.381305)
			(xy 109.445338 -230.407954) (xy 109.395724 -230.427426) (xy 109.343762 -230.439286) (xy 109.290612 -230.44327)
			(xy 109.237462 -230.439286) (xy 109.1855 -230.427426) (xy 109.135886 -230.407954) (xy 109.089728 -230.381305)
			(xy 109.048057 -230.348074) (xy 109.011805 -230.309003) (xy 108.981781 -230.264966) (xy 108.958655 -230.216945)
			(xy 108.942945 -230.166015) (xy 108.935002 -230.113311) (xy 108.706422 -230.113311) (xy 108.698479 -230.166015)
			(xy 108.682769 -230.216945) (xy 108.659643 -230.264966) (xy 108.629619 -230.309003) (xy 108.593367 -230.348074)
			(xy 108.551696 -230.381305) (xy 108.505538 -230.407954) (xy 108.455924 -230.427426) (xy 108.403962 -230.439286)
			(xy 108.350812 -230.44327) (xy 108.297662 -230.439286) (xy 108.2457 -230.427426) (xy 108.196086 -230.407954)
			(xy 108.149928 -230.381305) (xy 108.108257 -230.348074) (xy 108.072005 -230.309003) (xy 108.041981 -230.264966)
			(xy 108.018855 -230.216945) (xy 108.003145 -230.166015) (xy 107.995202 -230.113311) (xy 107.766622 -230.113311)
			(xy 107.758679 -230.166015) (xy 107.742969 -230.216945) (xy 107.719843 -230.264966) (xy 107.689819 -230.309003)
			(xy 107.653567 -230.348074) (xy 107.611896 -230.381305) (xy 107.565738 -230.407954) (xy 107.516124 -230.427426)
			(xy 107.464162 -230.439286) (xy 107.411012 -230.44327) (xy 107.357862 -230.439286) (xy 107.3059 -230.427426)
			(xy 107.256286 -230.407954) (xy 107.210128 -230.381305) (xy 107.168457 -230.348074) (xy 107.132205 -230.309003)
			(xy 107.102181 -230.264966) (xy 107.079055 -230.216945) (xy 107.063345 -230.166015) (xy 107.055402 -230.113311)
			(xy 106.827076 -230.113311) (xy 106.819133 -230.166015) (xy 106.803423 -230.216945) (xy 106.780297 -230.264966)
			(xy 106.750273 -230.309003) (xy 106.714021 -230.348074) (xy 106.67235 -230.381305) (xy 106.626192 -230.407954)
			(xy 106.576578 -230.427426) (xy 106.524616 -230.439286) (xy 106.471466 -230.44327) (xy 106.418316 -230.439286)
			(xy 106.366354 -230.427426) (xy 106.31674 -230.407954) (xy 106.270582 -230.381305) (xy 106.228911 -230.348074)
			(xy 106.192659 -230.309003) (xy 106.162635 -230.264966) (xy 106.139509 -230.216945) (xy 106.123799 -230.166015)
			(xy 106.115856 -230.113311) (xy 105.887022 -230.113311) (xy 105.879079 -230.166015) (xy 105.863369 -230.216945)
			(xy 105.840243 -230.264966) (xy 105.810219 -230.309003) (xy 105.773967 -230.348074) (xy 105.732296 -230.381305)
			(xy 105.686138 -230.407954) (xy 105.636524 -230.427426) (xy 105.584562 -230.439286) (xy 105.531412 -230.44327)
			(xy 105.478262 -230.439286) (xy 105.4263 -230.427426) (xy 105.376686 -230.407954) (xy 105.330528 -230.381305)
			(xy 105.288857 -230.348074) (xy 105.252605 -230.309003) (xy 105.222581 -230.264966) (xy 105.199455 -230.216945)
			(xy 105.183745 -230.166015) (xy 105.175802 -230.113311) (xy 104.947222 -230.113311) (xy 104.939279 -230.166015)
			(xy 104.923569 -230.216945) (xy 104.900443 -230.264966) (xy 104.870419 -230.309003) (xy 104.834167 -230.348074)
			(xy 104.792496 -230.381305) (xy 104.746338 -230.407954) (xy 104.696724 -230.427426) (xy 104.644762 -230.439286)
			(xy 104.591612 -230.44327) (xy 104.538462 -230.439286) (xy 104.4865 -230.427426) (xy 104.436886 -230.407954)
			(xy 104.390728 -230.381305) (xy 104.349057 -230.348074) (xy 104.312805 -230.309003) (xy 104.282781 -230.264966)
			(xy 104.259655 -230.216945) (xy 104.243945 -230.166015) (xy 104.236002 -230.113311) (xy 104.007422 -230.113311)
			(xy 103.999479 -230.166015) (xy 103.983769 -230.216945) (xy 103.960643 -230.264966) (xy 103.930619 -230.309003)
			(xy 103.894367 -230.348074) (xy 103.852696 -230.381305) (xy 103.806538 -230.407954) (xy 103.756924 -230.427426)
			(xy 103.704962 -230.439286) (xy 103.651812 -230.44327) (xy 103.598662 -230.439286) (xy 103.5467 -230.427426)
			(xy 103.497086 -230.407954) (xy 103.450928 -230.381305) (xy 103.409257 -230.348074) (xy 103.373005 -230.309003)
			(xy 103.342981 -230.264966) (xy 103.319855 -230.216945) (xy 103.304145 -230.166015) (xy 103.296202 -230.113311)
			(xy 103.067622 -230.113311) (xy 103.059679 -230.166015) (xy 103.043969 -230.216945) (xy 103.020843 -230.264966)
			(xy 102.990819 -230.309003) (xy 102.954567 -230.348074) (xy 102.912896 -230.381305) (xy 102.866738 -230.407954)
			(xy 102.817124 -230.427426) (xy 102.765162 -230.439286) (xy 102.712012 -230.44327) (xy 102.658862 -230.439286)
			(xy 102.6069 -230.427426) (xy 102.557286 -230.407954) (xy 102.511128 -230.381305) (xy 102.469457 -230.348074)
			(xy 102.433205 -230.309003) (xy 102.403181 -230.264966) (xy 102.380055 -230.216945) (xy 102.364345 -230.166015)
			(xy 102.356402 -230.113311) (xy 102.127822 -230.113311) (xy 102.119879 -230.166015) (xy 102.104169 -230.216945)
			(xy 102.081043 -230.264966) (xy 102.051019 -230.309003) (xy 102.014767 -230.348074) (xy 101.973096 -230.381305)
			(xy 101.926938 -230.407954) (xy 101.877324 -230.427426) (xy 101.825362 -230.439286) (xy 101.772212 -230.44327)
			(xy 101.719062 -230.439286) (xy 101.6671 -230.427426) (xy 101.617486 -230.407954) (xy 101.571328 -230.381305)
			(xy 101.529657 -230.348074) (xy 101.493405 -230.309003) (xy 101.463381 -230.264966) (xy 101.440255 -230.216945)
			(xy 101.424545 -230.166015) (xy 101.416602 -230.113311) (xy 101.188022 -230.113311) (xy 101.180079 -230.166015)
			(xy 101.164369 -230.216945) (xy 101.141243 -230.264966) (xy 101.111219 -230.309003) (xy 101.074967 -230.348074)
			(xy 101.033296 -230.381305) (xy 100.987138 -230.407954) (xy 100.937524 -230.427426) (xy 100.885562 -230.439286)
			(xy 100.832412 -230.44327) (xy 100.779262 -230.439286) (xy 100.7273 -230.427426) (xy 100.677686 -230.407954)
			(xy 100.631528 -230.381305) (xy 100.589857 -230.348074) (xy 100.553605 -230.309003) (xy 100.523581 -230.264966)
			(xy 100.500455 -230.216945) (xy 100.484745 -230.166015) (xy 100.476802 -230.113311) (xy 100.248222 -230.113311)
			(xy 100.240279 -230.166015) (xy 100.224569 -230.216945) (xy 100.201443 -230.264966) (xy 100.171419 -230.309003)
			(xy 100.135167 -230.348074) (xy 100.093496 -230.381305) (xy 100.047338 -230.407954) (xy 99.997724 -230.427426)
			(xy 99.945762 -230.439286) (xy 99.892612 -230.44327) (xy 99.839462 -230.439286) (xy 99.7875 -230.427426)
			(xy 99.737886 -230.407954) (xy 99.691728 -230.381305) (xy 99.650057 -230.348074) (xy 99.613805 -230.309003)
			(xy 99.583781 -230.264966) (xy 99.560655 -230.216945) (xy 99.544945 -230.166015) (xy 99.537002 -230.113311)
			(xy 99.308422 -230.113311) (xy 99.300479 -230.166015) (xy 99.284769 -230.216945) (xy 99.261643 -230.264966)
			(xy 99.231619 -230.309003) (xy 99.195367 -230.348074) (xy 99.153696 -230.381305) (xy 99.107538 -230.407954)
			(xy 99.057924 -230.427426) (xy 99.005962 -230.439286) (xy 98.952812 -230.44327) (xy 98.899662 -230.439286)
			(xy 98.8477 -230.427426) (xy 98.798086 -230.407954) (xy 98.751928 -230.381305) (xy 98.710257 -230.348074)
			(xy 98.674005 -230.309003) (xy 98.643981 -230.264966) (xy 98.620855 -230.216945) (xy 98.605145 -230.166015)
			(xy 98.597202 -230.113311) (xy 98.368622 -230.113311) (xy 98.360679 -230.166015) (xy 98.344969 -230.216945)
			(xy 98.321843 -230.264966) (xy 98.291819 -230.309003) (xy 98.255567 -230.348074) (xy 98.213896 -230.381305)
			(xy 98.167738 -230.407954) (xy 98.118124 -230.427426) (xy 98.066162 -230.439286) (xy 98.013012 -230.44327)
			(xy 97.959862 -230.439286) (xy 97.9079 -230.427426) (xy 97.858286 -230.407954) (xy 97.812128 -230.381305)
			(xy 97.770457 -230.348074) (xy 97.734205 -230.309003) (xy 97.704181 -230.264966) (xy 97.681055 -230.216945)
			(xy 97.665345 -230.166015) (xy 97.657402 -230.113311) (xy 97.429076 -230.113311) (xy 97.421133 -230.166015)
			(xy 97.405423 -230.216945) (xy 97.382297 -230.264966) (xy 97.352273 -230.309003) (xy 97.316021 -230.348074)
			(xy 97.27435 -230.381305) (xy 97.228192 -230.407954) (xy 97.178578 -230.427426) (xy 97.126616 -230.439286)
			(xy 97.073466 -230.44327) (xy 97.020316 -230.439286) (xy 96.968354 -230.427426) (xy 96.91874 -230.407954)
			(xy 96.872582 -230.381305) (xy 96.830911 -230.348074) (xy 96.794659 -230.309003) (xy 96.764635 -230.264966)
			(xy 96.741509 -230.216945) (xy 96.725799 -230.166015) (xy 96.717856 -230.113311) (xy 96.489022 -230.113311)
			(xy 96.481079 -230.166015) (xy 96.465369 -230.216945) (xy 96.442243 -230.264966) (xy 96.412219 -230.309003)
			(xy 96.375967 -230.348074) (xy 96.334296 -230.381305) (xy 96.288138 -230.407954) (xy 96.238524 -230.427426)
			(xy 96.186562 -230.439286) (xy 96.133412 -230.44327) (xy 96.080262 -230.439286) (xy 96.0283 -230.427426)
			(xy 95.978686 -230.407954) (xy 95.932528 -230.381305) (xy 95.890857 -230.348074) (xy 95.854605 -230.309003)
			(xy 95.824581 -230.264966) (xy 95.801455 -230.216945) (xy 95.785745 -230.166015) (xy 95.777802 -230.113311)
			(xy 95.549222 -230.113311) (xy 95.541279 -230.166015) (xy 95.525569 -230.216945) (xy 95.502443 -230.264966)
			(xy 95.472419 -230.309003) (xy 95.436167 -230.348074) (xy 95.394496 -230.381305) (xy 95.348338 -230.407954)
			(xy 95.298724 -230.427426) (xy 95.246762 -230.439286) (xy 95.193612 -230.44327) (xy 95.140462 -230.439286)
			(xy 95.0885 -230.427426) (xy 95.038886 -230.407954) (xy 94.992728 -230.381305) (xy 94.951057 -230.348074)
			(xy 94.914805 -230.309003) (xy 94.884781 -230.264966) (xy 94.861655 -230.216945) (xy 94.845945 -230.166015)
			(xy 94.838002 -230.113311) (xy 94.609422 -230.113311) (xy 94.601479 -230.166015) (xy 94.585769 -230.216945)
			(xy 94.562643 -230.264966) (xy 94.532619 -230.309003) (xy 94.496367 -230.348074) (xy 94.454696 -230.381305)
			(xy 94.408538 -230.407954) (xy 94.358924 -230.427426) (xy 94.306962 -230.439286) (xy 94.253812 -230.44327)
			(xy 94.200662 -230.439286) (xy 94.1487 -230.427426) (xy 94.099086 -230.407954) (xy 94.052928 -230.381305)
			(xy 94.011257 -230.348074) (xy 93.975005 -230.309003) (xy 93.944981 -230.264966) (xy 93.921855 -230.216945)
			(xy 93.906145 -230.166015) (xy 93.898202 -230.113311) (xy 93.669622 -230.113311) (xy 93.661679 -230.166015)
			(xy 93.645969 -230.216945) (xy 93.622843 -230.264966) (xy 93.592819 -230.309003) (xy 93.556567 -230.348074)
			(xy 93.514896 -230.381305) (xy 93.468738 -230.407954) (xy 93.419124 -230.427426) (xy 93.367162 -230.439286)
			(xy 93.314012 -230.44327) (xy 93.260862 -230.439286) (xy 93.2089 -230.427426) (xy 93.159286 -230.407954)
			(xy 93.113128 -230.381305) (xy 93.071457 -230.348074) (xy 93.035205 -230.309003) (xy 93.005181 -230.264966)
			(xy 92.982055 -230.216945) (xy 92.966345 -230.166015) (xy 92.958402 -230.113311) (xy 92.729822 -230.113311)
			(xy 92.721879 -230.166015) (xy 92.706169 -230.216945) (xy 92.683043 -230.264966) (xy 92.653019 -230.309003)
			(xy 92.616767 -230.348074) (xy 92.575096 -230.381305) (xy 92.528938 -230.407954) (xy 92.479324 -230.427426)
			(xy 92.427362 -230.439286) (xy 92.374212 -230.44327) (xy 92.321062 -230.439286) (xy 92.2691 -230.427426)
			(xy 92.219486 -230.407954) (xy 92.173328 -230.381305) (xy 92.131657 -230.348074) (xy 92.095405 -230.309003)
			(xy 92.065381 -230.264966) (xy 92.042255 -230.216945) (xy 92.026545 -230.166015) (xy 92.018602 -230.113311)
			(xy 91.790022 -230.113311) (xy 91.782079 -230.166015) (xy 91.766369 -230.216945) (xy 91.743243 -230.264966)
			(xy 91.713219 -230.309003) (xy 91.676967 -230.348074) (xy 91.635296 -230.381305) (xy 91.589138 -230.407954)
			(xy 91.539524 -230.427426) (xy 91.487562 -230.439286) (xy 91.434412 -230.44327) (xy 91.381262 -230.439286)
			(xy 91.3293 -230.427426) (xy 91.279686 -230.407954) (xy 91.233528 -230.381305) (xy 91.191857 -230.348074)
			(xy 91.155605 -230.309003) (xy 91.125581 -230.264966) (xy 91.102455 -230.216945) (xy 91.086745 -230.166015)
			(xy 91.078802 -230.113311) (xy 90.850222 -230.113311) (xy 90.842279 -230.166015) (xy 90.826569 -230.216945)
			(xy 90.803443 -230.264966) (xy 90.773419 -230.309003) (xy 90.737167 -230.348074) (xy 90.695496 -230.381305)
			(xy 90.649338 -230.407954) (xy 90.599724 -230.427426) (xy 90.547762 -230.439286) (xy 90.494612 -230.44327)
			(xy 90.441462 -230.439286) (xy 90.3895 -230.427426) (xy 90.339886 -230.407954) (xy 90.293728 -230.381305)
			(xy 90.252057 -230.348074) (xy 90.215805 -230.309003) (xy 90.185781 -230.264966) (xy 90.162655 -230.216945)
			(xy 90.146945 -230.166015) (xy 90.139002 -230.113311) (xy 89.910422 -230.113311) (xy 89.902479 -230.166015)
			(xy 89.886769 -230.216945) (xy 89.863643 -230.264966) (xy 89.833619 -230.309003) (xy 89.797367 -230.348074)
			(xy 89.755696 -230.381305) (xy 89.709538 -230.407954) (xy 89.659924 -230.427426) (xy 89.607962 -230.439286)
			(xy 89.554812 -230.44327) (xy 89.501662 -230.439286) (xy 89.4497 -230.427426) (xy 89.400086 -230.407954)
			(xy 89.353928 -230.381305) (xy 89.312257 -230.348074) (xy 89.276005 -230.309003) (xy 89.245981 -230.264966)
			(xy 89.222855 -230.216945) (xy 89.207145 -230.166015) (xy 89.199202 -230.113311) (xy 88.970669 -230.113311)
			(xy 88.970669 -230.113444) (xy 88.96266 -230.166397) (xy 88.946817 -230.217555) (xy 88.93556 -230.241856)
			(xy 88.93048 -230.25227) (xy 88.93048 -230.445818) (xy 88.930955 -230.460118) (xy 88.938876 -230.487598)
			(xy 88.954119 -230.511796) (xy 88.975484 -230.530807) (xy 89.001288 -230.543137) (xy 89.029502 -230.547813)
			(xy 89.043764 -230.546656) (xy 89.054078 -230.545552) (xy 89.074793 -230.544408) (xy 89.085166 -230.54437)
			(xy 89.11182 -230.544841) (xy 89.164535 -230.552782) (xy 89.215476 -230.568491) (xy 89.263507 -230.591617)
			(xy 89.307555 -230.621645) (xy 89.346635 -230.657902) (xy 89.379874 -230.699579) (xy 89.40653 -230.745745)
			(xy 89.426007 -230.795368) (xy 89.43787 -230.84734) (xy 89.441854 -230.9005) (xy 89.439858 -230.927127)
			(xy 89.669356 -230.927127) (xy 89.669356 -230.873829) (xy 89.677299 -230.821125) (xy 89.693009 -230.770195)
			(xy 89.716135 -230.722174) (xy 89.746159 -230.678137) (xy 89.782411 -230.639066) (xy 89.824082 -230.605835)
			(xy 89.87024 -230.579186) (xy 89.919854 -230.559714) (xy 89.971816 -230.547854) (xy 90.024966 -230.543871)
			(xy 90.078116 -230.547854) (xy 90.130078 -230.559714) (xy 90.179692 -230.579186) (xy 90.22585 -230.605835)
			(xy 90.267521 -230.639066) (xy 90.303773 -230.678137) (xy 90.333797 -230.722174) (xy 90.356923 -230.770195)
			(xy 90.372633 -230.821125) (xy 90.380576 -230.873829) (xy 90.381074 -230.900478) (xy 90.380576 -230.927127)
			(xy 90.608902 -230.927127) (xy 90.608902 -230.873829) (xy 90.616845 -230.821125) (xy 90.632555 -230.770195)
			(xy 90.655681 -230.722174) (xy 90.685705 -230.678137) (xy 90.721957 -230.639066) (xy 90.763628 -230.605835)
			(xy 90.809786 -230.579186) (xy 90.8594 -230.559714) (xy 90.911362 -230.547854) (xy 90.964512 -230.543871)
			(xy 91.017662 -230.547854) (xy 91.069624 -230.559714) (xy 91.119238 -230.579186) (xy 91.165396 -230.605835)
			(xy 91.207067 -230.639066) (xy 91.243319 -230.678137) (xy 91.273343 -230.722174) (xy 91.296469 -230.770195)
			(xy 91.312179 -230.821125) (xy 91.320122 -230.873829) (xy 91.32062 -230.900478) (xy 91.320122 -230.927127)
			(xy 91.548956 -230.927127) (xy 91.548956 -230.873829) (xy 91.556899 -230.821125) (xy 91.572609 -230.770195)
			(xy 91.595735 -230.722174) (xy 91.625759 -230.678137) (xy 91.662011 -230.639066) (xy 91.703682 -230.605835)
			(xy 91.74984 -230.579186) (xy 91.799454 -230.559714) (xy 91.851416 -230.547854) (xy 91.904566 -230.543871)
			(xy 91.957716 -230.547854) (xy 92.009678 -230.559714) (xy 92.059292 -230.579186) (xy 92.10545 -230.605835)
			(xy 92.147121 -230.639066) (xy 92.183373 -230.678137) (xy 92.213397 -230.722174) (xy 92.236523 -230.770195)
			(xy 92.252233 -230.821125) (xy 92.260176 -230.873829) (xy 92.260674 -230.900478) (xy 92.260176 -230.927127)
			(xy 92.488756 -230.927127) (xy 92.488756 -230.873829) (xy 92.496699 -230.821125) (xy 92.512409 -230.770195)
			(xy 92.535535 -230.722174) (xy 92.565559 -230.678137) (xy 92.601811 -230.639066) (xy 92.643482 -230.605835)
			(xy 92.68964 -230.579186) (xy 92.739254 -230.559714) (xy 92.791216 -230.547854) (xy 92.844366 -230.543871)
			(xy 92.897516 -230.547854) (xy 92.949478 -230.559714) (xy 92.999092 -230.579186) (xy 93.04525 -230.605835)
			(xy 93.086921 -230.639066) (xy 93.123173 -230.678137) (xy 93.153197 -230.722174) (xy 93.176323 -230.770195)
			(xy 93.192033 -230.821125) (xy 93.199976 -230.873829) (xy 93.200474 -230.900478) (xy 93.199976 -230.927127)
			(xy 93.428556 -230.927127) (xy 93.428556 -230.873829) (xy 93.436499 -230.821125) (xy 93.452209 -230.770195)
			(xy 93.475335 -230.722174) (xy 93.505359 -230.678137) (xy 93.541611 -230.639066) (xy 93.583282 -230.605835)
			(xy 93.62944 -230.579186) (xy 93.679054 -230.559714) (xy 93.731016 -230.547854) (xy 93.784166 -230.543871)
			(xy 93.837316 -230.547854) (xy 93.889278 -230.559714) (xy 93.938892 -230.579186) (xy 93.98505 -230.605835)
			(xy 94.026721 -230.639066) (xy 94.062973 -230.678137) (xy 94.092997 -230.722174) (xy 94.116123 -230.770195)
			(xy 94.131833 -230.821125) (xy 94.139776 -230.873829) (xy 94.140274 -230.900478) (xy 94.139776 -230.927127)
			(xy 94.368356 -230.927127) (xy 94.368356 -230.873829) (xy 94.376299 -230.821125) (xy 94.392009 -230.770195)
			(xy 94.415135 -230.722174) (xy 94.445159 -230.678137) (xy 94.481411 -230.639066) (xy 94.523082 -230.605835)
			(xy 94.56924 -230.579186) (xy 94.618854 -230.559714) (xy 94.670816 -230.547854) (xy 94.723966 -230.543871)
			(xy 94.777116 -230.547854) (xy 94.829078 -230.559714) (xy 94.878692 -230.579186) (xy 94.92485 -230.605835)
			(xy 94.966521 -230.639066) (xy 95.002773 -230.678137) (xy 95.032797 -230.722174) (xy 95.055923 -230.770195)
			(xy 95.071633 -230.821125) (xy 95.079576 -230.873829) (xy 95.080074 -230.900478) (xy 95.079576 -230.927127)
			(xy 95.308156 -230.927127) (xy 95.308156 -230.873829) (xy 95.316099 -230.821125) (xy 95.331809 -230.770195)
			(xy 95.354935 -230.722174) (xy 95.384959 -230.678137) (xy 95.421211 -230.639066) (xy 95.462882 -230.605835)
			(xy 95.50904 -230.579186) (xy 95.558654 -230.559714) (xy 95.610616 -230.547854) (xy 95.663766 -230.543871)
			(xy 95.716916 -230.547854) (xy 95.768878 -230.559714) (xy 95.818492 -230.579186) (xy 95.86465 -230.605835)
			(xy 95.906321 -230.639066) (xy 95.942573 -230.678137) (xy 95.972597 -230.722174) (xy 95.995723 -230.770195)
			(xy 96.011433 -230.821125) (xy 96.019376 -230.873829) (xy 96.019874 -230.900478) (xy 96.019376 -230.927127)
			(xy 96.247956 -230.927127) (xy 96.247956 -230.873829) (xy 96.255899 -230.821125) (xy 96.271609 -230.770195)
			(xy 96.294735 -230.722174) (xy 96.324759 -230.678137) (xy 96.361011 -230.639066) (xy 96.402682 -230.605835)
			(xy 96.44884 -230.579186) (xy 96.498454 -230.559714) (xy 96.550416 -230.547854) (xy 96.603566 -230.543871)
			(xy 96.656716 -230.547854) (xy 96.708678 -230.559714) (xy 96.758292 -230.579186) (xy 96.80445 -230.605835)
			(xy 96.846121 -230.639066) (xy 96.882373 -230.678137) (xy 96.912397 -230.722174) (xy 96.935523 -230.770195)
			(xy 96.951233 -230.821125) (xy 96.959176 -230.873829) (xy 96.959674 -230.900478) (xy 96.959176 -230.927127)
			(xy 97.187502 -230.927127) (xy 97.187502 -230.873829) (xy 97.195445 -230.821125) (xy 97.211155 -230.770195)
			(xy 97.234281 -230.722174) (xy 97.264305 -230.678137) (xy 97.300557 -230.639066) (xy 97.342228 -230.605835)
			(xy 97.388386 -230.579186) (xy 97.438 -230.559714) (xy 97.489962 -230.547854) (xy 97.543112 -230.543871)
			(xy 97.596262 -230.547854) (xy 97.648224 -230.559714) (xy 97.697838 -230.579186) (xy 97.743996 -230.605835)
			(xy 97.785667 -230.639066) (xy 97.821919 -230.678137) (xy 97.851943 -230.722174) (xy 97.875069 -230.770195)
			(xy 97.890779 -230.821125) (xy 97.898722 -230.873829) (xy 97.89922 -230.900478) (xy 97.898722 -230.927127)
			(xy 98.127556 -230.927127) (xy 98.127556 -230.873829) (xy 98.135499 -230.821125) (xy 98.151209 -230.770195)
			(xy 98.174335 -230.722174) (xy 98.204359 -230.678137) (xy 98.240611 -230.639066) (xy 98.282282 -230.605835)
			(xy 98.32844 -230.579186) (xy 98.378054 -230.559714) (xy 98.430016 -230.547854) (xy 98.483166 -230.543871)
			(xy 98.536316 -230.547854) (xy 98.588278 -230.559714) (xy 98.637892 -230.579186) (xy 98.68405 -230.605835)
			(xy 98.725721 -230.639066) (xy 98.761973 -230.678137) (xy 98.791997 -230.722174) (xy 98.815123 -230.770195)
			(xy 98.830833 -230.821125) (xy 98.838776 -230.873829) (xy 98.839274 -230.900478) (xy 98.838776 -230.927127)
			(xy 99.067356 -230.927127) (xy 99.067356 -230.873829) (xy 99.075299 -230.821125) (xy 99.091009 -230.770195)
			(xy 99.114135 -230.722174) (xy 99.144159 -230.678137) (xy 99.180411 -230.639066) (xy 99.222082 -230.605835)
			(xy 99.26824 -230.579186) (xy 99.317854 -230.559714) (xy 99.369816 -230.547854) (xy 99.422966 -230.543871)
			(xy 99.476116 -230.547854) (xy 99.528078 -230.559714) (xy 99.577692 -230.579186) (xy 99.62385 -230.605835)
			(xy 99.665521 -230.639066) (xy 99.701773 -230.678137) (xy 99.731797 -230.722174) (xy 99.754923 -230.770195)
			(xy 99.770633 -230.821125) (xy 99.778576 -230.873829) (xy 99.779074 -230.900478) (xy 99.778576 -230.927127)
			(xy 100.007156 -230.927127) (xy 100.007156 -230.873829) (xy 100.015099 -230.821125) (xy 100.030809 -230.770195)
			(xy 100.053935 -230.722174) (xy 100.083959 -230.678137) (xy 100.120211 -230.639066) (xy 100.161882 -230.605835)
			(xy 100.20804 -230.579186) (xy 100.257654 -230.559714) (xy 100.309616 -230.547854) (xy 100.362766 -230.543871)
			(xy 100.415916 -230.547854) (xy 100.467878 -230.559714) (xy 100.517492 -230.579186) (xy 100.56365 -230.605835)
			(xy 100.605321 -230.639066) (xy 100.641573 -230.678137) (xy 100.671597 -230.722174) (xy 100.694723 -230.770195)
			(xy 100.710433 -230.821125) (xy 100.718376 -230.873829) (xy 100.718874 -230.900478) (xy 100.718376 -230.927127)
			(xy 100.946956 -230.927127) (xy 100.946956 -230.873829) (xy 100.954899 -230.821125) (xy 100.970609 -230.770195)
			(xy 100.993735 -230.722174) (xy 101.023759 -230.678137) (xy 101.060011 -230.639066) (xy 101.101682 -230.605835)
			(xy 101.14784 -230.579186) (xy 101.197454 -230.559714) (xy 101.249416 -230.547854) (xy 101.302566 -230.543871)
			(xy 101.355716 -230.547854) (xy 101.407678 -230.559714) (xy 101.457292 -230.579186) (xy 101.50345 -230.605835)
			(xy 101.545121 -230.639066) (xy 101.581373 -230.678137) (xy 101.611397 -230.722174) (xy 101.634523 -230.770195)
			(xy 101.650233 -230.821125) (xy 101.658176 -230.873829) (xy 101.658674 -230.900478) (xy 101.658176 -230.927127)
			(xy 101.886756 -230.927127) (xy 101.886756 -230.873829) (xy 101.894699 -230.821125) (xy 101.910409 -230.770195)
			(xy 101.933535 -230.722174) (xy 101.963559 -230.678137) (xy 101.999811 -230.639066) (xy 102.041482 -230.605835)
			(xy 102.08764 -230.579186) (xy 102.137254 -230.559714) (xy 102.189216 -230.547854) (xy 102.242366 -230.543871)
			(xy 102.295516 -230.547854) (xy 102.347478 -230.559714) (xy 102.397092 -230.579186) (xy 102.44325 -230.605835)
			(xy 102.484921 -230.639066) (xy 102.521173 -230.678137) (xy 102.551197 -230.722174) (xy 102.574323 -230.770195)
			(xy 102.590033 -230.821125) (xy 102.597976 -230.873829) (xy 102.598474 -230.900478) (xy 102.597976 -230.927127)
			(xy 102.826556 -230.927127) (xy 102.826556 -230.873829) (xy 102.834499 -230.821125) (xy 102.850209 -230.770195)
			(xy 102.873335 -230.722174) (xy 102.903359 -230.678137) (xy 102.939611 -230.639066) (xy 102.981282 -230.605835)
			(xy 103.02744 -230.579186) (xy 103.077054 -230.559714) (xy 103.129016 -230.547854) (xy 103.182166 -230.543871)
			(xy 103.235316 -230.547854) (xy 103.287278 -230.559714) (xy 103.336892 -230.579186) (xy 103.38305 -230.605835)
			(xy 103.424721 -230.639066) (xy 103.460973 -230.678137) (xy 103.490997 -230.722174) (xy 103.514123 -230.770195)
			(xy 103.529833 -230.821125) (xy 103.537776 -230.873829) (xy 103.538274 -230.900478) (xy 103.537776 -230.927127)
			(xy 103.766356 -230.927127) (xy 103.766356 -230.873829) (xy 103.774299 -230.821125) (xy 103.790009 -230.770195)
			(xy 103.813135 -230.722174) (xy 103.843159 -230.678137) (xy 103.879411 -230.639066) (xy 103.921082 -230.605835)
			(xy 103.96724 -230.579186) (xy 104.016854 -230.559714) (xy 104.068816 -230.547854) (xy 104.121966 -230.543871)
			(xy 104.175116 -230.547854) (xy 104.227078 -230.559714) (xy 104.276692 -230.579186) (xy 104.32285 -230.605835)
			(xy 104.364521 -230.639066) (xy 104.400773 -230.678137) (xy 104.430797 -230.722174) (xy 104.453923 -230.770195)
			(xy 104.469633 -230.821125) (xy 104.477576 -230.873829) (xy 104.478074 -230.900478) (xy 104.477576 -230.927127)
			(xy 104.706156 -230.927127) (xy 104.706156 -230.873829) (xy 104.714099 -230.821125) (xy 104.729809 -230.770195)
			(xy 104.752935 -230.722174) (xy 104.782959 -230.678137) (xy 104.819211 -230.639066) (xy 104.860882 -230.605835)
			(xy 104.90704 -230.579186) (xy 104.956654 -230.559714) (xy 105.008616 -230.547854) (xy 105.061766 -230.543871)
			(xy 105.114916 -230.547854) (xy 105.166878 -230.559714) (xy 105.216492 -230.579186) (xy 105.26265 -230.605835)
			(xy 105.304321 -230.639066) (xy 105.340573 -230.678137) (xy 105.370597 -230.722174) (xy 105.393723 -230.770195)
			(xy 105.409433 -230.821125) (xy 105.417376 -230.873829) (xy 105.417874 -230.900478) (xy 105.417376 -230.927127)
			(xy 105.645956 -230.927127) (xy 105.645956 -230.873829) (xy 105.653899 -230.821125) (xy 105.669609 -230.770195)
			(xy 105.692735 -230.722174) (xy 105.722759 -230.678137) (xy 105.759011 -230.639066) (xy 105.800682 -230.605835)
			(xy 105.84684 -230.579186) (xy 105.896454 -230.559714) (xy 105.948416 -230.547854) (xy 106.001566 -230.543871)
			(xy 106.054716 -230.547854) (xy 106.106678 -230.559714) (xy 106.156292 -230.579186) (xy 106.20245 -230.605835)
			(xy 106.244121 -230.639066) (xy 106.280373 -230.678137) (xy 106.310397 -230.722174) (xy 106.333523 -230.770195)
			(xy 106.349233 -230.821125) (xy 106.357176 -230.873829) (xy 106.357674 -230.900478) (xy 106.357176 -230.927127)
			(xy 106.585756 -230.927127) (xy 106.585756 -230.873829) (xy 106.593699 -230.821125) (xy 106.609409 -230.770195)
			(xy 106.632535 -230.722174) (xy 106.662559 -230.678137) (xy 106.698811 -230.639066) (xy 106.740482 -230.605835)
			(xy 106.78664 -230.579186) (xy 106.836254 -230.559714) (xy 106.888216 -230.547854) (xy 106.941366 -230.543871)
			(xy 106.994516 -230.547854) (xy 107.046478 -230.559714) (xy 107.096092 -230.579186) (xy 107.14225 -230.605835)
			(xy 107.183921 -230.639066) (xy 107.220173 -230.678137) (xy 107.250197 -230.722174) (xy 107.273323 -230.770195)
			(xy 107.289033 -230.821125) (xy 107.296976 -230.873829) (xy 107.297474 -230.900478) (xy 107.296976 -230.927127)
			(xy 107.525302 -230.927127) (xy 107.525302 -230.873829) (xy 107.533245 -230.821125) (xy 107.548955 -230.770195)
			(xy 107.572081 -230.722174) (xy 107.602105 -230.678137) (xy 107.638357 -230.639066) (xy 107.680028 -230.605835)
			(xy 107.726186 -230.579186) (xy 107.7758 -230.559714) (xy 107.827762 -230.547854) (xy 107.880912 -230.543871)
			(xy 107.934062 -230.547854) (xy 107.986024 -230.559714) (xy 108.035638 -230.579186) (xy 108.081796 -230.605835)
			(xy 108.123467 -230.639066) (xy 108.159719 -230.678137) (xy 108.189743 -230.722174) (xy 108.212869 -230.770195)
			(xy 108.228579 -230.821125) (xy 108.236522 -230.873829) (xy 108.23702 -230.900478) (xy 108.236522 -230.927127)
			(xy 108.465356 -230.927127) (xy 108.465356 -230.873829) (xy 108.473299 -230.821125) (xy 108.489009 -230.770195)
			(xy 108.512135 -230.722174) (xy 108.542159 -230.678137) (xy 108.578411 -230.639066) (xy 108.620082 -230.605835)
			(xy 108.66624 -230.579186) (xy 108.715854 -230.559714) (xy 108.767816 -230.547854) (xy 108.820966 -230.543871)
			(xy 108.874116 -230.547854) (xy 108.926078 -230.559714) (xy 108.975692 -230.579186) (xy 109.02185 -230.605835)
			(xy 109.063521 -230.639066) (xy 109.099773 -230.678137) (xy 109.129797 -230.722174) (xy 109.152923 -230.770195)
			(xy 109.168633 -230.821125) (xy 109.176576 -230.873829) (xy 109.177074 -230.900478) (xy 109.176576 -230.927127)
			(xy 109.404902 -230.927127) (xy 109.404902 -230.873829) (xy 109.412845 -230.821125) (xy 109.428555 -230.770195)
			(xy 109.451681 -230.722174) (xy 109.481705 -230.678137) (xy 109.517957 -230.639066) (xy 109.559628 -230.605835)
			(xy 109.605786 -230.579186) (xy 109.6554 -230.559714) (xy 109.707362 -230.547854) (xy 109.760512 -230.543871)
			(xy 109.813662 -230.547854) (xy 109.865624 -230.559714) (xy 109.915238 -230.579186) (xy 109.961396 -230.605835)
			(xy 110.003067 -230.639066) (xy 110.039319 -230.678137) (xy 110.069343 -230.722174) (xy 110.092469 -230.770195)
			(xy 110.108179 -230.821125) (xy 110.116122 -230.873829) (xy 110.11662 -230.900478) (xy 110.116122 -230.927127)
			(xy 110.344956 -230.927127) (xy 110.344956 -230.873829) (xy 110.352899 -230.821125) (xy 110.368609 -230.770195)
			(xy 110.391735 -230.722174) (xy 110.421759 -230.678137) (xy 110.458011 -230.639066) (xy 110.499682 -230.605835)
			(xy 110.54584 -230.579186) (xy 110.595454 -230.559714) (xy 110.647416 -230.547854) (xy 110.700566 -230.543871)
			(xy 110.753716 -230.547854) (xy 110.805678 -230.559714) (xy 110.855292 -230.579186) (xy 110.90145 -230.605835)
			(xy 110.943121 -230.639066) (xy 110.979373 -230.678137) (xy 111.009397 -230.722174) (xy 111.032523 -230.770195)
			(xy 111.048233 -230.821125) (xy 111.056176 -230.873829) (xy 111.056674 -230.900478) (xy 111.056176 -230.927127)
			(xy 111.048233 -230.979831) (xy 111.032523 -231.030761) (xy 111.009397 -231.078782) (xy 110.979373 -231.122819)
			(xy 110.943121 -231.16189) (xy 110.90145 -231.195121) (xy 110.855292 -231.22177) (xy 110.805678 -231.241242)
			(xy 110.753716 -231.253102) (xy 110.700566 -231.257086) (xy 110.647416 -231.253102) (xy 110.595454 -231.241242)
			(xy 110.54584 -231.22177) (xy 110.499682 -231.195121) (xy 110.458011 -231.16189) (xy 110.421759 -231.122819)
			(xy 110.391735 -231.078782) (xy 110.368609 -231.030761) (xy 110.352899 -230.979831) (xy 110.344956 -230.927127)
			(xy 110.116122 -230.927127) (xy 110.108179 -230.979831) (xy 110.092469 -231.030761) (xy 110.069343 -231.078782)
			(xy 110.039319 -231.122819) (xy 110.003067 -231.16189) (xy 109.961396 -231.195121) (xy 109.915238 -231.22177)
			(xy 109.865624 -231.241242) (xy 109.813662 -231.253102) (xy 109.760512 -231.257086) (xy 109.707362 -231.253102)
			(xy 109.6554 -231.241242) (xy 109.605786 -231.22177) (xy 109.559628 -231.195121) (xy 109.517957 -231.16189)
			(xy 109.481705 -231.122819) (xy 109.451681 -231.078782) (xy 109.428555 -231.030761) (xy 109.412845 -230.979831)
			(xy 109.404902 -230.927127) (xy 109.176576 -230.927127) (xy 109.168633 -230.979831) (xy 109.152923 -231.030761)
			(xy 109.129797 -231.078782) (xy 109.099773 -231.122819) (xy 109.063521 -231.16189) (xy 109.02185 -231.195121)
			(xy 108.975692 -231.22177) (xy 108.926078 -231.241242) (xy 108.874116 -231.253102) (xy 108.820966 -231.257086)
			(xy 108.767816 -231.253102) (xy 108.715854 -231.241242) (xy 108.66624 -231.22177) (xy 108.620082 -231.195121)
			(xy 108.578411 -231.16189) (xy 108.542159 -231.122819) (xy 108.512135 -231.078782) (xy 108.489009 -231.030761)
			(xy 108.473299 -230.979831) (xy 108.465356 -230.927127) (xy 108.236522 -230.927127) (xy 108.228579 -230.979831)
			(xy 108.212869 -231.030761) (xy 108.189743 -231.078782) (xy 108.159719 -231.122819) (xy 108.123467 -231.16189)
			(xy 108.081796 -231.195121) (xy 108.035638 -231.22177) (xy 107.986024 -231.241242) (xy 107.934062 -231.253102)
			(xy 107.880912 -231.257086) (xy 107.827762 -231.253102) (xy 107.7758 -231.241242) (xy 107.726186 -231.22177)
			(xy 107.680028 -231.195121) (xy 107.638357 -231.16189) (xy 107.602105 -231.122819) (xy 107.572081 -231.078782)
			(xy 107.548955 -231.030761) (xy 107.533245 -230.979831) (xy 107.525302 -230.927127) (xy 107.296976 -230.927127)
			(xy 107.289033 -230.979831) (xy 107.273323 -231.030761) (xy 107.250197 -231.078782) (xy 107.220173 -231.122819)
			(xy 107.183921 -231.16189) (xy 107.14225 -231.195121) (xy 107.096092 -231.22177) (xy 107.046478 -231.241242)
			(xy 106.994516 -231.253102) (xy 106.941366 -231.257086) (xy 106.888216 -231.253102) (xy 106.836254 -231.241242)
			(xy 106.78664 -231.22177) (xy 106.740482 -231.195121) (xy 106.698811 -231.16189) (xy 106.662559 -231.122819)
			(xy 106.632535 -231.078782) (xy 106.609409 -231.030761) (xy 106.593699 -230.979831) (xy 106.585756 -230.927127)
			(xy 106.357176 -230.927127) (xy 106.349233 -230.979831) (xy 106.333523 -231.030761) (xy 106.310397 -231.078782)
			(xy 106.280373 -231.122819) (xy 106.244121 -231.16189) (xy 106.20245 -231.195121) (xy 106.156292 -231.22177)
			(xy 106.106678 -231.241242) (xy 106.054716 -231.253102) (xy 106.001566 -231.257086) (xy 105.948416 -231.253102)
			(xy 105.896454 -231.241242) (xy 105.84684 -231.22177) (xy 105.800682 -231.195121) (xy 105.759011 -231.16189)
			(xy 105.722759 -231.122819) (xy 105.692735 -231.078782) (xy 105.669609 -231.030761) (xy 105.653899 -230.979831)
			(xy 105.645956 -230.927127) (xy 105.417376 -230.927127) (xy 105.409433 -230.979831) (xy 105.393723 -231.030761)
			(xy 105.370597 -231.078782) (xy 105.340573 -231.122819) (xy 105.304321 -231.16189) (xy 105.26265 -231.195121)
			(xy 105.216492 -231.22177) (xy 105.166878 -231.241242) (xy 105.114916 -231.253102) (xy 105.061766 -231.257086)
			(xy 105.008616 -231.253102) (xy 104.956654 -231.241242) (xy 104.90704 -231.22177) (xy 104.860882 -231.195121)
			(xy 104.819211 -231.16189) (xy 104.782959 -231.122819) (xy 104.752935 -231.078782) (xy 104.729809 -231.030761)
			(xy 104.714099 -230.979831) (xy 104.706156 -230.927127) (xy 104.477576 -230.927127) (xy 104.469633 -230.979831)
			(xy 104.453923 -231.030761) (xy 104.430797 -231.078782) (xy 104.400773 -231.122819) (xy 104.364521 -231.16189)
			(xy 104.32285 -231.195121) (xy 104.276692 -231.22177) (xy 104.227078 -231.241242) (xy 104.175116 -231.253102)
			(xy 104.121966 -231.257086) (xy 104.068816 -231.253102) (xy 104.016854 -231.241242) (xy 103.96724 -231.22177)
			(xy 103.921082 -231.195121) (xy 103.879411 -231.16189) (xy 103.843159 -231.122819) (xy 103.813135 -231.078782)
			(xy 103.790009 -231.030761) (xy 103.774299 -230.979831) (xy 103.766356 -230.927127) (xy 103.537776 -230.927127)
			(xy 103.529833 -230.979831) (xy 103.514123 -231.030761) (xy 103.490997 -231.078782) (xy 103.460973 -231.122819)
			(xy 103.424721 -231.16189) (xy 103.38305 -231.195121) (xy 103.336892 -231.22177) (xy 103.287278 -231.241242)
			(xy 103.235316 -231.253102) (xy 103.182166 -231.257086) (xy 103.129016 -231.253102) (xy 103.077054 -231.241242)
			(xy 103.02744 -231.22177) (xy 102.981282 -231.195121) (xy 102.939611 -231.16189) (xy 102.903359 -231.122819)
			(xy 102.873335 -231.078782) (xy 102.850209 -231.030761) (xy 102.834499 -230.979831) (xy 102.826556 -230.927127)
			(xy 102.597976 -230.927127) (xy 102.590033 -230.979831) (xy 102.574323 -231.030761) (xy 102.551197 -231.078782)
			(xy 102.521173 -231.122819) (xy 102.484921 -231.16189) (xy 102.44325 -231.195121) (xy 102.397092 -231.22177)
			(xy 102.347478 -231.241242) (xy 102.295516 -231.253102) (xy 102.242366 -231.257086) (xy 102.189216 -231.253102)
			(xy 102.137254 -231.241242) (xy 102.08764 -231.22177) (xy 102.041482 -231.195121) (xy 101.999811 -231.16189)
			(xy 101.963559 -231.122819) (xy 101.933535 -231.078782) (xy 101.910409 -231.030761) (xy 101.894699 -230.979831)
			(xy 101.886756 -230.927127) (xy 101.658176 -230.927127) (xy 101.650233 -230.979831) (xy 101.634523 -231.030761)
			(xy 101.611397 -231.078782) (xy 101.581373 -231.122819) (xy 101.545121 -231.16189) (xy 101.50345 -231.195121)
			(xy 101.457292 -231.22177) (xy 101.407678 -231.241242) (xy 101.355716 -231.253102) (xy 101.302566 -231.257086)
			(xy 101.249416 -231.253102) (xy 101.197454 -231.241242) (xy 101.14784 -231.22177) (xy 101.101682 -231.195121)
			(xy 101.060011 -231.16189) (xy 101.023759 -231.122819) (xy 100.993735 -231.078782) (xy 100.970609 -231.030761)
			(xy 100.954899 -230.979831) (xy 100.946956 -230.927127) (xy 100.718376 -230.927127) (xy 100.710433 -230.979831)
			(xy 100.694723 -231.030761) (xy 100.671597 -231.078782) (xy 100.641573 -231.122819) (xy 100.605321 -231.16189)
			(xy 100.56365 -231.195121) (xy 100.517492 -231.22177) (xy 100.467878 -231.241242) (xy 100.415916 -231.253102)
			(xy 100.362766 -231.257086) (xy 100.309616 -231.253102) (xy 100.257654 -231.241242) (xy 100.20804 -231.22177)
			(xy 100.161882 -231.195121) (xy 100.120211 -231.16189) (xy 100.083959 -231.122819) (xy 100.053935 -231.078782)
			(xy 100.030809 -231.030761) (xy 100.015099 -230.979831) (xy 100.007156 -230.927127) (xy 99.778576 -230.927127)
			(xy 99.770633 -230.979831) (xy 99.754923 -231.030761) (xy 99.731797 -231.078782) (xy 99.701773 -231.122819)
			(xy 99.665521 -231.16189) (xy 99.62385 -231.195121) (xy 99.577692 -231.22177) (xy 99.528078 -231.241242)
			(xy 99.476116 -231.253102) (xy 99.422966 -231.257086) (xy 99.369816 -231.253102) (xy 99.317854 -231.241242)
			(xy 99.26824 -231.22177) (xy 99.222082 -231.195121) (xy 99.180411 -231.16189) (xy 99.144159 -231.122819)
			(xy 99.114135 -231.078782) (xy 99.091009 -231.030761) (xy 99.075299 -230.979831) (xy 99.067356 -230.927127)
			(xy 98.838776 -230.927127) (xy 98.830833 -230.979831) (xy 98.815123 -231.030761) (xy 98.791997 -231.078782)
			(xy 98.761973 -231.122819) (xy 98.725721 -231.16189) (xy 98.68405 -231.195121) (xy 98.637892 -231.22177)
			(xy 98.588278 -231.241242) (xy 98.536316 -231.253102) (xy 98.483166 -231.257086) (xy 98.430016 -231.253102)
			(xy 98.378054 -231.241242) (xy 98.32844 -231.22177) (xy 98.282282 -231.195121) (xy 98.240611 -231.16189)
			(xy 98.204359 -231.122819) (xy 98.174335 -231.078782) (xy 98.151209 -231.030761) (xy 98.135499 -230.979831)
			(xy 98.127556 -230.927127) (xy 97.898722 -230.927127) (xy 97.890779 -230.979831) (xy 97.875069 -231.030761)
			(xy 97.851943 -231.078782) (xy 97.821919 -231.122819) (xy 97.785667 -231.16189) (xy 97.743996 -231.195121)
			(xy 97.697838 -231.22177) (xy 97.648224 -231.241242) (xy 97.596262 -231.253102) (xy 97.543112 -231.257086)
			(xy 97.489962 -231.253102) (xy 97.438 -231.241242) (xy 97.388386 -231.22177) (xy 97.342228 -231.195121)
			(xy 97.300557 -231.16189) (xy 97.264305 -231.122819) (xy 97.234281 -231.078782) (xy 97.211155 -231.030761)
			(xy 97.195445 -230.979831) (xy 97.187502 -230.927127) (xy 96.959176 -230.927127) (xy 96.951233 -230.979831)
			(xy 96.935523 -231.030761) (xy 96.912397 -231.078782) (xy 96.882373 -231.122819) (xy 96.846121 -231.16189)
			(xy 96.80445 -231.195121) (xy 96.758292 -231.22177) (xy 96.708678 -231.241242) (xy 96.656716 -231.253102)
			(xy 96.603566 -231.257086) (xy 96.550416 -231.253102) (xy 96.498454 -231.241242) (xy 96.44884 -231.22177)
			(xy 96.402682 -231.195121) (xy 96.361011 -231.16189) (xy 96.324759 -231.122819) (xy 96.294735 -231.078782)
			(xy 96.271609 -231.030761) (xy 96.255899 -230.979831) (xy 96.247956 -230.927127) (xy 96.019376 -230.927127)
			(xy 96.011433 -230.979831) (xy 95.995723 -231.030761) (xy 95.972597 -231.078782) (xy 95.942573 -231.122819)
			(xy 95.906321 -231.16189) (xy 95.86465 -231.195121) (xy 95.818492 -231.22177) (xy 95.768878 -231.241242)
			(xy 95.716916 -231.253102) (xy 95.663766 -231.257086) (xy 95.610616 -231.253102) (xy 95.558654 -231.241242)
			(xy 95.50904 -231.22177) (xy 95.462882 -231.195121) (xy 95.421211 -231.16189) (xy 95.384959 -231.122819)
			(xy 95.354935 -231.078782) (xy 95.331809 -231.030761) (xy 95.316099 -230.979831) (xy 95.308156 -230.927127)
			(xy 95.079576 -230.927127) (xy 95.071633 -230.979831) (xy 95.055923 -231.030761) (xy 95.032797 -231.078782)
			(xy 95.002773 -231.122819) (xy 94.966521 -231.16189) (xy 94.92485 -231.195121) (xy 94.878692 -231.22177)
			(xy 94.829078 -231.241242) (xy 94.777116 -231.253102) (xy 94.723966 -231.257086) (xy 94.670816 -231.253102)
			(xy 94.618854 -231.241242) (xy 94.56924 -231.22177) (xy 94.523082 -231.195121) (xy 94.481411 -231.16189)
			(xy 94.445159 -231.122819) (xy 94.415135 -231.078782) (xy 94.392009 -231.030761) (xy 94.376299 -230.979831)
			(xy 94.368356 -230.927127) (xy 94.139776 -230.927127) (xy 94.131833 -230.979831) (xy 94.116123 -231.030761)
			(xy 94.092997 -231.078782) (xy 94.062973 -231.122819) (xy 94.026721 -231.16189) (xy 93.98505 -231.195121)
			(xy 93.938892 -231.22177) (xy 93.889278 -231.241242) (xy 93.837316 -231.253102) (xy 93.784166 -231.257086)
			(xy 93.731016 -231.253102) (xy 93.679054 -231.241242) (xy 93.62944 -231.22177) (xy 93.583282 -231.195121)
			(xy 93.541611 -231.16189) (xy 93.505359 -231.122819) (xy 93.475335 -231.078782) (xy 93.452209 -231.030761)
			(xy 93.436499 -230.979831) (xy 93.428556 -230.927127) (xy 93.199976 -230.927127) (xy 93.192033 -230.979831)
			(xy 93.176323 -231.030761) (xy 93.153197 -231.078782) (xy 93.123173 -231.122819) (xy 93.086921 -231.16189)
			(xy 93.04525 -231.195121) (xy 92.999092 -231.22177) (xy 92.949478 -231.241242) (xy 92.897516 -231.253102)
			(xy 92.844366 -231.257086) (xy 92.791216 -231.253102) (xy 92.739254 -231.241242) (xy 92.68964 -231.22177)
			(xy 92.643482 -231.195121) (xy 92.601811 -231.16189) (xy 92.565559 -231.122819) (xy 92.535535 -231.078782)
			(xy 92.512409 -231.030761) (xy 92.496699 -230.979831) (xy 92.488756 -230.927127) (xy 92.260176 -230.927127)
			(xy 92.252233 -230.979831) (xy 92.236523 -231.030761) (xy 92.213397 -231.078782) (xy 92.183373 -231.122819)
			(xy 92.147121 -231.16189) (xy 92.10545 -231.195121) (xy 92.059292 -231.22177) (xy 92.009678 -231.241242)
			(xy 91.957716 -231.253102) (xy 91.904566 -231.257086) (xy 91.851416 -231.253102) (xy 91.799454 -231.241242)
			(xy 91.74984 -231.22177) (xy 91.703682 -231.195121) (xy 91.662011 -231.16189) (xy 91.625759 -231.122819)
			(xy 91.595735 -231.078782) (xy 91.572609 -231.030761) (xy 91.556899 -230.979831) (xy 91.548956 -230.927127)
			(xy 91.320122 -230.927127) (xy 91.312179 -230.979831) (xy 91.296469 -231.030761) (xy 91.273343 -231.078782)
			(xy 91.243319 -231.122819) (xy 91.207067 -231.16189) (xy 91.165396 -231.195121) (xy 91.119238 -231.22177)
			(xy 91.069624 -231.241242) (xy 91.017662 -231.253102) (xy 90.964512 -231.257086) (xy 90.911362 -231.253102)
			(xy 90.8594 -231.241242) (xy 90.809786 -231.22177) (xy 90.763628 -231.195121) (xy 90.721957 -231.16189)
			(xy 90.685705 -231.122819) (xy 90.655681 -231.078782) (xy 90.632555 -231.030761) (xy 90.616845 -230.979831)
			(xy 90.608902 -230.927127) (xy 90.380576 -230.927127) (xy 90.372633 -230.979831) (xy 90.356923 -231.030761)
			(xy 90.333797 -231.078782) (xy 90.303773 -231.122819) (xy 90.267521 -231.16189) (xy 90.22585 -231.195121)
			(xy 90.179692 -231.22177) (xy 90.130078 -231.241242) (xy 90.078116 -231.253102) (xy 90.024966 -231.257086)
			(xy 89.971816 -231.253102) (xy 89.919854 -231.241242) (xy 89.87024 -231.22177) (xy 89.824082 -231.195121)
			(xy 89.782411 -231.16189) (xy 89.746159 -231.122819) (xy 89.716135 -231.078782) (xy 89.693009 -231.030761)
			(xy 89.677299 -230.979831) (xy 89.669356 -230.927127) (xy 89.439858 -230.927127) (xy 89.43787 -230.95366)
			(xy 89.426007 -231.005632) (xy 89.40653 -231.055255) (xy 89.379874 -231.101421) (xy 89.346635 -231.143098)
			(xy 89.307555 -231.179355) (xy 89.263507 -231.209383) (xy 89.215476 -231.232509) (xy 89.164535 -231.248218)
			(xy 89.11182 -231.256159) (xy 89.085166 -231.256586) (xy 89.074793 -231.25654) (xy 89.054079 -231.255398)
			(xy 89.043764 -231.2543) (xy 89.029507 -231.253139) (xy 89.001308 -231.257855) (xy 88.975518 -231.270199)
			(xy 88.954157 -231.289204) (xy 88.938898 -231.313383) (xy 88.930933 -231.340843) (xy 88.93048 -231.355138)
			(xy 88.93048 -231.54894) (xy 88.93556 -231.559354) (xy 88.946785 -231.583667) (xy 88.962625 -231.63482)
			(xy 88.970632 -231.687768) (xy 88.970626 -231.741197) (xy 89.199202 -231.741197) (xy 89.199202 -231.687899)
			(xy 89.207145 -231.635195) (xy 89.222855 -231.584265) (xy 89.245981 -231.536244) (xy 89.276005 -231.492207)
			(xy 89.312257 -231.453136) (xy 89.353928 -231.419905) (xy 89.400086 -231.393256) (xy 89.4497 -231.373784)
			(xy 89.501662 -231.361924) (xy 89.554812 -231.357941) (xy 89.607962 -231.361924) (xy 89.659924 -231.373784)
			(xy 89.709538 -231.393256) (xy 89.755696 -231.419905) (xy 89.797367 -231.453136) (xy 89.833619 -231.492207)
			(xy 89.863643 -231.536244) (xy 89.886769 -231.584265) (xy 89.902479 -231.635195) (xy 89.910422 -231.687899)
			(xy 89.91092 -231.714548) (xy 89.910422 -231.741197) (xy 90.139002 -231.741197) (xy 90.139002 -231.687899)
			(xy 90.146945 -231.635195) (xy 90.162655 -231.584265) (xy 90.185781 -231.536244) (xy 90.215805 -231.492207)
			(xy 90.252057 -231.453136) (xy 90.293728 -231.419905) (xy 90.339886 -231.393256) (xy 90.3895 -231.373784)
			(xy 90.441462 -231.361924) (xy 90.494612 -231.357941) (xy 90.547762 -231.361924) (xy 90.599724 -231.373784)
			(xy 90.649338 -231.393256) (xy 90.695496 -231.419905) (xy 90.737167 -231.453136) (xy 90.773419 -231.492207)
			(xy 90.803443 -231.536244) (xy 90.826569 -231.584265) (xy 90.842279 -231.635195) (xy 90.850222 -231.687899)
			(xy 90.85072 -231.714548) (xy 90.850222 -231.741197) (xy 91.078802 -231.741197) (xy 91.078802 -231.687899)
			(xy 91.086745 -231.635195) (xy 91.102455 -231.584265) (xy 91.125581 -231.536244) (xy 91.155605 -231.492207)
			(xy 91.191857 -231.453136) (xy 91.233528 -231.419905) (xy 91.279686 -231.393256) (xy 91.3293 -231.373784)
			(xy 91.381262 -231.361924) (xy 91.434412 -231.357941) (xy 91.487562 -231.361924) (xy 91.539524 -231.373784)
			(xy 91.589138 -231.393256) (xy 91.635296 -231.419905) (xy 91.676967 -231.453136) (xy 91.713219 -231.492207)
			(xy 91.743243 -231.536244) (xy 91.766369 -231.584265) (xy 91.782079 -231.635195) (xy 91.790022 -231.687899)
			(xy 91.79052 -231.714548) (xy 91.790022 -231.741197) (xy 92.018602 -231.741197) (xy 92.018602 -231.687899)
			(xy 92.026545 -231.635195) (xy 92.042255 -231.584265) (xy 92.065381 -231.536244) (xy 92.095405 -231.492207)
			(xy 92.131657 -231.453136) (xy 92.173328 -231.419905) (xy 92.219486 -231.393256) (xy 92.2691 -231.373784)
			(xy 92.321062 -231.361924) (xy 92.374212 -231.357941) (xy 92.427362 -231.361924) (xy 92.479324 -231.373784)
			(xy 92.528938 -231.393256) (xy 92.575096 -231.419905) (xy 92.616767 -231.453136) (xy 92.653019 -231.492207)
			(xy 92.683043 -231.536244) (xy 92.706169 -231.584265) (xy 92.721879 -231.635195) (xy 92.729822 -231.687899)
			(xy 92.73032 -231.714548) (xy 92.729822 -231.741197) (xy 92.958402 -231.741197) (xy 92.958402 -231.687899)
			(xy 92.966345 -231.635195) (xy 92.982055 -231.584265) (xy 93.005181 -231.536244) (xy 93.035205 -231.492207)
			(xy 93.071457 -231.453136) (xy 93.113128 -231.419905) (xy 93.159286 -231.393256) (xy 93.2089 -231.373784)
			(xy 93.260862 -231.361924) (xy 93.314012 -231.357941) (xy 93.367162 -231.361924) (xy 93.419124 -231.373784)
			(xy 93.468738 -231.393256) (xy 93.514896 -231.419905) (xy 93.556567 -231.453136) (xy 93.592819 -231.492207)
			(xy 93.622843 -231.536244) (xy 93.645969 -231.584265) (xy 93.661679 -231.635195) (xy 93.669622 -231.687899)
			(xy 93.67012 -231.714548) (xy 93.669622 -231.741197) (xy 93.898456 -231.741197) (xy 93.898456 -231.687899)
			(xy 93.906399 -231.635195) (xy 93.922109 -231.584265) (xy 93.945235 -231.536244) (xy 93.975259 -231.492207)
			(xy 94.011511 -231.453136) (xy 94.053182 -231.419905) (xy 94.09934 -231.393256) (xy 94.148954 -231.373784)
			(xy 94.200916 -231.361924) (xy 94.254066 -231.357941) (xy 94.307216 -231.361924) (xy 94.359178 -231.373784)
			(xy 94.408792 -231.393256) (xy 94.45495 -231.419905) (xy 94.496621 -231.453136) (xy 94.532873 -231.492207)
			(xy 94.562897 -231.536244) (xy 94.586023 -231.584265) (xy 94.601733 -231.635195) (xy 94.609676 -231.687899)
			(xy 94.610174 -231.714548) (xy 94.609676 -231.741197) (xy 94.838002 -231.741197) (xy 94.838002 -231.687899)
			(xy 94.845945 -231.635195) (xy 94.861655 -231.584265) (xy 94.884781 -231.536244) (xy 94.914805 -231.492207)
			(xy 94.951057 -231.453136) (xy 94.992728 -231.419905) (xy 95.038886 -231.393256) (xy 95.0885 -231.373784)
			(xy 95.140462 -231.361924) (xy 95.193612 -231.357941) (xy 95.246762 -231.361924) (xy 95.298724 -231.373784)
			(xy 95.348338 -231.393256) (xy 95.394496 -231.419905) (xy 95.436167 -231.453136) (xy 95.472419 -231.492207)
			(xy 95.502443 -231.536244) (xy 95.525569 -231.584265) (xy 95.541279 -231.635195) (xy 95.549222 -231.687899)
			(xy 95.54972 -231.714548) (xy 95.549222 -231.741197) (xy 95.777802 -231.741197) (xy 95.777802 -231.687899)
			(xy 95.785745 -231.635195) (xy 95.801455 -231.584265) (xy 95.824581 -231.536244) (xy 95.854605 -231.492207)
			(xy 95.890857 -231.453136) (xy 95.932528 -231.419905) (xy 95.978686 -231.393256) (xy 96.0283 -231.373784)
			(xy 96.080262 -231.361924) (xy 96.133412 -231.357941) (xy 96.186562 -231.361924) (xy 96.238524 -231.373784)
			(xy 96.288138 -231.393256) (xy 96.334296 -231.419905) (xy 96.375967 -231.453136) (xy 96.412219 -231.492207)
			(xy 96.442243 -231.536244) (xy 96.465369 -231.584265) (xy 96.481079 -231.635195) (xy 96.489022 -231.687899)
			(xy 96.48952 -231.714548) (xy 96.489022 -231.741197) (xy 96.717602 -231.741197) (xy 96.717602 -231.687899)
			(xy 96.725545 -231.635195) (xy 96.741255 -231.584265) (xy 96.764381 -231.536244) (xy 96.794405 -231.492207)
			(xy 96.830657 -231.453136) (xy 96.872328 -231.419905) (xy 96.918486 -231.393256) (xy 96.9681 -231.373784)
			(xy 97.020062 -231.361924) (xy 97.073212 -231.357941) (xy 97.126362 -231.361924) (xy 97.178324 -231.373784)
			(xy 97.227938 -231.393256) (xy 97.274096 -231.419905) (xy 97.315767 -231.453136) (xy 97.352019 -231.492207)
			(xy 97.382043 -231.536244) (xy 97.405169 -231.584265) (xy 97.420879 -231.635195) (xy 97.428822 -231.687899)
			(xy 97.42932 -231.714548) (xy 97.428822 -231.741197) (xy 97.657402 -231.741197) (xy 97.657402 -231.687899)
			(xy 97.665345 -231.635195) (xy 97.681055 -231.584265) (xy 97.704181 -231.536244) (xy 97.734205 -231.492207)
			(xy 97.770457 -231.453136) (xy 97.812128 -231.419905) (xy 97.858286 -231.393256) (xy 97.9079 -231.373784)
			(xy 97.959862 -231.361924) (xy 98.013012 -231.357941) (xy 98.066162 -231.361924) (xy 98.118124 -231.373784)
			(xy 98.167738 -231.393256) (xy 98.213896 -231.419905) (xy 98.255567 -231.453136) (xy 98.291819 -231.492207)
			(xy 98.321843 -231.536244) (xy 98.344969 -231.584265) (xy 98.360679 -231.635195) (xy 98.368622 -231.687899)
			(xy 98.36912 -231.714548) (xy 98.368622 -231.741197) (xy 98.597202 -231.741197) (xy 98.597202 -231.687899)
			(xy 98.605145 -231.635195) (xy 98.620855 -231.584265) (xy 98.643981 -231.536244) (xy 98.674005 -231.492207)
			(xy 98.710257 -231.453136) (xy 98.751928 -231.419905) (xy 98.798086 -231.393256) (xy 98.8477 -231.373784)
			(xy 98.899662 -231.361924) (xy 98.952812 -231.357941) (xy 99.005962 -231.361924) (xy 99.057924 -231.373784)
			(xy 99.107538 -231.393256) (xy 99.153696 -231.419905) (xy 99.195367 -231.453136) (xy 99.231619 -231.492207)
			(xy 99.261643 -231.536244) (xy 99.284769 -231.584265) (xy 99.300479 -231.635195) (xy 99.308422 -231.687899)
			(xy 99.30892 -231.714548) (xy 99.308422 -231.741197) (xy 99.537002 -231.741197) (xy 99.537002 -231.687899)
			(xy 99.544945 -231.635195) (xy 99.560655 -231.584265) (xy 99.583781 -231.536244) (xy 99.613805 -231.492207)
			(xy 99.650057 -231.453136) (xy 99.691728 -231.419905) (xy 99.737886 -231.393256) (xy 99.7875 -231.373784)
			(xy 99.839462 -231.361924) (xy 99.892612 -231.357941) (xy 99.945762 -231.361924) (xy 99.997724 -231.373784)
			(xy 100.047338 -231.393256) (xy 100.093496 -231.419905) (xy 100.135167 -231.453136) (xy 100.171419 -231.492207)
			(xy 100.201443 -231.536244) (xy 100.224569 -231.584265) (xy 100.240279 -231.635195) (xy 100.248222 -231.687899)
			(xy 100.24872 -231.714548) (xy 100.248222 -231.741197) (xy 100.477056 -231.741197) (xy 100.477056 -231.687899)
			(xy 100.484999 -231.635195) (xy 100.500709 -231.584265) (xy 100.523835 -231.536244) (xy 100.553859 -231.492207)
			(xy 100.590111 -231.453136) (xy 100.631782 -231.419905) (xy 100.67794 -231.393256) (xy 100.727554 -231.373784)
			(xy 100.779516 -231.361924) (xy 100.832666 -231.357941) (xy 100.885816 -231.361924) (xy 100.937778 -231.373784)
			(xy 100.987392 -231.393256) (xy 101.03355 -231.419905) (xy 101.075221 -231.453136) (xy 101.111473 -231.492207)
			(xy 101.141497 -231.536244) (xy 101.164623 -231.584265) (xy 101.180333 -231.635195) (xy 101.188276 -231.687899)
			(xy 101.188774 -231.714548) (xy 101.188276 -231.741197) (xy 101.416602 -231.741197) (xy 101.416602 -231.687899)
			(xy 101.424545 -231.635195) (xy 101.440255 -231.584265) (xy 101.463381 -231.536244) (xy 101.493405 -231.492207)
			(xy 101.529657 -231.453136) (xy 101.571328 -231.419905) (xy 101.617486 -231.393256) (xy 101.6671 -231.373784)
			(xy 101.719062 -231.361924) (xy 101.772212 -231.357941) (xy 101.825362 -231.361924) (xy 101.877324 -231.373784)
			(xy 101.926938 -231.393256) (xy 101.973096 -231.419905) (xy 102.014767 -231.453136) (xy 102.051019 -231.492207)
			(xy 102.081043 -231.536244) (xy 102.104169 -231.584265) (xy 102.119879 -231.635195) (xy 102.127822 -231.687899)
			(xy 102.12832 -231.714548) (xy 102.127822 -231.741197) (xy 102.356402 -231.741197) (xy 102.356402 -231.687899)
			(xy 102.364345 -231.635195) (xy 102.380055 -231.584265) (xy 102.403181 -231.536244) (xy 102.433205 -231.492207)
			(xy 102.469457 -231.453136) (xy 102.511128 -231.419905) (xy 102.557286 -231.393256) (xy 102.6069 -231.373784)
			(xy 102.658862 -231.361924) (xy 102.712012 -231.357941) (xy 102.765162 -231.361924) (xy 102.817124 -231.373784)
			(xy 102.866738 -231.393256) (xy 102.912896 -231.419905) (xy 102.954567 -231.453136) (xy 102.990819 -231.492207)
			(xy 103.020843 -231.536244) (xy 103.043969 -231.584265) (xy 103.059679 -231.635195) (xy 103.067622 -231.687899)
			(xy 103.06812 -231.714548) (xy 103.067622 -231.741197) (xy 103.296202 -231.741197) (xy 103.296202 -231.687899)
			(xy 103.304145 -231.635195) (xy 103.319855 -231.584265) (xy 103.342981 -231.536244) (xy 103.373005 -231.492207)
			(xy 103.409257 -231.453136) (xy 103.450928 -231.419905) (xy 103.497086 -231.393256) (xy 103.5467 -231.373784)
			(xy 103.598662 -231.361924) (xy 103.651812 -231.357941) (xy 103.704962 -231.361924) (xy 103.756924 -231.373784)
			(xy 103.806538 -231.393256) (xy 103.852696 -231.419905) (xy 103.894367 -231.453136) (xy 103.930619 -231.492207)
			(xy 103.960643 -231.536244) (xy 103.983769 -231.584265) (xy 103.999479 -231.635195) (xy 104.007422 -231.687899)
			(xy 104.00792 -231.714548) (xy 104.007422 -231.741197) (xy 104.236002 -231.741197) (xy 104.236002 -231.687899)
			(xy 104.243945 -231.635195) (xy 104.259655 -231.584265) (xy 104.282781 -231.536244) (xy 104.312805 -231.492207)
			(xy 104.349057 -231.453136) (xy 104.390728 -231.419905) (xy 104.436886 -231.393256) (xy 104.4865 -231.373784)
			(xy 104.538462 -231.361924) (xy 104.591612 -231.357941) (xy 104.644762 -231.361924) (xy 104.696724 -231.373784)
			(xy 104.746338 -231.393256) (xy 104.792496 -231.419905) (xy 104.834167 -231.453136) (xy 104.870419 -231.492207)
			(xy 104.900443 -231.536244) (xy 104.923569 -231.584265) (xy 104.939279 -231.635195) (xy 104.947222 -231.687899)
			(xy 104.94772 -231.714548) (xy 104.947222 -231.741197) (xy 105.175802 -231.741197) (xy 105.175802 -231.687899)
			(xy 105.183745 -231.635195) (xy 105.199455 -231.584265) (xy 105.222581 -231.536244) (xy 105.252605 -231.492207)
			(xy 105.288857 -231.453136) (xy 105.330528 -231.419905) (xy 105.376686 -231.393256) (xy 105.4263 -231.373784)
			(xy 105.478262 -231.361924) (xy 105.531412 -231.357941) (xy 105.584562 -231.361924) (xy 105.636524 -231.373784)
			(xy 105.686138 -231.393256) (xy 105.732296 -231.419905) (xy 105.773967 -231.453136) (xy 105.810219 -231.492207)
			(xy 105.840243 -231.536244) (xy 105.863369 -231.584265) (xy 105.879079 -231.635195) (xy 105.887022 -231.687899)
			(xy 105.88752 -231.714548) (xy 105.887022 -231.741197) (xy 106.115602 -231.741197) (xy 106.115602 -231.687899)
			(xy 106.123545 -231.635195) (xy 106.139255 -231.584265) (xy 106.162381 -231.536244) (xy 106.192405 -231.492207)
			(xy 106.228657 -231.453136) (xy 106.270328 -231.419905) (xy 106.316486 -231.393256) (xy 106.3661 -231.373784)
			(xy 106.418062 -231.361924) (xy 106.471212 -231.357941) (xy 106.524362 -231.361924) (xy 106.576324 -231.373784)
			(xy 106.625938 -231.393256) (xy 106.672096 -231.419905) (xy 106.713767 -231.453136) (xy 106.750019 -231.492207)
			(xy 106.780043 -231.536244) (xy 106.803169 -231.584265) (xy 106.818879 -231.635195) (xy 106.826822 -231.687899)
			(xy 106.82732 -231.714548) (xy 106.826822 -231.741197) (xy 107.055402 -231.741197) (xy 107.055402 -231.687899)
			(xy 107.063345 -231.635195) (xy 107.079055 -231.584265) (xy 107.102181 -231.536244) (xy 107.132205 -231.492207)
			(xy 107.168457 -231.453136) (xy 107.210128 -231.419905) (xy 107.256286 -231.393256) (xy 107.3059 -231.373784)
			(xy 107.357862 -231.361924) (xy 107.411012 -231.357941) (xy 107.464162 -231.361924) (xy 107.516124 -231.373784)
			(xy 107.565738 -231.393256) (xy 107.611896 -231.419905) (xy 107.653567 -231.453136) (xy 107.689819 -231.492207)
			(xy 107.719843 -231.536244) (xy 107.742969 -231.584265) (xy 107.758679 -231.635195) (xy 107.766622 -231.687899)
			(xy 107.76712 -231.714548) (xy 107.766622 -231.741197) (xy 107.995202 -231.741197) (xy 107.995202 -231.687899)
			(xy 108.003145 -231.635195) (xy 108.018855 -231.584265) (xy 108.041981 -231.536244) (xy 108.072005 -231.492207)
			(xy 108.108257 -231.453136) (xy 108.149928 -231.419905) (xy 108.196086 -231.393256) (xy 108.2457 -231.373784)
			(xy 108.297662 -231.361924) (xy 108.350812 -231.357941) (xy 108.403962 -231.361924) (xy 108.455924 -231.373784)
			(xy 108.505538 -231.393256) (xy 108.551696 -231.419905) (xy 108.593367 -231.453136) (xy 108.629619 -231.492207)
			(xy 108.659643 -231.536244) (xy 108.682769 -231.584265) (xy 108.698479 -231.635195) (xy 108.706422 -231.687899)
			(xy 108.70692 -231.714548) (xy 108.706422 -231.741197) (xy 108.935002 -231.741197) (xy 108.935002 -231.687899)
			(xy 108.942945 -231.635195) (xy 108.958655 -231.584265) (xy 108.981781 -231.536244) (xy 109.011805 -231.492207)
			(xy 109.048057 -231.453136) (xy 109.089728 -231.419905) (xy 109.135886 -231.393256) (xy 109.1855 -231.373784)
			(xy 109.237462 -231.361924) (xy 109.290612 -231.357941) (xy 109.343762 -231.361924) (xy 109.395724 -231.373784)
			(xy 109.445338 -231.393256) (xy 109.491496 -231.419905) (xy 109.533167 -231.453136) (xy 109.569419 -231.492207)
			(xy 109.599443 -231.536244) (xy 109.622569 -231.584265) (xy 109.638279 -231.635195) (xy 109.646222 -231.687899)
			(xy 109.64672 -231.714548) (xy 109.646222 -231.741197) (xy 109.638279 -231.793901) (xy 109.622569 -231.844831)
			(xy 109.599443 -231.892852) (xy 109.569419 -231.936889) (xy 109.533167 -231.97596) (xy 109.491496 -232.009191)
			(xy 109.445338 -232.03584) (xy 109.395724 -232.055312) (xy 109.343762 -232.067172) (xy 109.290612 -232.071156)
			(xy 109.237462 -232.067172) (xy 109.1855 -232.055312) (xy 109.135886 -232.03584) (xy 109.089728 -232.009191)
			(xy 109.048057 -231.97596) (xy 109.011805 -231.936889) (xy 108.981781 -231.892852) (xy 108.958655 -231.844831)
			(xy 108.942945 -231.793901) (xy 108.935002 -231.741197) (xy 108.706422 -231.741197) (xy 108.698479 -231.793901)
			(xy 108.682769 -231.844831) (xy 108.659643 -231.892852) (xy 108.629619 -231.936889) (xy 108.593367 -231.97596)
			(xy 108.551696 -232.009191) (xy 108.505538 -232.03584) (xy 108.455924 -232.055312) (xy 108.403962 -232.067172)
			(xy 108.350812 -232.071156) (xy 108.297662 -232.067172) (xy 108.2457 -232.055312) (xy 108.196086 -232.03584)
			(xy 108.149928 -232.009191) (xy 108.108257 -231.97596) (xy 108.072005 -231.936889) (xy 108.041981 -231.892852)
			(xy 108.018855 -231.844831) (xy 108.003145 -231.793901) (xy 107.995202 -231.741197) (xy 107.766622 -231.741197)
			(xy 107.758679 -231.793901) (xy 107.742969 -231.844831) (xy 107.719843 -231.892852) (xy 107.689819 -231.936889)
			(xy 107.653567 -231.97596) (xy 107.611896 -232.009191) (xy 107.565738 -232.03584) (xy 107.516124 -232.055312)
			(xy 107.464162 -232.067172) (xy 107.411012 -232.071156) (xy 107.357862 -232.067172) (xy 107.3059 -232.055312)
			(xy 107.256286 -232.03584) (xy 107.210128 -232.009191) (xy 107.168457 -231.97596) (xy 107.132205 -231.936889)
			(xy 107.102181 -231.892852) (xy 107.079055 -231.844831) (xy 107.063345 -231.793901) (xy 107.055402 -231.741197)
			(xy 106.826822 -231.741197) (xy 106.818879 -231.793901) (xy 106.803169 -231.844831) (xy 106.780043 -231.892852)
			(xy 106.750019 -231.936889) (xy 106.713767 -231.97596) (xy 106.672096 -232.009191) (xy 106.625938 -232.03584)
			(xy 106.576324 -232.055312) (xy 106.524362 -232.067172) (xy 106.471212 -232.071156) (xy 106.418062 -232.067172)
			(xy 106.3661 -232.055312) (xy 106.316486 -232.03584) (xy 106.270328 -232.009191) (xy 106.228657 -231.97596)
			(xy 106.192405 -231.936889) (xy 106.162381 -231.892852) (xy 106.139255 -231.844831) (xy 106.123545 -231.793901)
			(xy 106.115602 -231.741197) (xy 105.887022 -231.741197) (xy 105.879079 -231.793901) (xy 105.863369 -231.844831)
			(xy 105.840243 -231.892852) (xy 105.810219 -231.936889) (xy 105.773967 -231.97596) (xy 105.732296 -232.009191)
			(xy 105.686138 -232.03584) (xy 105.636524 -232.055312) (xy 105.584562 -232.067172) (xy 105.531412 -232.071156)
			(xy 105.478262 -232.067172) (xy 105.4263 -232.055312) (xy 105.376686 -232.03584) (xy 105.330528 -232.009191)
			(xy 105.288857 -231.97596) (xy 105.252605 -231.936889) (xy 105.222581 -231.892852) (xy 105.199455 -231.844831)
			(xy 105.183745 -231.793901) (xy 105.175802 -231.741197) (xy 104.947222 -231.741197) (xy 104.939279 -231.793901)
			(xy 104.923569 -231.844831) (xy 104.900443 -231.892852) (xy 104.870419 -231.936889) (xy 104.834167 -231.97596)
			(xy 104.792496 -232.009191) (xy 104.746338 -232.03584) (xy 104.696724 -232.055312) (xy 104.644762 -232.067172)
			(xy 104.591612 -232.071156) (xy 104.538462 -232.067172) (xy 104.4865 -232.055312) (xy 104.436886 -232.03584)
			(xy 104.390728 -232.009191) (xy 104.349057 -231.97596) (xy 104.312805 -231.936889) (xy 104.282781 -231.892852)
			(xy 104.259655 -231.844831) (xy 104.243945 -231.793901) (xy 104.236002 -231.741197) (xy 104.007422 -231.741197)
			(xy 103.999479 -231.793901) (xy 103.983769 -231.844831) (xy 103.960643 -231.892852) (xy 103.930619 -231.936889)
			(xy 103.894367 -231.97596) (xy 103.852696 -232.009191) (xy 103.806538 -232.03584) (xy 103.756924 -232.055312)
			(xy 103.704962 -232.067172) (xy 103.651812 -232.071156) (xy 103.598662 -232.067172) (xy 103.5467 -232.055312)
			(xy 103.497086 -232.03584) (xy 103.450928 -232.009191) (xy 103.409257 -231.97596) (xy 103.373005 -231.936889)
			(xy 103.342981 -231.892852) (xy 103.319855 -231.844831) (xy 103.304145 -231.793901) (xy 103.296202 -231.741197)
			(xy 103.067622 -231.741197) (xy 103.059679 -231.793901) (xy 103.043969 -231.844831) (xy 103.020843 -231.892852)
			(xy 102.990819 -231.936889) (xy 102.954567 -231.97596) (xy 102.912896 -232.009191) (xy 102.866738 -232.03584)
			(xy 102.817124 -232.055312) (xy 102.765162 -232.067172) (xy 102.712012 -232.071156) (xy 102.658862 -232.067172)
			(xy 102.6069 -232.055312) (xy 102.557286 -232.03584) (xy 102.511128 -232.009191) (xy 102.469457 -231.97596)
			(xy 102.433205 -231.936889) (xy 102.403181 -231.892852) (xy 102.380055 -231.844831) (xy 102.364345 -231.793901)
			(xy 102.356402 -231.741197) (xy 102.127822 -231.741197) (xy 102.119879 -231.793901) (xy 102.104169 -231.844831)
			(xy 102.081043 -231.892852) (xy 102.051019 -231.936889) (xy 102.014767 -231.97596) (xy 101.973096 -232.009191)
			(xy 101.926938 -232.03584) (xy 101.877324 -232.055312) (xy 101.825362 -232.067172) (xy 101.772212 -232.071156)
			(xy 101.719062 -232.067172) (xy 101.6671 -232.055312) (xy 101.617486 -232.03584) (xy 101.571328 -232.009191)
			(xy 101.529657 -231.97596) (xy 101.493405 -231.936889) (xy 101.463381 -231.892852) (xy 101.440255 -231.844831)
			(xy 101.424545 -231.793901) (xy 101.416602 -231.741197) (xy 101.188276 -231.741197) (xy 101.180333 -231.793901)
			(xy 101.164623 -231.844831) (xy 101.141497 -231.892852) (xy 101.111473 -231.936889) (xy 101.075221 -231.97596)
			(xy 101.03355 -232.009191) (xy 100.987392 -232.03584) (xy 100.937778 -232.055312) (xy 100.885816 -232.067172)
			(xy 100.832666 -232.071156) (xy 100.779516 -232.067172) (xy 100.727554 -232.055312) (xy 100.67794 -232.03584)
			(xy 100.631782 -232.009191) (xy 100.590111 -231.97596) (xy 100.553859 -231.936889) (xy 100.523835 -231.892852)
			(xy 100.500709 -231.844831) (xy 100.484999 -231.793901) (xy 100.477056 -231.741197) (xy 100.248222 -231.741197)
			(xy 100.240279 -231.793901) (xy 100.224569 -231.844831) (xy 100.201443 -231.892852) (xy 100.171419 -231.936889)
			(xy 100.135167 -231.97596) (xy 100.093496 -232.009191) (xy 100.047338 -232.03584) (xy 99.997724 -232.055312)
			(xy 99.945762 -232.067172) (xy 99.892612 -232.071156) (xy 99.839462 -232.067172) (xy 99.7875 -232.055312)
			(xy 99.737886 -232.03584) (xy 99.691728 -232.009191) (xy 99.650057 -231.97596) (xy 99.613805 -231.936889)
			(xy 99.583781 -231.892852) (xy 99.560655 -231.844831) (xy 99.544945 -231.793901) (xy 99.537002 -231.741197)
			(xy 99.308422 -231.741197) (xy 99.300479 -231.793901) (xy 99.284769 -231.844831) (xy 99.261643 -231.892852)
			(xy 99.231619 -231.936889) (xy 99.195367 -231.97596) (xy 99.153696 -232.009191) (xy 99.107538 -232.03584)
			(xy 99.057924 -232.055312) (xy 99.005962 -232.067172) (xy 98.952812 -232.071156) (xy 98.899662 -232.067172)
			(xy 98.8477 -232.055312) (xy 98.798086 -232.03584) (xy 98.751928 -232.009191) (xy 98.710257 -231.97596)
			(xy 98.674005 -231.936889) (xy 98.643981 -231.892852) (xy 98.620855 -231.844831) (xy 98.605145 -231.793901)
			(xy 98.597202 -231.741197) (xy 98.368622 -231.741197) (xy 98.360679 -231.793901) (xy 98.344969 -231.844831)
			(xy 98.321843 -231.892852) (xy 98.291819 -231.936889) (xy 98.255567 -231.97596) (xy 98.213896 -232.009191)
			(xy 98.167738 -232.03584) (xy 98.118124 -232.055312) (xy 98.066162 -232.067172) (xy 98.013012 -232.071156)
			(xy 97.959862 -232.067172) (xy 97.9079 -232.055312) (xy 97.858286 -232.03584) (xy 97.812128 -232.009191)
			(xy 97.770457 -231.97596) (xy 97.734205 -231.936889) (xy 97.704181 -231.892852) (xy 97.681055 -231.844831)
			(xy 97.665345 -231.793901) (xy 97.657402 -231.741197) (xy 97.428822 -231.741197) (xy 97.420879 -231.793901)
			(xy 97.405169 -231.844831) (xy 97.382043 -231.892852) (xy 97.352019 -231.936889) (xy 97.315767 -231.97596)
			(xy 97.274096 -232.009191) (xy 97.227938 -232.03584) (xy 97.178324 -232.055312) (xy 97.126362 -232.067172)
			(xy 97.073212 -232.071156) (xy 97.020062 -232.067172) (xy 96.9681 -232.055312) (xy 96.918486 -232.03584)
			(xy 96.872328 -232.009191) (xy 96.830657 -231.97596) (xy 96.794405 -231.936889) (xy 96.764381 -231.892852)
			(xy 96.741255 -231.844831) (xy 96.725545 -231.793901) (xy 96.717602 -231.741197) (xy 96.489022 -231.741197)
			(xy 96.481079 -231.793901) (xy 96.465369 -231.844831) (xy 96.442243 -231.892852) (xy 96.412219 -231.936889)
			(xy 96.375967 -231.97596) (xy 96.334296 -232.009191) (xy 96.288138 -232.03584) (xy 96.238524 -232.055312)
			(xy 96.186562 -232.067172) (xy 96.133412 -232.071156) (xy 96.080262 -232.067172) (xy 96.0283 -232.055312)
			(xy 95.978686 -232.03584) (xy 95.932528 -232.009191) (xy 95.890857 -231.97596) (xy 95.854605 -231.936889)
			(xy 95.824581 -231.892852) (xy 95.801455 -231.844831) (xy 95.785745 -231.793901) (xy 95.777802 -231.741197)
			(xy 95.549222 -231.741197) (xy 95.541279 -231.793901) (xy 95.525569 -231.844831) (xy 95.502443 -231.892852)
			(xy 95.472419 -231.936889) (xy 95.436167 -231.97596) (xy 95.394496 -232.009191) (xy 95.348338 -232.03584)
			(xy 95.298724 -232.055312) (xy 95.246762 -232.067172) (xy 95.193612 -232.071156) (xy 95.140462 -232.067172)
			(xy 95.0885 -232.055312) (xy 95.038886 -232.03584) (xy 94.992728 -232.009191) (xy 94.951057 -231.97596)
			(xy 94.914805 -231.936889) (xy 94.884781 -231.892852) (xy 94.861655 -231.844831) (xy 94.845945 -231.793901)
			(xy 94.838002 -231.741197) (xy 94.609676 -231.741197) (xy 94.601733 -231.793901) (xy 94.586023 -231.844831)
			(xy 94.562897 -231.892852) (xy 94.532873 -231.936889) (xy 94.496621 -231.97596) (xy 94.45495 -232.009191)
			(xy 94.408792 -232.03584) (xy 94.359178 -232.055312) (xy 94.307216 -232.067172) (xy 94.254066 -232.071156)
			(xy 94.200916 -232.067172) (xy 94.148954 -232.055312) (xy 94.09934 -232.03584) (xy 94.053182 -232.009191)
			(xy 94.011511 -231.97596) (xy 93.975259 -231.936889) (xy 93.945235 -231.892852) (xy 93.922109 -231.844831)
			(xy 93.906399 -231.793901) (xy 93.898456 -231.741197) (xy 93.669622 -231.741197) (xy 93.661679 -231.793901)
			(xy 93.645969 -231.844831) (xy 93.622843 -231.892852) (xy 93.592819 -231.936889) (xy 93.556567 -231.97596)
			(xy 93.514896 -232.009191) (xy 93.468738 -232.03584) (xy 93.419124 -232.055312) (xy 93.367162 -232.067172)
			(xy 93.314012 -232.071156) (xy 93.260862 -232.067172) (xy 93.2089 -232.055312) (xy 93.159286 -232.03584)
			(xy 93.113128 -232.009191) (xy 93.071457 -231.97596) (xy 93.035205 -231.936889) (xy 93.005181 -231.892852)
			(xy 92.982055 -231.844831) (xy 92.966345 -231.793901) (xy 92.958402 -231.741197) (xy 92.729822 -231.741197)
			(xy 92.721879 -231.793901) (xy 92.706169 -231.844831) (xy 92.683043 -231.892852) (xy 92.653019 -231.936889)
			(xy 92.616767 -231.97596) (xy 92.575096 -232.009191) (xy 92.528938 -232.03584) (xy 92.479324 -232.055312)
			(xy 92.427362 -232.067172) (xy 92.374212 -232.071156) (xy 92.321062 -232.067172) (xy 92.2691 -232.055312)
			(xy 92.219486 -232.03584) (xy 92.173328 -232.009191) (xy 92.131657 -231.97596) (xy 92.095405 -231.936889)
			(xy 92.065381 -231.892852) (xy 92.042255 -231.844831) (xy 92.026545 -231.793901) (xy 92.018602 -231.741197)
			(xy 91.790022 -231.741197) (xy 91.782079 -231.793901) (xy 91.766369 -231.844831) (xy 91.743243 -231.892852)
			(xy 91.713219 -231.936889) (xy 91.676967 -231.97596) (xy 91.635296 -232.009191) (xy 91.589138 -232.03584)
			(xy 91.539524 -232.055312) (xy 91.487562 -232.067172) (xy 91.434412 -232.071156) (xy 91.381262 -232.067172)
			(xy 91.3293 -232.055312) (xy 91.279686 -232.03584) (xy 91.233528 -232.009191) (xy 91.191857 -231.97596)
			(xy 91.155605 -231.936889) (xy 91.125581 -231.892852) (xy 91.102455 -231.844831) (xy 91.086745 -231.793901)
			(xy 91.078802 -231.741197) (xy 90.850222 -231.741197) (xy 90.842279 -231.793901) (xy 90.826569 -231.844831)
			(xy 90.803443 -231.892852) (xy 90.773419 -231.936889) (xy 90.737167 -231.97596) (xy 90.695496 -232.009191)
			(xy 90.649338 -232.03584) (xy 90.599724 -232.055312) (xy 90.547762 -232.067172) (xy 90.494612 -232.071156)
			(xy 90.441462 -232.067172) (xy 90.3895 -232.055312) (xy 90.339886 -232.03584) (xy 90.293728 -232.009191)
			(xy 90.252057 -231.97596) (xy 90.215805 -231.936889) (xy 90.185781 -231.892852) (xy 90.162655 -231.844831)
			(xy 90.146945 -231.793901) (xy 90.139002 -231.741197) (xy 89.910422 -231.741197) (xy 89.902479 -231.793901)
			(xy 89.886769 -231.844831) (xy 89.863643 -231.892852) (xy 89.833619 -231.936889) (xy 89.797367 -231.97596)
			(xy 89.755696 -232.009191) (xy 89.709538 -232.03584) (xy 89.659924 -232.055312) (xy 89.607962 -232.067172)
			(xy 89.554812 -232.071156) (xy 89.501662 -232.067172) (xy 89.4497 -232.055312) (xy 89.400086 -232.03584)
			(xy 89.353928 -232.009191) (xy 89.312257 -231.97596) (xy 89.276005 -231.936889) (xy 89.245981 -231.892852)
			(xy 89.222855 -231.844831) (xy 89.207145 -231.793901) (xy 89.199202 -231.741197) (xy 88.970626 -231.741197)
			(xy 88.970626 -231.741318) (xy 88.962606 -231.794264) (xy 88.946753 -231.845413) (xy 88.93556 -231.869742)
			(xy 88.93048 -231.880156) (xy 88.93048 -232.073704) (xy 88.930953 -232.088005) (xy 88.938872 -232.115488)
			(xy 88.954114 -232.13969) (xy 88.97548 -232.158705) (xy 89.001286 -232.171036) (xy 89.029502 -232.175713)
			(xy 89.043764 -232.174542) (xy 89.054078 -232.173438) (xy 89.074793 -232.172294) (xy 89.085166 -232.172256)
			(xy 89.111821 -232.172727) (xy 89.164538 -232.180668) (xy 89.215481 -232.196378) (xy 89.263514 -232.219505)
			(xy 89.307564 -232.249534) (xy 89.346645 -232.285792) (xy 89.379886 -232.327471) (xy 89.406543 -232.373639)
			(xy 89.42602 -232.423264) (xy 89.437884 -232.475238) (xy 89.441868 -232.5284) (xy 89.439874 -232.555013)
			(xy 89.669356 -232.555013) (xy 89.669356 -232.501715) (xy 89.677299 -232.449011) (xy 89.693009 -232.398081)
			(xy 89.716135 -232.35006) (xy 89.746159 -232.306023) (xy 89.782411 -232.266952) (xy 89.824082 -232.233721)
			(xy 89.87024 -232.207072) (xy 89.919854 -232.1876) (xy 89.971816 -232.17574) (xy 90.024966 -232.171757)
			(xy 90.078116 -232.17574) (xy 90.130078 -232.1876) (xy 90.179692 -232.207072) (xy 90.22585 -232.233721)
			(xy 90.267521 -232.266952) (xy 90.303773 -232.306023) (xy 90.333797 -232.35006) (xy 90.356923 -232.398081)
			(xy 90.372633 -232.449011) (xy 90.380576 -232.501715) (xy 90.381074 -232.528364) (xy 90.380576 -232.555013)
			(xy 90.609156 -232.555013) (xy 90.609156 -232.501715) (xy 90.617099 -232.449011) (xy 90.632809 -232.398081)
			(xy 90.655935 -232.35006) (xy 90.685959 -232.306023) (xy 90.722211 -232.266952) (xy 90.763882 -232.233721)
			(xy 90.81004 -232.207072) (xy 90.859654 -232.1876) (xy 90.911616 -232.17574) (xy 90.964766 -232.171757)
			(xy 91.017916 -232.17574) (xy 91.069878 -232.1876) (xy 91.119492 -232.207072) (xy 91.16565 -232.233721)
			(xy 91.207321 -232.266952) (xy 91.243573 -232.306023) (xy 91.273597 -232.35006) (xy 91.296723 -232.398081)
			(xy 91.312433 -232.449011) (xy 91.320376 -232.501715) (xy 91.320874 -232.528364) (xy 91.320376 -232.555013)
			(xy 91.548702 -232.555013) (xy 91.548702 -232.501715) (xy 91.556645 -232.449011) (xy 91.572355 -232.398081)
			(xy 91.595481 -232.35006) (xy 91.625505 -232.306023) (xy 91.661757 -232.266952) (xy 91.703428 -232.233721)
			(xy 91.749586 -232.207072) (xy 91.7992 -232.1876) (xy 91.851162 -232.17574) (xy 91.904312 -232.171757)
			(xy 91.957462 -232.17574) (xy 92.009424 -232.1876) (xy 92.059038 -232.207072) (xy 92.105196 -232.233721)
			(xy 92.146867 -232.266952) (xy 92.183119 -232.306023) (xy 92.213143 -232.35006) (xy 92.236269 -232.398081)
			(xy 92.251979 -232.449011) (xy 92.259922 -232.501715) (xy 92.26042 -232.528364) (xy 92.259922 -232.555013)
			(xy 92.488756 -232.555013) (xy 92.488756 -232.501715) (xy 92.496699 -232.449011) (xy 92.512409 -232.398081)
			(xy 92.535535 -232.35006) (xy 92.565559 -232.306023) (xy 92.601811 -232.266952) (xy 92.643482 -232.233721)
			(xy 92.68964 -232.207072) (xy 92.739254 -232.1876) (xy 92.791216 -232.17574) (xy 92.844366 -232.171757)
			(xy 92.897516 -232.17574) (xy 92.949478 -232.1876) (xy 92.999092 -232.207072) (xy 93.04525 -232.233721)
			(xy 93.086921 -232.266952) (xy 93.123173 -232.306023) (xy 93.153197 -232.35006) (xy 93.176323 -232.398081)
			(xy 93.192033 -232.449011) (xy 93.199976 -232.501715) (xy 93.200474 -232.528364) (xy 93.199976 -232.555013)
			(xy 93.428556 -232.555013) (xy 93.428556 -232.501715) (xy 93.436499 -232.449011) (xy 93.452209 -232.398081)
			(xy 93.475335 -232.35006) (xy 93.505359 -232.306023) (xy 93.541611 -232.266952) (xy 93.583282 -232.233721)
			(xy 93.62944 -232.207072) (xy 93.679054 -232.1876) (xy 93.731016 -232.17574) (xy 93.784166 -232.171757)
			(xy 93.837316 -232.17574) (xy 93.889278 -232.1876) (xy 93.938892 -232.207072) (xy 93.98505 -232.233721)
			(xy 94.026721 -232.266952) (xy 94.062973 -232.306023) (xy 94.092997 -232.35006) (xy 94.116123 -232.398081)
			(xy 94.131833 -232.449011) (xy 94.139776 -232.501715) (xy 94.140274 -232.528364) (xy 94.139776 -232.555013)
			(xy 94.368356 -232.555013) (xy 94.368356 -232.501715) (xy 94.376299 -232.449011) (xy 94.392009 -232.398081)
			(xy 94.415135 -232.35006) (xy 94.445159 -232.306023) (xy 94.481411 -232.266952) (xy 94.523082 -232.233721)
			(xy 94.56924 -232.207072) (xy 94.618854 -232.1876) (xy 94.670816 -232.17574) (xy 94.723966 -232.171757)
			(xy 94.777116 -232.17574) (xy 94.829078 -232.1876) (xy 94.878692 -232.207072) (xy 94.92485 -232.233721)
			(xy 94.966521 -232.266952) (xy 95.002773 -232.306023) (xy 95.032797 -232.35006) (xy 95.055923 -232.398081)
			(xy 95.071633 -232.449011) (xy 95.079576 -232.501715) (xy 95.080074 -232.528364) (xy 95.079576 -232.555013)
			(xy 95.308156 -232.555013) (xy 95.308156 -232.501715) (xy 95.316099 -232.449011) (xy 95.331809 -232.398081)
			(xy 95.354935 -232.35006) (xy 95.384959 -232.306023) (xy 95.421211 -232.266952) (xy 95.462882 -232.233721)
			(xy 95.50904 -232.207072) (xy 95.558654 -232.1876) (xy 95.610616 -232.17574) (xy 95.663766 -232.171757)
			(xy 95.716916 -232.17574) (xy 95.768878 -232.1876) (xy 95.818492 -232.207072) (xy 95.86465 -232.233721)
			(xy 95.906321 -232.266952) (xy 95.942573 -232.306023) (xy 95.972597 -232.35006) (xy 95.995723 -232.398081)
			(xy 96.011433 -232.449011) (xy 96.019376 -232.501715) (xy 96.019874 -232.528364) (xy 96.019376 -232.555013)
			(xy 96.247956 -232.555013) (xy 96.247956 -232.501715) (xy 96.255899 -232.449011) (xy 96.271609 -232.398081)
			(xy 96.294735 -232.35006) (xy 96.324759 -232.306023) (xy 96.361011 -232.266952) (xy 96.402682 -232.233721)
			(xy 96.44884 -232.207072) (xy 96.498454 -232.1876) (xy 96.550416 -232.17574) (xy 96.603566 -232.171757)
			(xy 96.656716 -232.17574) (xy 96.708678 -232.1876) (xy 96.758292 -232.207072) (xy 96.80445 -232.233721)
			(xy 96.846121 -232.266952) (xy 96.882373 -232.306023) (xy 96.912397 -232.35006) (xy 96.935523 -232.398081)
			(xy 96.951233 -232.449011) (xy 96.959176 -232.501715) (xy 96.959674 -232.528364) (xy 96.959176 -232.555013)
			(xy 97.187756 -232.555013) (xy 97.187756 -232.501715) (xy 97.195699 -232.449011) (xy 97.211409 -232.398081)
			(xy 97.234535 -232.35006) (xy 97.264559 -232.306023) (xy 97.300811 -232.266952) (xy 97.342482 -232.233721)
			(xy 97.38864 -232.207072) (xy 97.438254 -232.1876) (xy 97.490216 -232.17574) (xy 97.543366 -232.171757)
			(xy 97.596516 -232.17574) (xy 97.648478 -232.1876) (xy 97.698092 -232.207072) (xy 97.74425 -232.233721)
			(xy 97.785921 -232.266952) (xy 97.822173 -232.306023) (xy 97.852197 -232.35006) (xy 97.875323 -232.398081)
			(xy 97.891033 -232.449011) (xy 97.898976 -232.501715) (xy 97.899474 -232.528364) (xy 97.898976 -232.555013)
			(xy 98.127302 -232.555013) (xy 98.127302 -232.501715) (xy 98.135245 -232.449011) (xy 98.150955 -232.398081)
			(xy 98.174081 -232.35006) (xy 98.204105 -232.306023) (xy 98.240357 -232.266952) (xy 98.282028 -232.233721)
			(xy 98.328186 -232.207072) (xy 98.3778 -232.1876) (xy 98.429762 -232.17574) (xy 98.482912 -232.171757)
			(xy 98.536062 -232.17574) (xy 98.588024 -232.1876) (xy 98.637638 -232.207072) (xy 98.683796 -232.233721)
			(xy 98.725467 -232.266952) (xy 98.761719 -232.306023) (xy 98.791743 -232.35006) (xy 98.814869 -232.398081)
			(xy 98.830579 -232.449011) (xy 98.838522 -232.501715) (xy 98.83902 -232.528364) (xy 98.838522 -232.555013)
			(xy 99.067356 -232.555013) (xy 99.067356 -232.501715) (xy 99.075299 -232.449011) (xy 99.091009 -232.398081)
			(xy 99.114135 -232.35006) (xy 99.144159 -232.306023) (xy 99.180411 -232.266952) (xy 99.222082 -232.233721)
			(xy 99.26824 -232.207072) (xy 99.317854 -232.1876) (xy 99.369816 -232.17574) (xy 99.422966 -232.171757)
			(xy 99.476116 -232.17574) (xy 99.528078 -232.1876) (xy 99.577692 -232.207072) (xy 99.62385 -232.233721)
			(xy 99.665521 -232.266952) (xy 99.701773 -232.306023) (xy 99.731797 -232.35006) (xy 99.754923 -232.398081)
			(xy 99.770633 -232.449011) (xy 99.778576 -232.501715) (xy 99.779074 -232.528364) (xy 99.778576 -232.555013)
			(xy 100.007156 -232.555013) (xy 100.007156 -232.501715) (xy 100.015099 -232.449011) (xy 100.030809 -232.398081)
			(xy 100.053935 -232.35006) (xy 100.083959 -232.306023) (xy 100.120211 -232.266952) (xy 100.161882 -232.233721)
			(xy 100.20804 -232.207072) (xy 100.257654 -232.1876) (xy 100.309616 -232.17574) (xy 100.362766 -232.171757)
			(xy 100.415916 -232.17574) (xy 100.467878 -232.1876) (xy 100.517492 -232.207072) (xy 100.56365 -232.233721)
			(xy 100.605321 -232.266952) (xy 100.641573 -232.306023) (xy 100.671597 -232.35006) (xy 100.694723 -232.398081)
			(xy 100.710433 -232.449011) (xy 100.718376 -232.501715) (xy 100.718874 -232.528364) (xy 100.718376 -232.555013)
			(xy 101.886756 -232.555013) (xy 101.886756 -232.501715) (xy 101.894699 -232.449011) (xy 101.910409 -232.398081)
			(xy 101.933535 -232.35006) (xy 101.963559 -232.306023) (xy 101.999811 -232.266952) (xy 102.041482 -232.233721)
			(xy 102.08764 -232.207072) (xy 102.137254 -232.1876) (xy 102.189216 -232.17574) (xy 102.242366 -232.171757)
			(xy 102.295516 -232.17574) (xy 102.347478 -232.1876) (xy 102.397092 -232.207072) (xy 102.44325 -232.233721)
			(xy 102.484921 -232.266952) (xy 102.521173 -232.306023) (xy 102.551197 -232.35006) (xy 102.574323 -232.398081)
			(xy 102.590033 -232.449011) (xy 102.597976 -232.501715) (xy 102.598474 -232.528364) (xy 102.597976 -232.555013)
			(xy 102.826556 -232.555013) (xy 102.826556 -232.501715) (xy 102.834499 -232.449011) (xy 102.850209 -232.398081)
			(xy 102.873335 -232.35006) (xy 102.903359 -232.306023) (xy 102.939611 -232.266952) (xy 102.981282 -232.233721)
			(xy 103.02744 -232.207072) (xy 103.077054 -232.1876) (xy 103.129016 -232.17574) (xy 103.182166 -232.171757)
			(xy 103.235316 -232.17574) (xy 103.287278 -232.1876) (xy 103.336892 -232.207072) (xy 103.38305 -232.233721)
			(xy 103.424721 -232.266952) (xy 103.460973 -232.306023) (xy 103.490997 -232.35006) (xy 103.514123 -232.398081)
			(xy 103.529833 -232.449011) (xy 103.537776 -232.501715) (xy 103.538274 -232.528364) (xy 103.537776 -232.555013)
			(xy 103.766356 -232.555013) (xy 103.766356 -232.501715) (xy 103.774299 -232.449011) (xy 103.790009 -232.398081)
			(xy 103.813135 -232.35006) (xy 103.843159 -232.306023) (xy 103.879411 -232.266952) (xy 103.921082 -232.233721)
			(xy 103.96724 -232.207072) (xy 104.016854 -232.1876) (xy 104.068816 -232.17574) (xy 104.121966 -232.171757)
			(xy 104.175116 -232.17574) (xy 104.227078 -232.1876) (xy 104.276692 -232.207072) (xy 104.32285 -232.233721)
			(xy 104.364521 -232.266952) (xy 104.400773 -232.306023) (xy 104.430797 -232.35006) (xy 104.453923 -232.398081)
			(xy 104.469633 -232.449011) (xy 104.477576 -232.501715) (xy 104.478074 -232.528364) (xy 104.477576 -232.555013)
			(xy 104.706156 -232.555013) (xy 104.706156 -232.501715) (xy 104.714099 -232.449011) (xy 104.729809 -232.398081)
			(xy 104.752935 -232.35006) (xy 104.782959 -232.306023) (xy 104.819211 -232.266952) (xy 104.860882 -232.233721)
			(xy 104.90704 -232.207072) (xy 104.956654 -232.1876) (xy 105.008616 -232.17574) (xy 105.061766 -232.171757)
			(xy 105.114916 -232.17574) (xy 105.166878 -232.1876) (xy 105.216492 -232.207072) (xy 105.26265 -232.233721)
			(xy 105.304321 -232.266952) (xy 105.340573 -232.306023) (xy 105.370597 -232.35006) (xy 105.393723 -232.398081)
			(xy 105.409433 -232.449011) (xy 105.417376 -232.501715) (xy 105.417874 -232.528364) (xy 105.417376 -232.555013)
			(xy 105.645956 -232.555013) (xy 105.645956 -232.501715) (xy 105.653899 -232.449011) (xy 105.669609 -232.398081)
			(xy 105.692735 -232.35006) (xy 105.722759 -232.306023) (xy 105.759011 -232.266952) (xy 105.800682 -232.233721)
			(xy 105.84684 -232.207072) (xy 105.896454 -232.1876) (xy 105.948416 -232.17574) (xy 106.001566 -232.171757)
			(xy 106.054716 -232.17574) (xy 106.106678 -232.1876) (xy 106.156292 -232.207072) (xy 106.20245 -232.233721)
			(xy 106.244121 -232.266952) (xy 106.280373 -232.306023) (xy 106.310397 -232.35006) (xy 106.333523 -232.398081)
			(xy 106.349233 -232.449011) (xy 106.357176 -232.501715) (xy 106.357674 -232.528364) (xy 106.357176 -232.555013)
			(xy 106.585756 -232.555013) (xy 106.585756 -232.501715) (xy 106.593699 -232.449011) (xy 106.609409 -232.398081)
			(xy 106.632535 -232.35006) (xy 106.662559 -232.306023) (xy 106.698811 -232.266952) (xy 106.740482 -232.233721)
			(xy 106.78664 -232.207072) (xy 106.836254 -232.1876) (xy 106.888216 -232.17574) (xy 106.941366 -232.171757)
			(xy 106.994516 -232.17574) (xy 107.046478 -232.1876) (xy 107.096092 -232.207072) (xy 107.14225 -232.233721)
			(xy 107.183921 -232.266952) (xy 107.220173 -232.306023) (xy 107.250197 -232.35006) (xy 107.273323 -232.398081)
			(xy 107.289033 -232.449011) (xy 107.296976 -232.501715) (xy 107.297474 -232.528364) (xy 107.296976 -232.555013)
			(xy 107.525556 -232.555013) (xy 107.525556 -232.501715) (xy 107.533499 -232.449011) (xy 107.549209 -232.398081)
			(xy 107.572335 -232.35006) (xy 107.602359 -232.306023) (xy 107.638611 -232.266952) (xy 107.680282 -232.233721)
			(xy 107.72644 -232.207072) (xy 107.776054 -232.1876) (xy 107.828016 -232.17574) (xy 107.881166 -232.171757)
			(xy 107.934316 -232.17574) (xy 107.986278 -232.1876) (xy 108.035892 -232.207072) (xy 108.08205 -232.233721)
			(xy 108.123721 -232.266952) (xy 108.159973 -232.306023) (xy 108.189997 -232.35006) (xy 108.213123 -232.398081)
			(xy 108.228833 -232.449011) (xy 108.236776 -232.501715) (xy 108.237274 -232.528364) (xy 108.236776 -232.555013)
			(xy 108.465356 -232.555013) (xy 108.465356 -232.501715) (xy 108.473299 -232.449011) (xy 108.489009 -232.398081)
			(xy 108.512135 -232.35006) (xy 108.542159 -232.306023) (xy 108.578411 -232.266952) (xy 108.620082 -232.233721)
			(xy 108.66624 -232.207072) (xy 108.715854 -232.1876) (xy 108.767816 -232.17574) (xy 108.820966 -232.171757)
			(xy 108.874116 -232.17574) (xy 108.926078 -232.1876) (xy 108.975692 -232.207072) (xy 109.02185 -232.233721)
			(xy 109.063521 -232.266952) (xy 109.099773 -232.306023) (xy 109.129797 -232.35006) (xy 109.152923 -232.398081)
			(xy 109.168633 -232.449011) (xy 109.176576 -232.501715) (xy 109.177074 -232.528364) (xy 109.176576 -232.555013)
			(xy 109.168633 -232.607717) (xy 109.152923 -232.658647) (xy 109.129797 -232.706668) (xy 109.099773 -232.750705)
			(xy 109.063521 -232.789776) (xy 109.02185 -232.823007) (xy 108.975692 -232.849656) (xy 108.926078 -232.869128)
			(xy 108.874116 -232.880988) (xy 108.820966 -232.884972) (xy 108.767816 -232.880988) (xy 108.715854 -232.869128)
			(xy 108.66624 -232.849656) (xy 108.620082 -232.823007) (xy 108.578411 -232.789776) (xy 108.542159 -232.750705)
			(xy 108.512135 -232.706668) (xy 108.489009 -232.658647) (xy 108.473299 -232.607717) (xy 108.465356 -232.555013)
			(xy 108.236776 -232.555013) (xy 108.228833 -232.607717) (xy 108.213123 -232.658647) (xy 108.189997 -232.706668)
			(xy 108.159973 -232.750705) (xy 108.123721 -232.789776) (xy 108.08205 -232.823007) (xy 108.035892 -232.849656)
			(xy 107.986278 -232.869128) (xy 107.934316 -232.880988) (xy 107.881166 -232.884972) (xy 107.828016 -232.880988)
			(xy 107.776054 -232.869128) (xy 107.72644 -232.849656) (xy 107.680282 -232.823007) (xy 107.638611 -232.789776)
			(xy 107.602359 -232.750705) (xy 107.572335 -232.706668) (xy 107.549209 -232.658647) (xy 107.533499 -232.607717)
			(xy 107.525556 -232.555013) (xy 107.296976 -232.555013) (xy 107.289033 -232.607717) (xy 107.273323 -232.658647)
			(xy 107.250197 -232.706668) (xy 107.220173 -232.750705) (xy 107.183921 -232.789776) (xy 107.14225 -232.823007)
			(xy 107.096092 -232.849656) (xy 107.046478 -232.869128) (xy 106.994516 -232.880988) (xy 106.941366 -232.884972)
			(xy 106.888216 -232.880988) (xy 106.836254 -232.869128) (xy 106.78664 -232.849656) (xy 106.740482 -232.823007)
			(xy 106.698811 -232.789776) (xy 106.662559 -232.750705) (xy 106.632535 -232.706668) (xy 106.609409 -232.658647)
			(xy 106.593699 -232.607717) (xy 106.585756 -232.555013) (xy 106.357176 -232.555013) (xy 106.349233 -232.607717)
			(xy 106.333523 -232.658647) (xy 106.310397 -232.706668) (xy 106.280373 -232.750705) (xy 106.244121 -232.789776)
			(xy 106.20245 -232.823007) (xy 106.156292 -232.849656) (xy 106.106678 -232.869128) (xy 106.054716 -232.880988)
			(xy 106.001566 -232.884972) (xy 105.948416 -232.880988) (xy 105.896454 -232.869128) (xy 105.84684 -232.849656)
			(xy 105.800682 -232.823007) (xy 105.759011 -232.789776) (xy 105.722759 -232.750705) (xy 105.692735 -232.706668)
			(xy 105.669609 -232.658647) (xy 105.653899 -232.607717) (xy 105.645956 -232.555013) (xy 105.417376 -232.555013)
			(xy 105.409433 -232.607717) (xy 105.393723 -232.658647) (xy 105.370597 -232.706668) (xy 105.340573 -232.750705)
			(xy 105.304321 -232.789776) (xy 105.26265 -232.823007) (xy 105.216492 -232.849656) (xy 105.166878 -232.869128)
			(xy 105.114916 -232.880988) (xy 105.061766 -232.884972) (xy 105.008616 -232.880988) (xy 104.956654 -232.869128)
			(xy 104.90704 -232.849656) (xy 104.860882 -232.823007) (xy 104.819211 -232.789776) (xy 104.782959 -232.750705)
			(xy 104.752935 -232.706668) (xy 104.729809 -232.658647) (xy 104.714099 -232.607717) (xy 104.706156 -232.555013)
			(xy 104.477576 -232.555013) (xy 104.469633 -232.607717) (xy 104.453923 -232.658647) (xy 104.430797 -232.706668)
			(xy 104.400773 -232.750705) (xy 104.364521 -232.789776) (xy 104.32285 -232.823007) (xy 104.276692 -232.849656)
			(xy 104.227078 -232.869128) (xy 104.175116 -232.880988) (xy 104.121966 -232.884972) (xy 104.068816 -232.880988)
			(xy 104.016854 -232.869128) (xy 103.96724 -232.849656) (xy 103.921082 -232.823007) (xy 103.879411 -232.789776)
			(xy 103.843159 -232.750705) (xy 103.813135 -232.706668) (xy 103.790009 -232.658647) (xy 103.774299 -232.607717)
			(xy 103.766356 -232.555013) (xy 103.537776 -232.555013) (xy 103.529833 -232.607717) (xy 103.514123 -232.658647)
			(xy 103.490997 -232.706668) (xy 103.460973 -232.750705) (xy 103.424721 -232.789776) (xy 103.38305 -232.823007)
			(xy 103.336892 -232.849656) (xy 103.287278 -232.869128) (xy 103.235316 -232.880988) (xy 103.182166 -232.884972)
			(xy 103.129016 -232.880988) (xy 103.077054 -232.869128) (xy 103.02744 -232.849656) (xy 102.981282 -232.823007)
			(xy 102.939611 -232.789776) (xy 102.903359 -232.750705) (xy 102.873335 -232.706668) (xy 102.850209 -232.658647)
			(xy 102.834499 -232.607717) (xy 102.826556 -232.555013) (xy 102.597976 -232.555013) (xy 102.590033 -232.607717)
			(xy 102.574323 -232.658647) (xy 102.551197 -232.706668) (xy 102.521173 -232.750705) (xy 102.484921 -232.789776)
			(xy 102.44325 -232.823007) (xy 102.397092 -232.849656) (xy 102.347478 -232.869128) (xy 102.295516 -232.880988)
			(xy 102.242366 -232.884972) (xy 102.189216 -232.880988) (xy 102.137254 -232.869128) (xy 102.08764 -232.849656)
			(xy 102.041482 -232.823007) (xy 101.999811 -232.789776) (xy 101.963559 -232.750705) (xy 101.933535 -232.706668)
			(xy 101.910409 -232.658647) (xy 101.894699 -232.607717) (xy 101.886756 -232.555013) (xy 100.718376 -232.555013)
			(xy 100.710433 -232.607717) (xy 100.694723 -232.658647) (xy 100.671597 -232.706668) (xy 100.641573 -232.750705)
			(xy 100.605321 -232.789776) (xy 100.56365 -232.823007) (xy 100.517492 -232.849656) (xy 100.467878 -232.869128)
			(xy 100.415916 -232.880988) (xy 100.362766 -232.884972) (xy 100.309616 -232.880988) (xy 100.257654 -232.869128)
			(xy 100.20804 -232.849656) (xy 100.161882 -232.823007) (xy 100.120211 -232.789776) (xy 100.083959 -232.750705)
			(xy 100.053935 -232.706668) (xy 100.030809 -232.658647) (xy 100.015099 -232.607717) (xy 100.007156 -232.555013)
			(xy 99.778576 -232.555013) (xy 99.770633 -232.607717) (xy 99.754923 -232.658647) (xy 99.731797 -232.706668)
			(xy 99.701773 -232.750705) (xy 99.665521 -232.789776) (xy 99.62385 -232.823007) (xy 99.577692 -232.849656)
			(xy 99.528078 -232.869128) (xy 99.476116 -232.880988) (xy 99.422966 -232.884972) (xy 99.369816 -232.880988)
			(xy 99.317854 -232.869128) (xy 99.26824 -232.849656) (xy 99.222082 -232.823007) (xy 99.180411 -232.789776)
			(xy 99.144159 -232.750705) (xy 99.114135 -232.706668) (xy 99.091009 -232.658647) (xy 99.075299 -232.607717)
			(xy 99.067356 -232.555013) (xy 98.838522 -232.555013) (xy 98.830579 -232.607717) (xy 98.814869 -232.658647)
			(xy 98.791743 -232.706668) (xy 98.761719 -232.750705) (xy 98.725467 -232.789776) (xy 98.683796 -232.823007)
			(xy 98.637638 -232.849656) (xy 98.588024 -232.869128) (xy 98.536062 -232.880988) (xy 98.482912 -232.884972)
			(xy 98.429762 -232.880988) (xy 98.3778 -232.869128) (xy 98.328186 -232.849656) (xy 98.282028 -232.823007)
			(xy 98.240357 -232.789776) (xy 98.204105 -232.750705) (xy 98.174081 -232.706668) (xy 98.150955 -232.658647)
			(xy 98.135245 -232.607717) (xy 98.127302 -232.555013) (xy 97.898976 -232.555013) (xy 97.891033 -232.607717)
			(xy 97.875323 -232.658647) (xy 97.852197 -232.706668) (xy 97.822173 -232.750705) (xy 97.785921 -232.789776)
			(xy 97.74425 -232.823007) (xy 97.698092 -232.849656) (xy 97.648478 -232.869128) (xy 97.596516 -232.880988)
			(xy 97.543366 -232.884972) (xy 97.490216 -232.880988) (xy 97.438254 -232.869128) (xy 97.38864 -232.849656)
			(xy 97.342482 -232.823007) (xy 97.300811 -232.789776) (xy 97.264559 -232.750705) (xy 97.234535 -232.706668)
			(xy 97.211409 -232.658647) (xy 97.195699 -232.607717) (xy 97.187756 -232.555013) (xy 96.959176 -232.555013)
			(xy 96.951233 -232.607717) (xy 96.935523 -232.658647) (xy 96.912397 -232.706668) (xy 96.882373 -232.750705)
			(xy 96.846121 -232.789776) (xy 96.80445 -232.823007) (xy 96.758292 -232.849656) (xy 96.708678 -232.869128)
			(xy 96.656716 -232.880988) (xy 96.603566 -232.884972) (xy 96.550416 -232.880988) (xy 96.498454 -232.869128)
			(xy 96.44884 -232.849656) (xy 96.402682 -232.823007) (xy 96.361011 -232.789776) (xy 96.324759 -232.750705)
			(xy 96.294735 -232.706668) (xy 96.271609 -232.658647) (xy 96.255899 -232.607717) (xy 96.247956 -232.555013)
			(xy 96.019376 -232.555013) (xy 96.011433 -232.607717) (xy 95.995723 -232.658647) (xy 95.972597 -232.706668)
			(xy 95.942573 -232.750705) (xy 95.906321 -232.789776) (xy 95.86465 -232.823007) (xy 95.818492 -232.849656)
			(xy 95.768878 -232.869128) (xy 95.716916 -232.880988) (xy 95.663766 -232.884972) (xy 95.610616 -232.880988)
			(xy 95.558654 -232.869128) (xy 95.50904 -232.849656) (xy 95.462882 -232.823007) (xy 95.421211 -232.789776)
			(xy 95.384959 -232.750705) (xy 95.354935 -232.706668) (xy 95.331809 -232.658647) (xy 95.316099 -232.607717)
			(xy 95.308156 -232.555013) (xy 95.079576 -232.555013) (xy 95.071633 -232.607717) (xy 95.055923 -232.658647)
			(xy 95.032797 -232.706668) (xy 95.002773 -232.750705) (xy 94.966521 -232.789776) (xy 94.92485 -232.823007)
			(xy 94.878692 -232.849656) (xy 94.829078 -232.869128) (xy 94.777116 -232.880988) (xy 94.723966 -232.884972)
			(xy 94.670816 -232.880988) (xy 94.618854 -232.869128) (xy 94.56924 -232.849656) (xy 94.523082 -232.823007)
			(xy 94.481411 -232.789776) (xy 94.445159 -232.750705) (xy 94.415135 -232.706668) (xy 94.392009 -232.658647)
			(xy 94.376299 -232.607717) (xy 94.368356 -232.555013) (xy 94.139776 -232.555013) (xy 94.131833 -232.607717)
			(xy 94.116123 -232.658647) (xy 94.092997 -232.706668) (xy 94.062973 -232.750705) (xy 94.026721 -232.789776)
			(xy 93.98505 -232.823007) (xy 93.938892 -232.849656) (xy 93.889278 -232.869128) (xy 93.837316 -232.880988)
			(xy 93.784166 -232.884972) (xy 93.731016 -232.880988) (xy 93.679054 -232.869128) (xy 93.62944 -232.849656)
			(xy 93.583282 -232.823007) (xy 93.541611 -232.789776) (xy 93.505359 -232.750705) (xy 93.475335 -232.706668)
			(xy 93.452209 -232.658647) (xy 93.436499 -232.607717) (xy 93.428556 -232.555013) (xy 93.199976 -232.555013)
			(xy 93.192033 -232.607717) (xy 93.176323 -232.658647) (xy 93.153197 -232.706668) (xy 93.123173 -232.750705)
			(xy 93.086921 -232.789776) (xy 93.04525 -232.823007) (xy 92.999092 -232.849656) (xy 92.949478 -232.869128)
			(xy 92.897516 -232.880988) (xy 92.844366 -232.884972) (xy 92.791216 -232.880988) (xy 92.739254 -232.869128)
			(xy 92.68964 -232.849656) (xy 92.643482 -232.823007) (xy 92.601811 -232.789776) (xy 92.565559 -232.750705)
			(xy 92.535535 -232.706668) (xy 92.512409 -232.658647) (xy 92.496699 -232.607717) (xy 92.488756 -232.555013)
			(xy 92.259922 -232.555013) (xy 92.251979 -232.607717) (xy 92.236269 -232.658647) (xy 92.213143 -232.706668)
			(xy 92.183119 -232.750705) (xy 92.146867 -232.789776) (xy 92.105196 -232.823007) (xy 92.059038 -232.849656)
			(xy 92.009424 -232.869128) (xy 91.957462 -232.880988) (xy 91.904312 -232.884972) (xy 91.851162 -232.880988)
			(xy 91.7992 -232.869128) (xy 91.749586 -232.849656) (xy 91.703428 -232.823007) (xy 91.661757 -232.789776)
			(xy 91.625505 -232.750705) (xy 91.595481 -232.706668) (xy 91.572355 -232.658647) (xy 91.556645 -232.607717)
			(xy 91.548702 -232.555013) (xy 91.320376 -232.555013) (xy 91.312433 -232.607717) (xy 91.296723 -232.658647)
			(xy 91.273597 -232.706668) (xy 91.243573 -232.750705) (xy 91.207321 -232.789776) (xy 91.16565 -232.823007)
			(xy 91.119492 -232.849656) (xy 91.069878 -232.869128) (xy 91.017916 -232.880988) (xy 90.964766 -232.884972)
			(xy 90.911616 -232.880988) (xy 90.859654 -232.869128) (xy 90.81004 -232.849656) (xy 90.763882 -232.823007)
			(xy 90.722211 -232.789776) (xy 90.685959 -232.750705) (xy 90.655935 -232.706668) (xy 90.632809 -232.658647)
			(xy 90.617099 -232.607717) (xy 90.609156 -232.555013) (xy 90.380576 -232.555013) (xy 90.372633 -232.607717)
			(xy 90.356923 -232.658647) (xy 90.333797 -232.706668) (xy 90.303773 -232.750705) (xy 90.267521 -232.789776)
			(xy 90.22585 -232.823007) (xy 90.179692 -232.849656) (xy 90.130078 -232.869128) (xy 90.078116 -232.880988)
			(xy 90.024966 -232.884972) (xy 89.971816 -232.880988) (xy 89.919854 -232.869128) (xy 89.87024 -232.849656)
			(xy 89.824082 -232.823007) (xy 89.782411 -232.789776) (xy 89.746159 -232.750705) (xy 89.716135 -232.706668)
			(xy 89.693009 -232.658647) (xy 89.677299 -232.607717) (xy 89.669356 -232.555013) (xy 89.439874 -232.555013)
			(xy 89.437884 -232.581562) (xy 89.42602 -232.633536) (xy 89.406543 -232.683161) (xy 89.379886 -232.729329)
			(xy 89.346645 -232.771008) (xy 89.307564 -232.807266) (xy 89.263514 -232.837295) (xy 89.215481 -232.860422)
			(xy 89.164538 -232.876132) (xy 89.111821 -232.884073) (xy 89.085166 -232.884472) (xy 89.074793 -232.884426)
			(xy 89.054079 -232.883284) (xy 89.043764 -232.882186) (xy 89.029507 -232.881025) (xy 89.001306 -232.885741)
			(xy 88.975514 -232.898085) (xy 88.954152 -232.91709) (xy 88.938889 -232.941268) (xy 88.930922 -232.968728)
			(xy 88.93048 -232.983024) (xy 88.93048 -233.176572) (xy 88.93556 -233.186986) (xy 88.94679 -233.211299)
			(xy 88.962641 -233.262454) (xy 88.970657 -233.315405) (xy 88.97066 -233.368829) (xy 89.199202 -233.368829)
			(xy 89.199202 -233.315531) (xy 89.207145 -233.262827) (xy 89.222855 -233.211897) (xy 89.245981 -233.163876)
			(xy 89.276005 -233.119839) (xy 89.312257 -233.080768) (xy 89.353928 -233.047537) (xy 89.400086 -233.020888)
			(xy 89.4497 -233.001416) (xy 89.501662 -232.989556) (xy 89.554812 -232.985573) (xy 89.607962 -232.989556)
			(xy 89.659924 -233.001416) (xy 89.709538 -233.020888) (xy 89.755696 -233.047537) (xy 89.797367 -233.080768)
			(xy 89.833619 -233.119839) (xy 89.863643 -233.163876) (xy 89.886769 -233.211897) (xy 89.902479 -233.262827)
			(xy 89.910422 -233.315531) (xy 89.91092 -233.34218) (xy 89.910422 -233.368829) (xy 90.139002 -233.368829)
			(xy 90.139002 -233.315531) (xy 90.146945 -233.262827) (xy 90.162655 -233.211897) (xy 90.185781 -233.163876)
			(xy 90.215805 -233.119839) (xy 90.252057 -233.080768) (xy 90.293728 -233.047537) (xy 90.339886 -233.020888)
			(xy 90.3895 -233.001416) (xy 90.441462 -232.989556) (xy 90.494612 -232.985573) (xy 90.547762 -232.989556)
			(xy 90.599724 -233.001416) (xy 90.649338 -233.020888) (xy 90.695496 -233.047537) (xy 90.737167 -233.080768)
			(xy 90.773419 -233.119839) (xy 90.803443 -233.163876) (xy 90.826569 -233.211897) (xy 90.842279 -233.262827)
			(xy 90.850222 -233.315531) (xy 90.85072 -233.34218) (xy 90.850222 -233.368829) (xy 91.079056 -233.368829)
			(xy 91.079056 -233.315531) (xy 91.086999 -233.262827) (xy 91.102709 -233.211897) (xy 91.125835 -233.163876)
			(xy 91.155859 -233.119839) (xy 91.192111 -233.080768) (xy 91.233782 -233.047537) (xy 91.27994 -233.020888)
			(xy 91.329554 -233.001416) (xy 91.381516 -232.989556) (xy 91.434666 -232.985573) (xy 91.487816 -232.989556)
			(xy 91.539778 -233.001416) (xy 91.589392 -233.020888) (xy 91.63555 -233.047537) (xy 91.677221 -233.080768)
			(xy 91.713473 -233.119839) (xy 91.743497 -233.163876) (xy 91.766623 -233.211897) (xy 91.782333 -233.262827)
			(xy 91.790276 -233.315531) (xy 91.790774 -233.34218) (xy 91.790276 -233.368829) (xy 92.018602 -233.368829)
			(xy 92.018602 -233.315531) (xy 92.026545 -233.262827) (xy 92.042255 -233.211897) (xy 92.065381 -233.163876)
			(xy 92.095405 -233.119839) (xy 92.131657 -233.080768) (xy 92.173328 -233.047537) (xy 92.219486 -233.020888)
			(xy 92.2691 -233.001416) (xy 92.321062 -232.989556) (xy 92.374212 -232.985573) (xy 92.427362 -232.989556)
			(xy 92.479324 -233.001416) (xy 92.528938 -233.020888) (xy 92.575096 -233.047537) (xy 92.616767 -233.080768)
			(xy 92.653019 -233.119839) (xy 92.683043 -233.163876) (xy 92.706169 -233.211897) (xy 92.721879 -233.262827)
			(xy 92.729822 -233.315531) (xy 92.73032 -233.34218) (xy 92.729822 -233.368829) (xy 92.958402 -233.368829)
			(xy 92.958402 -233.315531) (xy 92.966345 -233.262827) (xy 92.982055 -233.211897) (xy 93.005181 -233.163876)
			(xy 93.035205 -233.119839) (xy 93.071457 -233.080768) (xy 93.113128 -233.047537) (xy 93.159286 -233.020888)
			(xy 93.2089 -233.001416) (xy 93.260862 -232.989556) (xy 93.314012 -232.985573) (xy 93.367162 -232.989556)
			(xy 93.419124 -233.001416) (xy 93.468738 -233.020888) (xy 93.514896 -233.047537) (xy 93.556567 -233.080768)
			(xy 93.592819 -233.119839) (xy 93.622843 -233.163876) (xy 93.645969 -233.211897) (xy 93.661679 -233.262827)
			(xy 93.669622 -233.315531) (xy 93.67012 -233.34218) (xy 93.669622 -233.368829) (xy 93.898202 -233.368829)
			(xy 93.898202 -233.315531) (xy 93.906145 -233.262827) (xy 93.921855 -233.211897) (xy 93.944981 -233.163876)
			(xy 93.975005 -233.119839) (xy 94.011257 -233.080768) (xy 94.052928 -233.047537) (xy 94.099086 -233.020888)
			(xy 94.1487 -233.001416) (xy 94.200662 -232.989556) (xy 94.253812 -232.985573) (xy 94.306962 -232.989556)
			(xy 94.358924 -233.001416) (xy 94.408538 -233.020888) (xy 94.454696 -233.047537) (xy 94.496367 -233.080768)
			(xy 94.532619 -233.119839) (xy 94.562643 -233.163876) (xy 94.585769 -233.211897) (xy 94.601479 -233.262827)
			(xy 94.609422 -233.315531) (xy 94.60992 -233.34218) (xy 94.609422 -233.368829) (xy 94.838002 -233.368829)
			(xy 94.838002 -233.315531) (xy 94.845945 -233.262827) (xy 94.861655 -233.211897) (xy 94.884781 -233.163876)
			(xy 94.914805 -233.119839) (xy 94.951057 -233.080768) (xy 94.992728 -233.047537) (xy 95.038886 -233.020888)
			(xy 95.0885 -233.001416) (xy 95.140462 -232.989556) (xy 95.193612 -232.985573) (xy 95.246762 -232.989556)
			(xy 95.298724 -233.001416) (xy 95.348338 -233.020888) (xy 95.394496 -233.047537) (xy 95.436167 -233.080768)
			(xy 95.472419 -233.119839) (xy 95.502443 -233.163876) (xy 95.525569 -233.211897) (xy 95.541279 -233.262827)
			(xy 95.549222 -233.315531) (xy 95.54972 -233.34218) (xy 95.549222 -233.368829) (xy 95.777802 -233.368829)
			(xy 95.777802 -233.315531) (xy 95.785745 -233.262827) (xy 95.801455 -233.211897) (xy 95.824581 -233.163876)
			(xy 95.854605 -233.119839) (xy 95.890857 -233.080768) (xy 95.932528 -233.047537) (xy 95.978686 -233.020888)
			(xy 96.0283 -233.001416) (xy 96.080262 -232.989556) (xy 96.133412 -232.985573) (xy 96.186562 -232.989556)
			(xy 96.238524 -233.001416) (xy 96.288138 -233.020888) (xy 96.334296 -233.047537) (xy 96.375967 -233.080768)
			(xy 96.412219 -233.119839) (xy 96.442243 -233.163876) (xy 96.465369 -233.211897) (xy 96.481079 -233.262827)
			(xy 96.489022 -233.315531) (xy 96.48952 -233.34218) (xy 96.489022 -233.368829) (xy 96.717602 -233.368829)
			(xy 96.717602 -233.315531) (xy 96.725545 -233.262827) (xy 96.741255 -233.211897) (xy 96.764381 -233.163876)
			(xy 96.794405 -233.119839) (xy 96.830657 -233.080768) (xy 96.872328 -233.047537) (xy 96.918486 -233.020888)
			(xy 96.9681 -233.001416) (xy 97.020062 -232.989556) (xy 97.073212 -232.985573) (xy 97.126362 -232.989556)
			(xy 97.178324 -233.001416) (xy 97.227938 -233.020888) (xy 97.274096 -233.047537) (xy 97.315767 -233.080768)
			(xy 97.352019 -233.119839) (xy 97.382043 -233.163876) (xy 97.405169 -233.211897) (xy 97.420879 -233.262827)
			(xy 97.428822 -233.315531) (xy 97.42932 -233.34218) (xy 97.428822 -233.368829) (xy 97.657656 -233.368829)
			(xy 97.657656 -233.315531) (xy 97.665599 -233.262827) (xy 97.681309 -233.211897) (xy 97.704435 -233.163876)
			(xy 97.734459 -233.119839) (xy 97.770711 -233.080768) (xy 97.812382 -233.047537) (xy 97.85854 -233.020888)
			(xy 97.908154 -233.001416) (xy 97.960116 -232.989556) (xy 98.013266 -232.985573) (xy 98.066416 -232.989556)
			(xy 98.118378 -233.001416) (xy 98.167992 -233.020888) (xy 98.21415 -233.047537) (xy 98.255821 -233.080768)
			(xy 98.292073 -233.119839) (xy 98.322097 -233.163876) (xy 98.345223 -233.211897) (xy 98.360933 -233.262827)
			(xy 98.368876 -233.315531) (xy 98.369374 -233.34218) (xy 98.368876 -233.368829) (xy 98.597202 -233.368829)
			(xy 98.597202 -233.315531) (xy 98.605145 -233.262827) (xy 98.620855 -233.211897) (xy 98.643981 -233.163876)
			(xy 98.674005 -233.119839) (xy 98.710257 -233.080768) (xy 98.751928 -233.047537) (xy 98.798086 -233.020888)
			(xy 98.8477 -233.001416) (xy 98.899662 -232.989556) (xy 98.952812 -232.985573) (xy 99.005962 -232.989556)
			(xy 99.057924 -233.001416) (xy 99.107538 -233.020888) (xy 99.153696 -233.047537) (xy 99.195367 -233.080768)
			(xy 99.231619 -233.119839) (xy 99.261643 -233.163876) (xy 99.284769 -233.211897) (xy 99.300479 -233.262827)
			(xy 99.308422 -233.315531) (xy 99.30892 -233.34218) (xy 99.308422 -233.368829) (xy 99.537002 -233.368829)
			(xy 99.537002 -233.315531) (xy 99.544945 -233.262827) (xy 99.560655 -233.211897) (xy 99.583781 -233.163876)
			(xy 99.613805 -233.119839) (xy 99.650057 -233.080768) (xy 99.691728 -233.047537) (xy 99.737886 -233.020888)
			(xy 99.7875 -233.001416) (xy 99.839462 -232.989556) (xy 99.892612 -232.985573) (xy 99.945762 -232.989556)
			(xy 99.997724 -233.001416) (xy 100.047338 -233.020888) (xy 100.093496 -233.047537) (xy 100.135167 -233.080768)
			(xy 100.171419 -233.119839) (xy 100.201443 -233.163876) (xy 100.224569 -233.211897) (xy 100.240279 -233.262827)
			(xy 100.248222 -233.315531) (xy 100.24872 -233.34218) (xy 100.248222 -233.368829) (xy 100.476802 -233.368829)
			(xy 100.476802 -233.315531) (xy 100.484745 -233.262827) (xy 100.500455 -233.211897) (xy 100.523581 -233.163876)
			(xy 100.553605 -233.119839) (xy 100.589857 -233.080768) (xy 100.631528 -233.047537) (xy 100.677686 -233.020888)
			(xy 100.7273 -233.001416) (xy 100.779262 -232.989556) (xy 100.832412 -232.985573) (xy 100.885562 -232.989556)
			(xy 100.937524 -233.001416) (xy 100.987138 -233.020888) (xy 101.033296 -233.047537) (xy 101.074967 -233.080768)
			(xy 101.111219 -233.119839) (xy 101.141243 -233.163876) (xy 101.164369 -233.211897) (xy 101.180079 -233.262827)
			(xy 101.188022 -233.315531) (xy 101.18852 -233.34218) (xy 101.188022 -233.368829) (xy 102.356402 -233.368829)
			(xy 102.356402 -233.315531) (xy 102.364345 -233.262827) (xy 102.380055 -233.211897) (xy 102.403181 -233.163876)
			(xy 102.433205 -233.119839) (xy 102.469457 -233.080768) (xy 102.511128 -233.047537) (xy 102.557286 -233.020888)
			(xy 102.6069 -233.001416) (xy 102.658862 -232.989556) (xy 102.712012 -232.985573) (xy 102.765162 -232.989556)
			(xy 102.817124 -233.001416) (xy 102.866738 -233.020888) (xy 102.912896 -233.047537) (xy 102.954567 -233.080768)
			(xy 102.990819 -233.119839) (xy 103.020843 -233.163876) (xy 103.043969 -233.211897) (xy 103.059679 -233.262827)
			(xy 103.067622 -233.315531) (xy 103.06812 -233.34218) (xy 103.067622 -233.368829) (xy 103.059679 -233.421533)
			(xy 103.043969 -233.472463) (xy 103.020843 -233.520484) (xy 102.990819 -233.564521) (xy 102.954567 -233.603592)
			(xy 102.912896 -233.636823) (xy 102.866738 -233.663472) (xy 102.817124 -233.682944) (xy 102.765162 -233.694804)
			(xy 102.712012 -233.698788) (xy 102.658862 -233.694804) (xy 102.6069 -233.682944) (xy 102.557286 -233.663472)
			(xy 102.511128 -233.636823) (xy 102.469457 -233.603592) (xy 102.433205 -233.564521) (xy 102.403181 -233.520484)
			(xy 102.380055 -233.472463) (xy 102.364345 -233.421533) (xy 102.356402 -233.368829) (xy 101.188022 -233.368829)
			(xy 101.180079 -233.421533) (xy 101.164369 -233.472463) (xy 101.141243 -233.520484) (xy 101.111219 -233.564521)
			(xy 101.074967 -233.603592) (xy 101.033296 -233.636823) (xy 100.987138 -233.663472) (xy 100.937524 -233.682944)
			(xy 100.885562 -233.694804) (xy 100.832412 -233.698788) (xy 100.779262 -233.694804) (xy 100.7273 -233.682944)
			(xy 100.677686 -233.663472) (xy 100.631528 -233.636823) (xy 100.589857 -233.603592) (xy 100.553605 -233.564521)
			(xy 100.523581 -233.520484) (xy 100.500455 -233.472463) (xy 100.484745 -233.421533) (xy 100.476802 -233.368829)
			(xy 100.248222 -233.368829) (xy 100.240279 -233.421533) (xy 100.224569 -233.472463) (xy 100.201443 -233.520484)
			(xy 100.171419 -233.564521) (xy 100.135167 -233.603592) (xy 100.093496 -233.636823) (xy 100.047338 -233.663472)
			(xy 99.997724 -233.682944) (xy 99.945762 -233.694804) (xy 99.892612 -233.698788) (xy 99.839462 -233.694804)
			(xy 99.7875 -233.682944) (xy 99.737886 -233.663472) (xy 99.691728 -233.636823) (xy 99.650057 -233.603592)
			(xy 99.613805 -233.564521) (xy 99.583781 -233.520484) (xy 99.560655 -233.472463) (xy 99.544945 -233.421533)
			(xy 99.537002 -233.368829) (xy 99.308422 -233.368829) (xy 99.300479 -233.421533) (xy 99.284769 -233.472463)
			(xy 99.261643 -233.520484) (xy 99.231619 -233.564521) (xy 99.195367 -233.603592) (xy 99.153696 -233.636823)
			(xy 99.107538 -233.663472) (xy 99.057924 -233.682944) (xy 99.005962 -233.694804) (xy 98.952812 -233.698788)
			(xy 98.899662 -233.694804) (xy 98.8477 -233.682944) (xy 98.798086 -233.663472) (xy 98.751928 -233.636823)
			(xy 98.710257 -233.603592) (xy 98.674005 -233.564521) (xy 98.643981 -233.520484) (xy 98.620855 -233.472463)
			(xy 98.605145 -233.421533) (xy 98.597202 -233.368829) (xy 98.368876 -233.368829) (xy 98.360933 -233.421533)
			(xy 98.345223 -233.472463) (xy 98.322097 -233.520484) (xy 98.292073 -233.564521) (xy 98.255821 -233.603592)
			(xy 98.21415 -233.636823) (xy 98.167992 -233.663472) (xy 98.118378 -233.682944) (xy 98.066416 -233.694804)
			(xy 98.013266 -233.698788) (xy 97.960116 -233.694804) (xy 97.908154 -233.682944) (xy 97.85854 -233.663472)
			(xy 97.812382 -233.636823) (xy 97.770711 -233.603592) (xy 97.734459 -233.564521) (xy 97.704435 -233.520484)
			(xy 97.681309 -233.472463) (xy 97.665599 -233.421533) (xy 97.657656 -233.368829) (xy 97.428822 -233.368829)
			(xy 97.420879 -233.421533) (xy 97.405169 -233.472463) (xy 97.382043 -233.520484) (xy 97.352019 -233.564521)
			(xy 97.315767 -233.603592) (xy 97.274096 -233.636823) (xy 97.227938 -233.663472) (xy 97.178324 -233.682944)
			(xy 97.126362 -233.694804) (xy 97.073212 -233.698788) (xy 97.020062 -233.694804) (xy 96.9681 -233.682944)
			(xy 96.918486 -233.663472) (xy 96.872328 -233.636823) (xy 96.830657 -233.603592) (xy 96.794405 -233.564521)
			(xy 96.764381 -233.520484) (xy 96.741255 -233.472463) (xy 96.725545 -233.421533) (xy 96.717602 -233.368829)
			(xy 96.489022 -233.368829) (xy 96.481079 -233.421533) (xy 96.465369 -233.472463) (xy 96.442243 -233.520484)
			(xy 96.412219 -233.564521) (xy 96.375967 -233.603592) (xy 96.334296 -233.636823) (xy 96.288138 -233.663472)
			(xy 96.238524 -233.682944) (xy 96.186562 -233.694804) (xy 96.133412 -233.698788) (xy 96.080262 -233.694804)
			(xy 96.0283 -233.682944) (xy 95.978686 -233.663472) (xy 95.932528 -233.636823) (xy 95.890857 -233.603592)
			(xy 95.854605 -233.564521) (xy 95.824581 -233.520484) (xy 95.801455 -233.472463) (xy 95.785745 -233.421533)
			(xy 95.777802 -233.368829) (xy 95.549222 -233.368829) (xy 95.541279 -233.421533) (xy 95.525569 -233.472463)
			(xy 95.502443 -233.520484) (xy 95.472419 -233.564521) (xy 95.436167 -233.603592) (xy 95.394496 -233.636823)
			(xy 95.348338 -233.663472) (xy 95.298724 -233.682944) (xy 95.246762 -233.694804) (xy 95.193612 -233.698788)
			(xy 95.140462 -233.694804) (xy 95.0885 -233.682944) (xy 95.038886 -233.663472) (xy 94.992728 -233.636823)
			(xy 94.951057 -233.603592) (xy 94.914805 -233.564521) (xy 94.884781 -233.520484) (xy 94.861655 -233.472463)
			(xy 94.845945 -233.421533) (xy 94.838002 -233.368829) (xy 94.609422 -233.368829) (xy 94.601479 -233.421533)
			(xy 94.585769 -233.472463) (xy 94.562643 -233.520484) (xy 94.532619 -233.564521) (xy 94.496367 -233.603592)
			(xy 94.454696 -233.636823) (xy 94.408538 -233.663472) (xy 94.358924 -233.682944) (xy 94.306962 -233.694804)
			(xy 94.253812 -233.698788) (xy 94.200662 -233.694804) (xy 94.1487 -233.682944) (xy 94.099086 -233.663472)
			(xy 94.052928 -233.636823) (xy 94.011257 -233.603592) (xy 93.975005 -233.564521) (xy 93.944981 -233.520484)
			(xy 93.921855 -233.472463) (xy 93.906145 -233.421533) (xy 93.898202 -233.368829) (xy 93.669622 -233.368829)
			(xy 93.661679 -233.421533) (xy 93.645969 -233.472463) (xy 93.622843 -233.520484) (xy 93.592819 -233.564521)
			(xy 93.556567 -233.603592) (xy 93.514896 -233.636823) (xy 93.468738 -233.663472) (xy 93.419124 -233.682944)
			(xy 93.367162 -233.694804) (xy 93.314012 -233.698788) (xy 93.260862 -233.694804) (xy 93.2089 -233.682944)
			(xy 93.159286 -233.663472) (xy 93.113128 -233.636823) (xy 93.071457 -233.603592) (xy 93.035205 -233.564521)
			(xy 93.005181 -233.520484) (xy 92.982055 -233.472463) (xy 92.966345 -233.421533) (xy 92.958402 -233.368829)
			(xy 92.729822 -233.368829) (xy 92.721879 -233.421533) (xy 92.706169 -233.472463) (xy 92.683043 -233.520484)
			(xy 92.653019 -233.564521) (xy 92.616767 -233.603592) (xy 92.575096 -233.636823) (xy 92.528938 -233.663472)
			(xy 92.479324 -233.682944) (xy 92.427362 -233.694804) (xy 92.374212 -233.698788) (xy 92.321062 -233.694804)
			(xy 92.2691 -233.682944) (xy 92.219486 -233.663472) (xy 92.173328 -233.636823) (xy 92.131657 -233.603592)
			(xy 92.095405 -233.564521) (xy 92.065381 -233.520484) (xy 92.042255 -233.472463) (xy 92.026545 -233.421533)
			(xy 92.018602 -233.368829) (xy 91.790276 -233.368829) (xy 91.782333 -233.421533) (xy 91.766623 -233.472463)
			(xy 91.743497 -233.520484) (xy 91.713473 -233.564521) (xy 91.677221 -233.603592) (xy 91.63555 -233.636823)
			(xy 91.589392 -233.663472) (xy 91.539778 -233.682944) (xy 91.487816 -233.694804) (xy 91.434666 -233.698788)
			(xy 91.381516 -233.694804) (xy 91.329554 -233.682944) (xy 91.27994 -233.663472) (xy 91.233782 -233.636823)
			(xy 91.192111 -233.603592) (xy 91.155859 -233.564521) (xy 91.125835 -233.520484) (xy 91.102709 -233.472463)
			(xy 91.086999 -233.421533) (xy 91.079056 -233.368829) (xy 90.850222 -233.368829) (xy 90.842279 -233.421533)
			(xy 90.826569 -233.472463) (xy 90.803443 -233.520484) (xy 90.773419 -233.564521) (xy 90.737167 -233.603592)
			(xy 90.695496 -233.636823) (xy 90.649338 -233.663472) (xy 90.599724 -233.682944) (xy 90.547762 -233.694804)
			(xy 90.494612 -233.698788) (xy 90.441462 -233.694804) (xy 90.3895 -233.682944) (xy 90.339886 -233.663472)
			(xy 90.293728 -233.636823) (xy 90.252057 -233.603592) (xy 90.215805 -233.564521) (xy 90.185781 -233.520484)
			(xy 90.162655 -233.472463) (xy 90.146945 -233.421533) (xy 90.139002 -233.368829) (xy 89.910422 -233.368829)
			(xy 89.902479 -233.421533) (xy 89.886769 -233.472463) (xy 89.863643 -233.520484) (xy 89.833619 -233.564521)
			(xy 89.797367 -233.603592) (xy 89.755696 -233.636823) (xy 89.709538 -233.663472) (xy 89.659924 -233.682944)
			(xy 89.607962 -233.694804) (xy 89.554812 -233.698788) (xy 89.501662 -233.694804) (xy 89.4497 -233.682944)
			(xy 89.400086 -233.663472) (xy 89.353928 -233.636823) (xy 89.312257 -233.603592) (xy 89.276005 -233.564521)
			(xy 89.245981 -233.520484) (xy 89.222855 -233.472463) (xy 89.207145 -233.421533) (xy 89.199202 -233.368829)
			(xy 88.97066 -233.368829) (xy 88.97066 -233.368959) (xy 88.962649 -233.421911) (xy 88.946803 -233.473067)
			(xy 88.93556 -233.497374) (xy 88.93048 -233.507788) (xy 88.93048 -233.70159) (xy 88.930964 -233.715883)
			(xy 88.938898 -233.743345) (xy 88.954144 -233.767525) (xy 88.975505 -233.786521) (xy 89.001299 -233.79884)
			(xy 89.0295 -233.803513) (xy 89.043764 -233.802428) (xy 89.054078 -233.801324) (xy 89.074793 -233.80018)
			(xy 89.085166 -233.800142) (xy 89.111815 -233.800613) (xy 89.164519 -233.808552) (xy 89.21545 -233.824258)
			(xy 89.263471 -233.84738) (xy 89.30751 -233.877401) (xy 89.346582 -233.913651) (xy 89.379815 -233.955319)
			(xy 89.406465 -234.001476) (xy 89.425938 -234.051089) (xy 89.437799 -234.103051) (xy 89.441782 -234.1562)
			(xy 89.439781 -234.182899) (xy 89.669356 -234.182899) (xy 89.669356 -234.129601) (xy 89.677299 -234.076897)
			(xy 89.693009 -234.025967) (xy 89.716135 -233.977946) (xy 89.746159 -233.933909) (xy 89.782411 -233.894838)
			(xy 89.824082 -233.861607) (xy 89.87024 -233.834958) (xy 89.919854 -233.815486) (xy 89.971816 -233.803626)
			(xy 90.024966 -233.799643) (xy 90.078116 -233.803626) (xy 90.130078 -233.815486) (xy 90.179692 -233.834958)
			(xy 90.22585 -233.861607) (xy 90.267521 -233.894838) (xy 90.303773 -233.933909) (xy 90.333797 -233.977946)
			(xy 90.356923 -234.025967) (xy 90.372633 -234.076897) (xy 90.380576 -234.129601) (xy 90.381074 -234.15625)
			(xy 90.380576 -234.182899) (xy 90.609156 -234.182899) (xy 90.609156 -234.129601) (xy 90.617099 -234.076897)
			(xy 90.632809 -234.025967) (xy 90.655935 -233.977946) (xy 90.685959 -233.933909) (xy 90.722211 -233.894838)
			(xy 90.763882 -233.861607) (xy 90.81004 -233.834958) (xy 90.859654 -233.815486) (xy 90.911616 -233.803626)
			(xy 90.964766 -233.799643) (xy 91.017916 -233.803626) (xy 91.069878 -233.815486) (xy 91.119492 -233.834958)
			(xy 91.16565 -233.861607) (xy 91.207321 -233.894838) (xy 91.243573 -233.933909) (xy 91.273597 -233.977946)
			(xy 91.296723 -234.025967) (xy 91.312433 -234.076897) (xy 91.320376 -234.129601) (xy 91.320874 -234.15625)
			(xy 91.320376 -234.182899) (xy 91.548956 -234.182899) (xy 91.548956 -234.129601) (xy 91.556899 -234.076897)
			(xy 91.572609 -234.025967) (xy 91.595735 -233.977946) (xy 91.625759 -233.933909) (xy 91.662011 -233.894838)
			(xy 91.703682 -233.861607) (xy 91.74984 -233.834958) (xy 91.799454 -233.815486) (xy 91.851416 -233.803626)
			(xy 91.904566 -233.799643) (xy 91.957716 -233.803626) (xy 92.009678 -233.815486) (xy 92.059292 -233.834958)
			(xy 92.10545 -233.861607) (xy 92.147121 -233.894838) (xy 92.183373 -233.933909) (xy 92.213397 -233.977946)
			(xy 92.236523 -234.025967) (xy 92.252233 -234.076897) (xy 92.260176 -234.129601) (xy 92.260674 -234.15625)
			(xy 92.260176 -234.182899) (xy 92.488756 -234.182899) (xy 92.488756 -234.129601) (xy 92.496699 -234.076897)
			(xy 92.512409 -234.025967) (xy 92.535535 -233.977946) (xy 92.565559 -233.933909) (xy 92.601811 -233.894838)
			(xy 92.643482 -233.861607) (xy 92.68964 -233.834958) (xy 92.739254 -233.815486) (xy 92.791216 -233.803626)
			(xy 92.844366 -233.799643) (xy 92.897516 -233.803626) (xy 92.949478 -233.815486) (xy 92.999092 -233.834958)
			(xy 93.04525 -233.861607) (xy 93.086921 -233.894838) (xy 93.123173 -233.933909) (xy 93.153197 -233.977946)
			(xy 93.176323 -234.025967) (xy 93.192033 -234.076897) (xy 93.199976 -234.129601) (xy 93.200474 -234.15625)
			(xy 93.199976 -234.182899) (xy 93.428556 -234.182899) (xy 93.428556 -234.129601) (xy 93.436499 -234.076897)
			(xy 93.452209 -234.025967) (xy 93.475335 -233.977946) (xy 93.505359 -233.933909) (xy 93.541611 -233.894838)
			(xy 93.583282 -233.861607) (xy 93.62944 -233.834958) (xy 93.679054 -233.815486) (xy 93.731016 -233.803626)
			(xy 93.784166 -233.799643) (xy 93.837316 -233.803626) (xy 93.889278 -233.815486) (xy 93.938892 -233.834958)
			(xy 93.98505 -233.861607) (xy 94.026721 -233.894838) (xy 94.062973 -233.933909) (xy 94.092997 -233.977946)
			(xy 94.116123 -234.025967) (xy 94.131833 -234.076897) (xy 94.139776 -234.129601) (xy 94.140274 -234.15625)
			(xy 94.139776 -234.182899) (xy 94.368102 -234.182899) (xy 94.368102 -234.129601) (xy 94.376045 -234.076897)
			(xy 94.391755 -234.025967) (xy 94.414881 -233.977946) (xy 94.444905 -233.933909) (xy 94.481157 -233.894838)
			(xy 94.522828 -233.861607) (xy 94.568986 -233.834958) (xy 94.6186 -233.815486) (xy 94.670562 -233.803626)
			(xy 94.723712 -233.799643) (xy 94.776862 -233.803626) (xy 94.828824 -233.815486) (xy 94.878438 -233.834958)
			(xy 94.924596 -233.861607) (xy 94.966267 -233.894838) (xy 95.002519 -233.933909) (xy 95.032543 -233.977946)
			(xy 95.055669 -234.025967) (xy 95.071379 -234.076897) (xy 95.079322 -234.129601) (xy 95.07982 -234.15625)
			(xy 95.079322 -234.182899) (xy 95.308156 -234.182899) (xy 95.308156 -234.129601) (xy 95.316099 -234.076897)
			(xy 95.331809 -234.025967) (xy 95.354935 -233.977946) (xy 95.384959 -233.933909) (xy 95.421211 -233.894838)
			(xy 95.462882 -233.861607) (xy 95.50904 -233.834958) (xy 95.558654 -233.815486) (xy 95.610616 -233.803626)
			(xy 95.663766 -233.799643) (xy 95.716916 -233.803626) (xy 95.768878 -233.815486) (xy 95.818492 -233.834958)
			(xy 95.86465 -233.861607) (xy 95.906321 -233.894838) (xy 95.942573 -233.933909) (xy 95.972597 -233.977946)
			(xy 95.995723 -234.025967) (xy 96.011433 -234.076897) (xy 96.019376 -234.129601) (xy 96.019874 -234.15625)
			(xy 96.019376 -234.182899) (xy 96.247956 -234.182899) (xy 96.247956 -234.129601) (xy 96.255899 -234.076897)
			(xy 96.271609 -234.025967) (xy 96.294735 -233.977946) (xy 96.324759 -233.933909) (xy 96.361011 -233.894838)
			(xy 96.402682 -233.861607) (xy 96.44884 -233.834958) (xy 96.498454 -233.815486) (xy 96.550416 -233.803626)
			(xy 96.603566 -233.799643) (xy 96.656716 -233.803626) (xy 96.708678 -233.815486) (xy 96.758292 -233.834958)
			(xy 96.80445 -233.861607) (xy 96.846121 -233.894838) (xy 96.882373 -233.933909) (xy 96.912397 -233.977946)
			(xy 96.935523 -234.025967) (xy 96.951233 -234.076897) (xy 96.959176 -234.129601) (xy 96.959674 -234.15625)
			(xy 96.959176 -234.182899) (xy 97.187756 -234.182899) (xy 97.187756 -234.129601) (xy 97.195699 -234.076897)
			(xy 97.211409 -234.025967) (xy 97.234535 -233.977946) (xy 97.264559 -233.933909) (xy 97.300811 -233.894838)
			(xy 97.342482 -233.861607) (xy 97.38864 -233.834958) (xy 97.438254 -233.815486) (xy 97.490216 -233.803626)
			(xy 97.543366 -233.799643) (xy 97.596516 -233.803626) (xy 97.648478 -233.815486) (xy 97.698092 -233.834958)
			(xy 97.74425 -233.861607) (xy 97.785921 -233.894838) (xy 97.822173 -233.933909) (xy 97.852197 -233.977946)
			(xy 97.875323 -234.025967) (xy 97.891033 -234.076897) (xy 97.898976 -234.129601) (xy 97.899474 -234.15625)
			(xy 97.898976 -234.182899) (xy 98.127556 -234.182899) (xy 98.127556 -234.129601) (xy 98.135499 -234.076897)
			(xy 98.151209 -234.025967) (xy 98.174335 -233.977946) (xy 98.204359 -233.933909) (xy 98.240611 -233.894838)
			(xy 98.282282 -233.861607) (xy 98.32844 -233.834958) (xy 98.378054 -233.815486) (xy 98.430016 -233.803626)
			(xy 98.483166 -233.799643) (xy 98.536316 -233.803626) (xy 98.588278 -233.815486) (xy 98.637892 -233.834958)
			(xy 98.68405 -233.861607) (xy 98.725721 -233.894838) (xy 98.761973 -233.933909) (xy 98.791997 -233.977946)
			(xy 98.815123 -234.025967) (xy 98.830833 -234.076897) (xy 98.838776 -234.129601) (xy 98.839274 -234.15625)
			(xy 98.838776 -234.182899) (xy 99.067356 -234.182899) (xy 99.067356 -234.129601) (xy 99.075299 -234.076897)
			(xy 99.091009 -234.025967) (xy 99.114135 -233.977946) (xy 99.144159 -233.933909) (xy 99.180411 -233.894838)
			(xy 99.222082 -233.861607) (xy 99.26824 -233.834958) (xy 99.317854 -233.815486) (xy 99.369816 -233.803626)
			(xy 99.422966 -233.799643) (xy 99.476116 -233.803626) (xy 99.528078 -233.815486) (xy 99.577692 -233.834958)
			(xy 99.62385 -233.861607) (xy 99.665521 -233.894838) (xy 99.701773 -233.933909) (xy 99.731797 -233.977946)
			(xy 99.754923 -234.025967) (xy 99.770633 -234.076897) (xy 99.778576 -234.129601) (xy 99.779074 -234.15625)
			(xy 99.778576 -234.182899) (xy 100.007156 -234.182899) (xy 100.007156 -234.129601) (xy 100.015099 -234.076897)
			(xy 100.030809 -234.025967) (xy 100.053935 -233.977946) (xy 100.083959 -233.933909) (xy 100.120211 -233.894838)
			(xy 100.161882 -233.861607) (xy 100.20804 -233.834958) (xy 100.257654 -233.815486) (xy 100.309616 -233.803626)
			(xy 100.362766 -233.799643) (xy 100.415916 -233.803626) (xy 100.467878 -233.815486) (xy 100.517492 -233.834958)
			(xy 100.56365 -233.861607) (xy 100.605321 -233.894838) (xy 100.641573 -233.933909) (xy 100.671597 -233.977946)
			(xy 100.694723 -234.025967) (xy 100.710433 -234.076897) (xy 100.718376 -234.129601) (xy 100.718874 -234.15625)
			(xy 100.718376 -234.182899) (xy 100.946702 -234.182899) (xy 100.946702 -234.129601) (xy 100.954645 -234.076897)
			(xy 100.970355 -234.025967) (xy 100.993481 -233.977946) (xy 101.023505 -233.933909) (xy 101.059757 -233.894838)
			(xy 101.101428 -233.861607) (xy 101.147586 -233.834958) (xy 101.1972 -233.815486) (xy 101.249162 -233.803626)
			(xy 101.302312 -233.799643) (xy 101.355462 -233.803626) (xy 101.407424 -233.815486) (xy 101.457038 -233.834958)
			(xy 101.503196 -233.861607) (xy 101.544867 -233.894838) (xy 101.581119 -233.933909) (xy 101.611143 -233.977946)
			(xy 101.634269 -234.025967) (xy 101.649979 -234.076897) (xy 101.657922 -234.129601) (xy 101.65842 -234.15625)
			(xy 101.657922 -234.182899) (xy 101.886756 -234.182899) (xy 101.886756 -234.129601) (xy 101.894699 -234.076897)
			(xy 101.910409 -234.025967) (xy 101.933535 -233.977946) (xy 101.963559 -233.933909) (xy 101.999811 -233.894838)
			(xy 102.041482 -233.861607) (xy 102.08764 -233.834958) (xy 102.137254 -233.815486) (xy 102.189216 -233.803626)
			(xy 102.242366 -233.799643) (xy 102.295516 -233.803626) (xy 102.347478 -233.815486) (xy 102.397092 -233.834958)
			(xy 102.44325 -233.861607) (xy 102.484921 -233.894838) (xy 102.521173 -233.933909) (xy 102.551197 -233.977946)
			(xy 102.574323 -234.025967) (xy 102.590033 -234.076897) (xy 102.597976 -234.129601) (xy 102.598474 -234.15625)
			(xy 102.597976 -234.182899) (xy 102.590033 -234.235603) (xy 102.574323 -234.286533) (xy 102.551197 -234.334554)
			(xy 102.521173 -234.378591) (xy 102.484921 -234.417662) (xy 102.44325 -234.450893) (xy 102.397092 -234.477542)
			(xy 102.347478 -234.497014) (xy 102.295516 -234.508874) (xy 102.242366 -234.512858) (xy 102.189216 -234.508874)
			(xy 102.137254 -234.497014) (xy 102.08764 -234.477542) (xy 102.041482 -234.450893) (xy 101.999811 -234.417662)
			(xy 101.963559 -234.378591) (xy 101.933535 -234.334554) (xy 101.910409 -234.286533) (xy 101.894699 -234.235603)
			(xy 101.886756 -234.182899) (xy 101.657922 -234.182899) (xy 101.649979 -234.235603) (xy 101.634269 -234.286533)
			(xy 101.611143 -234.334554) (xy 101.581119 -234.378591) (xy 101.544867 -234.417662) (xy 101.503196 -234.450893)
			(xy 101.457038 -234.477542) (xy 101.407424 -234.497014) (xy 101.355462 -234.508874) (xy 101.302312 -234.512858)
			(xy 101.249162 -234.508874) (xy 101.1972 -234.497014) (xy 101.147586 -234.477542) (xy 101.101428 -234.450893)
			(xy 101.059757 -234.417662) (xy 101.023505 -234.378591) (xy 100.993481 -234.334554) (xy 100.970355 -234.286533)
			(xy 100.954645 -234.235603) (xy 100.946702 -234.182899) (xy 100.718376 -234.182899) (xy 100.710433 -234.235603)
			(xy 100.694723 -234.286533) (xy 100.671597 -234.334554) (xy 100.641573 -234.378591) (xy 100.605321 -234.417662)
			(xy 100.56365 -234.450893) (xy 100.517492 -234.477542) (xy 100.467878 -234.497014) (xy 100.415916 -234.508874)
			(xy 100.362766 -234.512858) (xy 100.309616 -234.508874) (xy 100.257654 -234.497014) (xy 100.20804 -234.477542)
			(xy 100.161882 -234.450893) (xy 100.120211 -234.417662) (xy 100.083959 -234.378591) (xy 100.053935 -234.334554)
			(xy 100.030809 -234.286533) (xy 100.015099 -234.235603) (xy 100.007156 -234.182899) (xy 99.778576 -234.182899)
			(xy 99.770633 -234.235603) (xy 99.754923 -234.286533) (xy 99.731797 -234.334554) (xy 99.701773 -234.378591)
			(xy 99.665521 -234.417662) (xy 99.62385 -234.450893) (xy 99.577692 -234.477542) (xy 99.528078 -234.497014)
			(xy 99.476116 -234.508874) (xy 99.422966 -234.512858) (xy 99.369816 -234.508874) (xy 99.317854 -234.497014)
			(xy 99.26824 -234.477542) (xy 99.222082 -234.450893) (xy 99.180411 -234.417662) (xy 99.144159 -234.378591)
			(xy 99.114135 -234.334554) (xy 99.091009 -234.286533) (xy 99.075299 -234.235603) (xy 99.067356 -234.182899)
			(xy 98.838776 -234.182899) (xy 98.830833 -234.235603) (xy 98.815123 -234.286533) (xy 98.791997 -234.334554)
			(xy 98.761973 -234.378591) (xy 98.725721 -234.417662) (xy 98.68405 -234.450893) (xy 98.637892 -234.477542)
			(xy 98.588278 -234.497014) (xy 98.536316 -234.508874) (xy 98.483166 -234.512858) (xy 98.430016 -234.508874)
			(xy 98.378054 -234.497014) (xy 98.32844 -234.477542) (xy 98.282282 -234.450893) (xy 98.240611 -234.417662)
			(xy 98.204359 -234.378591) (xy 98.174335 -234.334554) (xy 98.151209 -234.286533) (xy 98.135499 -234.235603)
			(xy 98.127556 -234.182899) (xy 97.898976 -234.182899) (xy 97.891033 -234.235603) (xy 97.875323 -234.286533)
			(xy 97.852197 -234.334554) (xy 97.822173 -234.378591) (xy 97.785921 -234.417662) (xy 97.74425 -234.450893)
			(xy 97.698092 -234.477542) (xy 97.648478 -234.497014) (xy 97.596516 -234.508874) (xy 97.543366 -234.512858)
			(xy 97.490216 -234.508874) (xy 97.438254 -234.497014) (xy 97.38864 -234.477542) (xy 97.342482 -234.450893)
			(xy 97.300811 -234.417662) (xy 97.264559 -234.378591) (xy 97.234535 -234.334554) (xy 97.211409 -234.286533)
			(xy 97.195699 -234.235603) (xy 97.187756 -234.182899) (xy 96.959176 -234.182899) (xy 96.951233 -234.235603)
			(xy 96.935523 -234.286533) (xy 96.912397 -234.334554) (xy 96.882373 -234.378591) (xy 96.846121 -234.417662)
			(xy 96.80445 -234.450893) (xy 96.758292 -234.477542) (xy 96.708678 -234.497014) (xy 96.656716 -234.508874)
			(xy 96.603566 -234.512858) (xy 96.550416 -234.508874) (xy 96.498454 -234.497014) (xy 96.44884 -234.477542)
			(xy 96.402682 -234.450893) (xy 96.361011 -234.417662) (xy 96.324759 -234.378591) (xy 96.294735 -234.334554)
			(xy 96.271609 -234.286533) (xy 96.255899 -234.235603) (xy 96.247956 -234.182899) (xy 96.019376 -234.182899)
			(xy 96.011433 -234.235603) (xy 95.995723 -234.286533) (xy 95.972597 -234.334554) (xy 95.942573 -234.378591)
			(xy 95.906321 -234.417662) (xy 95.86465 -234.450893) (xy 95.818492 -234.477542) (xy 95.768878 -234.497014)
			(xy 95.716916 -234.508874) (xy 95.663766 -234.512858) (xy 95.610616 -234.508874) (xy 95.558654 -234.497014)
			(xy 95.50904 -234.477542) (xy 95.462882 -234.450893) (xy 95.421211 -234.417662) (xy 95.384959 -234.378591)
			(xy 95.354935 -234.334554) (xy 95.331809 -234.286533) (xy 95.316099 -234.235603) (xy 95.308156 -234.182899)
			(xy 95.079322 -234.182899) (xy 95.071379 -234.235603) (xy 95.055669 -234.286533) (xy 95.032543 -234.334554)
			(xy 95.002519 -234.378591) (xy 94.966267 -234.417662) (xy 94.924596 -234.450893) (xy 94.878438 -234.477542)
			(xy 94.828824 -234.497014) (xy 94.776862 -234.508874) (xy 94.723712 -234.512858) (xy 94.670562 -234.508874)
			(xy 94.6186 -234.497014) (xy 94.568986 -234.477542) (xy 94.522828 -234.450893) (xy 94.481157 -234.417662)
			(xy 94.444905 -234.378591) (xy 94.414881 -234.334554) (xy 94.391755 -234.286533) (xy 94.376045 -234.235603)
			(xy 94.368102 -234.182899) (xy 94.139776 -234.182899) (xy 94.131833 -234.235603) (xy 94.116123 -234.286533)
			(xy 94.092997 -234.334554) (xy 94.062973 -234.378591) (xy 94.026721 -234.417662) (xy 93.98505 -234.450893)
			(xy 93.938892 -234.477542) (xy 93.889278 -234.497014) (xy 93.837316 -234.508874) (xy 93.784166 -234.512858)
			(xy 93.731016 -234.508874) (xy 93.679054 -234.497014) (xy 93.62944 -234.477542) (xy 93.583282 -234.450893)
			(xy 93.541611 -234.417662) (xy 93.505359 -234.378591) (xy 93.475335 -234.334554) (xy 93.452209 -234.286533)
			(xy 93.436499 -234.235603) (xy 93.428556 -234.182899) (xy 93.199976 -234.182899) (xy 93.192033 -234.235603)
			(xy 93.176323 -234.286533) (xy 93.153197 -234.334554) (xy 93.123173 -234.378591) (xy 93.086921 -234.417662)
			(xy 93.04525 -234.450893) (xy 92.999092 -234.477542) (xy 92.949478 -234.497014) (xy 92.897516 -234.508874)
			(xy 92.844366 -234.512858) (xy 92.791216 -234.508874) (xy 92.739254 -234.497014) (xy 92.68964 -234.477542)
			(xy 92.643482 -234.450893) (xy 92.601811 -234.417662) (xy 92.565559 -234.378591) (xy 92.535535 -234.334554)
			(xy 92.512409 -234.286533) (xy 92.496699 -234.235603) (xy 92.488756 -234.182899) (xy 92.260176 -234.182899)
			(xy 92.252233 -234.235603) (xy 92.236523 -234.286533) (xy 92.213397 -234.334554) (xy 92.183373 -234.378591)
			(xy 92.147121 -234.417662) (xy 92.10545 -234.450893) (xy 92.059292 -234.477542) (xy 92.009678 -234.497014)
			(xy 91.957716 -234.508874) (xy 91.904566 -234.512858) (xy 91.851416 -234.508874) (xy 91.799454 -234.497014)
			(xy 91.74984 -234.477542) (xy 91.703682 -234.450893) (xy 91.662011 -234.417662) (xy 91.625759 -234.378591)
			(xy 91.595735 -234.334554) (xy 91.572609 -234.286533) (xy 91.556899 -234.235603) (xy 91.548956 -234.182899)
			(xy 91.320376 -234.182899) (xy 91.312433 -234.235603) (xy 91.296723 -234.286533) (xy 91.273597 -234.334554)
			(xy 91.243573 -234.378591) (xy 91.207321 -234.417662) (xy 91.16565 -234.450893) (xy 91.119492 -234.477542)
			(xy 91.069878 -234.497014) (xy 91.017916 -234.508874) (xy 90.964766 -234.512858) (xy 90.911616 -234.508874)
			(xy 90.859654 -234.497014) (xy 90.81004 -234.477542) (xy 90.763882 -234.450893) (xy 90.722211 -234.417662)
			(xy 90.685959 -234.378591) (xy 90.655935 -234.334554) (xy 90.632809 -234.286533) (xy 90.617099 -234.235603)
			(xy 90.609156 -234.182899) (xy 90.380576 -234.182899) (xy 90.372633 -234.235603) (xy 90.356923 -234.286533)
			(xy 90.333797 -234.334554) (xy 90.303773 -234.378591) (xy 90.267521 -234.417662) (xy 90.22585 -234.450893)
			(xy 90.179692 -234.477542) (xy 90.130078 -234.497014) (xy 90.078116 -234.508874) (xy 90.024966 -234.512858)
			(xy 89.971816 -234.508874) (xy 89.919854 -234.497014) (xy 89.87024 -234.477542) (xy 89.824082 -234.450893)
			(xy 89.782411 -234.417662) (xy 89.746159 -234.378591) (xy 89.716135 -234.334554) (xy 89.693009 -234.286533)
			(xy 89.677299 -234.235603) (xy 89.669356 -234.182899) (xy 89.439781 -234.182899) (xy 89.437799 -234.209349)
			(xy 89.425938 -234.261311) (xy 89.406465 -234.310924) (xy 89.379815 -234.357081) (xy 89.346582 -234.398749)
			(xy 89.30751 -234.434999) (xy 89.263471 -234.46502) (xy 89.21545 -234.488142) (xy 89.164519 -234.503848)
			(xy 89.111815 -234.511787) (xy 89.085166 -234.512358) (xy 89.074793 -234.512312) (xy 89.054079 -234.51117)
			(xy 89.043764 -234.510072) (xy 89.029511 -234.508911) (xy 89.001318 -234.513627) (xy 88.975537 -234.525973)
			(xy 88.954187 -234.54498) (xy 88.938942 -234.56916) (xy 88.930996 -234.596618) (xy 88.93048 -234.61091)
			(xy 88.93048 -234.804458) (xy 88.93556 -234.814872) (xy 88.946791 -234.839185) (xy 88.962644 -234.89034)
			(xy 88.970662 -234.943292) (xy 88.970667 -234.996715) (xy 89.199202 -234.996715) (xy 89.199202 -234.943417)
			(xy 89.207145 -234.890713) (xy 89.222855 -234.839783) (xy 89.245981 -234.791762) (xy 89.276005 -234.747725)
			(xy 89.312257 -234.708654) (xy 89.353928 -234.675423) (xy 89.400086 -234.648774) (xy 89.4497 -234.629302)
			(xy 89.501662 -234.617442) (xy 89.554812 -234.613459) (xy 89.607962 -234.617442) (xy 89.659924 -234.629302)
			(xy 89.709538 -234.648774) (xy 89.755696 -234.675423) (xy 89.797367 -234.708654) (xy 89.833619 -234.747725)
			(xy 89.863643 -234.791762) (xy 89.886769 -234.839783) (xy 89.902479 -234.890713) (xy 89.910422 -234.943417)
			(xy 89.91092 -234.970066) (xy 89.910422 -234.996715) (xy 90.139256 -234.996715) (xy 90.139256 -234.943417)
			(xy 90.147199 -234.890713) (xy 90.162909 -234.839783) (xy 90.186035 -234.791762) (xy 90.216059 -234.747725)
			(xy 90.252311 -234.708654) (xy 90.293982 -234.675423) (xy 90.34014 -234.648774) (xy 90.389754 -234.629302)
			(xy 90.441716 -234.617442) (xy 90.494866 -234.613459) (xy 90.548016 -234.617442) (xy 90.599978 -234.629302)
			(xy 90.649592 -234.648774) (xy 90.69575 -234.675423) (xy 90.737421 -234.708654) (xy 90.773673 -234.747725)
			(xy 90.803697 -234.791762) (xy 90.826823 -234.839783) (xy 90.842533 -234.890713) (xy 90.850476 -234.943417)
			(xy 90.850974 -234.970066) (xy 90.850476 -234.996715) (xy 91.078802 -234.996715) (xy 91.078802 -234.943417)
			(xy 91.086745 -234.890713) (xy 91.102455 -234.839783) (xy 91.125581 -234.791762) (xy 91.155605 -234.747725)
			(xy 91.191857 -234.708654) (xy 91.233528 -234.675423) (xy 91.279686 -234.648774) (xy 91.3293 -234.629302)
			(xy 91.381262 -234.617442) (xy 91.434412 -234.613459) (xy 91.487562 -234.617442) (xy 91.539524 -234.629302)
			(xy 91.589138 -234.648774) (xy 91.635296 -234.675423) (xy 91.676967 -234.708654) (xy 91.713219 -234.747725)
			(xy 91.743243 -234.791762) (xy 91.766369 -234.839783) (xy 91.782079 -234.890713) (xy 91.790022 -234.943417)
			(xy 91.79052 -234.970066) (xy 91.790022 -234.996715) (xy 92.018602 -234.996715) (xy 92.018602 -234.943417)
			(xy 92.026545 -234.890713) (xy 92.042255 -234.839783) (xy 92.065381 -234.791762) (xy 92.095405 -234.747725)
			(xy 92.131657 -234.708654) (xy 92.173328 -234.675423) (xy 92.219486 -234.648774) (xy 92.2691 -234.629302)
			(xy 92.321062 -234.617442) (xy 92.374212 -234.613459) (xy 92.427362 -234.617442) (xy 92.479324 -234.629302)
			(xy 92.528938 -234.648774) (xy 92.575096 -234.675423) (xy 92.616767 -234.708654) (xy 92.653019 -234.747725)
			(xy 92.683043 -234.791762) (xy 92.706169 -234.839783) (xy 92.721879 -234.890713) (xy 92.729822 -234.943417)
			(xy 92.73032 -234.970066) (xy 92.729822 -234.996715) (xy 92.958402 -234.996715) (xy 92.958402 -234.943417)
			(xy 92.966345 -234.890713) (xy 92.982055 -234.839783) (xy 93.005181 -234.791762) (xy 93.035205 -234.747725)
			(xy 93.071457 -234.708654) (xy 93.113128 -234.675423) (xy 93.159286 -234.648774) (xy 93.2089 -234.629302)
			(xy 93.260862 -234.617442) (xy 93.314012 -234.613459) (xy 93.367162 -234.617442) (xy 93.419124 -234.629302)
			(xy 93.468738 -234.648774) (xy 93.514896 -234.675423) (xy 93.556567 -234.708654) (xy 93.592819 -234.747725)
			(xy 93.622843 -234.791762) (xy 93.645969 -234.839783) (xy 93.661679 -234.890713) (xy 93.669622 -234.943417)
			(xy 93.67012 -234.970066) (xy 93.669622 -234.996715) (xy 93.898202 -234.996715) (xy 93.898202 -234.943417)
			(xy 93.906145 -234.890713) (xy 93.921855 -234.839783) (xy 93.944981 -234.791762) (xy 93.975005 -234.747725)
			(xy 94.011257 -234.708654) (xy 94.052928 -234.675423) (xy 94.099086 -234.648774) (xy 94.1487 -234.629302)
			(xy 94.200662 -234.617442) (xy 94.253812 -234.613459) (xy 94.306962 -234.617442) (xy 94.358924 -234.629302)
			(xy 94.408538 -234.648774) (xy 94.454696 -234.675423) (xy 94.496367 -234.708654) (xy 94.532619 -234.747725)
			(xy 94.562643 -234.791762) (xy 94.585769 -234.839783) (xy 94.601479 -234.890713) (xy 94.609422 -234.943417)
			(xy 94.60992 -234.970066) (xy 94.609422 -234.996715) (xy 94.838002 -234.996715) (xy 94.838002 -234.943417)
			(xy 94.845945 -234.890713) (xy 94.861655 -234.839783) (xy 94.884781 -234.791762) (xy 94.914805 -234.747725)
			(xy 94.951057 -234.708654) (xy 94.992728 -234.675423) (xy 95.038886 -234.648774) (xy 95.0885 -234.629302)
			(xy 95.140462 -234.617442) (xy 95.193612 -234.613459) (xy 95.246762 -234.617442) (xy 95.298724 -234.629302)
			(xy 95.348338 -234.648774) (xy 95.394496 -234.675423) (xy 95.436167 -234.708654) (xy 95.472419 -234.747725)
			(xy 95.502443 -234.791762) (xy 95.525569 -234.839783) (xy 95.541279 -234.890713) (xy 95.549222 -234.943417)
			(xy 95.54972 -234.970066) (xy 95.549222 -234.996715) (xy 95.777802 -234.996715) (xy 95.777802 -234.943417)
			(xy 95.785745 -234.890713) (xy 95.801455 -234.839783) (xy 95.824581 -234.791762) (xy 95.854605 -234.747725)
			(xy 95.890857 -234.708654) (xy 95.932528 -234.675423) (xy 95.978686 -234.648774) (xy 96.0283 -234.629302)
			(xy 96.080262 -234.617442) (xy 96.133412 -234.613459) (xy 96.186562 -234.617442) (xy 96.238524 -234.629302)
			(xy 96.288138 -234.648774) (xy 96.334296 -234.675423) (xy 96.375967 -234.708654) (xy 96.412219 -234.747725)
			(xy 96.442243 -234.791762) (xy 96.465369 -234.839783) (xy 96.481079 -234.890713) (xy 96.489022 -234.943417)
			(xy 96.48952 -234.970066) (xy 96.489022 -234.996715) (xy 96.717856 -234.996715) (xy 96.717856 -234.943417)
			(xy 96.725799 -234.890713) (xy 96.741509 -234.839783) (xy 96.764635 -234.791762) (xy 96.794659 -234.747725)
			(xy 96.830911 -234.708654) (xy 96.872582 -234.675423) (xy 96.91874 -234.648774) (xy 96.968354 -234.629302)
			(xy 97.020316 -234.617442) (xy 97.073466 -234.613459) (xy 97.126616 -234.617442) (xy 97.178578 -234.629302)
			(xy 97.228192 -234.648774) (xy 97.27435 -234.675423) (xy 97.316021 -234.708654) (xy 97.352273 -234.747725)
			(xy 97.382297 -234.791762) (xy 97.405423 -234.839783) (xy 97.421133 -234.890713) (xy 97.429076 -234.943417)
			(xy 97.429574 -234.970066) (xy 97.429076 -234.996715) (xy 97.657402 -234.996715) (xy 97.657402 -234.943417)
			(xy 97.665345 -234.890713) (xy 97.681055 -234.839783) (xy 97.704181 -234.791762) (xy 97.734205 -234.747725)
			(xy 97.770457 -234.708654) (xy 97.812128 -234.675423) (xy 97.858286 -234.648774) (xy 97.9079 -234.629302)
			(xy 97.959862 -234.617442) (xy 98.013012 -234.613459) (xy 98.066162 -234.617442) (xy 98.118124 -234.629302)
			(xy 98.167738 -234.648774) (xy 98.213896 -234.675423) (xy 98.255567 -234.708654) (xy 98.291819 -234.747725)
			(xy 98.321843 -234.791762) (xy 98.344969 -234.839783) (xy 98.360679 -234.890713) (xy 98.368622 -234.943417)
			(xy 98.36912 -234.970066) (xy 98.368622 -234.996715) (xy 98.597202 -234.996715) (xy 98.597202 -234.943417)
			(xy 98.605145 -234.890713) (xy 98.620855 -234.839783) (xy 98.643981 -234.791762) (xy 98.674005 -234.747725)
			(xy 98.710257 -234.708654) (xy 98.751928 -234.675423) (xy 98.798086 -234.648774) (xy 98.8477 -234.629302)
			(xy 98.899662 -234.617442) (xy 98.952812 -234.613459) (xy 99.005962 -234.617442) (xy 99.057924 -234.629302)
			(xy 99.107538 -234.648774) (xy 99.153696 -234.675423) (xy 99.195367 -234.708654) (xy 99.231619 -234.747725)
			(xy 99.261643 -234.791762) (xy 99.284769 -234.839783) (xy 99.300479 -234.890713) (xy 99.308422 -234.943417)
			(xy 99.30892 -234.970066) (xy 99.308422 -234.996715) (xy 99.537002 -234.996715) (xy 99.537002 -234.943417)
			(xy 99.544945 -234.890713) (xy 99.560655 -234.839783) (xy 99.583781 -234.791762) (xy 99.613805 -234.747725)
			(xy 99.650057 -234.708654) (xy 99.691728 -234.675423) (xy 99.737886 -234.648774) (xy 99.7875 -234.629302)
			(xy 99.839462 -234.617442) (xy 99.892612 -234.613459) (xy 99.945762 -234.617442) (xy 99.997724 -234.629302)
			(xy 100.047338 -234.648774) (xy 100.093496 -234.675423) (xy 100.135167 -234.708654) (xy 100.171419 -234.747725)
			(xy 100.201443 -234.791762) (xy 100.224569 -234.839783) (xy 100.240279 -234.890713) (xy 100.248222 -234.943417)
			(xy 100.24872 -234.970066) (xy 100.248222 -234.996715) (xy 100.476802 -234.996715) (xy 100.476802 -234.943417)
			(xy 100.484745 -234.890713) (xy 100.500455 -234.839783) (xy 100.523581 -234.791762) (xy 100.553605 -234.747725)
			(xy 100.589857 -234.708654) (xy 100.631528 -234.675423) (xy 100.677686 -234.648774) (xy 100.7273 -234.629302)
			(xy 100.779262 -234.617442) (xy 100.832412 -234.613459) (xy 100.885562 -234.617442) (xy 100.937524 -234.629302)
			(xy 100.987138 -234.648774) (xy 101.033296 -234.675423) (xy 101.074967 -234.708654) (xy 101.111219 -234.747725)
			(xy 101.141243 -234.791762) (xy 101.164369 -234.839783) (xy 101.180079 -234.890713) (xy 101.188022 -234.943417)
			(xy 101.18852 -234.970066) (xy 101.188022 -234.996715) (xy 101.180079 -235.049419) (xy 101.164369 -235.100349)
			(xy 101.141243 -235.14837) (xy 101.111219 -235.192407) (xy 101.074967 -235.231478) (xy 101.033296 -235.264709)
			(xy 100.987138 -235.291358) (xy 100.937524 -235.31083) (xy 100.885562 -235.32269) (xy 100.832412 -235.326674)
			(xy 100.779262 -235.32269) (xy 100.7273 -235.31083) (xy 100.677686 -235.291358) (xy 100.631528 -235.264709)
			(xy 100.589857 -235.231478) (xy 100.553605 -235.192407) (xy 100.523581 -235.14837) (xy 100.500455 -235.100349)
			(xy 100.484745 -235.049419) (xy 100.476802 -234.996715) (xy 100.248222 -234.996715) (xy 100.240279 -235.049419)
			(xy 100.224569 -235.100349) (xy 100.201443 -235.14837) (xy 100.171419 -235.192407) (xy 100.135167 -235.231478)
			(xy 100.093496 -235.264709) (xy 100.047338 -235.291358) (xy 99.997724 -235.31083) (xy 99.945762 -235.32269)
			(xy 99.892612 -235.326674) (xy 99.839462 -235.32269) (xy 99.7875 -235.31083) (xy 99.737886 -235.291358)
			(xy 99.691728 -235.264709) (xy 99.650057 -235.231478) (xy 99.613805 -235.192407) (xy 99.583781 -235.14837)
			(xy 99.560655 -235.100349) (xy 99.544945 -235.049419) (xy 99.537002 -234.996715) (xy 99.308422 -234.996715)
			(xy 99.300479 -235.049419) (xy 99.284769 -235.100349) (xy 99.261643 -235.14837) (xy 99.231619 -235.192407)
			(xy 99.195367 -235.231478) (xy 99.153696 -235.264709) (xy 99.107538 -235.291358) (xy 99.057924 -235.31083)
			(xy 99.005962 -235.32269) (xy 98.952812 -235.326674) (xy 98.899662 -235.32269) (xy 98.8477 -235.31083)
			(xy 98.798086 -235.291358) (xy 98.751928 -235.264709) (xy 98.710257 -235.231478) (xy 98.674005 -235.192407)
			(xy 98.643981 -235.14837) (xy 98.620855 -235.100349) (xy 98.605145 -235.049419) (xy 98.597202 -234.996715)
			(xy 98.368622 -234.996715) (xy 98.360679 -235.049419) (xy 98.344969 -235.100349) (xy 98.321843 -235.14837)
			(xy 98.291819 -235.192407) (xy 98.255567 -235.231478) (xy 98.213896 -235.264709) (xy 98.167738 -235.291358)
			(xy 98.118124 -235.31083) (xy 98.066162 -235.32269) (xy 98.013012 -235.326674) (xy 97.959862 -235.32269)
			(xy 97.9079 -235.31083) (xy 97.858286 -235.291358) (xy 97.812128 -235.264709) (xy 97.770457 -235.231478)
			(xy 97.734205 -235.192407) (xy 97.704181 -235.14837) (xy 97.681055 -235.100349) (xy 97.665345 -235.049419)
			(xy 97.657402 -234.996715) (xy 97.429076 -234.996715) (xy 97.421133 -235.049419) (xy 97.405423 -235.100349)
			(xy 97.382297 -235.14837) (xy 97.352273 -235.192407) (xy 97.316021 -235.231478) (xy 97.27435 -235.264709)
			(xy 97.228192 -235.291358) (xy 97.178578 -235.31083) (xy 97.126616 -235.32269) (xy 97.073466 -235.326674)
			(xy 97.020316 -235.32269) (xy 96.968354 -235.31083) (xy 96.91874 -235.291358) (xy 96.872582 -235.264709)
			(xy 96.830911 -235.231478) (xy 96.794659 -235.192407) (xy 96.764635 -235.14837) (xy 96.741509 -235.100349)
			(xy 96.725799 -235.049419) (xy 96.717856 -234.996715) (xy 96.489022 -234.996715) (xy 96.481079 -235.049419)
			(xy 96.465369 -235.100349) (xy 96.442243 -235.14837) (xy 96.412219 -235.192407) (xy 96.375967 -235.231478)
			(xy 96.334296 -235.264709) (xy 96.288138 -235.291358) (xy 96.238524 -235.31083) (xy 96.186562 -235.32269)
			(xy 96.133412 -235.326674) (xy 96.080262 -235.32269) (xy 96.0283 -235.31083) (xy 95.978686 -235.291358)
			(xy 95.932528 -235.264709) (xy 95.890857 -235.231478) (xy 95.854605 -235.192407) (xy 95.824581 -235.14837)
			(xy 95.801455 -235.100349) (xy 95.785745 -235.049419) (xy 95.777802 -234.996715) (xy 95.549222 -234.996715)
			(xy 95.541279 -235.049419) (xy 95.525569 -235.100349) (xy 95.502443 -235.14837) (xy 95.472419 -235.192407)
			(xy 95.436167 -235.231478) (xy 95.394496 -235.264709) (xy 95.348338 -235.291358) (xy 95.298724 -235.31083)
			(xy 95.246762 -235.32269) (xy 95.193612 -235.326674) (xy 95.140462 -235.32269) (xy 95.0885 -235.31083)
			(xy 95.038886 -235.291358) (xy 94.992728 -235.264709) (xy 94.951057 -235.231478) (xy 94.914805 -235.192407)
			(xy 94.884781 -235.14837) (xy 94.861655 -235.100349) (xy 94.845945 -235.049419) (xy 94.838002 -234.996715)
			(xy 94.609422 -234.996715) (xy 94.601479 -235.049419) (xy 94.585769 -235.100349) (xy 94.562643 -235.14837)
			(xy 94.532619 -235.192407) (xy 94.496367 -235.231478) (xy 94.454696 -235.264709) (xy 94.408538 -235.291358)
			(xy 94.358924 -235.31083) (xy 94.306962 -235.32269) (xy 94.253812 -235.326674) (xy 94.200662 -235.32269)
			(xy 94.1487 -235.31083) (xy 94.099086 -235.291358) (xy 94.052928 -235.264709) (xy 94.011257 -235.231478)
			(xy 93.975005 -235.192407) (xy 93.944981 -235.14837) (xy 93.921855 -235.100349) (xy 93.906145 -235.049419)
			(xy 93.898202 -234.996715) (xy 93.669622 -234.996715) (xy 93.661679 -235.049419) (xy 93.645969 -235.100349)
			(xy 93.622843 -235.14837) (xy 93.592819 -235.192407) (xy 93.556567 -235.231478) (xy 93.514896 -235.264709)
			(xy 93.468738 -235.291358) (xy 93.419124 -235.31083) (xy 93.367162 -235.32269) (xy 93.314012 -235.326674)
			(xy 93.260862 -235.32269) (xy 93.2089 -235.31083) (xy 93.159286 -235.291358) (xy 93.113128 -235.264709)
			(xy 93.071457 -235.231478) (xy 93.035205 -235.192407) (xy 93.005181 -235.14837) (xy 92.982055 -235.100349)
			(xy 92.966345 -235.049419) (xy 92.958402 -234.996715) (xy 92.729822 -234.996715) (xy 92.721879 -235.049419)
			(xy 92.706169 -235.100349) (xy 92.683043 -235.14837) (xy 92.653019 -235.192407) (xy 92.616767 -235.231478)
			(xy 92.575096 -235.264709) (xy 92.528938 -235.291358) (xy 92.479324 -235.31083) (xy 92.427362 -235.32269)
			(xy 92.374212 -235.326674) (xy 92.321062 -235.32269) (xy 92.2691 -235.31083) (xy 92.219486 -235.291358)
			(xy 92.173328 -235.264709) (xy 92.131657 -235.231478) (xy 92.095405 -235.192407) (xy 92.065381 -235.14837)
			(xy 92.042255 -235.100349) (xy 92.026545 -235.049419) (xy 92.018602 -234.996715) (xy 91.790022 -234.996715)
			(xy 91.782079 -235.049419) (xy 91.766369 -235.100349) (xy 91.743243 -235.14837) (xy 91.713219 -235.192407)
			(xy 91.676967 -235.231478) (xy 91.635296 -235.264709) (xy 91.589138 -235.291358) (xy 91.539524 -235.31083)
			(xy 91.487562 -235.32269) (xy 91.434412 -235.326674) (xy 91.381262 -235.32269) (xy 91.3293 -235.31083)
			(xy 91.279686 -235.291358) (xy 91.233528 -235.264709) (xy 91.191857 -235.231478) (xy 91.155605 -235.192407)
			(xy 91.125581 -235.14837) (xy 91.102455 -235.100349) (xy 91.086745 -235.049419) (xy 91.078802 -234.996715)
			(xy 90.850476 -234.996715) (xy 90.842533 -235.049419) (xy 90.826823 -235.100349) (xy 90.803697 -235.14837)
			(xy 90.773673 -235.192407) (xy 90.737421 -235.231478) (xy 90.69575 -235.264709) (xy 90.649592 -235.291358)
			(xy 90.599978 -235.31083) (xy 90.548016 -235.32269) (xy 90.494866 -235.326674) (xy 90.441716 -235.32269)
			(xy 90.389754 -235.31083) (xy 90.34014 -235.291358) (xy 90.293982 -235.264709) (xy 90.252311 -235.231478)
			(xy 90.216059 -235.192407) (xy 90.186035 -235.14837) (xy 90.162909 -235.100349) (xy 90.147199 -235.049419)
			(xy 90.139256 -234.996715) (xy 89.910422 -234.996715) (xy 89.902479 -235.049419) (xy 89.886769 -235.100349)
			(xy 89.863643 -235.14837) (xy 89.833619 -235.192407) (xy 89.797367 -235.231478) (xy 89.755696 -235.264709)
			(xy 89.709538 -235.291358) (xy 89.659924 -235.31083) (xy 89.607962 -235.32269) (xy 89.554812 -235.326674)
			(xy 89.501662 -235.32269) (xy 89.4497 -235.31083) (xy 89.400086 -235.291358) (xy 89.353928 -235.264709)
			(xy 89.312257 -235.231478) (xy 89.276005 -235.192407) (xy 89.245981 -235.14837) (xy 89.222855 -235.100349)
			(xy 89.207145 -235.049419) (xy 89.199202 -234.996715) (xy 88.970667 -234.996715) (xy 88.970667 -234.996847)
			(xy 88.962657 -235.0498) (xy 88.946814 -235.100958) (xy 88.93556 -235.12526) (xy 88.93048 -235.135674)
			(xy 88.93048 -235.329222) (xy 88.930955 -235.343521) (xy 88.938878 -235.371) (xy 88.954121 -235.395197)
			(xy 88.975485 -235.414208) (xy 89.001289 -235.426537) (xy 89.029502 -235.431213) (xy 89.043764 -235.43006)
			(xy 89.054078 -235.428956) (xy 89.074793 -235.427812) (xy 89.085166 -235.427774) (xy 89.11182 -235.428245)
			(xy 89.164534 -235.436185) (xy 89.215475 -235.451894) (xy 89.263505 -235.475021) (xy 89.307552 -235.505048)
			(xy 89.346632 -235.541305) (xy 89.379871 -235.582981) (xy 89.406526 -235.629147) (xy 89.426003 -235.678769)
			(xy 89.437866 -235.730741) (xy 89.44185 -235.7839) (xy 89.439854 -235.810531) (xy 89.669356 -235.810531)
			(xy 89.669356 -235.757233) (xy 89.677299 -235.704529) (xy 89.693009 -235.653599) (xy 89.716135 -235.605578)
			(xy 89.746159 -235.561541) (xy 89.782411 -235.52247) (xy 89.824082 -235.489239) (xy 89.87024 -235.46259)
			(xy 89.919854 -235.443118) (xy 89.971816 -235.431258) (xy 90.024966 -235.427275) (xy 90.078116 -235.431258)
			(xy 90.130078 -235.443118) (xy 90.179692 -235.46259) (xy 90.22585 -235.489239) (xy 90.267521 -235.52247)
			(xy 90.303773 -235.561541) (xy 90.333797 -235.605578) (xy 90.356923 -235.653599) (xy 90.372633 -235.704529)
			(xy 90.380576 -235.757233) (xy 90.381074 -235.783882) (xy 90.380576 -235.810531) (xy 90.608902 -235.810531)
			(xy 90.608902 -235.757233) (xy 90.616845 -235.704529) (xy 90.632555 -235.653599) (xy 90.655681 -235.605578)
			(xy 90.685705 -235.561541) (xy 90.721957 -235.52247) (xy 90.763628 -235.489239) (xy 90.809786 -235.46259)
			(xy 90.8594 -235.443118) (xy 90.911362 -235.431258) (xy 90.964512 -235.427275) (xy 91.017662 -235.431258)
			(xy 91.069624 -235.443118) (xy 91.119238 -235.46259) (xy 91.165396 -235.489239) (xy 91.207067 -235.52247)
			(xy 91.243319 -235.561541) (xy 91.273343 -235.605578) (xy 91.296469 -235.653599) (xy 91.312179 -235.704529)
			(xy 91.320122 -235.757233) (xy 91.32062 -235.783882) (xy 91.320122 -235.810531) (xy 91.548956 -235.810531)
			(xy 91.548956 -235.757233) (xy 91.556899 -235.704529) (xy 91.572609 -235.653599) (xy 91.595735 -235.605578)
			(xy 91.625759 -235.561541) (xy 91.662011 -235.52247) (xy 91.703682 -235.489239) (xy 91.74984 -235.46259)
			(xy 91.799454 -235.443118) (xy 91.851416 -235.431258) (xy 91.904566 -235.427275) (xy 91.957716 -235.431258)
			(xy 92.009678 -235.443118) (xy 92.059292 -235.46259) (xy 92.10545 -235.489239) (xy 92.147121 -235.52247)
			(xy 92.183373 -235.561541) (xy 92.213397 -235.605578) (xy 92.236523 -235.653599) (xy 92.252233 -235.704529)
			(xy 92.260176 -235.757233) (xy 92.260674 -235.783882) (xy 92.260176 -235.810531) (xy 92.488756 -235.810531)
			(xy 92.488756 -235.757233) (xy 92.496699 -235.704529) (xy 92.512409 -235.653599) (xy 92.535535 -235.605578)
			(xy 92.565559 -235.561541) (xy 92.601811 -235.52247) (xy 92.643482 -235.489239) (xy 92.68964 -235.46259)
			(xy 92.739254 -235.443118) (xy 92.791216 -235.431258) (xy 92.844366 -235.427275) (xy 92.897516 -235.431258)
			(xy 92.949478 -235.443118) (xy 92.999092 -235.46259) (xy 93.04525 -235.489239) (xy 93.086921 -235.52247)
			(xy 93.123173 -235.561541) (xy 93.153197 -235.605578) (xy 93.176323 -235.653599) (xy 93.192033 -235.704529)
			(xy 93.199976 -235.757233) (xy 93.200474 -235.783882) (xy 93.199976 -235.810531) (xy 93.428556 -235.810531)
			(xy 93.428556 -235.757233) (xy 93.436499 -235.704529) (xy 93.452209 -235.653599) (xy 93.475335 -235.605578)
			(xy 93.505359 -235.561541) (xy 93.541611 -235.52247) (xy 93.583282 -235.489239) (xy 93.62944 -235.46259)
			(xy 93.679054 -235.443118) (xy 93.731016 -235.431258) (xy 93.784166 -235.427275) (xy 93.837316 -235.431258)
			(xy 93.889278 -235.443118) (xy 93.938892 -235.46259) (xy 93.98505 -235.489239) (xy 94.026721 -235.52247)
			(xy 94.062973 -235.561541) (xy 94.092997 -235.605578) (xy 94.116123 -235.653599) (xy 94.131833 -235.704529)
			(xy 94.139776 -235.757233) (xy 94.140274 -235.783882) (xy 94.139776 -235.810531) (xy 94.368356 -235.810531)
			(xy 94.368356 -235.757233) (xy 94.376299 -235.704529) (xy 94.392009 -235.653599) (xy 94.415135 -235.605578)
			(xy 94.445159 -235.561541) (xy 94.481411 -235.52247) (xy 94.523082 -235.489239) (xy 94.56924 -235.46259)
			(xy 94.618854 -235.443118) (xy 94.670816 -235.431258) (xy 94.723966 -235.427275) (xy 94.777116 -235.431258)
			(xy 94.829078 -235.443118) (xy 94.878692 -235.46259) (xy 94.92485 -235.489239) (xy 94.966521 -235.52247)
			(xy 95.002773 -235.561541) (xy 95.032797 -235.605578) (xy 95.055923 -235.653599) (xy 95.071633 -235.704529)
			(xy 95.079576 -235.757233) (xy 95.080074 -235.783882) (xy 95.079576 -235.810531) (xy 95.308156 -235.810531)
			(xy 95.308156 -235.757233) (xy 95.316099 -235.704529) (xy 95.331809 -235.653599) (xy 95.354935 -235.605578)
			(xy 95.384959 -235.561541) (xy 95.421211 -235.52247) (xy 95.462882 -235.489239) (xy 95.50904 -235.46259)
			(xy 95.558654 -235.443118) (xy 95.610616 -235.431258) (xy 95.663766 -235.427275) (xy 95.716916 -235.431258)
			(xy 95.768878 -235.443118) (xy 95.818492 -235.46259) (xy 95.86465 -235.489239) (xy 95.906321 -235.52247)
			(xy 95.942573 -235.561541) (xy 95.972597 -235.605578) (xy 95.995723 -235.653599) (xy 96.011433 -235.704529)
			(xy 96.019376 -235.757233) (xy 96.019874 -235.783882) (xy 96.019376 -235.810531) (xy 96.247956 -235.810531)
			(xy 96.247956 -235.757233) (xy 96.255899 -235.704529) (xy 96.271609 -235.653599) (xy 96.294735 -235.605578)
			(xy 96.324759 -235.561541) (xy 96.361011 -235.52247) (xy 96.402682 -235.489239) (xy 96.44884 -235.46259)
			(xy 96.498454 -235.443118) (xy 96.550416 -235.431258) (xy 96.603566 -235.427275) (xy 96.656716 -235.431258)
			(xy 96.708678 -235.443118) (xy 96.758292 -235.46259) (xy 96.80445 -235.489239) (xy 96.846121 -235.52247)
			(xy 96.882373 -235.561541) (xy 96.912397 -235.605578) (xy 96.935523 -235.653599) (xy 96.951233 -235.704529)
			(xy 96.959176 -235.757233) (xy 96.959674 -235.783882) (xy 96.959176 -235.810531) (xy 97.187502 -235.810531)
			(xy 97.187502 -235.757233) (xy 97.195445 -235.704529) (xy 97.211155 -235.653599) (xy 97.234281 -235.605578)
			(xy 97.264305 -235.561541) (xy 97.300557 -235.52247) (xy 97.342228 -235.489239) (xy 97.388386 -235.46259)
			(xy 97.438 -235.443118) (xy 97.489962 -235.431258) (xy 97.543112 -235.427275) (xy 97.596262 -235.431258)
			(xy 97.648224 -235.443118) (xy 97.697838 -235.46259) (xy 97.743996 -235.489239) (xy 97.785667 -235.52247)
			(xy 97.821919 -235.561541) (xy 97.851943 -235.605578) (xy 97.875069 -235.653599) (xy 97.890779 -235.704529)
			(xy 97.898722 -235.757233) (xy 97.89922 -235.783882) (xy 97.898722 -235.810531) (xy 98.127556 -235.810531)
			(xy 98.127556 -235.757233) (xy 98.135499 -235.704529) (xy 98.151209 -235.653599) (xy 98.174335 -235.605578)
			(xy 98.204359 -235.561541) (xy 98.240611 -235.52247) (xy 98.282282 -235.489239) (xy 98.32844 -235.46259)
			(xy 98.378054 -235.443118) (xy 98.430016 -235.431258) (xy 98.483166 -235.427275) (xy 98.536316 -235.431258)
			(xy 98.588278 -235.443118) (xy 98.637892 -235.46259) (xy 98.68405 -235.489239) (xy 98.725721 -235.52247)
			(xy 98.761973 -235.561541) (xy 98.791997 -235.605578) (xy 98.815123 -235.653599) (xy 98.830833 -235.704529)
			(xy 98.838776 -235.757233) (xy 98.839274 -235.783882) (xy 98.838776 -235.810531) (xy 99.067356 -235.810531)
			(xy 99.067356 -235.757233) (xy 99.075299 -235.704529) (xy 99.091009 -235.653599) (xy 99.114135 -235.605578)
			(xy 99.144159 -235.561541) (xy 99.180411 -235.52247) (xy 99.222082 -235.489239) (xy 99.26824 -235.46259)
			(xy 99.317854 -235.443118) (xy 99.369816 -235.431258) (xy 99.422966 -235.427275) (xy 99.476116 -235.431258)
			(xy 99.528078 -235.443118) (xy 99.577692 -235.46259) (xy 99.62385 -235.489239) (xy 99.665521 -235.52247)
			(xy 99.701773 -235.561541) (xy 99.731797 -235.605578) (xy 99.754923 -235.653599) (xy 99.770633 -235.704529)
			(xy 99.778576 -235.757233) (xy 99.779074 -235.783882) (xy 99.778576 -235.810531) (xy 100.007156 -235.810531)
			(xy 100.007156 -235.757233) (xy 100.015099 -235.704529) (xy 100.030809 -235.653599) (xy 100.053935 -235.605578)
			(xy 100.083959 -235.561541) (xy 100.120211 -235.52247) (xy 100.161882 -235.489239) (xy 100.20804 -235.46259)
			(xy 100.257654 -235.443118) (xy 100.309616 -235.431258) (xy 100.362766 -235.427275) (xy 100.415916 -235.431258)
			(xy 100.467878 -235.443118) (xy 100.517492 -235.46259) (xy 100.56365 -235.489239) (xy 100.605321 -235.52247)
			(xy 100.641573 -235.561541) (xy 100.671597 -235.605578) (xy 100.694723 -235.653599) (xy 100.710433 -235.704529)
			(xy 100.718376 -235.757233) (xy 100.718874 -235.783882) (xy 100.718376 -235.810531) (xy 100.710433 -235.863235)
			(xy 100.694723 -235.914165) (xy 100.671597 -235.962186) (xy 100.641573 -236.006223) (xy 100.605321 -236.045294)
			(xy 100.56365 -236.078525) (xy 100.517492 -236.105174) (xy 100.467878 -236.124646) (xy 100.415916 -236.136506)
			(xy 100.362766 -236.14049) (xy 100.309616 -236.136506) (xy 100.257654 -236.124646) (xy 100.20804 -236.105174)
			(xy 100.161882 -236.078525) (xy 100.120211 -236.045294) (xy 100.083959 -236.006223) (xy 100.053935 -235.962186)
			(xy 100.030809 -235.914165) (xy 100.015099 -235.863235) (xy 100.007156 -235.810531) (xy 99.778576 -235.810531)
			(xy 99.770633 -235.863235) (xy 99.754923 -235.914165) (xy 99.731797 -235.962186) (xy 99.701773 -236.006223)
			(xy 99.665521 -236.045294) (xy 99.62385 -236.078525) (xy 99.577692 -236.105174) (xy 99.528078 -236.124646)
			(xy 99.476116 -236.136506) (xy 99.422966 -236.14049) (xy 99.369816 -236.136506) (xy 99.317854 -236.124646)
			(xy 99.26824 -236.105174) (xy 99.222082 -236.078525) (xy 99.180411 -236.045294) (xy 99.144159 -236.006223)
			(xy 99.114135 -235.962186) (xy 99.091009 -235.914165) (xy 99.075299 -235.863235) (xy 99.067356 -235.810531)
			(xy 98.838776 -235.810531) (xy 98.830833 -235.863235) (xy 98.815123 -235.914165) (xy 98.791997 -235.962186)
			(xy 98.761973 -236.006223) (xy 98.725721 -236.045294) (xy 98.68405 -236.078525) (xy 98.637892 -236.105174)
			(xy 98.588278 -236.124646) (xy 98.536316 -236.136506) (xy 98.483166 -236.14049) (xy 98.430016 -236.136506)
			(xy 98.378054 -236.124646) (xy 98.32844 -236.105174) (xy 98.282282 -236.078525) (xy 98.240611 -236.045294)
			(xy 98.204359 -236.006223) (xy 98.174335 -235.962186) (xy 98.151209 -235.914165) (xy 98.135499 -235.863235)
			(xy 98.127556 -235.810531) (xy 97.898722 -235.810531) (xy 97.890779 -235.863235) (xy 97.875069 -235.914165)
			(xy 97.851943 -235.962186) (xy 97.821919 -236.006223) (xy 97.785667 -236.045294) (xy 97.743996 -236.078525)
			(xy 97.697838 -236.105174) (xy 97.648224 -236.124646) (xy 97.596262 -236.136506) (xy 97.543112 -236.14049)
			(xy 97.489962 -236.136506) (xy 97.438 -236.124646) (xy 97.388386 -236.105174) (xy 97.342228 -236.078525)
			(xy 97.300557 -236.045294) (xy 97.264305 -236.006223) (xy 97.234281 -235.962186) (xy 97.211155 -235.914165)
			(xy 97.195445 -235.863235) (xy 97.187502 -235.810531) (xy 96.959176 -235.810531) (xy 96.951233 -235.863235)
			(xy 96.935523 -235.914165) (xy 96.912397 -235.962186) (xy 96.882373 -236.006223) (xy 96.846121 -236.045294)
			(xy 96.80445 -236.078525) (xy 96.758292 -236.105174) (xy 96.708678 -236.124646) (xy 96.656716 -236.136506)
			(xy 96.603566 -236.14049) (xy 96.550416 -236.136506) (xy 96.498454 -236.124646) (xy 96.44884 -236.105174)
			(xy 96.402682 -236.078525) (xy 96.361011 -236.045294) (xy 96.324759 -236.006223) (xy 96.294735 -235.962186)
			(xy 96.271609 -235.914165) (xy 96.255899 -235.863235) (xy 96.247956 -235.810531) (xy 96.019376 -235.810531)
			(xy 96.011433 -235.863235) (xy 95.995723 -235.914165) (xy 95.972597 -235.962186) (xy 95.942573 -236.006223)
			(xy 95.906321 -236.045294) (xy 95.86465 -236.078525) (xy 95.818492 -236.105174) (xy 95.768878 -236.124646)
			(xy 95.716916 -236.136506) (xy 95.663766 -236.14049) (xy 95.610616 -236.136506) (xy 95.558654 -236.124646)
			(xy 95.50904 -236.105174) (xy 95.462882 -236.078525) (xy 95.421211 -236.045294) (xy 95.384959 -236.006223)
			(xy 95.354935 -235.962186) (xy 95.331809 -235.914165) (xy 95.316099 -235.863235) (xy 95.308156 -235.810531)
			(xy 95.079576 -235.810531) (xy 95.071633 -235.863235) (xy 95.055923 -235.914165) (xy 95.032797 -235.962186)
			(xy 95.002773 -236.006223) (xy 94.966521 -236.045294) (xy 94.92485 -236.078525) (xy 94.878692 -236.105174)
			(xy 94.829078 -236.124646) (xy 94.777116 -236.136506) (xy 94.723966 -236.14049) (xy 94.670816 -236.136506)
			(xy 94.618854 -236.124646) (xy 94.56924 -236.105174) (xy 94.523082 -236.078525) (xy 94.481411 -236.045294)
			(xy 94.445159 -236.006223) (xy 94.415135 -235.962186) (xy 94.392009 -235.914165) (xy 94.376299 -235.863235)
			(xy 94.368356 -235.810531) (xy 94.139776 -235.810531) (xy 94.131833 -235.863235) (xy 94.116123 -235.914165)
			(xy 94.092997 -235.962186) (xy 94.062973 -236.006223) (xy 94.026721 -236.045294) (xy 93.98505 -236.078525)
			(xy 93.938892 -236.105174) (xy 93.889278 -236.124646) (xy 93.837316 -236.136506) (xy 93.784166 -236.14049)
			(xy 93.731016 -236.136506) (xy 93.679054 -236.124646) (xy 93.62944 -236.105174) (xy 93.583282 -236.078525)
			(xy 93.541611 -236.045294) (xy 93.505359 -236.006223) (xy 93.475335 -235.962186) (xy 93.452209 -235.914165)
			(xy 93.436499 -235.863235) (xy 93.428556 -235.810531) (xy 93.199976 -235.810531) (xy 93.192033 -235.863235)
			(xy 93.176323 -235.914165) (xy 93.153197 -235.962186) (xy 93.123173 -236.006223) (xy 93.086921 -236.045294)
			(xy 93.04525 -236.078525) (xy 92.999092 -236.105174) (xy 92.949478 -236.124646) (xy 92.897516 -236.136506)
			(xy 92.844366 -236.14049) (xy 92.791216 -236.136506) (xy 92.739254 -236.124646) (xy 92.68964 -236.105174)
			(xy 92.643482 -236.078525) (xy 92.601811 -236.045294) (xy 92.565559 -236.006223) (xy 92.535535 -235.962186)
			(xy 92.512409 -235.914165) (xy 92.496699 -235.863235) (xy 92.488756 -235.810531) (xy 92.260176 -235.810531)
			(xy 92.252233 -235.863235) (xy 92.236523 -235.914165) (xy 92.213397 -235.962186) (xy 92.183373 -236.006223)
			(xy 92.147121 -236.045294) (xy 92.10545 -236.078525) (xy 92.059292 -236.105174) (xy 92.009678 -236.124646)
			(xy 91.957716 -236.136506) (xy 91.904566 -236.14049) (xy 91.851416 -236.136506) (xy 91.799454 -236.124646)
			(xy 91.74984 -236.105174) (xy 91.703682 -236.078525) (xy 91.662011 -236.045294) (xy 91.625759 -236.006223)
			(xy 91.595735 -235.962186) (xy 91.572609 -235.914165) (xy 91.556899 -235.863235) (xy 91.548956 -235.810531)
			(xy 91.320122 -235.810531) (xy 91.312179 -235.863235) (xy 91.296469 -235.914165) (xy 91.273343 -235.962186)
			(xy 91.243319 -236.006223) (xy 91.207067 -236.045294) (xy 91.165396 -236.078525) (xy 91.119238 -236.105174)
			(xy 91.069624 -236.124646) (xy 91.017662 -236.136506) (xy 90.964512 -236.14049) (xy 90.911362 -236.136506)
			(xy 90.8594 -236.124646) (xy 90.809786 -236.105174) (xy 90.763628 -236.078525) (xy 90.721957 -236.045294)
			(xy 90.685705 -236.006223) (xy 90.655681 -235.962186) (xy 90.632555 -235.914165) (xy 90.616845 -235.863235)
			(xy 90.608902 -235.810531) (xy 90.380576 -235.810531) (xy 90.372633 -235.863235) (xy 90.356923 -235.914165)
			(xy 90.333797 -235.962186) (xy 90.303773 -236.006223) (xy 90.267521 -236.045294) (xy 90.22585 -236.078525)
			(xy 90.179692 -236.105174) (xy 90.130078 -236.124646) (xy 90.078116 -236.136506) (xy 90.024966 -236.14049)
			(xy 89.971816 -236.136506) (xy 89.919854 -236.124646) (xy 89.87024 -236.105174) (xy 89.824082 -236.078525)
			(xy 89.782411 -236.045294) (xy 89.746159 -236.006223) (xy 89.716135 -235.962186) (xy 89.693009 -235.914165)
			(xy 89.677299 -235.863235) (xy 89.669356 -235.810531) (xy 89.439854 -235.810531) (xy 89.437866 -235.837059)
			(xy 89.426003 -235.889031) (xy 89.406526 -235.938653) (xy 89.379871 -235.984819) (xy 89.346632 -236.026495)
			(xy 89.307552 -236.062752) (xy 89.263505 -236.092779) (xy 89.215475 -236.115906) (xy 89.164534 -236.131615)
			(xy 89.11182 -236.139555) (xy 89.085166 -236.13999) (xy 89.074793 -236.139944) (xy 89.054079 -236.138802)
			(xy 89.043764 -236.137704) (xy 89.029508 -236.136543) (xy 89.001308 -236.14126) (xy 88.975519 -236.153604)
			(xy 88.95416 -236.172609) (xy 88.938901 -236.196788) (xy 88.930937 -236.224247) (xy 88.93048 -236.238542)
			(xy 88.93048 -236.431836) (xy 88.93556 -236.44225) (xy 88.946864 -236.466633) (xy 88.962826 -236.517952)
			(xy 88.970902 -236.571085) (xy 88.970909 -236.624601) (xy 89.199202 -236.624601) (xy 89.199202 -236.571303)
			(xy 89.207145 -236.518599) (xy 89.222855 -236.467669) (xy 89.245981 -236.419648) (xy 89.276005 -236.375611)
			(xy 89.312257 -236.33654) (xy 89.353928 -236.303309) (xy 89.400086 -236.27666) (xy 89.4497 -236.257188)
			(xy 89.501662 -236.245328) (xy 89.554812 -236.241345) (xy 89.607962 -236.245328) (xy 89.659924 -236.257188)
			(xy 89.709538 -236.27666) (xy 89.755696 -236.303309) (xy 89.797367 -236.33654) (xy 89.833619 -236.375611)
			(xy 89.863643 -236.419648) (xy 89.886769 -236.467669) (xy 89.902479 -236.518599) (xy 89.910422 -236.571303)
			(xy 89.91092 -236.597952) (xy 89.910422 -236.624601) (xy 90.139002 -236.624601) (xy 90.139002 -236.571303)
			(xy 90.146945 -236.518599) (xy 90.162655 -236.467669) (xy 90.185781 -236.419648) (xy 90.215805 -236.375611)
			(xy 90.252057 -236.33654) (xy 90.293728 -236.303309) (xy 90.339886 -236.27666) (xy 90.3895 -236.257188)
			(xy 90.441462 -236.245328) (xy 90.494612 -236.241345) (xy 90.547762 -236.245328) (xy 90.599724 -236.257188)
			(xy 90.649338 -236.27666) (xy 90.695496 -236.303309) (xy 90.737167 -236.33654) (xy 90.773419 -236.375611)
			(xy 90.803443 -236.419648) (xy 90.826569 -236.467669) (xy 90.842279 -236.518599) (xy 90.850222 -236.571303)
			(xy 90.85072 -236.597952) (xy 90.850222 -236.624601) (xy 91.078802 -236.624601) (xy 91.078802 -236.571303)
			(xy 91.086745 -236.518599) (xy 91.102455 -236.467669) (xy 91.125581 -236.419648) (xy 91.155605 -236.375611)
			(xy 91.191857 -236.33654) (xy 91.233528 -236.303309) (xy 91.279686 -236.27666) (xy 91.3293 -236.257188)
			(xy 91.381262 -236.245328) (xy 91.434412 -236.241345) (xy 91.487562 -236.245328) (xy 91.539524 -236.257188)
			(xy 91.589138 -236.27666) (xy 91.635296 -236.303309) (xy 91.676967 -236.33654) (xy 91.713219 -236.375611)
			(xy 91.743243 -236.419648) (xy 91.766369 -236.467669) (xy 91.782079 -236.518599) (xy 91.790022 -236.571303)
			(xy 91.79052 -236.597952) (xy 91.790022 -236.624601) (xy 92.018602 -236.624601) (xy 92.018602 -236.571303)
			(xy 92.026545 -236.518599) (xy 92.042255 -236.467669) (xy 92.065381 -236.419648) (xy 92.095405 -236.375611)
			(xy 92.131657 -236.33654) (xy 92.173328 -236.303309) (xy 92.219486 -236.27666) (xy 92.2691 -236.257188)
			(xy 92.321062 -236.245328) (xy 92.374212 -236.241345) (xy 92.427362 -236.245328) (xy 92.479324 -236.257188)
			(xy 92.528938 -236.27666) (xy 92.575096 -236.303309) (xy 92.616767 -236.33654) (xy 92.653019 -236.375611)
			(xy 92.683043 -236.419648) (xy 92.706169 -236.467669) (xy 92.721879 -236.518599) (xy 92.729822 -236.571303)
			(xy 92.73032 -236.597952) (xy 92.729822 -236.624601) (xy 92.958402 -236.624601) (xy 92.958402 -236.571303)
			(xy 92.966345 -236.518599) (xy 92.982055 -236.467669) (xy 93.005181 -236.419648) (xy 93.035205 -236.375611)
			(xy 93.071457 -236.33654) (xy 93.113128 -236.303309) (xy 93.159286 -236.27666) (xy 93.2089 -236.257188)
			(xy 93.260862 -236.245328) (xy 93.314012 -236.241345) (xy 93.367162 -236.245328) (xy 93.419124 -236.257188)
			(xy 93.468738 -236.27666) (xy 93.514896 -236.303309) (xy 93.556567 -236.33654) (xy 93.592819 -236.375611)
			(xy 93.622843 -236.419648) (xy 93.645969 -236.467669) (xy 93.661679 -236.518599) (xy 93.669622 -236.571303)
			(xy 93.67012 -236.597952) (xy 93.669622 -236.624601) (xy 93.898456 -236.624601) (xy 93.898456 -236.571303)
			(xy 93.906399 -236.518599) (xy 93.922109 -236.467669) (xy 93.945235 -236.419648) (xy 93.975259 -236.375611)
			(xy 94.011511 -236.33654) (xy 94.053182 -236.303309) (xy 94.09934 -236.27666) (xy 94.148954 -236.257188)
			(xy 94.200916 -236.245328) (xy 94.254066 -236.241345) (xy 94.307216 -236.245328) (xy 94.359178 -236.257188)
			(xy 94.408792 -236.27666) (xy 94.45495 -236.303309) (xy 94.496621 -236.33654) (xy 94.532873 -236.375611)
			(xy 94.562897 -236.419648) (xy 94.586023 -236.467669) (xy 94.601733 -236.518599) (xy 94.609676 -236.571303)
			(xy 94.610174 -236.597952) (xy 94.609676 -236.624601) (xy 94.838002 -236.624601) (xy 94.838002 -236.571303)
			(xy 94.845945 -236.518599) (xy 94.861655 -236.467669) (xy 94.884781 -236.419648) (xy 94.914805 -236.375611)
			(xy 94.951057 -236.33654) (xy 94.992728 -236.303309) (xy 95.038886 -236.27666) (xy 95.0885 -236.257188)
			(xy 95.140462 -236.245328) (xy 95.193612 -236.241345) (xy 95.246762 -236.245328) (xy 95.298724 -236.257188)
			(xy 95.348338 -236.27666) (xy 95.394496 -236.303309) (xy 95.436167 -236.33654) (xy 95.472419 -236.375611)
			(xy 95.502443 -236.419648) (xy 95.525569 -236.467669) (xy 95.541279 -236.518599) (xy 95.549222 -236.571303)
			(xy 95.54972 -236.597952) (xy 95.549222 -236.624601) (xy 95.777802 -236.624601) (xy 95.777802 -236.571303)
			(xy 95.785745 -236.518599) (xy 95.801455 -236.467669) (xy 95.824581 -236.419648) (xy 95.854605 -236.375611)
			(xy 95.890857 -236.33654) (xy 95.932528 -236.303309) (xy 95.978686 -236.27666) (xy 96.0283 -236.257188)
			(xy 96.080262 -236.245328) (xy 96.133412 -236.241345) (xy 96.186562 -236.245328) (xy 96.238524 -236.257188)
			(xy 96.288138 -236.27666) (xy 96.334296 -236.303309) (xy 96.375967 -236.33654) (xy 96.412219 -236.375611)
			(xy 96.442243 -236.419648) (xy 96.465369 -236.467669) (xy 96.481079 -236.518599) (xy 96.489022 -236.571303)
			(xy 96.48952 -236.597952) (xy 96.489022 -236.624601) (xy 96.717602 -236.624601) (xy 96.717602 -236.571303)
			(xy 96.725545 -236.518599) (xy 96.741255 -236.467669) (xy 96.764381 -236.419648) (xy 96.794405 -236.375611)
			(xy 96.830657 -236.33654) (xy 96.872328 -236.303309) (xy 96.918486 -236.27666) (xy 96.9681 -236.257188)
			(xy 97.020062 -236.245328) (xy 97.073212 -236.241345) (xy 97.126362 -236.245328) (xy 97.178324 -236.257188)
			(xy 97.227938 -236.27666) (xy 97.274096 -236.303309) (xy 97.315767 -236.33654) (xy 97.352019 -236.375611)
			(xy 97.382043 -236.419648) (xy 97.405169 -236.467669) (xy 97.420879 -236.518599) (xy 97.428822 -236.571303)
			(xy 97.42932 -236.597952) (xy 97.428822 -236.624601) (xy 97.657402 -236.624601) (xy 97.657402 -236.571303)
			(xy 97.665345 -236.518599) (xy 97.681055 -236.467669) (xy 97.704181 -236.419648) (xy 97.734205 -236.375611)
			(xy 97.770457 -236.33654) (xy 97.812128 -236.303309) (xy 97.858286 -236.27666) (xy 97.9079 -236.257188)
			(xy 97.959862 -236.245328) (xy 98.013012 -236.241345) (xy 98.066162 -236.245328) (xy 98.118124 -236.257188)
			(xy 98.167738 -236.27666) (xy 98.213896 -236.303309) (xy 98.255567 -236.33654) (xy 98.291819 -236.375611)
			(xy 98.321843 -236.419648) (xy 98.344969 -236.467669) (xy 98.360679 -236.518599) (xy 98.368622 -236.571303)
			(xy 98.36912 -236.597952) (xy 98.368622 -236.624601) (xy 98.597202 -236.624601) (xy 98.597202 -236.571303)
			(xy 98.605145 -236.518599) (xy 98.620855 -236.467669) (xy 98.643981 -236.419648) (xy 98.674005 -236.375611)
			(xy 98.710257 -236.33654) (xy 98.751928 -236.303309) (xy 98.798086 -236.27666) (xy 98.8477 -236.257188)
			(xy 98.899662 -236.245328) (xy 98.952812 -236.241345) (xy 99.005962 -236.245328) (xy 99.057924 -236.257188)
			(xy 99.107538 -236.27666) (xy 99.153696 -236.303309) (xy 99.195367 -236.33654) (xy 99.231619 -236.375611)
			(xy 99.261643 -236.419648) (xy 99.284769 -236.467669) (xy 99.300479 -236.518599) (xy 99.308422 -236.571303)
			(xy 99.30892 -236.597952) (xy 99.308422 -236.624601) (xy 99.300479 -236.677305) (xy 99.284769 -236.728235)
			(xy 99.261643 -236.776256) (xy 99.231619 -236.820293) (xy 99.195367 -236.859364) (xy 99.153696 -236.892595)
			(xy 99.107538 -236.919244) (xy 99.057924 -236.938716) (xy 99.005962 -236.950576) (xy 98.952812 -236.95456)
			(xy 98.899662 -236.950576) (xy 98.8477 -236.938716) (xy 98.798086 -236.919244) (xy 98.751928 -236.892595)
			(xy 98.710257 -236.859364) (xy 98.674005 -236.820293) (xy 98.643981 -236.776256) (xy 98.620855 -236.728235)
			(xy 98.605145 -236.677305) (xy 98.597202 -236.624601) (xy 98.368622 -236.624601) (xy 98.360679 -236.677305)
			(xy 98.344969 -236.728235) (xy 98.321843 -236.776256) (xy 98.291819 -236.820293) (xy 98.255567 -236.859364)
			(xy 98.213896 -236.892595) (xy 98.167738 -236.919244) (xy 98.118124 -236.938716) (xy 98.066162 -236.950576)
			(xy 98.013012 -236.95456) (xy 97.959862 -236.950576) (xy 97.9079 -236.938716) (xy 97.858286 -236.919244)
			(xy 97.812128 -236.892595) (xy 97.770457 -236.859364) (xy 97.734205 -236.820293) (xy 97.704181 -236.776256)
			(xy 97.681055 -236.728235) (xy 97.665345 -236.677305) (xy 97.657402 -236.624601) (xy 97.428822 -236.624601)
			(xy 97.420879 -236.677305) (xy 97.405169 -236.728235) (xy 97.382043 -236.776256) (xy 97.352019 -236.820293)
			(xy 97.315767 -236.859364) (xy 97.274096 -236.892595) (xy 97.227938 -236.919244) (xy 97.178324 -236.938716)
			(xy 97.126362 -236.950576) (xy 97.073212 -236.95456) (xy 97.020062 -236.950576) (xy 96.9681 -236.938716)
			(xy 96.918486 -236.919244) (xy 96.872328 -236.892595) (xy 96.830657 -236.859364) (xy 96.794405 -236.820293)
			(xy 96.764381 -236.776256) (xy 96.741255 -236.728235) (xy 96.725545 -236.677305) (xy 96.717602 -236.624601)
			(xy 96.489022 -236.624601) (xy 96.481079 -236.677305) (xy 96.465369 -236.728235) (xy 96.442243 -236.776256)
			(xy 96.412219 -236.820293) (xy 96.375967 -236.859364) (xy 96.334296 -236.892595) (xy 96.288138 -236.919244)
			(xy 96.238524 -236.938716) (xy 96.186562 -236.950576) (xy 96.133412 -236.95456) (xy 96.080262 -236.950576)
			(xy 96.0283 -236.938716) (xy 95.978686 -236.919244) (xy 95.932528 -236.892595) (xy 95.890857 -236.859364)
			(xy 95.854605 -236.820293) (xy 95.824581 -236.776256) (xy 95.801455 -236.728235) (xy 95.785745 -236.677305)
			(xy 95.777802 -236.624601) (xy 95.549222 -236.624601) (xy 95.541279 -236.677305) (xy 95.525569 -236.728235)
			(xy 95.502443 -236.776256) (xy 95.472419 -236.820293) (xy 95.436167 -236.859364) (xy 95.394496 -236.892595)
			(xy 95.348338 -236.919244) (xy 95.298724 -236.938716) (xy 95.246762 -236.950576) (xy 95.193612 -236.95456)
			(xy 95.140462 -236.950576) (xy 95.0885 -236.938716) (xy 95.038886 -236.919244) (xy 94.992728 -236.892595)
			(xy 94.951057 -236.859364) (xy 94.914805 -236.820293) (xy 94.884781 -236.776256) (xy 94.861655 -236.728235)
			(xy 94.845945 -236.677305) (xy 94.838002 -236.624601) (xy 94.609676 -236.624601) (xy 94.601733 -236.677305)
			(xy 94.586023 -236.728235) (xy 94.562897 -236.776256) (xy 94.532873 -236.820293) (xy 94.496621 -236.859364)
			(xy 94.45495 -236.892595) (xy 94.408792 -236.919244) (xy 94.359178 -236.938716) (xy 94.307216 -236.950576)
			(xy 94.254066 -236.95456) (xy 94.200916 -236.950576) (xy 94.148954 -236.938716) (xy 94.09934 -236.919244)
			(xy 94.053182 -236.892595) (xy 94.011511 -236.859364) (xy 93.975259 -236.820293) (xy 93.945235 -236.776256)
			(xy 93.922109 -236.728235) (xy 93.906399 -236.677305) (xy 93.898456 -236.624601) (xy 93.669622 -236.624601)
			(xy 93.661679 -236.677305) (xy 93.645969 -236.728235) (xy 93.622843 -236.776256) (xy 93.592819 -236.820293)
			(xy 93.556567 -236.859364) (xy 93.514896 -236.892595) (xy 93.468738 -236.919244) (xy 93.419124 -236.938716)
			(xy 93.367162 -236.950576) (xy 93.314012 -236.95456) (xy 93.260862 -236.950576) (xy 93.2089 -236.938716)
			(xy 93.159286 -236.919244) (xy 93.113128 -236.892595) (xy 93.071457 -236.859364) (xy 93.035205 -236.820293)
			(xy 93.005181 -236.776256) (xy 92.982055 -236.728235) (xy 92.966345 -236.677305) (xy 92.958402 -236.624601)
			(xy 92.729822 -236.624601) (xy 92.721879 -236.677305) (xy 92.706169 -236.728235) (xy 92.683043 -236.776256)
			(xy 92.653019 -236.820293) (xy 92.616767 -236.859364) (xy 92.575096 -236.892595) (xy 92.528938 -236.919244)
			(xy 92.479324 -236.938716) (xy 92.427362 -236.950576) (xy 92.374212 -236.95456) (xy 92.321062 -236.950576)
			(xy 92.2691 -236.938716) (xy 92.219486 -236.919244) (xy 92.173328 -236.892595) (xy 92.131657 -236.859364)
			(xy 92.095405 -236.820293) (xy 92.065381 -236.776256) (xy 92.042255 -236.728235) (xy 92.026545 -236.677305)
			(xy 92.018602 -236.624601) (xy 91.790022 -236.624601) (xy 91.782079 -236.677305) (xy 91.766369 -236.728235)
			(xy 91.743243 -236.776256) (xy 91.713219 -236.820293) (xy 91.676967 -236.859364) (xy 91.635296 -236.892595)
			(xy 91.589138 -236.919244) (xy 91.539524 -236.938716) (xy 91.487562 -236.950576) (xy 91.434412 -236.95456)
			(xy 91.381262 -236.950576) (xy 91.3293 -236.938716) (xy 91.279686 -236.919244) (xy 91.233528 -236.892595)
			(xy 91.191857 -236.859364) (xy 91.155605 -236.820293) (xy 91.125581 -236.776256) (xy 91.102455 -236.728235)
			(xy 91.086745 -236.677305) (xy 91.078802 -236.624601) (xy 90.850222 -236.624601) (xy 90.842279 -236.677305)
			(xy 90.826569 -236.728235) (xy 90.803443 -236.776256) (xy 90.773419 -236.820293) (xy 90.737167 -236.859364)
			(xy 90.695496 -236.892595) (xy 90.649338 -236.919244) (xy 90.599724 -236.938716) (xy 90.547762 -236.950576)
			(xy 90.494612 -236.95456) (xy 90.441462 -236.950576) (xy 90.3895 -236.938716) (xy 90.339886 -236.919244)
			(xy 90.293728 -236.892595) (xy 90.252057 -236.859364) (xy 90.215805 -236.820293) (xy 90.185781 -236.776256)
			(xy 90.162655 -236.728235) (xy 90.146945 -236.677305) (xy 90.139002 -236.624601) (xy 89.910422 -236.624601)
			(xy 89.902479 -236.677305) (xy 89.886769 -236.728235) (xy 89.863643 -236.776256) (xy 89.833619 -236.820293)
			(xy 89.797367 -236.859364) (xy 89.755696 -236.892595) (xy 89.709538 -236.919244) (xy 89.659924 -236.938716)
			(xy 89.607962 -236.950576) (xy 89.554812 -236.95456) (xy 89.501662 -236.950576) (xy 89.4497 -236.938716)
			(xy 89.400086 -236.919244) (xy 89.353928 -236.892595) (xy 89.312257 -236.859364) (xy 89.276005 -236.820293)
			(xy 89.245981 -236.776256) (xy 89.222855 -236.728235) (xy 89.207145 -236.677305) (xy 89.199202 -236.624601)
			(xy 88.970909 -236.624601) (xy 88.970909 -236.624829) (xy 88.962846 -236.677964) (xy 88.946896 -236.729286)
			(xy 88.93556 -236.753654) (xy 88.93048 -236.764068) (xy 88.93048 -236.956854) (xy 88.930959 -236.97115)
			(xy 88.938887 -236.998621) (xy 88.954132 -237.02281) (xy 88.975494 -237.041814) (xy 89.001294 -237.054139)
			(xy 89.029501 -237.058813) (xy 89.043764 -237.057692) (xy 89.054078 -237.056589) (xy 89.074793 -237.055446)
			(xy 89.085166 -237.055406) (xy 89.111818 -237.055877) (xy 89.164527 -237.063817) (xy 89.215463 -237.079524)
			(xy 89.263489 -237.102648) (xy 89.307532 -237.132673) (xy 89.346608 -237.168926) (xy 89.379844 -237.210599)
			(xy 89.406497 -237.25676) (xy 89.425973 -237.306379) (xy 89.437834 -237.358346) (xy 89.441818 -237.4115)
			(xy 89.43982 -237.438163) (xy 89.669356 -237.438163) (xy 89.669356 -237.384865) (xy 89.677299 -237.332161)
			(xy 89.693009 -237.281231) (xy 89.716135 -237.23321) (xy 89.746159 -237.189173) (xy 89.782411 -237.150102)
			(xy 89.824082 -237.116871) (xy 89.87024 -237.090222) (xy 89.919854 -237.07075) (xy 89.971816 -237.05889)
			(xy 90.024966 -237.054907) (xy 90.078116 -237.05889) (xy 90.130078 -237.07075) (xy 90.179692 -237.090222)
			(xy 90.22585 -237.116871) (xy 90.267521 -237.150102) (xy 90.303773 -237.189173) (xy 90.333797 -237.23321)
			(xy 90.356923 -237.281231) (xy 90.372633 -237.332161) (xy 90.380576 -237.384865) (xy 90.381074 -237.411514)
			(xy 90.380576 -237.438163) (xy 90.609156 -237.438163) (xy 90.609156 -237.384865) (xy 90.617099 -237.332161)
			(xy 90.632809 -237.281231) (xy 90.655935 -237.23321) (xy 90.685959 -237.189173) (xy 90.722211 -237.150102)
			(xy 90.763882 -237.116871) (xy 90.81004 -237.090222) (xy 90.859654 -237.07075) (xy 90.911616 -237.05889)
			(xy 90.964766 -237.054907) (xy 91.017916 -237.05889) (xy 91.069878 -237.07075) (xy 91.119492 -237.090222)
			(xy 91.16565 -237.116871) (xy 91.207321 -237.150102) (xy 91.243573 -237.189173) (xy 91.273597 -237.23321)
			(xy 91.296723 -237.281231) (xy 91.312433 -237.332161) (xy 91.320376 -237.384865) (xy 91.320874 -237.411514)
			(xy 91.320376 -237.438163) (xy 91.548702 -237.438163) (xy 91.548702 -237.384865) (xy 91.556645 -237.332161)
			(xy 91.572355 -237.281231) (xy 91.595481 -237.23321) (xy 91.625505 -237.189173) (xy 91.661757 -237.150102)
			(xy 91.703428 -237.116871) (xy 91.749586 -237.090222) (xy 91.7992 -237.07075) (xy 91.851162 -237.05889)
			(xy 91.904312 -237.054907) (xy 91.957462 -237.05889) (xy 92.009424 -237.07075) (xy 92.059038 -237.090222)
			(xy 92.105196 -237.116871) (xy 92.146867 -237.150102) (xy 92.183119 -237.189173) (xy 92.213143 -237.23321)
			(xy 92.236269 -237.281231) (xy 92.251979 -237.332161) (xy 92.259922 -237.384865) (xy 92.26042 -237.411514)
			(xy 92.259922 -237.438163) (xy 92.488756 -237.438163) (xy 92.488756 -237.384865) (xy 92.496699 -237.332161)
			(xy 92.512409 -237.281231) (xy 92.535535 -237.23321) (xy 92.565559 -237.189173) (xy 92.601811 -237.150102)
			(xy 92.643482 -237.116871) (xy 92.68964 -237.090222) (xy 92.739254 -237.07075) (xy 92.791216 -237.05889)
			(xy 92.844366 -237.054907) (xy 92.897516 -237.05889) (xy 92.949478 -237.07075) (xy 92.999092 -237.090222)
			(xy 93.04525 -237.116871) (xy 93.086921 -237.150102) (xy 93.123173 -237.189173) (xy 93.153197 -237.23321)
			(xy 93.176323 -237.281231) (xy 93.192033 -237.332161) (xy 93.199976 -237.384865) (xy 93.200474 -237.411514)
			(xy 93.199976 -237.438163) (xy 93.428556 -237.438163) (xy 93.428556 -237.384865) (xy 93.436499 -237.332161)
			(xy 93.452209 -237.281231) (xy 93.475335 -237.23321) (xy 93.505359 -237.189173) (xy 93.541611 -237.150102)
			(xy 93.583282 -237.116871) (xy 93.62944 -237.090222) (xy 93.679054 -237.07075) (xy 93.731016 -237.05889)
			(xy 93.784166 -237.054907) (xy 93.837316 -237.05889) (xy 93.889278 -237.07075) (xy 93.938892 -237.090222)
			(xy 93.98505 -237.116871) (xy 94.026721 -237.150102) (xy 94.062973 -237.189173) (xy 94.092997 -237.23321)
			(xy 94.116123 -237.281231) (xy 94.131833 -237.332161) (xy 94.139776 -237.384865) (xy 94.140274 -237.411514)
			(xy 94.139776 -237.438163) (xy 94.368356 -237.438163) (xy 94.368356 -237.384865) (xy 94.376299 -237.332161)
			(xy 94.392009 -237.281231) (xy 94.415135 -237.23321) (xy 94.445159 -237.189173) (xy 94.481411 -237.150102)
			(xy 94.523082 -237.116871) (xy 94.56924 -237.090222) (xy 94.618854 -237.07075) (xy 94.670816 -237.05889)
			(xy 94.723966 -237.054907) (xy 94.777116 -237.05889) (xy 94.829078 -237.07075) (xy 94.878692 -237.090222)
			(xy 94.92485 -237.116871) (xy 94.966521 -237.150102) (xy 95.002773 -237.189173) (xy 95.032797 -237.23321)
			(xy 95.055923 -237.281231) (xy 95.071633 -237.332161) (xy 95.079576 -237.384865) (xy 95.080074 -237.411514)
			(xy 95.079576 -237.438163) (xy 95.308156 -237.438163) (xy 95.308156 -237.384865) (xy 95.316099 -237.332161)
			(xy 95.331809 -237.281231) (xy 95.354935 -237.23321) (xy 95.384959 -237.189173) (xy 95.421211 -237.150102)
			(xy 95.462882 -237.116871) (xy 95.50904 -237.090222) (xy 95.558654 -237.07075) (xy 95.610616 -237.05889)
			(xy 95.663766 -237.054907) (xy 95.716916 -237.05889) (xy 95.768878 -237.07075) (xy 95.818492 -237.090222)
			(xy 95.86465 -237.116871) (xy 95.906321 -237.150102) (xy 95.942573 -237.189173) (xy 95.972597 -237.23321)
			(xy 95.995723 -237.281231) (xy 96.011433 -237.332161) (xy 96.019376 -237.384865) (xy 96.019874 -237.411514)
			(xy 96.019376 -237.438163) (xy 96.247956 -237.438163) (xy 96.247956 -237.384865) (xy 96.255899 -237.332161)
			(xy 96.271609 -237.281231) (xy 96.294735 -237.23321) (xy 96.324759 -237.189173) (xy 96.361011 -237.150102)
			(xy 96.402682 -237.116871) (xy 96.44884 -237.090222) (xy 96.498454 -237.07075) (xy 96.550416 -237.05889)
			(xy 96.603566 -237.054907) (xy 96.656716 -237.05889) (xy 96.708678 -237.07075) (xy 96.758292 -237.090222)
			(xy 96.80445 -237.116871) (xy 96.846121 -237.150102) (xy 96.882373 -237.189173) (xy 96.912397 -237.23321)
			(xy 96.935523 -237.281231) (xy 96.951233 -237.332161) (xy 96.959176 -237.384865) (xy 96.959674 -237.411514)
			(xy 96.959176 -237.438163) (xy 97.187756 -237.438163) (xy 97.187756 -237.384865) (xy 97.195699 -237.332161)
			(xy 97.211409 -237.281231) (xy 97.234535 -237.23321) (xy 97.264559 -237.189173) (xy 97.300811 -237.150102)
			(xy 97.342482 -237.116871) (xy 97.38864 -237.090222) (xy 97.438254 -237.07075) (xy 97.490216 -237.05889)
			(xy 97.543366 -237.054907) (xy 97.596516 -237.05889) (xy 97.648478 -237.07075) (xy 97.698092 -237.090222)
			(xy 97.74425 -237.116871) (xy 97.785921 -237.150102) (xy 97.822173 -237.189173) (xy 97.852197 -237.23321)
			(xy 97.875323 -237.281231) (xy 97.891033 -237.332161) (xy 97.898976 -237.384865) (xy 97.899474 -237.411514)
			(xy 97.898976 -237.438163) (xy 98.127302 -237.438163) (xy 98.127302 -237.384865) (xy 98.135245 -237.332161)
			(xy 98.150955 -237.281231) (xy 98.174081 -237.23321) (xy 98.204105 -237.189173) (xy 98.240357 -237.150102)
			(xy 98.282028 -237.116871) (xy 98.328186 -237.090222) (xy 98.3778 -237.07075) (xy 98.429762 -237.05889)
			(xy 98.482912 -237.054907) (xy 98.536062 -237.05889) (xy 98.588024 -237.07075) (xy 98.637638 -237.090222)
			(xy 98.683796 -237.116871) (xy 98.725467 -237.150102) (xy 98.761719 -237.189173) (xy 98.791743 -237.23321)
			(xy 98.814869 -237.281231) (xy 98.830579 -237.332161) (xy 98.838522 -237.384865) (xy 98.83902 -237.411514)
			(xy 98.838522 -237.438163) (xy 98.830579 -237.490867) (xy 98.814869 -237.541797) (xy 98.791743 -237.589818)
			(xy 98.761719 -237.633855) (xy 98.725467 -237.672926) (xy 98.683796 -237.706157) (xy 98.637638 -237.732806)
			(xy 98.588024 -237.752278) (xy 98.536062 -237.764138) (xy 98.482912 -237.768122) (xy 98.429762 -237.764138)
			(xy 98.3778 -237.752278) (xy 98.328186 -237.732806) (xy 98.282028 -237.706157) (xy 98.240357 -237.672926)
			(xy 98.204105 -237.633855) (xy 98.174081 -237.589818) (xy 98.150955 -237.541797) (xy 98.135245 -237.490867)
			(xy 98.127302 -237.438163) (xy 97.898976 -237.438163) (xy 97.891033 -237.490867) (xy 97.875323 -237.541797)
			(xy 97.852197 -237.589818) (xy 97.822173 -237.633855) (xy 97.785921 -237.672926) (xy 97.74425 -237.706157)
			(xy 97.698092 -237.732806) (xy 97.648478 -237.752278) (xy 97.596516 -237.764138) (xy 97.543366 -237.768122)
			(xy 97.490216 -237.764138) (xy 97.438254 -237.752278) (xy 97.38864 -237.732806) (xy 97.342482 -237.706157)
			(xy 97.300811 -237.672926) (xy 97.264559 -237.633855) (xy 97.234535 -237.589818) (xy 97.211409 -237.541797)
			(xy 97.195699 -237.490867) (xy 97.187756 -237.438163) (xy 96.959176 -237.438163) (xy 96.951233 -237.490867)
			(xy 96.935523 -237.541797) (xy 96.912397 -237.589818) (xy 96.882373 -237.633855) (xy 96.846121 -237.672926)
			(xy 96.80445 -237.706157) (xy 96.758292 -237.732806) (xy 96.708678 -237.752278) (xy 96.656716 -237.764138)
			(xy 96.603566 -237.768122) (xy 96.550416 -237.764138) (xy 96.498454 -237.752278) (xy 96.44884 -237.732806)
			(xy 96.402682 -237.706157) (xy 96.361011 -237.672926) (xy 96.324759 -237.633855) (xy 96.294735 -237.589818)
			(xy 96.271609 -237.541797) (xy 96.255899 -237.490867) (xy 96.247956 -237.438163) (xy 96.019376 -237.438163)
			(xy 96.011433 -237.490867) (xy 95.995723 -237.541797) (xy 95.972597 -237.589818) (xy 95.942573 -237.633855)
			(xy 95.906321 -237.672926) (xy 95.86465 -237.706157) (xy 95.818492 -237.732806) (xy 95.768878 -237.752278)
			(xy 95.716916 -237.764138) (xy 95.663766 -237.768122) (xy 95.610616 -237.764138) (xy 95.558654 -237.752278)
			(xy 95.50904 -237.732806) (xy 95.462882 -237.706157) (xy 95.421211 -237.672926) (xy 95.384959 -237.633855)
			(xy 95.354935 -237.589818) (xy 95.331809 -237.541797) (xy 95.316099 -237.490867) (xy 95.308156 -237.438163)
			(xy 95.079576 -237.438163) (xy 95.071633 -237.490867) (xy 95.055923 -237.541797) (xy 95.032797 -237.589818)
			(xy 95.002773 -237.633855) (xy 94.966521 -237.672926) (xy 94.92485 -237.706157) (xy 94.878692 -237.732806)
			(xy 94.829078 -237.752278) (xy 94.777116 -237.764138) (xy 94.723966 -237.768122) (xy 94.670816 -237.764138)
			(xy 94.618854 -237.752278) (xy 94.56924 -237.732806) (xy 94.523082 -237.706157) (xy 94.481411 -237.672926)
			(xy 94.445159 -237.633855) (xy 94.415135 -237.589818) (xy 94.392009 -237.541797) (xy 94.376299 -237.490867)
			(xy 94.368356 -237.438163) (xy 94.139776 -237.438163) (xy 94.131833 -237.490867) (xy 94.116123 -237.541797)
			(xy 94.092997 -237.589818) (xy 94.062973 -237.633855) (xy 94.026721 -237.672926) (xy 93.98505 -237.706157)
			(xy 93.938892 -237.732806) (xy 93.889278 -237.752278) (xy 93.837316 -237.764138) (xy 93.784166 -237.768122)
			(xy 93.731016 -237.764138) (xy 93.679054 -237.752278) (xy 93.62944 -237.732806) (xy 93.583282 -237.706157)
			(xy 93.541611 -237.672926) (xy 93.505359 -237.633855) (xy 93.475335 -237.589818) (xy 93.452209 -237.541797)
			(xy 93.436499 -237.490867) (xy 93.428556 -237.438163) (xy 93.199976 -237.438163) (xy 93.192033 -237.490867)
			(xy 93.176323 -237.541797) (xy 93.153197 -237.589818) (xy 93.123173 -237.633855) (xy 93.086921 -237.672926)
			(xy 93.04525 -237.706157) (xy 92.999092 -237.732806) (xy 92.949478 -237.752278) (xy 92.897516 -237.764138)
			(xy 92.844366 -237.768122) (xy 92.791216 -237.764138) (xy 92.739254 -237.752278) (xy 92.68964 -237.732806)
			(xy 92.643482 -237.706157) (xy 92.601811 -237.672926) (xy 92.565559 -237.633855) (xy 92.535535 -237.589818)
			(xy 92.512409 -237.541797) (xy 92.496699 -237.490867) (xy 92.488756 -237.438163) (xy 92.259922 -237.438163)
			(xy 92.251979 -237.490867) (xy 92.236269 -237.541797) (xy 92.213143 -237.589818) (xy 92.183119 -237.633855)
			(xy 92.146867 -237.672926) (xy 92.105196 -237.706157) (xy 92.059038 -237.732806) (xy 92.009424 -237.752278)
			(xy 91.957462 -237.764138) (xy 91.904312 -237.768122) (xy 91.851162 -237.764138) (xy 91.7992 -237.752278)
			(xy 91.749586 -237.732806) (xy 91.703428 -237.706157) (xy 91.661757 -237.672926) (xy 91.625505 -237.633855)
			(xy 91.595481 -237.589818) (xy 91.572355 -237.541797) (xy 91.556645 -237.490867) (xy 91.548702 -237.438163)
			(xy 91.320376 -237.438163) (xy 91.312433 -237.490867) (xy 91.296723 -237.541797) (xy 91.273597 -237.589818)
			(xy 91.243573 -237.633855) (xy 91.207321 -237.672926) (xy 91.16565 -237.706157) (xy 91.119492 -237.732806)
			(xy 91.069878 -237.752278) (xy 91.017916 -237.764138) (xy 90.964766 -237.768122) (xy 90.911616 -237.764138)
			(xy 90.859654 -237.752278) (xy 90.81004 -237.732806) (xy 90.763882 -237.706157) (xy 90.722211 -237.672926)
			(xy 90.685959 -237.633855) (xy 90.655935 -237.589818) (xy 90.632809 -237.541797) (xy 90.617099 -237.490867)
			(xy 90.609156 -237.438163) (xy 90.380576 -237.438163) (xy 90.372633 -237.490867) (xy 90.356923 -237.541797)
			(xy 90.333797 -237.589818) (xy 90.303773 -237.633855) (xy 90.267521 -237.672926) (xy 90.22585 -237.706157)
			(xy 90.179692 -237.732806) (xy 90.130078 -237.752278) (xy 90.078116 -237.764138) (xy 90.024966 -237.768122)
			(xy 89.971816 -237.764138) (xy 89.919854 -237.752278) (xy 89.87024 -237.732806) (xy 89.824082 -237.706157)
			(xy 89.782411 -237.672926) (xy 89.746159 -237.633855) (xy 89.716135 -237.589818) (xy 89.693009 -237.541797)
			(xy 89.677299 -237.490867) (xy 89.669356 -237.438163) (xy 89.43982 -237.438163) (xy 89.437834 -237.464654)
			(xy 89.425973 -237.516621) (xy 89.406497 -237.56624) (xy 89.379844 -237.612401) (xy 89.346608 -237.654074)
			(xy 89.307532 -237.690327) (xy 89.263489 -237.720352) (xy 89.215463 -237.743476) (xy 89.164527 -237.759183)
			(xy 89.111818 -237.767123) (xy 89.085166 -237.767622) (xy 89.074793 -237.767576) (xy 89.054079 -237.766434)
			(xy 89.043764 -237.765336) (xy 89.029509 -237.764175) (xy 89.001313 -237.768892) (xy 88.975528 -237.781236)
			(xy 88.954173 -237.800243) (xy 88.93892 -237.824422) (xy 88.930965 -237.851881) (xy 88.93048 -237.866174)
			(xy 88.93048 -238.059976) (xy 88.93556 -238.07039) (xy 88.94679 -238.094703) (xy 88.96264 -238.145858)
			(xy 88.970656 -238.198809) (xy 88.970658 -238.252233) (xy 89.199202 -238.252233) (xy 89.199202 -238.198935)
			(xy 89.207145 -238.146231) (xy 89.222855 -238.095301) (xy 89.245981 -238.04728) (xy 89.276005 -238.003243)
			(xy 89.312257 -237.964172) (xy 89.353928 -237.930941) (xy 89.400086 -237.904292) (xy 89.4497 -237.88482)
			(xy 89.501662 -237.87296) (xy 89.554812 -237.868977) (xy 89.607962 -237.87296) (xy 89.659924 -237.88482)
			(xy 89.709538 -237.904292) (xy 89.755696 -237.930941) (xy 89.797367 -237.964172) (xy 89.833619 -238.003243)
			(xy 89.863643 -238.04728) (xy 89.886769 -238.095301) (xy 89.902479 -238.146231) (xy 89.910422 -238.198935)
			(xy 89.91092 -238.225584) (xy 89.910422 -238.252233) (xy 90.139002 -238.252233) (xy 90.139002 -238.198935)
			(xy 90.146945 -238.146231) (xy 90.162655 -238.095301) (xy 90.185781 -238.04728) (xy 90.215805 -238.003243)
			(xy 90.252057 -237.964172) (xy 90.293728 -237.930941) (xy 90.339886 -237.904292) (xy 90.3895 -237.88482)
			(xy 90.441462 -237.87296) (xy 90.494612 -237.868977) (xy 90.547762 -237.87296) (xy 90.599724 -237.88482)
			(xy 90.649338 -237.904292) (xy 90.695496 -237.930941) (xy 90.737167 -237.964172) (xy 90.773419 -238.003243)
			(xy 90.803443 -238.04728) (xy 90.826569 -238.095301) (xy 90.842279 -238.146231) (xy 90.850222 -238.198935)
			(xy 90.85072 -238.225584) (xy 90.850222 -238.252233) (xy 91.079056 -238.252233) (xy 91.079056 -238.198935)
			(xy 91.086999 -238.146231) (xy 91.102709 -238.095301) (xy 91.125835 -238.04728) (xy 91.155859 -238.003243)
			(xy 91.192111 -237.964172) (xy 91.233782 -237.930941) (xy 91.27994 -237.904292) (xy 91.329554 -237.88482)
			(xy 91.381516 -237.87296) (xy 91.434666 -237.868977) (xy 91.487816 -237.87296) (xy 91.539778 -237.88482)
			(xy 91.589392 -237.904292) (xy 91.63555 -237.930941) (xy 91.677221 -237.964172) (xy 91.713473 -238.003243)
			(xy 91.743497 -238.04728) (xy 91.766623 -238.095301) (xy 91.782333 -238.146231) (xy 91.790276 -238.198935)
			(xy 91.790774 -238.225584) (xy 91.790276 -238.252233) (xy 92.018602 -238.252233) (xy 92.018602 -238.198935)
			(xy 92.026545 -238.146231) (xy 92.042255 -238.095301) (xy 92.065381 -238.04728) (xy 92.095405 -238.003243)
			(xy 92.131657 -237.964172) (xy 92.173328 -237.930941) (xy 92.219486 -237.904292) (xy 92.2691 -237.88482)
			(xy 92.321062 -237.87296) (xy 92.374212 -237.868977) (xy 92.427362 -237.87296) (xy 92.479324 -237.88482)
			(xy 92.528938 -237.904292) (xy 92.575096 -237.930941) (xy 92.616767 -237.964172) (xy 92.653019 -238.003243)
			(xy 92.683043 -238.04728) (xy 92.706169 -238.095301) (xy 92.721879 -238.146231) (xy 92.729822 -238.198935)
			(xy 92.73032 -238.225584) (xy 92.729822 -238.252233) (xy 92.958402 -238.252233) (xy 92.958402 -238.198935)
			(xy 92.966345 -238.146231) (xy 92.982055 -238.095301) (xy 93.005181 -238.04728) (xy 93.035205 -238.003243)
			(xy 93.071457 -237.964172) (xy 93.113128 -237.930941) (xy 93.159286 -237.904292) (xy 93.2089 -237.88482)
			(xy 93.260862 -237.87296) (xy 93.314012 -237.868977) (xy 93.367162 -237.87296) (xy 93.419124 -237.88482)
			(xy 93.468738 -237.904292) (xy 93.514896 -237.930941) (xy 93.556567 -237.964172) (xy 93.592819 -238.003243)
			(xy 93.622843 -238.04728) (xy 93.645969 -238.095301) (xy 93.661679 -238.146231) (xy 93.669622 -238.198935)
			(xy 93.67012 -238.225584) (xy 93.669622 -238.252233) (xy 93.898202 -238.252233) (xy 93.898202 -238.198935)
			(xy 93.906145 -238.146231) (xy 93.921855 -238.095301) (xy 93.944981 -238.04728) (xy 93.975005 -238.003243)
			(xy 94.011257 -237.964172) (xy 94.052928 -237.930941) (xy 94.099086 -237.904292) (xy 94.1487 -237.88482)
			(xy 94.200662 -237.87296) (xy 94.253812 -237.868977) (xy 94.306962 -237.87296) (xy 94.358924 -237.88482)
			(xy 94.408538 -237.904292) (xy 94.454696 -237.930941) (xy 94.496367 -237.964172) (xy 94.532619 -238.003243)
			(xy 94.562643 -238.04728) (xy 94.585769 -238.095301) (xy 94.601479 -238.146231) (xy 94.609422 -238.198935)
			(xy 94.60992 -238.225584) (xy 94.609422 -238.252233) (xy 94.838002 -238.252233) (xy 94.838002 -238.198935)
			(xy 94.845945 -238.146231) (xy 94.861655 -238.095301) (xy 94.884781 -238.04728) (xy 94.914805 -238.003243)
			(xy 94.951057 -237.964172) (xy 94.992728 -237.930941) (xy 95.038886 -237.904292) (xy 95.0885 -237.88482)
			(xy 95.140462 -237.87296) (xy 95.193612 -237.868977) (xy 95.246762 -237.87296) (xy 95.298724 -237.88482)
			(xy 95.348338 -237.904292) (xy 95.394496 -237.930941) (xy 95.436167 -237.964172) (xy 95.472419 -238.003243)
			(xy 95.502443 -238.04728) (xy 95.525569 -238.095301) (xy 95.541279 -238.146231) (xy 95.549222 -238.198935)
			(xy 95.54972 -238.225584) (xy 95.549222 -238.252233) (xy 95.777802 -238.252233) (xy 95.777802 -238.198935)
			(xy 95.785745 -238.146231) (xy 95.801455 -238.095301) (xy 95.824581 -238.04728) (xy 95.854605 -238.003243)
			(xy 95.890857 -237.964172) (xy 95.932528 -237.930941) (xy 95.978686 -237.904292) (xy 96.0283 -237.88482)
			(xy 96.080262 -237.87296) (xy 96.133412 -237.868977) (xy 96.186562 -237.87296) (xy 96.238524 -237.88482)
			(xy 96.288138 -237.904292) (xy 96.334296 -237.930941) (xy 96.375967 -237.964172) (xy 96.412219 -238.003243)
			(xy 96.442243 -238.04728) (xy 96.465369 -238.095301) (xy 96.481079 -238.146231) (xy 96.489022 -238.198935)
			(xy 96.48952 -238.225584) (xy 96.489022 -238.252233) (xy 96.717602 -238.252233) (xy 96.717602 -238.198935)
			(xy 96.725545 -238.146231) (xy 96.741255 -238.095301) (xy 96.764381 -238.04728) (xy 96.794405 -238.003243)
			(xy 96.830657 -237.964172) (xy 96.872328 -237.930941) (xy 96.918486 -237.904292) (xy 96.9681 -237.88482)
			(xy 97.020062 -237.87296) (xy 97.073212 -237.868977) (xy 97.126362 -237.87296) (xy 97.178324 -237.88482)
			(xy 97.227938 -237.904292) (xy 97.274096 -237.930941) (xy 97.315767 -237.964172) (xy 97.352019 -238.003243)
			(xy 97.382043 -238.04728) (xy 97.405169 -238.095301) (xy 97.420879 -238.146231) (xy 97.428822 -238.198935)
			(xy 97.42932 -238.225584) (xy 97.428822 -238.252233) (xy 97.657656 -238.252233) (xy 97.657656 -238.198935)
			(xy 97.665599 -238.146231) (xy 97.681309 -238.095301) (xy 97.704435 -238.04728) (xy 97.734459 -238.003243)
			(xy 97.770711 -237.964172) (xy 97.812382 -237.930941) (xy 97.85854 -237.904292) (xy 97.908154 -237.88482)
			(xy 97.960116 -237.87296) (xy 98.013266 -237.868977) (xy 98.066416 -237.87296) (xy 98.118378 -237.88482)
			(xy 98.167992 -237.904292) (xy 98.21415 -237.930941) (xy 98.255821 -237.964172) (xy 98.292073 -238.003243)
			(xy 98.322097 -238.04728) (xy 98.345223 -238.095301) (xy 98.360933 -238.146231) (xy 98.368876 -238.198935)
			(xy 98.369374 -238.225584) (xy 98.368876 -238.252233) (xy 98.597202 -238.252233) (xy 98.597202 -238.198935)
			(xy 98.605145 -238.146231) (xy 98.620855 -238.095301) (xy 98.643981 -238.04728) (xy 98.674005 -238.003243)
			(xy 98.710257 -237.964172) (xy 98.751928 -237.930941) (xy 98.798086 -237.904292) (xy 98.8477 -237.88482)
			(xy 98.899662 -237.87296) (xy 98.952812 -237.868977) (xy 99.005962 -237.87296) (xy 99.057924 -237.88482)
			(xy 99.107538 -237.904292) (xy 99.153696 -237.930941) (xy 99.195367 -237.964172) (xy 99.231619 -238.003243)
			(xy 99.261643 -238.04728) (xy 99.284769 -238.095301) (xy 99.300479 -238.146231) (xy 99.308422 -238.198935)
			(xy 99.30892 -238.225584) (xy 99.308422 -238.252233) (xy 99.300479 -238.304937) (xy 99.284769 -238.355867)
			(xy 99.261643 -238.403888) (xy 99.231619 -238.447925) (xy 99.195367 -238.486996) (xy 99.153696 -238.520227)
			(xy 99.107538 -238.546876) (xy 99.057924 -238.566348) (xy 99.005962 -238.578208) (xy 98.952812 -238.582192)
			(xy 98.899662 -238.578208) (xy 98.8477 -238.566348) (xy 98.798086 -238.546876) (xy 98.751928 -238.520227)
			(xy 98.710257 -238.486996) (xy 98.674005 -238.447925) (xy 98.643981 -238.403888) (xy 98.620855 -238.355867)
			(xy 98.605145 -238.304937) (xy 98.597202 -238.252233) (xy 98.368876 -238.252233) (xy 98.360933 -238.304937)
			(xy 98.345223 -238.355867) (xy 98.322097 -238.403888) (xy 98.292073 -238.447925) (xy 98.255821 -238.486996)
			(xy 98.21415 -238.520227) (xy 98.167992 -238.546876) (xy 98.118378 -238.566348) (xy 98.066416 -238.578208)
			(xy 98.013266 -238.582192) (xy 97.960116 -238.578208) (xy 97.908154 -238.566348) (xy 97.85854 -238.546876)
			(xy 97.812382 -238.520227) (xy 97.770711 -238.486996) (xy 97.734459 -238.447925) (xy 97.704435 -238.403888)
			(xy 97.681309 -238.355867) (xy 97.665599 -238.304937) (xy 97.657656 -238.252233) (xy 97.428822 -238.252233)
			(xy 97.420879 -238.304937) (xy 97.405169 -238.355867) (xy 97.382043 -238.403888) (xy 97.352019 -238.447925)
			(xy 97.315767 -238.486996) (xy 97.274096 -238.520227) (xy 97.227938 -238.546876) (xy 97.178324 -238.566348)
			(xy 97.126362 -238.578208) (xy 97.073212 -238.582192) (xy 97.020062 -238.578208) (xy 96.9681 -238.566348)
			(xy 96.918486 -238.546876) (xy 96.872328 -238.520227) (xy 96.830657 -238.486996) (xy 96.794405 -238.447925)
			(xy 96.764381 -238.403888) (xy 96.741255 -238.355867) (xy 96.725545 -238.304937) (xy 96.717602 -238.252233)
			(xy 96.489022 -238.252233) (xy 96.481079 -238.304937) (xy 96.465369 -238.355867) (xy 96.442243 -238.403888)
			(xy 96.412219 -238.447925) (xy 96.375967 -238.486996) (xy 96.334296 -238.520227) (xy 96.288138 -238.546876)
			(xy 96.238524 -238.566348) (xy 96.186562 -238.578208) (xy 96.133412 -238.582192) (xy 96.080262 -238.578208)
			(xy 96.0283 -238.566348) (xy 95.978686 -238.546876) (xy 95.932528 -238.520227) (xy 95.890857 -238.486996)
			(xy 95.854605 -238.447925) (xy 95.824581 -238.403888) (xy 95.801455 -238.355867) (xy 95.785745 -238.304937)
			(xy 95.777802 -238.252233) (xy 95.549222 -238.252233) (xy 95.541279 -238.304937) (xy 95.525569 -238.355867)
			(xy 95.502443 -238.403888) (xy 95.472419 -238.447925) (xy 95.436167 -238.486996) (xy 95.394496 -238.520227)
			(xy 95.348338 -238.546876) (xy 95.298724 -238.566348) (xy 95.246762 -238.578208) (xy 95.193612 -238.582192)
			(xy 95.140462 -238.578208) (xy 95.0885 -238.566348) (xy 95.038886 -238.546876) (xy 94.992728 -238.520227)
			(xy 94.951057 -238.486996) (xy 94.914805 -238.447925) (xy 94.884781 -238.403888) (xy 94.861655 -238.355867)
			(xy 94.845945 -238.304937) (xy 94.838002 -238.252233) (xy 94.609422 -238.252233) (xy 94.601479 -238.304937)
			(xy 94.585769 -238.355867) (xy 94.562643 -238.403888) (xy 94.532619 -238.447925) (xy 94.496367 -238.486996)
			(xy 94.454696 -238.520227) (xy 94.408538 -238.546876) (xy 94.358924 -238.566348) (xy 94.306962 -238.578208)
			(xy 94.253812 -238.582192) (xy 94.200662 -238.578208) (xy 94.1487 -238.566348) (xy 94.099086 -238.546876)
			(xy 94.052928 -238.520227) (xy 94.011257 -238.486996) (xy 93.975005 -238.447925) (xy 93.944981 -238.403888)
			(xy 93.921855 -238.355867) (xy 93.906145 -238.304937) (xy 93.898202 -238.252233) (xy 93.669622 -238.252233)
			(xy 93.661679 -238.304937) (xy 93.645969 -238.355867) (xy 93.622843 -238.403888) (xy 93.592819 -238.447925)
			(xy 93.556567 -238.486996) (xy 93.514896 -238.520227) (xy 93.468738 -238.546876) (xy 93.419124 -238.566348)
			(xy 93.367162 -238.578208) (xy 93.314012 -238.582192) (xy 93.260862 -238.578208) (xy 93.2089 -238.566348)
			(xy 93.159286 -238.546876) (xy 93.113128 -238.520227) (xy 93.071457 -238.486996) (xy 93.035205 -238.447925)
			(xy 93.005181 -238.403888) (xy 92.982055 -238.355867) (xy 92.966345 -238.304937) (xy 92.958402 -238.252233)
			(xy 92.729822 -238.252233) (xy 92.721879 -238.304937) (xy 92.706169 -238.355867) (xy 92.683043 -238.403888)
			(xy 92.653019 -238.447925) (xy 92.616767 -238.486996) (xy 92.575096 -238.520227) (xy 92.528938 -238.546876)
			(xy 92.479324 -238.566348) (xy 92.427362 -238.578208) (xy 92.374212 -238.582192) (xy 92.321062 -238.578208)
			(xy 92.2691 -238.566348) (xy 92.219486 -238.546876) (xy 92.173328 -238.520227) (xy 92.131657 -238.486996)
			(xy 92.095405 -238.447925) (xy 92.065381 -238.403888) (xy 92.042255 -238.355867) (xy 92.026545 -238.304937)
			(xy 92.018602 -238.252233) (xy 91.790276 -238.252233) (xy 91.782333 -238.304937) (xy 91.766623 -238.355867)
			(xy 91.743497 -238.403888) (xy 91.713473 -238.447925) (xy 91.677221 -238.486996) (xy 91.63555 -238.520227)
			(xy 91.589392 -238.546876) (xy 91.539778 -238.566348) (xy 91.487816 -238.578208) (xy 91.434666 -238.582192)
			(xy 91.381516 -238.578208) (xy 91.329554 -238.566348) (xy 91.27994 -238.546876) (xy 91.233782 -238.520227)
			(xy 91.192111 -238.486996) (xy 91.155859 -238.447925) (xy 91.125835 -238.403888) (xy 91.102709 -238.355867)
			(xy 91.086999 -238.304937) (xy 91.079056 -238.252233) (xy 90.850222 -238.252233) (xy 90.842279 -238.304937)
			(xy 90.826569 -238.355867) (xy 90.803443 -238.403888) (xy 90.773419 -238.447925) (xy 90.737167 -238.486996)
			(xy 90.695496 -238.520227) (xy 90.649338 -238.546876) (xy 90.599724 -238.566348) (xy 90.547762 -238.578208)
			(xy 90.494612 -238.582192) (xy 90.441462 -238.578208) (xy 90.3895 -238.566348) (xy 90.339886 -238.546876)
			(xy 90.293728 -238.520227) (xy 90.252057 -238.486996) (xy 90.215805 -238.447925) (xy 90.185781 -238.403888)
			(xy 90.162655 -238.355867) (xy 90.146945 -238.304937) (xy 90.139002 -238.252233) (xy 89.910422 -238.252233)
			(xy 89.902479 -238.304937) (xy 89.886769 -238.355867) (xy 89.863643 -238.403888) (xy 89.833619 -238.447925)
			(xy 89.797367 -238.486996) (xy 89.755696 -238.520227) (xy 89.709538 -238.546876) (xy 89.659924 -238.566348)
			(xy 89.607962 -238.578208) (xy 89.554812 -238.582192) (xy 89.501662 -238.578208) (xy 89.4497 -238.566348)
			(xy 89.400086 -238.546876) (xy 89.353928 -238.520227) (xy 89.312257 -238.486996) (xy 89.276005 -238.447925)
			(xy 89.245981 -238.403888) (xy 89.222855 -238.355867) (xy 89.207145 -238.304937) (xy 89.199202 -238.252233)
			(xy 88.970658 -238.252233) (xy 88.970658 -238.252363) (xy 88.962646 -238.305314) (xy 88.9468 -238.35647)
			(xy 88.93556 -238.380778) (xy 88.93048 -238.391192) (xy 88.93048 -238.58474) (xy 88.930958 -238.599038)
			(xy 88.938883 -238.626512) (xy 88.954127 -238.650705) (xy 88.97549 -238.669712) (xy 89.001292 -238.682038)
			(xy 89.029502 -238.686713) (xy 89.043764 -238.685578) (xy 89.054078 -238.684475) (xy 89.074793 -238.683332)
			(xy 89.085166 -238.683292) (xy 89.111819 -238.683763) (xy 89.16453 -238.691703) (xy 89.215468 -238.707411)
			(xy 89.263496 -238.730536) (xy 89.307541 -238.760562) (xy 89.346619 -238.796817) (xy 89.379856 -238.838491)
			(xy 89.40651 -238.884654) (xy 89.425986 -238.934275) (xy 89.437848 -238.986244) (xy 89.441832 -239.0394)
			(xy 89.439835 -239.066049) (xy 89.669356 -239.066049) (xy 89.669356 -239.012751) (xy 89.677299 -238.960047)
			(xy 89.693009 -238.909117) (xy 89.716135 -238.861096) (xy 89.746159 -238.817059) (xy 89.782411 -238.777988)
			(xy 89.824082 -238.744757) (xy 89.87024 -238.718108) (xy 89.919854 -238.698636) (xy 89.971816 -238.686776)
			(xy 90.024966 -238.682793) (xy 90.078116 -238.686776) (xy 90.130078 -238.698636) (xy 90.179692 -238.718108)
			(xy 90.22585 -238.744757) (xy 90.267521 -238.777988) (xy 90.303773 -238.817059) (xy 90.333797 -238.861096)
			(xy 90.356923 -238.909117) (xy 90.372633 -238.960047) (xy 90.380576 -239.012751) (xy 90.381074 -239.0394)
			(xy 90.380576 -239.066049) (xy 90.609156 -239.066049) (xy 90.609156 -239.012751) (xy 90.617099 -238.960047)
			(xy 90.632809 -238.909117) (xy 90.655935 -238.861096) (xy 90.685959 -238.817059) (xy 90.722211 -238.777988)
			(xy 90.763882 -238.744757) (xy 90.81004 -238.718108) (xy 90.859654 -238.698636) (xy 90.911616 -238.686776)
			(xy 90.964766 -238.682793) (xy 91.017916 -238.686776) (xy 91.069878 -238.698636) (xy 91.119492 -238.718108)
			(xy 91.16565 -238.744757) (xy 91.207321 -238.777988) (xy 91.243573 -238.817059) (xy 91.273597 -238.861096)
			(xy 91.296723 -238.909117) (xy 91.312433 -238.960047) (xy 91.320376 -239.012751) (xy 91.320874 -239.0394)
			(xy 91.320376 -239.066049) (xy 91.548956 -239.066049) (xy 91.548956 -239.012751) (xy 91.556899 -238.960047)
			(xy 91.572609 -238.909117) (xy 91.595735 -238.861096) (xy 91.625759 -238.817059) (xy 91.662011 -238.777988)
			(xy 91.703682 -238.744757) (xy 91.74984 -238.718108) (xy 91.799454 -238.698636) (xy 91.851416 -238.686776)
			(xy 91.904566 -238.682793) (xy 91.957716 -238.686776) (xy 92.009678 -238.698636) (xy 92.059292 -238.718108)
			(xy 92.10545 -238.744757) (xy 92.147121 -238.777988) (xy 92.183373 -238.817059) (xy 92.213397 -238.861096)
			(xy 92.236523 -238.909117) (xy 92.252233 -238.960047) (xy 92.260176 -239.012751) (xy 92.260674 -239.0394)
			(xy 92.260176 -239.066049) (xy 92.488756 -239.066049) (xy 92.488756 -239.012751) (xy 92.496699 -238.960047)
			(xy 92.512409 -238.909117) (xy 92.535535 -238.861096) (xy 92.565559 -238.817059) (xy 92.601811 -238.777988)
			(xy 92.643482 -238.744757) (xy 92.68964 -238.718108) (xy 92.739254 -238.698636) (xy 92.791216 -238.686776)
			(xy 92.844366 -238.682793) (xy 92.897516 -238.686776) (xy 92.949478 -238.698636) (xy 92.999092 -238.718108)
			(xy 93.04525 -238.744757) (xy 93.086921 -238.777988) (xy 93.123173 -238.817059) (xy 93.153197 -238.861096)
			(xy 93.176323 -238.909117) (xy 93.192033 -238.960047) (xy 93.199976 -239.012751) (xy 93.200474 -239.0394)
			(xy 93.199976 -239.066049) (xy 93.428556 -239.066049) (xy 93.428556 -239.012751) (xy 93.436499 -238.960047)
			(xy 93.452209 -238.909117) (xy 93.475335 -238.861096) (xy 93.505359 -238.817059) (xy 93.541611 -238.777988)
			(xy 93.583282 -238.744757) (xy 93.62944 -238.718108) (xy 93.679054 -238.698636) (xy 93.731016 -238.686776)
			(xy 93.784166 -238.682793) (xy 93.837316 -238.686776) (xy 93.889278 -238.698636) (xy 93.938892 -238.718108)
			(xy 93.98505 -238.744757) (xy 94.026721 -238.777988) (xy 94.062973 -238.817059) (xy 94.092997 -238.861096)
			(xy 94.116123 -238.909117) (xy 94.131833 -238.960047) (xy 94.139776 -239.012751) (xy 94.140274 -239.0394)
			(xy 94.139776 -239.066049) (xy 94.368102 -239.066049) (xy 94.368102 -239.012751) (xy 94.376045 -238.960047)
			(xy 94.391755 -238.909117) (xy 94.414881 -238.861096) (xy 94.444905 -238.817059) (xy 94.481157 -238.777988)
			(xy 94.522828 -238.744757) (xy 94.568986 -238.718108) (xy 94.6186 -238.698636) (xy 94.670562 -238.686776)
			(xy 94.723712 -238.682793) (xy 94.776862 -238.686776) (xy 94.828824 -238.698636) (xy 94.878438 -238.718108)
			(xy 94.924596 -238.744757) (xy 94.966267 -238.777988) (xy 95.002519 -238.817059) (xy 95.032543 -238.861096)
			(xy 95.055669 -238.909117) (xy 95.071379 -238.960047) (xy 95.079322 -239.012751) (xy 95.07982 -239.0394)
			(xy 95.079322 -239.066049) (xy 95.308156 -239.066049) (xy 95.308156 -239.012751) (xy 95.316099 -238.960047)
			(xy 95.331809 -238.909117) (xy 95.354935 -238.861096) (xy 95.384959 -238.817059) (xy 95.421211 -238.777988)
			(xy 95.462882 -238.744757) (xy 95.50904 -238.718108) (xy 95.558654 -238.698636) (xy 95.610616 -238.686776)
			(xy 95.663766 -238.682793) (xy 95.716916 -238.686776) (xy 95.768878 -238.698636) (xy 95.818492 -238.718108)
			(xy 95.86465 -238.744757) (xy 95.906321 -238.777988) (xy 95.942573 -238.817059) (xy 95.972597 -238.861096)
			(xy 95.995723 -238.909117) (xy 96.011433 -238.960047) (xy 96.019376 -239.012751) (xy 96.019874 -239.0394)
			(xy 96.019376 -239.066049) (xy 96.247956 -239.066049) (xy 96.247956 -239.012751) (xy 96.255899 -238.960047)
			(xy 96.271609 -238.909117) (xy 96.294735 -238.861096) (xy 96.324759 -238.817059) (xy 96.361011 -238.777988)
			(xy 96.402682 -238.744757) (xy 96.44884 -238.718108) (xy 96.498454 -238.698636) (xy 96.550416 -238.686776)
			(xy 96.603566 -238.682793) (xy 96.656716 -238.686776) (xy 96.708678 -238.698636) (xy 96.758292 -238.718108)
			(xy 96.80445 -238.744757) (xy 96.846121 -238.777988) (xy 96.882373 -238.817059) (xy 96.912397 -238.861096)
			(xy 96.935523 -238.909117) (xy 96.951233 -238.960047) (xy 96.959176 -239.012751) (xy 96.959674 -239.0394)
			(xy 96.959176 -239.066049) (xy 97.187756 -239.066049) (xy 97.187756 -239.012751) (xy 97.195699 -238.960047)
			(xy 97.211409 -238.909117) (xy 97.234535 -238.861096) (xy 97.264559 -238.817059) (xy 97.300811 -238.777988)
			(xy 97.342482 -238.744757) (xy 97.38864 -238.718108) (xy 97.438254 -238.698636) (xy 97.490216 -238.686776)
			(xy 97.543366 -238.682793) (xy 97.596516 -238.686776) (xy 97.648478 -238.698636) (xy 97.698092 -238.718108)
			(xy 97.74425 -238.744757) (xy 97.785921 -238.777988) (xy 97.822173 -238.817059) (xy 97.852197 -238.861096)
			(xy 97.875323 -238.909117) (xy 97.891033 -238.960047) (xy 97.898976 -239.012751) (xy 97.899474 -239.0394)
			(xy 97.898976 -239.066049) (xy 98.127556 -239.066049) (xy 98.127556 -239.012751) (xy 98.135499 -238.960047)
			(xy 98.151209 -238.909117) (xy 98.174335 -238.861096) (xy 98.204359 -238.817059) (xy 98.240611 -238.777988)
			(xy 98.282282 -238.744757) (xy 98.32844 -238.718108) (xy 98.378054 -238.698636) (xy 98.430016 -238.686776)
			(xy 98.483166 -238.682793) (xy 98.536316 -238.686776) (xy 98.588278 -238.698636) (xy 98.637892 -238.718108)
			(xy 98.68405 -238.744757) (xy 98.725721 -238.777988) (xy 98.761973 -238.817059) (xy 98.791997 -238.861096)
			(xy 98.815123 -238.909117) (xy 98.830833 -238.960047) (xy 98.838776 -239.012751) (xy 98.839274 -239.0394)
			(xy 98.838776 -239.066049) (xy 98.830833 -239.118753) (xy 98.815123 -239.169683) (xy 98.791997 -239.217704)
			(xy 98.761973 -239.261741) (xy 98.725721 -239.300812) (xy 98.68405 -239.334043) (xy 98.637892 -239.360692)
			(xy 98.588278 -239.380164) (xy 98.536316 -239.392024) (xy 98.483166 -239.396008) (xy 98.430016 -239.392024)
			(xy 98.378054 -239.380164) (xy 98.32844 -239.360692) (xy 98.282282 -239.334043) (xy 98.240611 -239.300812)
			(xy 98.204359 -239.261741) (xy 98.174335 -239.217704) (xy 98.151209 -239.169683) (xy 98.135499 -239.118753)
			(xy 98.127556 -239.066049) (xy 97.898976 -239.066049) (xy 97.891033 -239.118753) (xy 97.875323 -239.169683)
			(xy 97.852197 -239.217704) (xy 97.822173 -239.261741) (xy 97.785921 -239.300812) (xy 97.74425 -239.334043)
			(xy 97.698092 -239.360692) (xy 97.648478 -239.380164) (xy 97.596516 -239.392024) (xy 97.543366 -239.396008)
			(xy 97.490216 -239.392024) (xy 97.438254 -239.380164) (xy 97.38864 -239.360692) (xy 97.342482 -239.334043)
			(xy 97.300811 -239.300812) (xy 97.264559 -239.261741) (xy 97.234535 -239.217704) (xy 97.211409 -239.169683)
			(xy 97.195699 -239.118753) (xy 97.187756 -239.066049) (xy 96.959176 -239.066049) (xy 96.951233 -239.118753)
			(xy 96.935523 -239.169683) (xy 96.912397 -239.217704) (xy 96.882373 -239.261741) (xy 96.846121 -239.300812)
			(xy 96.80445 -239.334043) (xy 96.758292 -239.360692) (xy 96.708678 -239.380164) (xy 96.656716 -239.392024)
			(xy 96.603566 -239.396008) (xy 96.550416 -239.392024) (xy 96.498454 -239.380164) (xy 96.44884 -239.360692)
			(xy 96.402682 -239.334043) (xy 96.361011 -239.300812) (xy 96.324759 -239.261741) (xy 96.294735 -239.217704)
			(xy 96.271609 -239.169683) (xy 96.255899 -239.118753) (xy 96.247956 -239.066049) (xy 96.019376 -239.066049)
			(xy 96.011433 -239.118753) (xy 95.995723 -239.169683) (xy 95.972597 -239.217704) (xy 95.942573 -239.261741)
			(xy 95.906321 -239.300812) (xy 95.86465 -239.334043) (xy 95.818492 -239.360692) (xy 95.768878 -239.380164)
			(xy 95.716916 -239.392024) (xy 95.663766 -239.396008) (xy 95.610616 -239.392024) (xy 95.558654 -239.380164)
			(xy 95.50904 -239.360692) (xy 95.462882 -239.334043) (xy 95.421211 -239.300812) (xy 95.384959 -239.261741)
			(xy 95.354935 -239.217704) (xy 95.331809 -239.169683) (xy 95.316099 -239.118753) (xy 95.308156 -239.066049)
			(xy 95.079322 -239.066049) (xy 95.071379 -239.118753) (xy 95.055669 -239.169683) (xy 95.032543 -239.217704)
			(xy 95.002519 -239.261741) (xy 94.966267 -239.300812) (xy 94.924596 -239.334043) (xy 94.878438 -239.360692)
			(xy 94.828824 -239.380164) (xy 94.776862 -239.392024) (xy 94.723712 -239.396008) (xy 94.670562 -239.392024)
			(xy 94.6186 -239.380164) (xy 94.568986 -239.360692) (xy 94.522828 -239.334043) (xy 94.481157 -239.300812)
			(xy 94.444905 -239.261741) (xy 94.414881 -239.217704) (xy 94.391755 -239.169683) (xy 94.376045 -239.118753)
			(xy 94.368102 -239.066049) (xy 94.139776 -239.066049) (xy 94.131833 -239.118753) (xy 94.116123 -239.169683)
			(xy 94.092997 -239.217704) (xy 94.062973 -239.261741) (xy 94.026721 -239.300812) (xy 93.98505 -239.334043)
			(xy 93.938892 -239.360692) (xy 93.889278 -239.380164) (xy 93.837316 -239.392024) (xy 93.784166 -239.396008)
			(xy 93.731016 -239.392024) (xy 93.679054 -239.380164) (xy 93.62944 -239.360692) (xy 93.583282 -239.334043)
			(xy 93.541611 -239.300812) (xy 93.505359 -239.261741) (xy 93.475335 -239.217704) (xy 93.452209 -239.169683)
			(xy 93.436499 -239.118753) (xy 93.428556 -239.066049) (xy 93.199976 -239.066049) (xy 93.192033 -239.118753)
			(xy 93.176323 -239.169683) (xy 93.153197 -239.217704) (xy 93.123173 -239.261741) (xy 93.086921 -239.300812)
			(xy 93.04525 -239.334043) (xy 92.999092 -239.360692) (xy 92.949478 -239.380164) (xy 92.897516 -239.392024)
			(xy 92.844366 -239.396008) (xy 92.791216 -239.392024) (xy 92.739254 -239.380164) (xy 92.68964 -239.360692)
			(xy 92.643482 -239.334043) (xy 92.601811 -239.300812) (xy 92.565559 -239.261741) (xy 92.535535 -239.217704)
			(xy 92.512409 -239.169683) (xy 92.496699 -239.118753) (xy 92.488756 -239.066049) (xy 92.260176 -239.066049)
			(xy 92.252233 -239.118753) (xy 92.236523 -239.169683) (xy 92.213397 -239.217704) (xy 92.183373 -239.261741)
			(xy 92.147121 -239.300812) (xy 92.10545 -239.334043) (xy 92.059292 -239.360692) (xy 92.009678 -239.380164)
			(xy 91.957716 -239.392024) (xy 91.904566 -239.396008) (xy 91.851416 -239.392024) (xy 91.799454 -239.380164)
			(xy 91.74984 -239.360692) (xy 91.703682 -239.334043) (xy 91.662011 -239.300812) (xy 91.625759 -239.261741)
			(xy 91.595735 -239.217704) (xy 91.572609 -239.169683) (xy 91.556899 -239.118753) (xy 91.548956 -239.066049)
			(xy 91.320376 -239.066049) (xy 91.312433 -239.118753) (xy 91.296723 -239.169683) (xy 91.273597 -239.217704)
			(xy 91.243573 -239.261741) (xy 91.207321 -239.300812) (xy 91.16565 -239.334043) (xy 91.119492 -239.360692)
			(xy 91.069878 -239.380164) (xy 91.017916 -239.392024) (xy 90.964766 -239.396008) (xy 90.911616 -239.392024)
			(xy 90.859654 -239.380164) (xy 90.81004 -239.360692) (xy 90.763882 -239.334043) (xy 90.722211 -239.300812)
			(xy 90.685959 -239.261741) (xy 90.655935 -239.217704) (xy 90.632809 -239.169683) (xy 90.617099 -239.118753)
			(xy 90.609156 -239.066049) (xy 90.380576 -239.066049) (xy 90.372633 -239.118753) (xy 90.356923 -239.169683)
			(xy 90.333797 -239.217704) (xy 90.303773 -239.261741) (xy 90.267521 -239.300812) (xy 90.22585 -239.334043)
			(xy 90.179692 -239.360692) (xy 90.130078 -239.380164) (xy 90.078116 -239.392024) (xy 90.024966 -239.396008)
			(xy 89.971816 -239.392024) (xy 89.919854 -239.380164) (xy 89.87024 -239.360692) (xy 89.824082 -239.334043)
			(xy 89.782411 -239.300812) (xy 89.746159 -239.261741) (xy 89.716135 -239.217704) (xy 89.693009 -239.169683)
			(xy 89.677299 -239.118753) (xy 89.669356 -239.066049) (xy 89.439835 -239.066049) (xy 89.437848 -239.092556)
			(xy 89.425986 -239.144525) (xy 89.40651 -239.194146) (xy 89.379856 -239.240309) (xy 89.346619 -239.281983)
			(xy 89.307541 -239.318238) (xy 89.263496 -239.348264) (xy 89.215468 -239.371389) (xy 89.16453 -239.387097)
			(xy 89.111819 -239.395037) (xy 89.085166 -239.395508) (xy 89.074793 -239.395462) (xy 89.054079 -239.39432)
			(xy 89.043764 -239.393222) (xy 89.029508 -239.392061) (xy 89.001311 -239.396778) (xy 88.975524 -239.409122)
			(xy 88.954167 -239.428128) (xy 88.938912 -239.452307) (xy 88.930953 -239.479766) (xy 88.93048 -239.49406)
			(xy 88.93048 -239.687608) (xy 88.93556 -239.698022) (xy 88.946787 -239.722335) (xy 88.962632 -239.773489)
			(xy 88.970644 -239.826438) (xy 88.970642 -239.879865) (xy 89.199202 -239.879865) (xy 89.199202 -239.826567)
			(xy 89.207145 -239.773863) (xy 89.222855 -239.722933) (xy 89.245981 -239.674912) (xy 89.276005 -239.630875)
			(xy 89.312257 -239.591804) (xy 89.353928 -239.558573) (xy 89.400086 -239.531924) (xy 89.4497 -239.512452)
			(xy 89.501662 -239.500592) (xy 89.554812 -239.496609) (xy 89.607962 -239.500592) (xy 89.659924 -239.512452)
			(xy 89.709538 -239.531924) (xy 89.755696 -239.558573) (xy 89.797367 -239.591804) (xy 89.833619 -239.630875)
			(xy 89.863643 -239.674912) (xy 89.886769 -239.722933) (xy 89.902479 -239.773863) (xy 89.910422 -239.826567)
			(xy 89.91092 -239.853216) (xy 89.910422 -239.879865) (xy 90.139256 -239.879865) (xy 90.139256 -239.826567)
			(xy 90.147199 -239.773863) (xy 90.162909 -239.722933) (xy 90.186035 -239.674912) (xy 90.216059 -239.630875)
			(xy 90.252311 -239.591804) (xy 90.293982 -239.558573) (xy 90.34014 -239.531924) (xy 90.389754 -239.512452)
			(xy 90.441716 -239.500592) (xy 90.494866 -239.496609) (xy 90.548016 -239.500592) (xy 90.599978 -239.512452)
			(xy 90.649592 -239.531924) (xy 90.69575 -239.558573) (xy 90.737421 -239.591804) (xy 90.773673 -239.630875)
			(xy 90.803697 -239.674912) (xy 90.826823 -239.722933) (xy 90.842533 -239.773863) (xy 90.850476 -239.826567)
			(xy 90.850974 -239.853216) (xy 90.850476 -239.879865) (xy 91.078802 -239.879865) (xy 91.078802 -239.826567)
			(xy 91.086745 -239.773863) (xy 91.102455 -239.722933) (xy 91.125581 -239.674912) (xy 91.155605 -239.630875)
			(xy 91.191857 -239.591804) (xy 91.233528 -239.558573) (xy 91.279686 -239.531924) (xy 91.3293 -239.512452)
			(xy 91.381262 -239.500592) (xy 91.434412 -239.496609) (xy 91.487562 -239.500592) (xy 91.539524 -239.512452)
			(xy 91.589138 -239.531924) (xy 91.635296 -239.558573) (xy 91.676967 -239.591804) (xy 91.713219 -239.630875)
			(xy 91.743243 -239.674912) (xy 91.766369 -239.722933) (xy 91.782079 -239.773863) (xy 91.790022 -239.826567)
			(xy 91.79052 -239.853216) (xy 91.790022 -239.879865) (xy 92.018602 -239.879865) (xy 92.018602 -239.826567)
			(xy 92.026545 -239.773863) (xy 92.042255 -239.722933) (xy 92.065381 -239.674912) (xy 92.095405 -239.630875)
			(xy 92.131657 -239.591804) (xy 92.173328 -239.558573) (xy 92.219486 -239.531924) (xy 92.2691 -239.512452)
			(xy 92.321062 -239.500592) (xy 92.374212 -239.496609) (xy 92.427362 -239.500592) (xy 92.479324 -239.512452)
			(xy 92.528938 -239.531924) (xy 92.575096 -239.558573) (xy 92.616767 -239.591804) (xy 92.653019 -239.630875)
			(xy 92.683043 -239.674912) (xy 92.706169 -239.722933) (xy 92.721879 -239.773863) (xy 92.729822 -239.826567)
			(xy 92.73032 -239.853216) (xy 92.729822 -239.879865) (xy 92.958402 -239.879865) (xy 92.958402 -239.826567)
			(xy 92.966345 -239.773863) (xy 92.982055 -239.722933) (xy 93.005181 -239.674912) (xy 93.035205 -239.630875)
			(xy 93.071457 -239.591804) (xy 93.113128 -239.558573) (xy 93.159286 -239.531924) (xy 93.2089 -239.512452)
			(xy 93.260862 -239.500592) (xy 93.314012 -239.496609) (xy 93.367162 -239.500592) (xy 93.419124 -239.512452)
			(xy 93.468738 -239.531924) (xy 93.514896 -239.558573) (xy 93.556567 -239.591804) (xy 93.592819 -239.630875)
			(xy 93.622843 -239.674912) (xy 93.645969 -239.722933) (xy 93.661679 -239.773863) (xy 93.669622 -239.826567)
			(xy 93.67012 -239.853216) (xy 93.669622 -239.879865) (xy 93.898202 -239.879865) (xy 93.898202 -239.826567)
			(xy 93.906145 -239.773863) (xy 93.921855 -239.722933) (xy 93.944981 -239.674912) (xy 93.975005 -239.630875)
			(xy 94.011257 -239.591804) (xy 94.052928 -239.558573) (xy 94.099086 -239.531924) (xy 94.1487 -239.512452)
			(xy 94.200662 -239.500592) (xy 94.253812 -239.496609) (xy 94.306962 -239.500592) (xy 94.358924 -239.512452)
			(xy 94.408538 -239.531924) (xy 94.454696 -239.558573) (xy 94.496367 -239.591804) (xy 94.532619 -239.630875)
			(xy 94.562643 -239.674912) (xy 94.585769 -239.722933) (xy 94.601479 -239.773863) (xy 94.609422 -239.826567)
			(xy 94.60992 -239.853216) (xy 94.609422 -239.879865) (xy 94.838002 -239.879865) (xy 94.838002 -239.826567)
			(xy 94.845945 -239.773863) (xy 94.861655 -239.722933) (xy 94.884781 -239.674912) (xy 94.914805 -239.630875)
			(xy 94.951057 -239.591804) (xy 94.992728 -239.558573) (xy 95.038886 -239.531924) (xy 95.0885 -239.512452)
			(xy 95.140462 -239.500592) (xy 95.193612 -239.496609) (xy 95.246762 -239.500592) (xy 95.298724 -239.512452)
			(xy 95.348338 -239.531924) (xy 95.394496 -239.558573) (xy 95.436167 -239.591804) (xy 95.472419 -239.630875)
			(xy 95.502443 -239.674912) (xy 95.525569 -239.722933) (xy 95.541279 -239.773863) (xy 95.549222 -239.826567)
			(xy 95.54972 -239.853216) (xy 95.549222 -239.879865) (xy 95.777802 -239.879865) (xy 95.777802 -239.826567)
			(xy 95.785745 -239.773863) (xy 95.801455 -239.722933) (xy 95.824581 -239.674912) (xy 95.854605 -239.630875)
			(xy 95.890857 -239.591804) (xy 95.932528 -239.558573) (xy 95.978686 -239.531924) (xy 96.0283 -239.512452)
			(xy 96.080262 -239.500592) (xy 96.133412 -239.496609) (xy 96.186562 -239.500592) (xy 96.238524 -239.512452)
			(xy 96.288138 -239.531924) (xy 96.334296 -239.558573) (xy 96.375967 -239.591804) (xy 96.412219 -239.630875)
			(xy 96.442243 -239.674912) (xy 96.465369 -239.722933) (xy 96.481079 -239.773863) (xy 96.489022 -239.826567)
			(xy 96.48952 -239.853216) (xy 96.489022 -239.879865) (xy 96.717856 -239.879865) (xy 96.717856 -239.826567)
			(xy 96.725799 -239.773863) (xy 96.741509 -239.722933) (xy 96.764635 -239.674912) (xy 96.794659 -239.630875)
			(xy 96.830911 -239.591804) (xy 96.872582 -239.558573) (xy 96.91874 -239.531924) (xy 96.968354 -239.512452)
			(xy 97.020316 -239.500592) (xy 97.073466 -239.496609) (xy 97.126616 -239.500592) (xy 97.178578 -239.512452)
			(xy 97.228192 -239.531924) (xy 97.27435 -239.558573) (xy 97.316021 -239.591804) (xy 97.352273 -239.630875)
			(xy 97.382297 -239.674912) (xy 97.405423 -239.722933) (xy 97.421133 -239.773863) (xy 97.429076 -239.826567)
			(xy 97.429574 -239.853216) (xy 97.429076 -239.879865) (xy 97.657402 -239.879865) (xy 97.657402 -239.826567)
			(xy 97.665345 -239.773863) (xy 97.681055 -239.722933) (xy 97.704181 -239.674912) (xy 97.734205 -239.630875)
			(xy 97.770457 -239.591804) (xy 97.812128 -239.558573) (xy 97.858286 -239.531924) (xy 97.9079 -239.512452)
			(xy 97.959862 -239.500592) (xy 98.013012 -239.496609) (xy 98.066162 -239.500592) (xy 98.118124 -239.512452)
			(xy 98.167738 -239.531924) (xy 98.213896 -239.558573) (xy 98.255567 -239.591804) (xy 98.291819 -239.630875)
			(xy 98.321843 -239.674912) (xy 98.344969 -239.722933) (xy 98.360679 -239.773863) (xy 98.368622 -239.826567)
			(xy 98.36912 -239.853216) (xy 98.368622 -239.879865) (xy 98.597202 -239.879865) (xy 98.597202 -239.826567)
			(xy 98.605145 -239.773863) (xy 98.620855 -239.722933) (xy 98.643981 -239.674912) (xy 98.674005 -239.630875)
			(xy 98.710257 -239.591804) (xy 98.751928 -239.558573) (xy 98.798086 -239.531924) (xy 98.8477 -239.512452)
			(xy 98.899662 -239.500592) (xy 98.952812 -239.496609) (xy 99.005962 -239.500592) (xy 99.057924 -239.512452)
			(xy 99.107538 -239.531924) (xy 99.153696 -239.558573) (xy 99.195367 -239.591804) (xy 99.231619 -239.630875)
			(xy 99.261643 -239.674912) (xy 99.284769 -239.722933) (xy 99.300479 -239.773863) (xy 99.308422 -239.826567)
			(xy 99.30892 -239.853216) (xy 99.308422 -239.879865) (xy 99.300479 -239.932569) (xy 99.284769 -239.983499)
			(xy 99.261643 -240.03152) (xy 99.231619 -240.075557) (xy 99.195367 -240.114628) (xy 99.153696 -240.147859)
			(xy 99.107538 -240.174508) (xy 99.057924 -240.19398) (xy 99.005962 -240.20584) (xy 98.952812 -240.209824)
			(xy 98.899662 -240.20584) (xy 98.8477 -240.19398) (xy 98.798086 -240.174508) (xy 98.751928 -240.147859)
			(xy 98.710257 -240.114628) (xy 98.674005 -240.075557) (xy 98.643981 -240.03152) (xy 98.620855 -239.983499)
			(xy 98.605145 -239.932569) (xy 98.597202 -239.879865) (xy 98.368622 -239.879865) (xy 98.360679 -239.932569)
			(xy 98.344969 -239.983499) (xy 98.321843 -240.03152) (xy 98.291819 -240.075557) (xy 98.255567 -240.114628)
			(xy 98.213896 -240.147859) (xy 98.167738 -240.174508) (xy 98.118124 -240.19398) (xy 98.066162 -240.20584)
			(xy 98.013012 -240.209824) (xy 97.959862 -240.20584) (xy 97.9079 -240.19398) (xy 97.858286 -240.174508)
			(xy 97.812128 -240.147859) (xy 97.770457 -240.114628) (xy 97.734205 -240.075557) (xy 97.704181 -240.03152)
			(xy 97.681055 -239.983499) (xy 97.665345 -239.932569) (xy 97.657402 -239.879865) (xy 97.429076 -239.879865)
			(xy 97.421133 -239.932569) (xy 97.405423 -239.983499) (xy 97.382297 -240.03152) (xy 97.352273 -240.075557)
			(xy 97.316021 -240.114628) (xy 97.27435 -240.147859) (xy 97.228192 -240.174508) (xy 97.178578 -240.19398)
			(xy 97.126616 -240.20584) (xy 97.073466 -240.209824) (xy 97.020316 -240.20584) (xy 96.968354 -240.19398)
			(xy 96.91874 -240.174508) (xy 96.872582 -240.147859) (xy 96.830911 -240.114628) (xy 96.794659 -240.075557)
			(xy 96.764635 -240.03152) (xy 96.741509 -239.983499) (xy 96.725799 -239.932569) (xy 96.717856 -239.879865)
			(xy 96.489022 -239.879865) (xy 96.481079 -239.932569) (xy 96.465369 -239.983499) (xy 96.442243 -240.03152)
			(xy 96.412219 -240.075557) (xy 96.375967 -240.114628) (xy 96.334296 -240.147859) (xy 96.288138 -240.174508)
			(xy 96.238524 -240.19398) (xy 96.186562 -240.20584) (xy 96.133412 -240.209824) (xy 96.080262 -240.20584)
			(xy 96.0283 -240.19398) (xy 95.978686 -240.174508) (xy 95.932528 -240.147859) (xy 95.890857 -240.114628)
			(xy 95.854605 -240.075557) (xy 95.824581 -240.03152) (xy 95.801455 -239.983499) (xy 95.785745 -239.932569)
			(xy 95.777802 -239.879865) (xy 95.549222 -239.879865) (xy 95.541279 -239.932569) (xy 95.525569 -239.983499)
			(xy 95.502443 -240.03152) (xy 95.472419 -240.075557) (xy 95.436167 -240.114628) (xy 95.394496 -240.147859)
			(xy 95.348338 -240.174508) (xy 95.298724 -240.19398) (xy 95.246762 -240.20584) (xy 95.193612 -240.209824)
			(xy 95.140462 -240.20584) (xy 95.0885 -240.19398) (xy 95.038886 -240.174508) (xy 94.992728 -240.147859)
			(xy 94.951057 -240.114628) (xy 94.914805 -240.075557) (xy 94.884781 -240.03152) (xy 94.861655 -239.983499)
			(xy 94.845945 -239.932569) (xy 94.838002 -239.879865) (xy 94.609422 -239.879865) (xy 94.601479 -239.932569)
			(xy 94.585769 -239.983499) (xy 94.562643 -240.03152) (xy 94.532619 -240.075557) (xy 94.496367 -240.114628)
			(xy 94.454696 -240.147859) (xy 94.408538 -240.174508) (xy 94.358924 -240.19398) (xy 94.306962 -240.20584)
			(xy 94.253812 -240.209824) (xy 94.200662 -240.20584) (xy 94.1487 -240.19398) (xy 94.099086 -240.174508)
			(xy 94.052928 -240.147859) (xy 94.011257 -240.114628) (xy 93.975005 -240.075557) (xy 93.944981 -240.03152)
			(xy 93.921855 -239.983499) (xy 93.906145 -239.932569) (xy 93.898202 -239.879865) (xy 93.669622 -239.879865)
			(xy 93.661679 -239.932569) (xy 93.645969 -239.983499) (xy 93.622843 -240.03152) (xy 93.592819 -240.075557)
			(xy 93.556567 -240.114628) (xy 93.514896 -240.147859) (xy 93.468738 -240.174508) (xy 93.419124 -240.19398)
			(xy 93.367162 -240.20584) (xy 93.314012 -240.209824) (xy 93.260862 -240.20584) (xy 93.2089 -240.19398)
			(xy 93.159286 -240.174508) (xy 93.113128 -240.147859) (xy 93.071457 -240.114628) (xy 93.035205 -240.075557)
			(xy 93.005181 -240.03152) (xy 92.982055 -239.983499) (xy 92.966345 -239.932569) (xy 92.958402 -239.879865)
			(xy 92.729822 -239.879865) (xy 92.721879 -239.932569) (xy 92.706169 -239.983499) (xy 92.683043 -240.03152)
			(xy 92.653019 -240.075557) (xy 92.616767 -240.114628) (xy 92.575096 -240.147859) (xy 92.528938 -240.174508)
			(xy 92.479324 -240.19398) (xy 92.427362 -240.20584) (xy 92.374212 -240.209824) (xy 92.321062 -240.20584)
			(xy 92.2691 -240.19398) (xy 92.219486 -240.174508) (xy 92.173328 -240.147859) (xy 92.131657 -240.114628)
			(xy 92.095405 -240.075557) (xy 92.065381 -240.03152) (xy 92.042255 -239.983499) (xy 92.026545 -239.932569)
			(xy 92.018602 -239.879865) (xy 91.790022 -239.879865) (xy 91.782079 -239.932569) (xy 91.766369 -239.983499)
			(xy 91.743243 -240.03152) (xy 91.713219 -240.075557) (xy 91.676967 -240.114628) (xy 91.635296 -240.147859)
			(xy 91.589138 -240.174508) (xy 91.539524 -240.19398) (xy 91.487562 -240.20584) (xy 91.434412 -240.209824)
			(xy 91.381262 -240.20584) (xy 91.3293 -240.19398) (xy 91.279686 -240.174508) (xy 91.233528 -240.147859)
			(xy 91.191857 -240.114628) (xy 91.155605 -240.075557) (xy 91.125581 -240.03152) (xy 91.102455 -239.983499)
			(xy 91.086745 -239.932569) (xy 91.078802 -239.879865) (xy 90.850476 -239.879865) (xy 90.842533 -239.932569)
			(xy 90.826823 -239.983499) (xy 90.803697 -240.03152) (xy 90.773673 -240.075557) (xy 90.737421 -240.114628)
			(xy 90.69575 -240.147859) (xy 90.649592 -240.174508) (xy 90.599978 -240.19398) (xy 90.548016 -240.20584)
			(xy 90.494866 -240.209824) (xy 90.441716 -240.20584) (xy 90.389754 -240.19398) (xy 90.34014 -240.174508)
			(xy 90.293982 -240.147859) (xy 90.252311 -240.114628) (xy 90.216059 -240.075557) (xy 90.186035 -240.03152)
			(xy 90.162909 -239.983499) (xy 90.147199 -239.932569) (xy 90.139256 -239.879865) (xy 89.910422 -239.879865)
			(xy 89.902479 -239.932569) (xy 89.886769 -239.983499) (xy 89.863643 -240.03152) (xy 89.833619 -240.075557)
			(xy 89.797367 -240.114628) (xy 89.755696 -240.147859) (xy 89.709538 -240.174508) (xy 89.659924 -240.19398)
			(xy 89.607962 -240.20584) (xy 89.554812 -240.209824) (xy 89.501662 -240.20584) (xy 89.4497 -240.19398)
			(xy 89.400086 -240.174508) (xy 89.353928 -240.147859) (xy 89.312257 -240.114628) (xy 89.276005 -240.075557)
			(xy 89.245981 -240.03152) (xy 89.222855 -239.983499) (xy 89.207145 -239.932569) (xy 89.199202 -239.879865)
			(xy 88.970642 -239.879865) (xy 88.970642 -239.87999) (xy 88.962626 -239.932939) (xy 88.946777 -239.984092)
			(xy 88.93556 -240.00841) (xy 88.93048 -240.018824) (xy 88.93048 -240.212626) (xy 88.930956 -240.226925)
			(xy 88.938879 -240.254403) (xy 88.954122 -240.278599) (xy 88.975486 -240.297609) (xy 89.00129 -240.309937)
			(xy 89.029502 -240.314613) (xy 89.043764 -240.313464) (xy 89.054078 -240.31236) (xy 89.074793 -240.311216)
			(xy 89.085166 -240.311178) (xy 89.11182 -240.311649) (xy 89.164533 -240.319589) (xy 89.215473 -240.335298)
			(xy 89.263503 -240.358424) (xy 89.30755 -240.388451) (xy 89.346629 -240.424707) (xy 89.379867 -240.466383)
			(xy 89.406523 -240.512548) (xy 89.425999 -240.562171) (xy 89.437862 -240.614141) (xy 89.441846 -240.6673)
			(xy 89.43985 -240.693935) (xy 89.669356 -240.693935) (xy 89.669356 -240.640637) (xy 89.677299 -240.587933)
			(xy 89.693009 -240.537003) (xy 89.716135 -240.488982) (xy 89.746159 -240.444945) (xy 89.782411 -240.405874)
			(xy 89.824082 -240.372643) (xy 89.87024 -240.345994) (xy 89.919854 -240.326522) (xy 89.971816 -240.314662)
			(xy 90.024966 -240.310679) (xy 90.078116 -240.314662) (xy 90.130078 -240.326522) (xy 90.179692 -240.345994)
			(xy 90.22585 -240.372643) (xy 90.267521 -240.405874) (xy 90.303773 -240.444945) (xy 90.333797 -240.488982)
			(xy 90.356923 -240.537003) (xy 90.372633 -240.587933) (xy 90.380576 -240.640637) (xy 90.381074 -240.667286)
			(xy 90.380576 -240.693935) (xy 90.608902 -240.693935) (xy 90.608902 -240.640637) (xy 90.616845 -240.587933)
			(xy 90.632555 -240.537003) (xy 90.655681 -240.488982) (xy 90.685705 -240.444945) (xy 90.721957 -240.405874)
			(xy 90.763628 -240.372643) (xy 90.809786 -240.345994) (xy 90.8594 -240.326522) (xy 90.911362 -240.314662)
			(xy 90.964512 -240.310679) (xy 91.017662 -240.314662) (xy 91.069624 -240.326522) (xy 91.119238 -240.345994)
			(xy 91.165396 -240.372643) (xy 91.207067 -240.405874) (xy 91.243319 -240.444945) (xy 91.273343 -240.488982)
			(xy 91.296469 -240.537003) (xy 91.312179 -240.587933) (xy 91.320122 -240.640637) (xy 91.32062 -240.667286)
			(xy 91.320122 -240.693935) (xy 91.548956 -240.693935) (xy 91.548956 -240.640637) (xy 91.556899 -240.587933)
			(xy 91.572609 -240.537003) (xy 91.595735 -240.488982) (xy 91.625759 -240.444945) (xy 91.662011 -240.405874)
			(xy 91.703682 -240.372643) (xy 91.74984 -240.345994) (xy 91.799454 -240.326522) (xy 91.851416 -240.314662)
			(xy 91.904566 -240.310679) (xy 91.957716 -240.314662) (xy 92.009678 -240.326522) (xy 92.059292 -240.345994)
			(xy 92.10545 -240.372643) (xy 92.147121 -240.405874) (xy 92.183373 -240.444945) (xy 92.213397 -240.488982)
			(xy 92.236523 -240.537003) (xy 92.252233 -240.587933) (xy 92.260176 -240.640637) (xy 92.260674 -240.667286)
			(xy 92.260176 -240.693935) (xy 92.488756 -240.693935) (xy 92.488756 -240.640637) (xy 92.496699 -240.587933)
			(xy 92.512409 -240.537003) (xy 92.535535 -240.488982) (xy 92.565559 -240.444945) (xy 92.601811 -240.405874)
			(xy 92.643482 -240.372643) (xy 92.68964 -240.345994) (xy 92.739254 -240.326522) (xy 92.791216 -240.314662)
			(xy 92.844366 -240.310679) (xy 92.897516 -240.314662) (xy 92.949478 -240.326522) (xy 92.999092 -240.345994)
			(xy 93.04525 -240.372643) (xy 93.086921 -240.405874) (xy 93.123173 -240.444945) (xy 93.153197 -240.488982)
			(xy 93.176323 -240.537003) (xy 93.192033 -240.587933) (xy 93.199976 -240.640637) (xy 93.200474 -240.667286)
			(xy 93.199976 -240.693935) (xy 93.428556 -240.693935) (xy 93.428556 -240.640637) (xy 93.436499 -240.587933)
			(xy 93.452209 -240.537003) (xy 93.475335 -240.488982) (xy 93.505359 -240.444945) (xy 93.541611 -240.405874)
			(xy 93.583282 -240.372643) (xy 93.62944 -240.345994) (xy 93.679054 -240.326522) (xy 93.731016 -240.314662)
			(xy 93.784166 -240.310679) (xy 93.837316 -240.314662) (xy 93.889278 -240.326522) (xy 93.938892 -240.345994)
			(xy 93.98505 -240.372643) (xy 94.026721 -240.405874) (xy 94.062973 -240.444945) (xy 94.092997 -240.488982)
			(xy 94.116123 -240.537003) (xy 94.131833 -240.587933) (xy 94.139776 -240.640637) (xy 94.140274 -240.667286)
			(xy 94.139776 -240.693935) (xy 94.368356 -240.693935) (xy 94.368356 -240.640637) (xy 94.376299 -240.587933)
			(xy 94.392009 -240.537003) (xy 94.415135 -240.488982) (xy 94.445159 -240.444945) (xy 94.481411 -240.405874)
			(xy 94.523082 -240.372643) (xy 94.56924 -240.345994) (xy 94.618854 -240.326522) (xy 94.670816 -240.314662)
			(xy 94.723966 -240.310679) (xy 94.777116 -240.314662) (xy 94.829078 -240.326522) (xy 94.878692 -240.345994)
			(xy 94.92485 -240.372643) (xy 94.966521 -240.405874) (xy 95.002773 -240.444945) (xy 95.032797 -240.488982)
			(xy 95.055923 -240.537003) (xy 95.071633 -240.587933) (xy 95.079576 -240.640637) (xy 95.080074 -240.667286)
			(xy 95.079576 -240.693935) (xy 95.308156 -240.693935) (xy 95.308156 -240.640637) (xy 95.316099 -240.587933)
			(xy 95.331809 -240.537003) (xy 95.354935 -240.488982) (xy 95.384959 -240.444945) (xy 95.421211 -240.405874)
			(xy 95.462882 -240.372643) (xy 95.50904 -240.345994) (xy 95.558654 -240.326522) (xy 95.610616 -240.314662)
			(xy 95.663766 -240.310679) (xy 95.716916 -240.314662) (xy 95.768878 -240.326522) (xy 95.818492 -240.345994)
			(xy 95.86465 -240.372643) (xy 95.906321 -240.405874) (xy 95.942573 -240.444945) (xy 95.972597 -240.488982)
			(xy 95.995723 -240.537003) (xy 96.011433 -240.587933) (xy 96.019376 -240.640637) (xy 96.019874 -240.667286)
			(xy 96.019376 -240.693935) (xy 96.247956 -240.693935) (xy 96.247956 -240.640637) (xy 96.255899 -240.587933)
			(xy 96.271609 -240.537003) (xy 96.294735 -240.488982) (xy 96.324759 -240.444945) (xy 96.361011 -240.405874)
			(xy 96.402682 -240.372643) (xy 96.44884 -240.345994) (xy 96.498454 -240.326522) (xy 96.550416 -240.314662)
			(xy 96.603566 -240.310679) (xy 96.656716 -240.314662) (xy 96.708678 -240.326522) (xy 96.758292 -240.345994)
			(xy 96.80445 -240.372643) (xy 96.846121 -240.405874) (xy 96.882373 -240.444945) (xy 96.912397 -240.488982)
			(xy 96.935523 -240.537003) (xy 96.951233 -240.587933) (xy 96.959176 -240.640637) (xy 96.959674 -240.667286)
			(xy 96.959176 -240.693935) (xy 97.187502 -240.693935) (xy 97.187502 -240.640637) (xy 97.195445 -240.587933)
			(xy 97.211155 -240.537003) (xy 97.234281 -240.488982) (xy 97.264305 -240.444945) (xy 97.300557 -240.405874)
			(xy 97.342228 -240.372643) (xy 97.388386 -240.345994) (xy 97.438 -240.326522) (xy 97.489962 -240.314662)
			(xy 97.543112 -240.310679) (xy 97.596262 -240.314662) (xy 97.648224 -240.326522) (xy 97.697838 -240.345994)
			(xy 97.743996 -240.372643) (xy 97.785667 -240.405874) (xy 97.821919 -240.444945) (xy 97.851943 -240.488982)
			(xy 97.875069 -240.537003) (xy 97.890779 -240.587933) (xy 97.898722 -240.640637) (xy 97.89922 -240.667286)
			(xy 97.898722 -240.693935) (xy 98.127556 -240.693935) (xy 98.127556 -240.640637) (xy 98.135499 -240.587933)
			(xy 98.151209 -240.537003) (xy 98.174335 -240.488982) (xy 98.204359 -240.444945) (xy 98.240611 -240.405874)
			(xy 98.282282 -240.372643) (xy 98.32844 -240.345994) (xy 98.378054 -240.326522) (xy 98.430016 -240.314662)
			(xy 98.483166 -240.310679) (xy 98.536316 -240.314662) (xy 98.588278 -240.326522) (xy 98.637892 -240.345994)
			(xy 98.68405 -240.372643) (xy 98.725721 -240.405874) (xy 98.761973 -240.444945) (xy 98.791997 -240.488982)
			(xy 98.815123 -240.537003) (xy 98.830833 -240.587933) (xy 98.838776 -240.640637) (xy 98.839274 -240.667286)
			(xy 98.838776 -240.693935) (xy 98.830833 -240.746639) (xy 98.815123 -240.797569) (xy 98.791997 -240.84559)
			(xy 98.761973 -240.889627) (xy 98.725721 -240.928698) (xy 98.68405 -240.961929) (xy 98.637892 -240.988578)
			(xy 98.588278 -241.00805) (xy 98.536316 -241.01991) (xy 98.483166 -241.023894) (xy 98.430016 -241.01991)
			(xy 98.378054 -241.00805) (xy 98.32844 -240.988578) (xy 98.282282 -240.961929) (xy 98.240611 -240.928698)
			(xy 98.204359 -240.889627) (xy 98.174335 -240.84559) (xy 98.151209 -240.797569) (xy 98.135499 -240.746639)
			(xy 98.127556 -240.693935) (xy 97.898722 -240.693935) (xy 97.890779 -240.746639) (xy 97.875069 -240.797569)
			(xy 97.851943 -240.84559) (xy 97.821919 -240.889627) (xy 97.785667 -240.928698) (xy 97.743996 -240.961929)
			(xy 97.697838 -240.988578) (xy 97.648224 -241.00805) (xy 97.596262 -241.01991) (xy 97.543112 -241.023894)
			(xy 97.489962 -241.01991) (xy 97.438 -241.00805) (xy 97.388386 -240.988578) (xy 97.342228 -240.961929)
			(xy 97.300557 -240.928698) (xy 97.264305 -240.889627) (xy 97.234281 -240.84559) (xy 97.211155 -240.797569)
			(xy 97.195445 -240.746639) (xy 97.187502 -240.693935) (xy 96.959176 -240.693935) (xy 96.951233 -240.746639)
			(xy 96.935523 -240.797569) (xy 96.912397 -240.84559) (xy 96.882373 -240.889627) (xy 96.846121 -240.928698)
			(xy 96.80445 -240.961929) (xy 96.758292 -240.988578) (xy 96.708678 -241.00805) (xy 96.656716 -241.01991)
			(xy 96.603566 -241.023894) (xy 96.550416 -241.01991) (xy 96.498454 -241.00805) (xy 96.44884 -240.988578)
			(xy 96.402682 -240.961929) (xy 96.361011 -240.928698) (xy 96.324759 -240.889627) (xy 96.294735 -240.84559)
			(xy 96.271609 -240.797569) (xy 96.255899 -240.746639) (xy 96.247956 -240.693935) (xy 96.019376 -240.693935)
			(xy 96.011433 -240.746639) (xy 95.995723 -240.797569) (xy 95.972597 -240.84559) (xy 95.942573 -240.889627)
			(xy 95.906321 -240.928698) (xy 95.86465 -240.961929) (xy 95.818492 -240.988578) (xy 95.768878 -241.00805)
			(xy 95.716916 -241.01991) (xy 95.663766 -241.023894) (xy 95.610616 -241.01991) (xy 95.558654 -241.00805)
			(xy 95.50904 -240.988578) (xy 95.462882 -240.961929) (xy 95.421211 -240.928698) (xy 95.384959 -240.889627)
			(xy 95.354935 -240.84559) (xy 95.331809 -240.797569) (xy 95.316099 -240.746639) (xy 95.308156 -240.693935)
			(xy 95.079576 -240.693935) (xy 95.071633 -240.746639) (xy 95.055923 -240.797569) (xy 95.032797 -240.84559)
			(xy 95.002773 -240.889627) (xy 94.966521 -240.928698) (xy 94.92485 -240.961929) (xy 94.878692 -240.988578)
			(xy 94.829078 -241.00805) (xy 94.777116 -241.01991) (xy 94.723966 -241.023894) (xy 94.670816 -241.01991)
			(xy 94.618854 -241.00805) (xy 94.56924 -240.988578) (xy 94.523082 -240.961929) (xy 94.481411 -240.928698)
			(xy 94.445159 -240.889627) (xy 94.415135 -240.84559) (xy 94.392009 -240.797569) (xy 94.376299 -240.746639)
			(xy 94.368356 -240.693935) (xy 94.139776 -240.693935) (xy 94.131833 -240.746639) (xy 94.116123 -240.797569)
			(xy 94.092997 -240.84559) (xy 94.062973 -240.889627) (xy 94.026721 -240.928698) (xy 93.98505 -240.961929)
			(xy 93.938892 -240.988578) (xy 93.889278 -241.00805) (xy 93.837316 -241.01991) (xy 93.784166 -241.023894)
			(xy 93.731016 -241.01991) (xy 93.679054 -241.00805) (xy 93.62944 -240.988578) (xy 93.583282 -240.961929)
			(xy 93.541611 -240.928698) (xy 93.505359 -240.889627) (xy 93.475335 -240.84559) (xy 93.452209 -240.797569)
			(xy 93.436499 -240.746639) (xy 93.428556 -240.693935) (xy 93.199976 -240.693935) (xy 93.192033 -240.746639)
			(xy 93.176323 -240.797569) (xy 93.153197 -240.84559) (xy 93.123173 -240.889627) (xy 93.086921 -240.928698)
			(xy 93.04525 -240.961929) (xy 92.999092 -240.988578) (xy 92.949478 -241.00805) (xy 92.897516 -241.01991)
			(xy 92.844366 -241.023894) (xy 92.791216 -241.01991) (xy 92.739254 -241.00805) (xy 92.68964 -240.988578)
			(xy 92.643482 -240.961929) (xy 92.601811 -240.928698) (xy 92.565559 -240.889627) (xy 92.535535 -240.84559)
			(xy 92.512409 -240.797569) (xy 92.496699 -240.746639) (xy 92.488756 -240.693935) (xy 92.260176 -240.693935)
			(xy 92.252233 -240.746639) (xy 92.236523 -240.797569) (xy 92.213397 -240.84559) (xy 92.183373 -240.889627)
			(xy 92.147121 -240.928698) (xy 92.10545 -240.961929) (xy 92.059292 -240.988578) (xy 92.009678 -241.00805)
			(xy 91.957716 -241.01991) (xy 91.904566 -241.023894) (xy 91.851416 -241.01991) (xy 91.799454 -241.00805)
			(xy 91.74984 -240.988578) (xy 91.703682 -240.961929) (xy 91.662011 -240.928698) (xy 91.625759 -240.889627)
			(xy 91.595735 -240.84559) (xy 91.572609 -240.797569) (xy 91.556899 -240.746639) (xy 91.548956 -240.693935)
			(xy 91.320122 -240.693935) (xy 91.312179 -240.746639) (xy 91.296469 -240.797569) (xy 91.273343 -240.84559)
			(xy 91.243319 -240.889627) (xy 91.207067 -240.928698) (xy 91.165396 -240.961929) (xy 91.119238 -240.988578)
			(xy 91.069624 -241.00805) (xy 91.017662 -241.01991) (xy 90.964512 -241.023894) (xy 90.911362 -241.01991)
			(xy 90.8594 -241.00805) (xy 90.809786 -240.988578) (xy 90.763628 -240.961929) (xy 90.721957 -240.928698)
			(xy 90.685705 -240.889627) (xy 90.655681 -240.84559) (xy 90.632555 -240.797569) (xy 90.616845 -240.746639)
			(xy 90.608902 -240.693935) (xy 90.380576 -240.693935) (xy 90.372633 -240.746639) (xy 90.356923 -240.797569)
			(xy 90.333797 -240.84559) (xy 90.303773 -240.889627) (xy 90.267521 -240.928698) (xy 90.22585 -240.961929)
			(xy 90.179692 -240.988578) (xy 90.130078 -241.00805) (xy 90.078116 -241.01991) (xy 90.024966 -241.023894)
			(xy 89.971816 -241.01991) (xy 89.919854 -241.00805) (xy 89.87024 -240.988578) (xy 89.824082 -240.961929)
			(xy 89.782411 -240.928698) (xy 89.746159 -240.889627) (xy 89.716135 -240.84559) (xy 89.693009 -240.797569)
			(xy 89.677299 -240.746639) (xy 89.669356 -240.693935) (xy 89.43985 -240.693935) (xy 89.437862 -240.720459)
			(xy 89.425999 -240.772429) (xy 89.406523 -240.822052) (xy 89.379867 -240.868217) (xy 89.346629 -240.909893)
			(xy 89.30755 -240.946149) (xy 89.263503 -240.976176) (xy 89.215473 -240.999302) (xy 89.164533 -241.015011)
			(xy 89.11182 -241.022951) (xy 89.085166 -241.023394) (xy 89.074793 -241.023348) (xy 89.054079 -241.022206)
			(xy 89.043764 -241.021108) (xy 89.029508 -241.019947) (xy 89.001309 -241.024664) (xy 88.97552 -241.037008)
			(xy 88.954161 -241.056013) (xy 88.938903 -241.080192) (xy 88.930941 -241.107651) (xy 88.93048 -241.121946)
			(xy 88.93048 -241.315494) (xy 88.93556 -241.325908) (xy 88.946788 -241.350221) (xy 88.962636 -241.401376)
			(xy 88.970649 -241.454325) (xy 88.970649 -241.507751) (xy 89.199202 -241.507751) (xy 89.199202 -241.454453)
			(xy 89.207145 -241.401749) (xy 89.222855 -241.350819) (xy 89.245981 -241.302798) (xy 89.276005 -241.258761)
			(xy 89.312257 -241.21969) (xy 89.353928 -241.186459) (xy 89.400086 -241.15981) (xy 89.4497 -241.140338)
			(xy 89.501662 -241.128478) (xy 89.554812 -241.124495) (xy 89.607962 -241.128478) (xy 89.659924 -241.140338)
			(xy 89.709538 -241.15981) (xy 89.755696 -241.186459) (xy 89.797367 -241.21969) (xy 89.833619 -241.258761)
			(xy 89.863643 -241.302798) (xy 89.886769 -241.350819) (xy 89.902479 -241.401749) (xy 89.910422 -241.454453)
			(xy 89.91092 -241.481102) (xy 89.910422 -241.507751) (xy 90.139002 -241.507751) (xy 90.139002 -241.454453)
			(xy 90.146945 -241.401749) (xy 90.162655 -241.350819) (xy 90.185781 -241.302798) (xy 90.215805 -241.258761)
			(xy 90.252057 -241.21969) (xy 90.293728 -241.186459) (xy 90.339886 -241.15981) (xy 90.3895 -241.140338)
			(xy 90.441462 -241.128478) (xy 90.494612 -241.124495) (xy 90.547762 -241.128478) (xy 90.599724 -241.140338)
			(xy 90.649338 -241.15981) (xy 90.695496 -241.186459) (xy 90.737167 -241.21969) (xy 90.773419 -241.258761)
			(xy 90.803443 -241.302798) (xy 90.826569 -241.350819) (xy 90.842279 -241.401749) (xy 90.850222 -241.454453)
			(xy 90.85072 -241.481102) (xy 90.850222 -241.507751) (xy 91.078802 -241.507751) (xy 91.078802 -241.454453)
			(xy 91.086745 -241.401749) (xy 91.102455 -241.350819) (xy 91.125581 -241.302798) (xy 91.155605 -241.258761)
			(xy 91.191857 -241.21969) (xy 91.233528 -241.186459) (xy 91.279686 -241.15981) (xy 91.3293 -241.140338)
			(xy 91.381262 -241.128478) (xy 91.434412 -241.124495) (xy 91.487562 -241.128478) (xy 91.539524 -241.140338)
			(xy 91.589138 -241.15981) (xy 91.635296 -241.186459) (xy 91.676967 -241.21969) (xy 91.713219 -241.258761)
			(xy 91.743243 -241.302798) (xy 91.766369 -241.350819) (xy 91.782079 -241.401749) (xy 91.790022 -241.454453)
			(xy 91.79052 -241.481102) (xy 91.790022 -241.507751) (xy 92.018602 -241.507751) (xy 92.018602 -241.454453)
			(xy 92.026545 -241.401749) (xy 92.042255 -241.350819) (xy 92.065381 -241.302798) (xy 92.095405 -241.258761)
			(xy 92.131657 -241.21969) (xy 92.173328 -241.186459) (xy 92.219486 -241.15981) (xy 92.2691 -241.140338)
			(xy 92.321062 -241.128478) (xy 92.374212 -241.124495) (xy 92.427362 -241.128478) (xy 92.479324 -241.140338)
			(xy 92.528938 -241.15981) (xy 92.575096 -241.186459) (xy 92.616767 -241.21969) (xy 92.653019 -241.258761)
			(xy 92.683043 -241.302798) (xy 92.706169 -241.350819) (xy 92.721879 -241.401749) (xy 92.729822 -241.454453)
			(xy 92.73032 -241.481102) (xy 92.729822 -241.507751) (xy 92.958402 -241.507751) (xy 92.958402 -241.454453)
			(xy 92.966345 -241.401749) (xy 92.982055 -241.350819) (xy 93.005181 -241.302798) (xy 93.035205 -241.258761)
			(xy 93.071457 -241.21969) (xy 93.113128 -241.186459) (xy 93.159286 -241.15981) (xy 93.2089 -241.140338)
			(xy 93.260862 -241.128478) (xy 93.314012 -241.124495) (xy 93.367162 -241.128478) (xy 93.419124 -241.140338)
			(xy 93.468738 -241.15981) (xy 93.514896 -241.186459) (xy 93.556567 -241.21969) (xy 93.592819 -241.258761)
			(xy 93.622843 -241.302798) (xy 93.645969 -241.350819) (xy 93.661679 -241.401749) (xy 93.669622 -241.454453)
			(xy 93.67012 -241.481102) (xy 93.669622 -241.507751) (xy 93.898456 -241.507751) (xy 93.898456 -241.454453)
			(xy 93.906399 -241.401749) (xy 93.922109 -241.350819) (xy 93.945235 -241.302798) (xy 93.975259 -241.258761)
			(xy 94.011511 -241.21969) (xy 94.053182 -241.186459) (xy 94.09934 -241.15981) (xy 94.148954 -241.140338)
			(xy 94.200916 -241.128478) (xy 94.254066 -241.124495) (xy 94.307216 -241.128478) (xy 94.359178 -241.140338)
			(xy 94.408792 -241.15981) (xy 94.45495 -241.186459) (xy 94.496621 -241.21969) (xy 94.532873 -241.258761)
			(xy 94.562897 -241.302798) (xy 94.586023 -241.350819) (xy 94.601733 -241.401749) (xy 94.609676 -241.454453)
			(xy 94.610174 -241.481102) (xy 94.609676 -241.507751) (xy 94.838002 -241.507751) (xy 94.838002 -241.454453)
			(xy 94.845945 -241.401749) (xy 94.861655 -241.350819) (xy 94.884781 -241.302798) (xy 94.914805 -241.258761)
			(xy 94.951057 -241.21969) (xy 94.992728 -241.186459) (xy 95.038886 -241.15981) (xy 95.0885 -241.140338)
			(xy 95.140462 -241.128478) (xy 95.193612 -241.124495) (xy 95.246762 -241.128478) (xy 95.298724 -241.140338)
			(xy 95.348338 -241.15981) (xy 95.394496 -241.186459) (xy 95.436167 -241.21969) (xy 95.472419 -241.258761)
			(xy 95.502443 -241.302798) (xy 95.525569 -241.350819) (xy 95.541279 -241.401749) (xy 95.549222 -241.454453)
			(xy 95.54972 -241.481102) (xy 95.549222 -241.507751) (xy 95.777802 -241.507751) (xy 95.777802 -241.454453)
			(xy 95.785745 -241.401749) (xy 95.801455 -241.350819) (xy 95.824581 -241.302798) (xy 95.854605 -241.258761)
			(xy 95.890857 -241.21969) (xy 95.932528 -241.186459) (xy 95.978686 -241.15981) (xy 96.0283 -241.140338)
			(xy 96.080262 -241.128478) (xy 96.133412 -241.124495) (xy 96.186562 -241.128478) (xy 96.238524 -241.140338)
			(xy 96.288138 -241.15981) (xy 96.334296 -241.186459) (xy 96.375967 -241.21969) (xy 96.412219 -241.258761)
			(xy 96.442243 -241.302798) (xy 96.465369 -241.350819) (xy 96.481079 -241.401749) (xy 96.489022 -241.454453)
			(xy 96.48952 -241.481102) (xy 96.489022 -241.507751) (xy 96.717602 -241.507751) (xy 96.717602 -241.454453)
			(xy 96.725545 -241.401749) (xy 96.741255 -241.350819) (xy 96.764381 -241.302798) (xy 96.794405 -241.258761)
			(xy 96.830657 -241.21969) (xy 96.872328 -241.186459) (xy 96.918486 -241.15981) (xy 96.9681 -241.140338)
			(xy 97.020062 -241.128478) (xy 97.073212 -241.124495) (xy 97.126362 -241.128478) (xy 97.178324 -241.140338)
			(xy 97.227938 -241.15981) (xy 97.274096 -241.186459) (xy 97.315767 -241.21969) (xy 97.352019 -241.258761)
			(xy 97.382043 -241.302798) (xy 97.405169 -241.350819) (xy 97.420879 -241.401749) (xy 97.428822 -241.454453)
			(xy 97.42932 -241.481102) (xy 97.428822 -241.507751) (xy 97.657402 -241.507751) (xy 97.657402 -241.454453)
			(xy 97.665345 -241.401749) (xy 97.681055 -241.350819) (xy 97.704181 -241.302798) (xy 97.734205 -241.258761)
			(xy 97.770457 -241.21969) (xy 97.812128 -241.186459) (xy 97.858286 -241.15981) (xy 97.9079 -241.140338)
			(xy 97.959862 -241.128478) (xy 98.013012 -241.124495) (xy 98.066162 -241.128478) (xy 98.118124 -241.140338)
			(xy 98.167738 -241.15981) (xy 98.213896 -241.186459) (xy 98.255567 -241.21969) (xy 98.291819 -241.258761)
			(xy 98.321843 -241.302798) (xy 98.344969 -241.350819) (xy 98.360679 -241.401749) (xy 98.368622 -241.454453)
			(xy 98.36912 -241.481102) (xy 98.368622 -241.507751) (xy 98.597202 -241.507751) (xy 98.597202 -241.454453)
			(xy 98.605145 -241.401749) (xy 98.620855 -241.350819) (xy 98.643981 -241.302798) (xy 98.674005 -241.258761)
			(xy 98.710257 -241.21969) (xy 98.751928 -241.186459) (xy 98.798086 -241.15981) (xy 98.8477 -241.140338)
			(xy 98.899662 -241.128478) (xy 98.952812 -241.124495) (xy 99.005962 -241.128478) (xy 99.057924 -241.140338)
			(xy 99.107538 -241.15981) (xy 99.153696 -241.186459) (xy 99.195367 -241.21969) (xy 99.231619 -241.258761)
			(xy 99.261643 -241.302798) (xy 99.284769 -241.350819) (xy 99.300479 -241.401749) (xy 99.308422 -241.454453)
			(xy 99.30892 -241.481102) (xy 99.308422 -241.507751) (xy 99.300479 -241.560455) (xy 99.284769 -241.611385)
			(xy 99.261643 -241.659406) (xy 99.231619 -241.703443) (xy 99.195367 -241.742514) (xy 99.153696 -241.775745)
			(xy 99.107538 -241.802394) (xy 99.057924 -241.821866) (xy 99.005962 -241.833726) (xy 98.952812 -241.83771)
			(xy 98.899662 -241.833726) (xy 98.8477 -241.821866) (xy 98.798086 -241.802394) (xy 98.751928 -241.775745)
			(xy 98.710257 -241.742514) (xy 98.674005 -241.703443) (xy 98.643981 -241.659406) (xy 98.620855 -241.611385)
			(xy 98.605145 -241.560455) (xy 98.597202 -241.507751) (xy 98.368622 -241.507751) (xy 98.360679 -241.560455)
			(xy 98.344969 -241.611385) (xy 98.321843 -241.659406) (xy 98.291819 -241.703443) (xy 98.255567 -241.742514)
			(xy 98.213896 -241.775745) (xy 98.167738 -241.802394) (xy 98.118124 -241.821866) (xy 98.066162 -241.833726)
			(xy 98.013012 -241.83771) (xy 97.959862 -241.833726) (xy 97.9079 -241.821866) (xy 97.858286 -241.802394)
			(xy 97.812128 -241.775745) (xy 97.770457 -241.742514) (xy 97.734205 -241.703443) (xy 97.704181 -241.659406)
			(xy 97.681055 -241.611385) (xy 97.665345 -241.560455) (xy 97.657402 -241.507751) (xy 97.428822 -241.507751)
			(xy 97.420879 -241.560455) (xy 97.405169 -241.611385) (xy 97.382043 -241.659406) (xy 97.352019 -241.703443)
			(xy 97.315767 -241.742514) (xy 97.274096 -241.775745) (xy 97.227938 -241.802394) (xy 97.178324 -241.821866)
			(xy 97.126362 -241.833726) (xy 97.073212 -241.83771) (xy 97.020062 -241.833726) (xy 96.9681 -241.821866)
			(xy 96.918486 -241.802394) (xy 96.872328 -241.775745) (xy 96.830657 -241.742514) (xy 96.794405 -241.703443)
			(xy 96.764381 -241.659406) (xy 96.741255 -241.611385) (xy 96.725545 -241.560455) (xy 96.717602 -241.507751)
			(xy 96.489022 -241.507751) (xy 96.481079 -241.560455) (xy 96.465369 -241.611385) (xy 96.442243 -241.659406)
			(xy 96.412219 -241.703443) (xy 96.375967 -241.742514) (xy 96.334296 -241.775745) (xy 96.288138 -241.802394)
			(xy 96.238524 -241.821866) (xy 96.186562 -241.833726) (xy 96.133412 -241.83771) (xy 96.080262 -241.833726)
			(xy 96.0283 -241.821866) (xy 95.978686 -241.802394) (xy 95.932528 -241.775745) (xy 95.890857 -241.742514)
			(xy 95.854605 -241.703443) (xy 95.824581 -241.659406) (xy 95.801455 -241.611385) (xy 95.785745 -241.560455)
			(xy 95.777802 -241.507751) (xy 95.549222 -241.507751) (xy 95.541279 -241.560455) (xy 95.525569 -241.611385)
			(xy 95.502443 -241.659406) (xy 95.472419 -241.703443) (xy 95.436167 -241.742514) (xy 95.394496 -241.775745)
			(xy 95.348338 -241.802394) (xy 95.298724 -241.821866) (xy 95.246762 -241.833726) (xy 95.193612 -241.83771)
			(xy 95.140462 -241.833726) (xy 95.0885 -241.821866) (xy 95.038886 -241.802394) (xy 94.992728 -241.775745)
			(xy 94.951057 -241.742514) (xy 94.914805 -241.703443) (xy 94.884781 -241.659406) (xy 94.861655 -241.611385)
			(xy 94.845945 -241.560455) (xy 94.838002 -241.507751) (xy 94.609676 -241.507751) (xy 94.601733 -241.560455)
			(xy 94.586023 -241.611385) (xy 94.562897 -241.659406) (xy 94.532873 -241.703443) (xy 94.496621 -241.742514)
			(xy 94.45495 -241.775745) (xy 94.408792 -241.802394) (xy 94.359178 -241.821866) (xy 94.307216 -241.833726)
			(xy 94.254066 -241.83771) (xy 94.200916 -241.833726) (xy 94.148954 -241.821866) (xy 94.09934 -241.802394)
			(xy 94.053182 -241.775745) (xy 94.011511 -241.742514) (xy 93.975259 -241.703443) (xy 93.945235 -241.659406)
			(xy 93.922109 -241.611385) (xy 93.906399 -241.560455) (xy 93.898456 -241.507751) (xy 93.669622 -241.507751)
			(xy 93.661679 -241.560455) (xy 93.645969 -241.611385) (xy 93.622843 -241.659406) (xy 93.592819 -241.703443)
			(xy 93.556567 -241.742514) (xy 93.514896 -241.775745) (xy 93.468738 -241.802394) (xy 93.419124 -241.821866)
			(xy 93.367162 -241.833726) (xy 93.314012 -241.83771) (xy 93.260862 -241.833726) (xy 93.2089 -241.821866)
			(xy 93.159286 -241.802394) (xy 93.113128 -241.775745) (xy 93.071457 -241.742514) (xy 93.035205 -241.703443)
			(xy 93.005181 -241.659406) (xy 92.982055 -241.611385) (xy 92.966345 -241.560455) (xy 92.958402 -241.507751)
			(xy 92.729822 -241.507751) (xy 92.721879 -241.560455) (xy 92.706169 -241.611385) (xy 92.683043 -241.659406)
			(xy 92.653019 -241.703443) (xy 92.616767 -241.742514) (xy 92.575096 -241.775745) (xy 92.528938 -241.802394)
			(xy 92.479324 -241.821866) (xy 92.427362 -241.833726) (xy 92.374212 -241.83771) (xy 92.321062 -241.833726)
			(xy 92.2691 -241.821866) (xy 92.219486 -241.802394) (xy 92.173328 -241.775745) (xy 92.131657 -241.742514)
			(xy 92.095405 -241.703443) (xy 92.065381 -241.659406) (xy 92.042255 -241.611385) (xy 92.026545 -241.560455)
			(xy 92.018602 -241.507751) (xy 91.790022 -241.507751) (xy 91.782079 -241.560455) (xy 91.766369 -241.611385)
			(xy 91.743243 -241.659406) (xy 91.713219 -241.703443) (xy 91.676967 -241.742514) (xy 91.635296 -241.775745)
			(xy 91.589138 -241.802394) (xy 91.539524 -241.821866) (xy 91.487562 -241.833726) (xy 91.434412 -241.83771)
			(xy 91.381262 -241.833726) (xy 91.3293 -241.821866) (xy 91.279686 -241.802394) (xy 91.233528 -241.775745)
			(xy 91.191857 -241.742514) (xy 91.155605 -241.703443) (xy 91.125581 -241.659406) (xy 91.102455 -241.611385)
			(xy 91.086745 -241.560455) (xy 91.078802 -241.507751) (xy 90.850222 -241.507751) (xy 90.842279 -241.560455)
			(xy 90.826569 -241.611385) (xy 90.803443 -241.659406) (xy 90.773419 -241.703443) (xy 90.737167 -241.742514)
			(xy 90.695496 -241.775745) (xy 90.649338 -241.802394) (xy 90.599724 -241.821866) (xy 90.547762 -241.833726)
			(xy 90.494612 -241.83771) (xy 90.441462 -241.833726) (xy 90.3895 -241.821866) (xy 90.339886 -241.802394)
			(xy 90.293728 -241.775745) (xy 90.252057 -241.742514) (xy 90.215805 -241.703443) (xy 90.185781 -241.659406)
			(xy 90.162655 -241.611385) (xy 90.146945 -241.560455) (xy 90.139002 -241.507751) (xy 89.910422 -241.507751)
			(xy 89.902479 -241.560455) (xy 89.886769 -241.611385) (xy 89.863643 -241.659406) (xy 89.833619 -241.703443)
			(xy 89.797367 -241.742514) (xy 89.755696 -241.775745) (xy 89.709538 -241.802394) (xy 89.659924 -241.821866)
			(xy 89.607962 -241.833726) (xy 89.554812 -241.83771) (xy 89.501662 -241.833726) (xy 89.4497 -241.821866)
			(xy 89.400086 -241.802394) (xy 89.353928 -241.775745) (xy 89.312257 -241.742514) (xy 89.276005 -241.703443)
			(xy 89.245981 -241.659406) (xy 89.222855 -241.611385) (xy 89.207145 -241.560455) (xy 89.199202 -241.507751)
			(xy 88.970649 -241.507751) (xy 88.970649 -241.507878) (xy 88.962635 -241.560828) (xy 88.946787 -241.611982)
			(xy 88.93556 -241.636296) (xy 88.93048 -241.64671) (xy 88.93048 -241.840258) (xy 88.93096 -241.854554)
			(xy 88.938888 -241.882024) (xy 88.954133 -241.906212) (xy 88.975495 -241.925215) (xy 89.001295 -241.937539)
			(xy 89.029501 -241.942213) (xy 89.043764 -241.941096) (xy 89.054078 -241.939993) (xy 89.074793 -241.93885)
			(xy 89.085166 -241.93881) (xy 89.111817 -241.939281) (xy 89.164526 -241.947221) (xy 89.215462 -241.962928)
			(xy 89.263487 -241.986052) (xy 89.30753 -242.016076) (xy 89.346606 -242.052329) (xy 89.379841 -242.094001)
			(xy 89.406494 -242.140162) (xy 89.425969 -242.18978) (xy 89.43783 -242.241746) (xy 89.441814 -242.2949)
			(xy 89.439815 -242.321567) (xy 89.669356 -242.321567) (xy 89.669356 -242.268269) (xy 89.677299 -242.215565)
			(xy 89.693009 -242.164635) (xy 89.716135 -242.116614) (xy 89.746159 -242.072577) (xy 89.782411 -242.033506)
			(xy 89.824082 -242.000275) (xy 89.87024 -241.973626) (xy 89.919854 -241.954154) (xy 89.971816 -241.942294)
			(xy 90.024966 -241.938311) (xy 90.078116 -241.942294) (xy 90.130078 -241.954154) (xy 90.179692 -241.973626)
			(xy 90.22585 -242.000275) (xy 90.267521 -242.033506) (xy 90.303773 -242.072577) (xy 90.333797 -242.116614)
			(xy 90.356923 -242.164635) (xy 90.372633 -242.215565) (xy 90.380576 -242.268269) (xy 90.381074 -242.294918)
			(xy 90.380576 -242.321567) (xy 90.609156 -242.321567) (xy 90.609156 -242.268269) (xy 90.617099 -242.215565)
			(xy 90.632809 -242.164635) (xy 90.655935 -242.116614) (xy 90.685959 -242.072577) (xy 90.722211 -242.033506)
			(xy 90.763882 -242.000275) (xy 90.81004 -241.973626) (xy 90.859654 -241.954154) (xy 90.911616 -241.942294)
			(xy 90.964766 -241.938311) (xy 91.017916 -241.942294) (xy 91.069878 -241.954154) (xy 91.119492 -241.973626)
			(xy 91.16565 -242.000275) (xy 91.207321 -242.033506) (xy 91.243573 -242.072577) (xy 91.273597 -242.116614)
			(xy 91.296723 -242.164635) (xy 91.312433 -242.215565) (xy 91.320376 -242.268269) (xy 91.320874 -242.294918)
			(xy 91.320376 -242.321567) (xy 91.548956 -242.321567) (xy 91.548956 -242.268269) (xy 91.556899 -242.215565)
			(xy 91.572609 -242.164635) (xy 91.595735 -242.116614) (xy 91.625759 -242.072577) (xy 91.662011 -242.033506)
			(xy 91.703682 -242.000275) (xy 91.74984 -241.973626) (xy 91.799454 -241.954154) (xy 91.851416 -241.942294)
			(xy 91.904566 -241.938311) (xy 91.957716 -241.942294) (xy 92.009678 -241.954154) (xy 92.059292 -241.973626)
			(xy 92.10545 -242.000275) (xy 92.147121 -242.033506) (xy 92.183373 -242.072577) (xy 92.213397 -242.116614)
			(xy 92.236523 -242.164635) (xy 92.252233 -242.215565) (xy 92.260176 -242.268269) (xy 92.260674 -242.294918)
			(xy 92.260176 -242.321567) (xy 92.488756 -242.321567) (xy 92.488756 -242.268269) (xy 92.496699 -242.215565)
			(xy 92.512409 -242.164635) (xy 92.535535 -242.116614) (xy 92.565559 -242.072577) (xy 92.601811 -242.033506)
			(xy 92.643482 -242.000275) (xy 92.68964 -241.973626) (xy 92.739254 -241.954154) (xy 92.791216 -241.942294)
			(xy 92.844366 -241.938311) (xy 92.897516 -241.942294) (xy 92.949478 -241.954154) (xy 92.999092 -241.973626)
			(xy 93.04525 -242.000275) (xy 93.086921 -242.033506) (xy 93.123173 -242.072577) (xy 93.153197 -242.116614)
			(xy 93.176323 -242.164635) (xy 93.192033 -242.215565) (xy 93.199976 -242.268269) (xy 93.200474 -242.294918)
			(xy 93.199976 -242.321567) (xy 93.428556 -242.321567) (xy 93.428556 -242.268269) (xy 93.436499 -242.215565)
			(xy 93.452209 -242.164635) (xy 93.475335 -242.116614) (xy 93.505359 -242.072577) (xy 93.541611 -242.033506)
			(xy 93.583282 -242.000275) (xy 93.62944 -241.973626) (xy 93.679054 -241.954154) (xy 93.731016 -241.942294)
			(xy 93.784166 -241.938311) (xy 93.837316 -241.942294) (xy 93.889278 -241.954154) (xy 93.938892 -241.973626)
			(xy 93.98505 -242.000275) (xy 94.026721 -242.033506) (xy 94.062973 -242.072577) (xy 94.092997 -242.116614)
			(xy 94.116123 -242.164635) (xy 94.131833 -242.215565) (xy 94.139776 -242.268269) (xy 94.140274 -242.294918)
			(xy 94.139776 -242.321567) (xy 94.368356 -242.321567) (xy 94.368356 -242.268269) (xy 94.376299 -242.215565)
			(xy 94.392009 -242.164635) (xy 94.415135 -242.116614) (xy 94.445159 -242.072577) (xy 94.481411 -242.033506)
			(xy 94.523082 -242.000275) (xy 94.56924 -241.973626) (xy 94.618854 -241.954154) (xy 94.670816 -241.942294)
			(xy 94.723966 -241.938311) (xy 94.777116 -241.942294) (xy 94.829078 -241.954154) (xy 94.878692 -241.973626)
			(xy 94.92485 -242.000275) (xy 94.966521 -242.033506) (xy 95.002773 -242.072577) (xy 95.032797 -242.116614)
			(xy 95.055923 -242.164635) (xy 95.071633 -242.215565) (xy 95.079576 -242.268269) (xy 95.080074 -242.294918)
			(xy 95.079576 -242.321567) (xy 95.308156 -242.321567) (xy 95.308156 -242.268269) (xy 95.316099 -242.215565)
			(xy 95.331809 -242.164635) (xy 95.354935 -242.116614) (xy 95.384959 -242.072577) (xy 95.421211 -242.033506)
			(xy 95.462882 -242.000275) (xy 95.50904 -241.973626) (xy 95.558654 -241.954154) (xy 95.610616 -241.942294)
			(xy 95.663766 -241.938311) (xy 95.716916 -241.942294) (xy 95.768878 -241.954154) (xy 95.818492 -241.973626)
			(xy 95.86465 -242.000275) (xy 95.906321 -242.033506) (xy 95.942573 -242.072577) (xy 95.972597 -242.116614)
			(xy 95.995723 -242.164635) (xy 96.011433 -242.215565) (xy 96.019376 -242.268269) (xy 96.019874 -242.294918)
			(xy 96.019376 -242.321567) (xy 96.247956 -242.321567) (xy 96.247956 -242.268269) (xy 96.255899 -242.215565)
			(xy 96.271609 -242.164635) (xy 96.294735 -242.116614) (xy 96.324759 -242.072577) (xy 96.361011 -242.033506)
			(xy 96.402682 -242.000275) (xy 96.44884 -241.973626) (xy 96.498454 -241.954154) (xy 96.550416 -241.942294)
			(xy 96.603566 -241.938311) (xy 96.656716 -241.942294) (xy 96.708678 -241.954154) (xy 96.758292 -241.973626)
			(xy 96.80445 -242.000275) (xy 96.846121 -242.033506) (xy 96.882373 -242.072577) (xy 96.912397 -242.116614)
			(xy 96.935523 -242.164635) (xy 96.951233 -242.215565) (xy 96.959176 -242.268269) (xy 96.959674 -242.294918)
			(xy 96.959176 -242.321567) (xy 97.187756 -242.321567) (xy 97.187756 -242.268269) (xy 97.195699 -242.215565)
			(xy 97.211409 -242.164635) (xy 97.234535 -242.116614) (xy 97.264559 -242.072577) (xy 97.300811 -242.033506)
			(xy 97.342482 -242.000275) (xy 97.38864 -241.973626) (xy 97.438254 -241.954154) (xy 97.490216 -241.942294)
			(xy 97.543366 -241.938311) (xy 97.596516 -241.942294) (xy 97.648478 -241.954154) (xy 97.698092 -241.973626)
			(xy 97.74425 -242.000275) (xy 97.785921 -242.033506) (xy 97.822173 -242.072577) (xy 97.852197 -242.116614)
			(xy 97.875323 -242.164635) (xy 97.891033 -242.215565) (xy 97.898976 -242.268269) (xy 97.899474 -242.294918)
			(xy 97.898976 -242.321567) (xy 98.127556 -242.321567) (xy 98.127556 -242.268269) (xy 98.135499 -242.215565)
			(xy 98.151209 -242.164635) (xy 98.174335 -242.116614) (xy 98.204359 -242.072577) (xy 98.240611 -242.033506)
			(xy 98.282282 -242.000275) (xy 98.32844 -241.973626) (xy 98.378054 -241.954154) (xy 98.430016 -241.942294)
			(xy 98.483166 -241.938311) (xy 98.536316 -241.942294) (xy 98.588278 -241.954154) (xy 98.637892 -241.973626)
			(xy 98.68405 -242.000275) (xy 98.725721 -242.033506) (xy 98.761973 -242.072577) (xy 98.791997 -242.116614)
			(xy 98.815123 -242.164635) (xy 98.830833 -242.215565) (xy 98.838776 -242.268269) (xy 98.839274 -242.294918)
			(xy 98.838776 -242.321567) (xy 98.830833 -242.374271) (xy 98.815123 -242.425201) (xy 98.791997 -242.473222)
			(xy 98.761973 -242.517259) (xy 98.725721 -242.55633) (xy 98.68405 -242.589561) (xy 98.637892 -242.61621)
			(xy 98.588278 -242.635682) (xy 98.536316 -242.647542) (xy 98.483166 -242.651526) (xy 98.430016 -242.647542)
			(xy 98.378054 -242.635682) (xy 98.32844 -242.61621) (xy 98.282282 -242.589561) (xy 98.240611 -242.55633)
			(xy 98.204359 -242.517259) (xy 98.174335 -242.473222) (xy 98.151209 -242.425201) (xy 98.135499 -242.374271)
			(xy 98.127556 -242.321567) (xy 97.898976 -242.321567) (xy 97.891033 -242.374271) (xy 97.875323 -242.425201)
			(xy 97.852197 -242.473222) (xy 97.822173 -242.517259) (xy 97.785921 -242.55633) (xy 97.74425 -242.589561)
			(xy 97.698092 -242.61621) (xy 97.648478 -242.635682) (xy 97.596516 -242.647542) (xy 97.543366 -242.651526)
			(xy 97.490216 -242.647542) (xy 97.438254 -242.635682) (xy 97.38864 -242.61621) (xy 97.342482 -242.589561)
			(xy 97.300811 -242.55633) (xy 97.264559 -242.517259) (xy 97.234535 -242.473222) (xy 97.211409 -242.425201)
			(xy 97.195699 -242.374271) (xy 97.187756 -242.321567) (xy 96.959176 -242.321567) (xy 96.951233 -242.374271)
			(xy 96.935523 -242.425201) (xy 96.912397 -242.473222) (xy 96.882373 -242.517259) (xy 96.846121 -242.55633)
			(xy 96.80445 -242.589561) (xy 96.758292 -242.61621) (xy 96.708678 -242.635682) (xy 96.656716 -242.647542)
			(xy 96.603566 -242.651526) (xy 96.550416 -242.647542) (xy 96.498454 -242.635682) (xy 96.44884 -242.61621)
			(xy 96.402682 -242.589561) (xy 96.361011 -242.55633) (xy 96.324759 -242.517259) (xy 96.294735 -242.473222)
			(xy 96.271609 -242.425201) (xy 96.255899 -242.374271) (xy 96.247956 -242.321567) (xy 96.019376 -242.321567)
			(xy 96.011433 -242.374271) (xy 95.995723 -242.425201) (xy 95.972597 -242.473222) (xy 95.942573 -242.517259)
			(xy 95.906321 -242.55633) (xy 95.86465 -242.589561) (xy 95.818492 -242.61621) (xy 95.768878 -242.635682)
			(xy 95.716916 -242.647542) (xy 95.663766 -242.651526) (xy 95.610616 -242.647542) (xy 95.558654 -242.635682)
			(xy 95.50904 -242.61621) (xy 95.462882 -242.589561) (xy 95.421211 -242.55633) (xy 95.384959 -242.517259)
			(xy 95.354935 -242.473222) (xy 95.331809 -242.425201) (xy 95.316099 -242.374271) (xy 95.308156 -242.321567)
			(xy 95.079576 -242.321567) (xy 95.071633 -242.374271) (xy 95.055923 -242.425201) (xy 95.032797 -242.473222)
			(xy 95.002773 -242.517259) (xy 94.966521 -242.55633) (xy 94.92485 -242.589561) (xy 94.878692 -242.61621)
			(xy 94.829078 -242.635682) (xy 94.777116 -242.647542) (xy 94.723966 -242.651526) (xy 94.670816 -242.647542)
			(xy 94.618854 -242.635682) (xy 94.56924 -242.61621) (xy 94.523082 -242.589561) (xy 94.481411 -242.55633)
			(xy 94.445159 -242.517259) (xy 94.415135 -242.473222) (xy 94.392009 -242.425201) (xy 94.376299 -242.374271)
			(xy 94.368356 -242.321567) (xy 94.139776 -242.321567) (xy 94.131833 -242.374271) (xy 94.116123 -242.425201)
			(xy 94.092997 -242.473222) (xy 94.062973 -242.517259) (xy 94.026721 -242.55633) (xy 93.98505 -242.589561)
			(xy 93.938892 -242.61621) (xy 93.889278 -242.635682) (xy 93.837316 -242.647542) (xy 93.784166 -242.651526)
			(xy 93.731016 -242.647542) (xy 93.679054 -242.635682) (xy 93.62944 -242.61621) (xy 93.583282 -242.589561)
			(xy 93.541611 -242.55633) (xy 93.505359 -242.517259) (xy 93.475335 -242.473222) (xy 93.452209 -242.425201)
			(xy 93.436499 -242.374271) (xy 93.428556 -242.321567) (xy 93.199976 -242.321567) (xy 93.192033 -242.374271)
			(xy 93.176323 -242.425201) (xy 93.153197 -242.473222) (xy 93.123173 -242.517259) (xy 93.086921 -242.55633)
			(xy 93.04525 -242.589561) (xy 92.999092 -242.61621) (xy 92.949478 -242.635682) (xy 92.897516 -242.647542)
			(xy 92.844366 -242.651526) (xy 92.791216 -242.647542) (xy 92.739254 -242.635682) (xy 92.68964 -242.61621)
			(xy 92.643482 -242.589561) (xy 92.601811 -242.55633) (xy 92.565559 -242.517259) (xy 92.535535 -242.473222)
			(xy 92.512409 -242.425201) (xy 92.496699 -242.374271) (xy 92.488756 -242.321567) (xy 92.260176 -242.321567)
			(xy 92.252233 -242.374271) (xy 92.236523 -242.425201) (xy 92.213397 -242.473222) (xy 92.183373 -242.517259)
			(xy 92.147121 -242.55633) (xy 92.10545 -242.589561) (xy 92.059292 -242.61621) (xy 92.009678 -242.635682)
			(xy 91.957716 -242.647542) (xy 91.904566 -242.651526) (xy 91.851416 -242.647542) (xy 91.799454 -242.635682)
			(xy 91.74984 -242.61621) (xy 91.703682 -242.589561) (xy 91.662011 -242.55633) (xy 91.625759 -242.517259)
			(xy 91.595735 -242.473222) (xy 91.572609 -242.425201) (xy 91.556899 -242.374271) (xy 91.548956 -242.321567)
			(xy 91.320376 -242.321567) (xy 91.312433 -242.374271) (xy 91.296723 -242.425201) (xy 91.273597 -242.473222)
			(xy 91.243573 -242.517259) (xy 91.207321 -242.55633) (xy 91.16565 -242.589561) (xy 91.119492 -242.61621)
			(xy 91.069878 -242.635682) (xy 91.017916 -242.647542) (xy 90.964766 -242.651526) (xy 90.911616 -242.647542)
			(xy 90.859654 -242.635682) (xy 90.81004 -242.61621) (xy 90.763882 -242.589561) (xy 90.722211 -242.55633)
			(xy 90.685959 -242.517259) (xy 90.655935 -242.473222) (xy 90.632809 -242.425201) (xy 90.617099 -242.374271)
			(xy 90.609156 -242.321567) (xy 90.380576 -242.321567) (xy 90.372633 -242.374271) (xy 90.356923 -242.425201)
			(xy 90.333797 -242.473222) (xy 90.303773 -242.517259) (xy 90.267521 -242.55633) (xy 90.22585 -242.589561)
			(xy 90.179692 -242.61621) (xy 90.130078 -242.635682) (xy 90.078116 -242.647542) (xy 90.024966 -242.651526)
			(xy 89.971816 -242.647542) (xy 89.919854 -242.635682) (xy 89.87024 -242.61621) (xy 89.824082 -242.589561)
			(xy 89.782411 -242.55633) (xy 89.746159 -242.517259) (xy 89.716135 -242.473222) (xy 89.693009 -242.425201)
			(xy 89.677299 -242.374271) (xy 89.669356 -242.321567) (xy 89.439815 -242.321567) (xy 89.43783 -242.348054)
			(xy 89.425969 -242.40002) (xy 89.406494 -242.449638) (xy 89.379841 -242.495799) (xy 89.346606 -242.537471)
			(xy 89.30753 -242.573724) (xy 89.263487 -242.603748) (xy 89.215462 -242.626872) (xy 89.164526 -242.642579)
			(xy 89.111817 -242.650519) (xy 89.085166 -242.651026) (xy 89.074793 -242.65098) (xy 89.054079 -242.649838)
			(xy 89.043764 -242.64874) (xy 89.029509 -242.647579) (xy 89.001313 -242.652296) (xy 88.975529 -242.66464)
			(xy 88.954174 -242.683647) (xy 88.938923 -242.707826) (xy 88.930968 -242.735285) (xy 88.93048 -242.749578)
			(xy 88.93048 -242.94338) (xy 88.93556 -242.953794) (xy 88.946789 -242.978107) (xy 88.962639 -243.029262)
			(xy 88.970654 -243.082212) (xy 88.970656 -243.135637) (xy 89.199202 -243.135637) (xy 89.199202 -243.082339)
			(xy 89.207145 -243.029635) (xy 89.222855 -242.978705) (xy 89.245981 -242.930684) (xy 89.276005 -242.886647)
			(xy 89.312257 -242.847576) (xy 89.353928 -242.814345) (xy 89.400086 -242.787696) (xy 89.4497 -242.768224)
			(xy 89.501662 -242.756364) (xy 89.554812 -242.752381) (xy 89.607962 -242.756364) (xy 89.659924 -242.768224)
			(xy 89.709538 -242.787696) (xy 89.755696 -242.814345) (xy 89.797367 -242.847576) (xy 89.833619 -242.886647)
			(xy 89.863643 -242.930684) (xy 89.886769 -242.978705) (xy 89.902479 -243.029635) (xy 89.910422 -243.082339)
			(xy 89.91092 -243.108988) (xy 89.910422 -243.135637) (xy 90.139002 -243.135637) (xy 90.139002 -243.082339)
			(xy 90.146945 -243.029635) (xy 90.162655 -242.978705) (xy 90.185781 -242.930684) (xy 90.215805 -242.886647)
			(xy 90.252057 -242.847576) (xy 90.293728 -242.814345) (xy 90.339886 -242.787696) (xy 90.3895 -242.768224)
			(xy 90.441462 -242.756364) (xy 90.494612 -242.752381) (xy 90.547762 -242.756364) (xy 90.599724 -242.768224)
			(xy 90.649338 -242.787696) (xy 90.695496 -242.814345) (xy 90.737167 -242.847576) (xy 90.773419 -242.886647)
			(xy 90.803443 -242.930684) (xy 90.826569 -242.978705) (xy 90.842279 -243.029635) (xy 90.850222 -243.082339)
			(xy 90.85072 -243.108988) (xy 90.850222 -243.135637) (xy 91.079056 -243.135637) (xy 91.079056 -243.082339)
			(xy 91.086999 -243.029635) (xy 91.102709 -242.978705) (xy 91.125835 -242.930684) (xy 91.155859 -242.886647)
			(xy 91.192111 -242.847576) (xy 91.233782 -242.814345) (xy 91.27994 -242.787696) (xy 91.329554 -242.768224)
			(xy 91.381516 -242.756364) (xy 91.434666 -242.752381) (xy 91.487816 -242.756364) (xy 91.539778 -242.768224)
			(xy 91.589392 -242.787696) (xy 91.63555 -242.814345) (xy 91.677221 -242.847576) (xy 91.713473 -242.886647)
			(xy 91.743497 -242.930684) (xy 91.766623 -242.978705) (xy 91.782333 -243.029635) (xy 91.790276 -243.082339)
			(xy 91.790774 -243.108988) (xy 91.790276 -243.135637) (xy 92.018602 -243.135637) (xy 92.018602 -243.082339)
			(xy 92.026545 -243.029635) (xy 92.042255 -242.978705) (xy 92.065381 -242.930684) (xy 92.095405 -242.886647)
			(xy 92.131657 -242.847576) (xy 92.173328 -242.814345) (xy 92.219486 -242.787696) (xy 92.2691 -242.768224)
			(xy 92.321062 -242.756364) (xy 92.374212 -242.752381) (xy 92.427362 -242.756364) (xy 92.479324 -242.768224)
			(xy 92.528938 -242.787696) (xy 92.575096 -242.814345) (xy 92.616767 -242.847576) (xy 92.653019 -242.886647)
			(xy 92.683043 -242.930684) (xy 92.706169 -242.978705) (xy 92.721879 -243.029635) (xy 92.729822 -243.082339)
			(xy 92.73032 -243.108988) (xy 92.729822 -243.135637) (xy 92.958402 -243.135637) (xy 92.958402 -243.082339)
			(xy 92.966345 -243.029635) (xy 92.982055 -242.978705) (xy 93.005181 -242.930684) (xy 93.035205 -242.886647)
			(xy 93.071457 -242.847576) (xy 93.113128 -242.814345) (xy 93.159286 -242.787696) (xy 93.2089 -242.768224)
			(xy 93.260862 -242.756364) (xy 93.314012 -242.752381) (xy 93.367162 -242.756364) (xy 93.419124 -242.768224)
			(xy 93.468738 -242.787696) (xy 93.514896 -242.814345) (xy 93.556567 -242.847576) (xy 93.592819 -242.886647)
			(xy 93.622843 -242.930684) (xy 93.645969 -242.978705) (xy 93.661679 -243.029635) (xy 93.669622 -243.082339)
			(xy 93.67012 -243.108988) (xy 93.669622 -243.135637) (xy 93.898202 -243.135637) (xy 93.898202 -243.082339)
			(xy 93.906145 -243.029635) (xy 93.921855 -242.978705) (xy 93.944981 -242.930684) (xy 93.975005 -242.886647)
			(xy 94.011257 -242.847576) (xy 94.052928 -242.814345) (xy 94.099086 -242.787696) (xy 94.1487 -242.768224)
			(xy 94.200662 -242.756364) (xy 94.253812 -242.752381) (xy 94.306962 -242.756364) (xy 94.358924 -242.768224)
			(xy 94.408538 -242.787696) (xy 94.454696 -242.814345) (xy 94.496367 -242.847576) (xy 94.532619 -242.886647)
			(xy 94.562643 -242.930684) (xy 94.585769 -242.978705) (xy 94.601479 -243.029635) (xy 94.609422 -243.082339)
			(xy 94.60992 -243.108988) (xy 94.609422 -243.135637) (xy 94.838002 -243.135637) (xy 94.838002 -243.082339)
			(xy 94.845945 -243.029635) (xy 94.861655 -242.978705) (xy 94.884781 -242.930684) (xy 94.914805 -242.886647)
			(xy 94.951057 -242.847576) (xy 94.992728 -242.814345) (xy 95.038886 -242.787696) (xy 95.0885 -242.768224)
			(xy 95.140462 -242.756364) (xy 95.193612 -242.752381) (xy 95.246762 -242.756364) (xy 95.298724 -242.768224)
			(xy 95.348338 -242.787696) (xy 95.394496 -242.814345) (xy 95.436167 -242.847576) (xy 95.472419 -242.886647)
			(xy 95.502443 -242.930684) (xy 95.525569 -242.978705) (xy 95.541279 -243.029635) (xy 95.549222 -243.082339)
			(xy 95.54972 -243.108988) (xy 95.549222 -243.135637) (xy 95.777802 -243.135637) (xy 95.777802 -243.082339)
			(xy 95.785745 -243.029635) (xy 95.801455 -242.978705) (xy 95.824581 -242.930684) (xy 95.854605 -242.886647)
			(xy 95.890857 -242.847576) (xy 95.932528 -242.814345) (xy 95.978686 -242.787696) (xy 96.0283 -242.768224)
			(xy 96.080262 -242.756364) (xy 96.133412 -242.752381) (xy 96.186562 -242.756364) (xy 96.238524 -242.768224)
			(xy 96.288138 -242.787696) (xy 96.334296 -242.814345) (xy 96.375967 -242.847576) (xy 96.412219 -242.886647)
			(xy 96.442243 -242.930684) (xy 96.465369 -242.978705) (xy 96.481079 -243.029635) (xy 96.489022 -243.082339)
			(xy 96.48952 -243.108988) (xy 96.489022 -243.135637) (xy 96.717602 -243.135637) (xy 96.717602 -243.082339)
			(xy 96.725545 -243.029635) (xy 96.741255 -242.978705) (xy 96.764381 -242.930684) (xy 96.794405 -242.886647)
			(xy 96.830657 -242.847576) (xy 96.872328 -242.814345) (xy 96.918486 -242.787696) (xy 96.9681 -242.768224)
			(xy 97.020062 -242.756364) (xy 97.073212 -242.752381) (xy 97.126362 -242.756364) (xy 97.178324 -242.768224)
			(xy 97.227938 -242.787696) (xy 97.274096 -242.814345) (xy 97.315767 -242.847576) (xy 97.352019 -242.886647)
			(xy 97.382043 -242.930684) (xy 97.405169 -242.978705) (xy 97.420879 -243.029635) (xy 97.428822 -243.082339)
			(xy 97.42932 -243.108988) (xy 97.428822 -243.135637) (xy 97.657656 -243.135637) (xy 97.657656 -243.082339)
			(xy 97.665599 -243.029635) (xy 97.681309 -242.978705) (xy 97.704435 -242.930684) (xy 97.734459 -242.886647)
			(xy 97.770711 -242.847576) (xy 97.812382 -242.814345) (xy 97.85854 -242.787696) (xy 97.908154 -242.768224)
			(xy 97.960116 -242.756364) (xy 98.013266 -242.752381) (xy 98.066416 -242.756364) (xy 98.118378 -242.768224)
			(xy 98.167992 -242.787696) (xy 98.21415 -242.814345) (xy 98.255821 -242.847576) (xy 98.292073 -242.886647)
			(xy 98.322097 -242.930684) (xy 98.345223 -242.978705) (xy 98.360933 -243.029635) (xy 98.368876 -243.082339)
			(xy 98.369374 -243.108988) (xy 98.368876 -243.135637) (xy 98.597202 -243.135637) (xy 98.597202 -243.082339)
			(xy 98.605145 -243.029635) (xy 98.620855 -242.978705) (xy 98.643981 -242.930684) (xy 98.674005 -242.886647)
			(xy 98.710257 -242.847576) (xy 98.751928 -242.814345) (xy 98.798086 -242.787696) (xy 98.8477 -242.768224)
			(xy 98.899662 -242.756364) (xy 98.952812 -242.752381) (xy 99.005962 -242.756364) (xy 99.057924 -242.768224)
			(xy 99.107538 -242.787696) (xy 99.153696 -242.814345) (xy 99.195367 -242.847576) (xy 99.231619 -242.886647)
			(xy 99.261643 -242.930684) (xy 99.284769 -242.978705) (xy 99.300479 -243.029635) (xy 99.308422 -243.082339)
			(xy 99.30892 -243.108988) (xy 99.308422 -243.135637) (xy 99.300479 -243.188341) (xy 99.284769 -243.239271)
			(xy 99.261643 -243.287292) (xy 99.231619 -243.331329) (xy 99.195367 -243.3704) (xy 99.153696 -243.403631)
			(xy 99.107538 -243.43028) (xy 99.057924 -243.449752) (xy 99.005962 -243.461612) (xy 98.952812 -243.465596)
			(xy 98.899662 -243.461612) (xy 98.8477 -243.449752) (xy 98.798086 -243.43028) (xy 98.751928 -243.403631)
			(xy 98.710257 -243.3704) (xy 98.674005 -243.331329) (xy 98.643981 -243.287292) (xy 98.620855 -243.239271)
			(xy 98.605145 -243.188341) (xy 98.597202 -243.135637) (xy 98.368876 -243.135637) (xy 98.360933 -243.188341)
			(xy 98.345223 -243.239271) (xy 98.322097 -243.287292) (xy 98.292073 -243.331329) (xy 98.255821 -243.3704)
			(xy 98.21415 -243.403631) (xy 98.167992 -243.43028) (xy 98.118378 -243.449752) (xy 98.066416 -243.461612)
			(xy 98.013266 -243.465596) (xy 97.960116 -243.461612) (xy 97.908154 -243.449752) (xy 97.85854 -243.43028)
			(xy 97.812382 -243.403631) (xy 97.770711 -243.3704) (xy 97.734459 -243.331329) (xy 97.704435 -243.287292)
			(xy 97.681309 -243.239271) (xy 97.665599 -243.188341) (xy 97.657656 -243.135637) (xy 97.428822 -243.135637)
			(xy 97.420879 -243.188341) (xy 97.405169 -243.239271) (xy 97.382043 -243.287292) (xy 97.352019 -243.331329)
			(xy 97.315767 -243.3704) (xy 97.274096 -243.403631) (xy 97.227938 -243.43028) (xy 97.178324 -243.449752)
			(xy 97.126362 -243.461612) (xy 97.073212 -243.465596) (xy 97.020062 -243.461612) (xy 96.9681 -243.449752)
			(xy 96.918486 -243.43028) (xy 96.872328 -243.403631) (xy 96.830657 -243.3704) (xy 96.794405 -243.331329)
			(xy 96.764381 -243.287292) (xy 96.741255 -243.239271) (xy 96.725545 -243.188341) (xy 96.717602 -243.135637)
			(xy 96.489022 -243.135637) (xy 96.481079 -243.188341) (xy 96.465369 -243.239271) (xy 96.442243 -243.287292)
			(xy 96.412219 -243.331329) (xy 96.375967 -243.3704) (xy 96.334296 -243.403631) (xy 96.288138 -243.43028)
			(xy 96.238524 -243.449752) (xy 96.186562 -243.461612) (xy 96.133412 -243.465596) (xy 96.080262 -243.461612)
			(xy 96.0283 -243.449752) (xy 95.978686 -243.43028) (xy 95.932528 -243.403631) (xy 95.890857 -243.3704)
			(xy 95.854605 -243.331329) (xy 95.824581 -243.287292) (xy 95.801455 -243.239271) (xy 95.785745 -243.188341)
			(xy 95.777802 -243.135637) (xy 95.549222 -243.135637) (xy 95.541279 -243.188341) (xy 95.525569 -243.239271)
			(xy 95.502443 -243.287292) (xy 95.472419 -243.331329) (xy 95.436167 -243.3704) (xy 95.394496 -243.403631)
			(xy 95.348338 -243.43028) (xy 95.298724 -243.449752) (xy 95.246762 -243.461612) (xy 95.193612 -243.465596)
			(xy 95.140462 -243.461612) (xy 95.0885 -243.449752) (xy 95.038886 -243.43028) (xy 94.992728 -243.403631)
			(xy 94.951057 -243.3704) (xy 94.914805 -243.331329) (xy 94.884781 -243.287292) (xy 94.861655 -243.239271)
			(xy 94.845945 -243.188341) (xy 94.838002 -243.135637) (xy 94.609422 -243.135637) (xy 94.601479 -243.188341)
			(xy 94.585769 -243.239271) (xy 94.562643 -243.287292) (xy 94.532619 -243.331329) (xy 94.496367 -243.3704)
			(xy 94.454696 -243.403631) (xy 94.408538 -243.43028) (xy 94.358924 -243.449752) (xy 94.306962 -243.461612)
			(xy 94.253812 -243.465596) (xy 94.200662 -243.461612) (xy 94.1487 -243.449752) (xy 94.099086 -243.43028)
			(xy 94.052928 -243.403631) (xy 94.011257 -243.3704) (xy 93.975005 -243.331329) (xy 93.944981 -243.287292)
			(xy 93.921855 -243.239271) (xy 93.906145 -243.188341) (xy 93.898202 -243.135637) (xy 93.669622 -243.135637)
			(xy 93.661679 -243.188341) (xy 93.645969 -243.239271) (xy 93.622843 -243.287292) (xy 93.592819 -243.331329)
			(xy 93.556567 -243.3704) (xy 93.514896 -243.403631) (xy 93.468738 -243.43028) (xy 93.419124 -243.449752)
			(xy 93.367162 -243.461612) (xy 93.314012 -243.465596) (xy 93.260862 -243.461612) (xy 93.2089 -243.449752)
			(xy 93.159286 -243.43028) (xy 93.113128 -243.403631) (xy 93.071457 -243.3704) (xy 93.035205 -243.331329)
			(xy 93.005181 -243.287292) (xy 92.982055 -243.239271) (xy 92.966345 -243.188341) (xy 92.958402 -243.135637)
			(xy 92.729822 -243.135637) (xy 92.721879 -243.188341) (xy 92.706169 -243.239271) (xy 92.683043 -243.287292)
			(xy 92.653019 -243.331329) (xy 92.616767 -243.3704) (xy 92.575096 -243.403631) (xy 92.528938 -243.43028)
			(xy 92.479324 -243.449752) (xy 92.427362 -243.461612) (xy 92.374212 -243.465596) (xy 92.321062 -243.461612)
			(xy 92.2691 -243.449752) (xy 92.219486 -243.43028) (xy 92.173328 -243.403631) (xy 92.131657 -243.3704)
			(xy 92.095405 -243.331329) (xy 92.065381 -243.287292) (xy 92.042255 -243.239271) (xy 92.026545 -243.188341)
			(xy 92.018602 -243.135637) (xy 91.790276 -243.135637) (xy 91.782333 -243.188341) (xy 91.766623 -243.239271)
			(xy 91.743497 -243.287292) (xy 91.713473 -243.331329) (xy 91.677221 -243.3704) (xy 91.63555 -243.403631)
			(xy 91.589392 -243.43028) (xy 91.539778 -243.449752) (xy 91.487816 -243.461612) (xy 91.434666 -243.465596)
			(xy 91.381516 -243.461612) (xy 91.329554 -243.449752) (xy 91.27994 -243.43028) (xy 91.233782 -243.403631)
			(xy 91.192111 -243.3704) (xy 91.155859 -243.331329) (xy 91.125835 -243.287292) (xy 91.102709 -243.239271)
			(xy 91.086999 -243.188341) (xy 91.079056 -243.135637) (xy 90.850222 -243.135637) (xy 90.842279 -243.188341)
			(xy 90.826569 -243.239271) (xy 90.803443 -243.287292) (xy 90.773419 -243.331329) (xy 90.737167 -243.3704)
			(xy 90.695496 -243.403631) (xy 90.649338 -243.43028) (xy 90.599724 -243.449752) (xy 90.547762 -243.461612)
			(xy 90.494612 -243.465596) (xy 90.441462 -243.461612) (xy 90.3895 -243.449752) (xy 90.339886 -243.43028)
			(xy 90.293728 -243.403631) (xy 90.252057 -243.3704) (xy 90.215805 -243.331329) (xy 90.185781 -243.287292)
			(xy 90.162655 -243.239271) (xy 90.146945 -243.188341) (xy 90.139002 -243.135637) (xy 89.910422 -243.135637)
			(xy 89.902479 -243.188341) (xy 89.886769 -243.239271) (xy 89.863643 -243.287292) (xy 89.833619 -243.331329)
			(xy 89.797367 -243.3704) (xy 89.755696 -243.403631) (xy 89.709538 -243.43028) (xy 89.659924 -243.449752)
			(xy 89.607962 -243.461612) (xy 89.554812 -243.465596) (xy 89.501662 -243.461612) (xy 89.4497 -243.449752)
			(xy 89.400086 -243.43028) (xy 89.353928 -243.403631) (xy 89.312257 -243.3704) (xy 89.276005 -243.331329)
			(xy 89.245981 -243.287292) (xy 89.222855 -243.239271) (xy 89.207145 -243.188341) (xy 89.199202 -243.135637)
			(xy 88.970656 -243.135637) (xy 88.970656 -243.135766) (xy 88.962644 -243.188717) (xy 88.946797 -243.239873)
			(xy 88.93556 -243.264182) (xy 88.93048 -243.274596) (xy 88.93048 -243.468144) (xy 88.930958 -243.482441)
			(xy 88.938884 -243.509915) (xy 88.954128 -243.534106) (xy 88.975491 -243.553112) (xy 89.001292 -243.565438)
			(xy 89.029501 -243.570113) (xy 89.043764 -243.568982) (xy 89.054078 -243.567879) (xy 89.074793 -243.566736)
			(xy 89.085166 -243.566696) (xy 89.111819 -243.567167) (xy 89.164529 -243.575107) (xy 89.215467 -243.590815)
			(xy 89.263494 -243.61394) (xy 89.307539 -243.643965) (xy 89.346616 -243.680219) (xy 89.379853 -243.721894)
			(xy 89.406507 -243.768056) (xy 89.425982 -243.817676) (xy 89.437844 -243.869644) (xy 89.441828 -243.9228)
			(xy 89.43983 -243.949453) (xy 89.669356 -243.949453) (xy 89.669356 -243.896155) (xy 89.677299 -243.843451)
			(xy 89.693009 -243.792521) (xy 89.716135 -243.7445) (xy 89.746159 -243.700463) (xy 89.782411 -243.661392)
			(xy 89.824082 -243.628161) (xy 89.87024 -243.601512) (xy 89.919854 -243.58204) (xy 89.971816 -243.57018)
			(xy 90.024966 -243.566197) (xy 90.078116 -243.57018) (xy 90.130078 -243.58204) (xy 90.179692 -243.601512)
			(xy 90.22585 -243.628161) (xy 90.267521 -243.661392) (xy 90.303773 -243.700463) (xy 90.333797 -243.7445)
			(xy 90.356923 -243.792521) (xy 90.372633 -243.843451) (xy 90.380576 -243.896155) (xy 90.381074 -243.922804)
			(xy 90.380576 -243.949453) (xy 90.609156 -243.949453) (xy 90.609156 -243.896155) (xy 90.617099 -243.843451)
			(xy 90.632809 -243.792521) (xy 90.655935 -243.7445) (xy 90.685959 -243.700463) (xy 90.722211 -243.661392)
			(xy 90.763882 -243.628161) (xy 90.81004 -243.601512) (xy 90.859654 -243.58204) (xy 90.911616 -243.57018)
			(xy 90.964766 -243.566197) (xy 91.017916 -243.57018) (xy 91.069878 -243.58204) (xy 91.119492 -243.601512)
			(xy 91.16565 -243.628161) (xy 91.207321 -243.661392) (xy 91.243573 -243.700463) (xy 91.273597 -243.7445)
			(xy 91.296723 -243.792521) (xy 91.312433 -243.843451) (xy 91.320376 -243.896155) (xy 91.320874 -243.922804)
			(xy 91.320376 -243.949453) (xy 91.548956 -243.949453) (xy 91.548956 -243.896155) (xy 91.556899 -243.843451)
			(xy 91.572609 -243.792521) (xy 91.595735 -243.7445) (xy 91.625759 -243.700463) (xy 91.662011 -243.661392)
			(xy 91.703682 -243.628161) (xy 91.74984 -243.601512) (xy 91.799454 -243.58204) (xy 91.851416 -243.57018)
			(xy 91.904566 -243.566197) (xy 91.957716 -243.57018) (xy 92.009678 -243.58204) (xy 92.059292 -243.601512)
			(xy 92.10545 -243.628161) (xy 92.147121 -243.661392) (xy 92.183373 -243.700463) (xy 92.213397 -243.7445)
			(xy 92.236523 -243.792521) (xy 92.252233 -243.843451) (xy 92.260176 -243.896155) (xy 92.260674 -243.922804)
			(xy 92.260176 -243.949453) (xy 92.488756 -243.949453) (xy 92.488756 -243.896155) (xy 92.496699 -243.843451)
			(xy 92.512409 -243.792521) (xy 92.535535 -243.7445) (xy 92.565559 -243.700463) (xy 92.601811 -243.661392)
			(xy 92.643482 -243.628161) (xy 92.68964 -243.601512) (xy 92.739254 -243.58204) (xy 92.791216 -243.57018)
			(xy 92.844366 -243.566197) (xy 92.897516 -243.57018) (xy 92.949478 -243.58204) (xy 92.999092 -243.601512)
			(xy 93.04525 -243.628161) (xy 93.086921 -243.661392) (xy 93.123173 -243.700463) (xy 93.153197 -243.7445)
			(xy 93.176323 -243.792521) (xy 93.192033 -243.843451) (xy 93.199976 -243.896155) (xy 93.200474 -243.922804)
			(xy 93.199976 -243.949453) (xy 93.428556 -243.949453) (xy 93.428556 -243.896155) (xy 93.436499 -243.843451)
			(xy 93.452209 -243.792521) (xy 93.475335 -243.7445) (xy 93.505359 -243.700463) (xy 93.541611 -243.661392)
			(xy 93.583282 -243.628161) (xy 93.62944 -243.601512) (xy 93.679054 -243.58204) (xy 93.731016 -243.57018)
			(xy 93.784166 -243.566197) (xy 93.837316 -243.57018) (xy 93.889278 -243.58204) (xy 93.938892 -243.601512)
			(xy 93.98505 -243.628161) (xy 94.026721 -243.661392) (xy 94.062973 -243.700463) (xy 94.092997 -243.7445)
			(xy 94.116123 -243.792521) (xy 94.131833 -243.843451) (xy 94.139776 -243.896155) (xy 94.140274 -243.922804)
			(xy 94.139776 -243.949453) (xy 94.368102 -243.949453) (xy 94.368102 -243.896155) (xy 94.376045 -243.843451)
			(xy 94.391755 -243.792521) (xy 94.414881 -243.7445) (xy 94.444905 -243.700463) (xy 94.481157 -243.661392)
			(xy 94.522828 -243.628161) (xy 94.568986 -243.601512) (xy 94.6186 -243.58204) (xy 94.670562 -243.57018)
			(xy 94.723712 -243.566197) (xy 94.776862 -243.57018) (xy 94.828824 -243.58204) (xy 94.878438 -243.601512)
			(xy 94.924596 -243.628161) (xy 94.966267 -243.661392) (xy 95.002519 -243.700463) (xy 95.032543 -243.7445)
			(xy 95.055669 -243.792521) (xy 95.071379 -243.843451) (xy 95.079322 -243.896155) (xy 95.07982 -243.922804)
			(xy 95.079322 -243.949453) (xy 95.308156 -243.949453) (xy 95.308156 -243.896155) (xy 95.316099 -243.843451)
			(xy 95.331809 -243.792521) (xy 95.354935 -243.7445) (xy 95.384959 -243.700463) (xy 95.421211 -243.661392)
			(xy 95.462882 -243.628161) (xy 95.50904 -243.601512) (xy 95.558654 -243.58204) (xy 95.610616 -243.57018)
			(xy 95.663766 -243.566197) (xy 95.716916 -243.57018) (xy 95.768878 -243.58204) (xy 95.818492 -243.601512)
			(xy 95.86465 -243.628161) (xy 95.906321 -243.661392) (xy 95.942573 -243.700463) (xy 95.972597 -243.7445)
			(xy 95.995723 -243.792521) (xy 96.011433 -243.843451) (xy 96.019376 -243.896155) (xy 96.019874 -243.922804)
			(xy 96.019376 -243.949453) (xy 96.247956 -243.949453) (xy 96.247956 -243.896155) (xy 96.255899 -243.843451)
			(xy 96.271609 -243.792521) (xy 96.294735 -243.7445) (xy 96.324759 -243.700463) (xy 96.361011 -243.661392)
			(xy 96.402682 -243.628161) (xy 96.44884 -243.601512) (xy 96.498454 -243.58204) (xy 96.550416 -243.57018)
			(xy 96.603566 -243.566197) (xy 96.656716 -243.57018) (xy 96.708678 -243.58204) (xy 96.758292 -243.601512)
			(xy 96.80445 -243.628161) (xy 96.846121 -243.661392) (xy 96.882373 -243.700463) (xy 96.912397 -243.7445)
			(xy 96.935523 -243.792521) (xy 96.951233 -243.843451) (xy 96.959176 -243.896155) (xy 96.959674 -243.922804)
			(xy 96.959176 -243.949453) (xy 97.187756 -243.949453) (xy 97.187756 -243.896155) (xy 97.195699 -243.843451)
			(xy 97.211409 -243.792521) (xy 97.234535 -243.7445) (xy 97.264559 -243.700463) (xy 97.300811 -243.661392)
			(xy 97.342482 -243.628161) (xy 97.38864 -243.601512) (xy 97.438254 -243.58204) (xy 97.490216 -243.57018)
			(xy 97.543366 -243.566197) (xy 97.596516 -243.57018) (xy 97.648478 -243.58204) (xy 97.698092 -243.601512)
			(xy 97.74425 -243.628161) (xy 97.785921 -243.661392) (xy 97.822173 -243.700463) (xy 97.852197 -243.7445)
			(xy 97.875323 -243.792521) (xy 97.891033 -243.843451) (xy 97.898976 -243.896155) (xy 97.899474 -243.922804)
			(xy 97.898976 -243.949453) (xy 98.127556 -243.949453) (xy 98.127556 -243.896155) (xy 98.135499 -243.843451)
			(xy 98.151209 -243.792521) (xy 98.174335 -243.7445) (xy 98.204359 -243.700463) (xy 98.240611 -243.661392)
			(xy 98.282282 -243.628161) (xy 98.32844 -243.601512) (xy 98.378054 -243.58204) (xy 98.430016 -243.57018)
			(xy 98.483166 -243.566197) (xy 98.536316 -243.57018) (xy 98.588278 -243.58204) (xy 98.637892 -243.601512)
			(xy 98.68405 -243.628161) (xy 98.725721 -243.661392) (xy 98.761973 -243.700463) (xy 98.791997 -243.7445)
			(xy 98.815123 -243.792521) (xy 98.830833 -243.843451) (xy 98.838776 -243.896155) (xy 98.839274 -243.922804)
			(xy 98.838776 -243.949453) (xy 98.830833 -244.002157) (xy 98.815123 -244.053087) (xy 98.791997 -244.101108)
			(xy 98.761973 -244.145145) (xy 98.725721 -244.184216) (xy 98.68405 -244.217447) (xy 98.637892 -244.244096)
			(xy 98.588278 -244.263568) (xy 98.536316 -244.275428) (xy 98.483166 -244.279412) (xy 98.430016 -244.275428)
			(xy 98.378054 -244.263568) (xy 98.32844 -244.244096) (xy 98.282282 -244.217447) (xy 98.240611 -244.184216)
			(xy 98.204359 -244.145145) (xy 98.174335 -244.101108) (xy 98.151209 -244.053087) (xy 98.135499 -244.002157)
			(xy 98.127556 -243.949453) (xy 97.898976 -243.949453) (xy 97.891033 -244.002157) (xy 97.875323 -244.053087)
			(xy 97.852197 -244.101108) (xy 97.822173 -244.145145) (xy 97.785921 -244.184216) (xy 97.74425 -244.217447)
			(xy 97.698092 -244.244096) (xy 97.648478 -244.263568) (xy 97.596516 -244.275428) (xy 97.543366 -244.279412)
			(xy 97.490216 -244.275428) (xy 97.438254 -244.263568) (xy 97.38864 -244.244096) (xy 97.342482 -244.217447)
			(xy 97.300811 -244.184216) (xy 97.264559 -244.145145) (xy 97.234535 -244.101108) (xy 97.211409 -244.053087)
			(xy 97.195699 -244.002157) (xy 97.187756 -243.949453) (xy 96.959176 -243.949453) (xy 96.951233 -244.002157)
			(xy 96.935523 -244.053087) (xy 96.912397 -244.101108) (xy 96.882373 -244.145145) (xy 96.846121 -244.184216)
			(xy 96.80445 -244.217447) (xy 96.758292 -244.244096) (xy 96.708678 -244.263568) (xy 96.656716 -244.275428)
			(xy 96.603566 -244.279412) (xy 96.550416 -244.275428) (xy 96.498454 -244.263568) (xy 96.44884 -244.244096)
			(xy 96.402682 -244.217447) (xy 96.361011 -244.184216) (xy 96.324759 -244.145145) (xy 96.294735 -244.101108)
			(xy 96.271609 -244.053087) (xy 96.255899 -244.002157) (xy 96.247956 -243.949453) (xy 96.019376 -243.949453)
			(xy 96.011433 -244.002157) (xy 95.995723 -244.053087) (xy 95.972597 -244.101108) (xy 95.942573 -244.145145)
			(xy 95.906321 -244.184216) (xy 95.86465 -244.217447) (xy 95.818492 -244.244096) (xy 95.768878 -244.263568)
			(xy 95.716916 -244.275428) (xy 95.663766 -244.279412) (xy 95.610616 -244.275428) (xy 95.558654 -244.263568)
			(xy 95.50904 -244.244096) (xy 95.462882 -244.217447) (xy 95.421211 -244.184216) (xy 95.384959 -244.145145)
			(xy 95.354935 -244.101108) (xy 95.331809 -244.053087) (xy 95.316099 -244.002157) (xy 95.308156 -243.949453)
			(xy 95.079322 -243.949453) (xy 95.071379 -244.002157) (xy 95.055669 -244.053087) (xy 95.032543 -244.101108)
			(xy 95.002519 -244.145145) (xy 94.966267 -244.184216) (xy 94.924596 -244.217447) (xy 94.878438 -244.244096)
			(xy 94.828824 -244.263568) (xy 94.776862 -244.275428) (xy 94.723712 -244.279412) (xy 94.670562 -244.275428)
			(xy 94.6186 -244.263568) (xy 94.568986 -244.244096) (xy 94.522828 -244.217447) (xy 94.481157 -244.184216)
			(xy 94.444905 -244.145145) (xy 94.414881 -244.101108) (xy 94.391755 -244.053087) (xy 94.376045 -244.002157)
			(xy 94.368102 -243.949453) (xy 94.139776 -243.949453) (xy 94.131833 -244.002157) (xy 94.116123 -244.053087)
			(xy 94.092997 -244.101108) (xy 94.062973 -244.145145) (xy 94.026721 -244.184216) (xy 93.98505 -244.217447)
			(xy 93.938892 -244.244096) (xy 93.889278 -244.263568) (xy 93.837316 -244.275428) (xy 93.784166 -244.279412)
			(xy 93.731016 -244.275428) (xy 93.679054 -244.263568) (xy 93.62944 -244.244096) (xy 93.583282 -244.217447)
			(xy 93.541611 -244.184216) (xy 93.505359 -244.145145) (xy 93.475335 -244.101108) (xy 93.452209 -244.053087)
			(xy 93.436499 -244.002157) (xy 93.428556 -243.949453) (xy 93.199976 -243.949453) (xy 93.192033 -244.002157)
			(xy 93.176323 -244.053087) (xy 93.153197 -244.101108) (xy 93.123173 -244.145145) (xy 93.086921 -244.184216)
			(xy 93.04525 -244.217447) (xy 92.999092 -244.244096) (xy 92.949478 -244.263568) (xy 92.897516 -244.275428)
			(xy 92.844366 -244.279412) (xy 92.791216 -244.275428) (xy 92.739254 -244.263568) (xy 92.68964 -244.244096)
			(xy 92.643482 -244.217447) (xy 92.601811 -244.184216) (xy 92.565559 -244.145145) (xy 92.535535 -244.101108)
			(xy 92.512409 -244.053087) (xy 92.496699 -244.002157) (xy 92.488756 -243.949453) (xy 92.260176 -243.949453)
			(xy 92.252233 -244.002157) (xy 92.236523 -244.053087) (xy 92.213397 -244.101108) (xy 92.183373 -244.145145)
			(xy 92.147121 -244.184216) (xy 92.10545 -244.217447) (xy 92.059292 -244.244096) (xy 92.009678 -244.263568)
			(xy 91.957716 -244.275428) (xy 91.904566 -244.279412) (xy 91.851416 -244.275428) (xy 91.799454 -244.263568)
			(xy 91.74984 -244.244096) (xy 91.703682 -244.217447) (xy 91.662011 -244.184216) (xy 91.625759 -244.145145)
			(xy 91.595735 -244.101108) (xy 91.572609 -244.053087) (xy 91.556899 -244.002157) (xy 91.548956 -243.949453)
			(xy 91.320376 -243.949453) (xy 91.312433 -244.002157) (xy 91.296723 -244.053087) (xy 91.273597 -244.101108)
			(xy 91.243573 -244.145145) (xy 91.207321 -244.184216) (xy 91.16565 -244.217447) (xy 91.119492 -244.244096)
			(xy 91.069878 -244.263568) (xy 91.017916 -244.275428) (xy 90.964766 -244.279412) (xy 90.911616 -244.275428)
			(xy 90.859654 -244.263568) (xy 90.81004 -244.244096) (xy 90.763882 -244.217447) (xy 90.722211 -244.184216)
			(xy 90.685959 -244.145145) (xy 90.655935 -244.101108) (xy 90.632809 -244.053087) (xy 90.617099 -244.002157)
			(xy 90.609156 -243.949453) (xy 90.380576 -243.949453) (xy 90.372633 -244.002157) (xy 90.356923 -244.053087)
			(xy 90.333797 -244.101108) (xy 90.303773 -244.145145) (xy 90.267521 -244.184216) (xy 90.22585 -244.217447)
			(xy 90.179692 -244.244096) (xy 90.130078 -244.263568) (xy 90.078116 -244.275428) (xy 90.024966 -244.279412)
			(xy 89.971816 -244.275428) (xy 89.919854 -244.263568) (xy 89.87024 -244.244096) (xy 89.824082 -244.217447)
			(xy 89.782411 -244.184216) (xy 89.746159 -244.145145) (xy 89.716135 -244.101108) (xy 89.693009 -244.053087)
			(xy 89.677299 -244.002157) (xy 89.669356 -243.949453) (xy 89.43983 -243.949453) (xy 89.437844 -243.975956)
			(xy 89.425982 -244.027924) (xy 89.406507 -244.077544) (xy 89.379853 -244.123706) (xy 89.346616 -244.165381)
			(xy 89.307539 -244.201635) (xy 89.263494 -244.23166) (xy 89.215467 -244.254785) (xy 89.164529 -244.270493)
			(xy 89.111819 -244.278433) (xy 89.085166 -244.278912) (xy 89.074793 -244.278866) (xy 89.054079 -244.277724)
			(xy 89.043764 -244.276626) (xy 89.029509 -244.275465) (xy 89.001311 -244.280182) (xy 88.975525 -244.292526)
			(xy 88.954169 -244.311532) (xy 88.938914 -244.335711) (xy 88.930956 -244.36317) (xy 88.93048 -244.377464)
			(xy 88.93048 -244.571012) (xy 88.93556 -244.581426) (xy 88.946787 -244.605739) (xy 88.962632 -244.656893)
			(xy 88.970643 -244.709842) (xy 88.97064 -244.763269) (xy 89.199202 -244.763269) (xy 89.199202 -244.709971)
			(xy 89.207145 -244.657267) (xy 89.222855 -244.606337) (xy 89.245981 -244.558316) (xy 89.276005 -244.514279)
			(xy 89.312257 -244.475208) (xy 89.353928 -244.441977) (xy 89.400086 -244.415328) (xy 89.4497 -244.395856)
			(xy 89.501662 -244.383996) (xy 89.554812 -244.380013) (xy 89.607962 -244.383996) (xy 89.659924 -244.395856)
			(xy 89.709538 -244.415328) (xy 89.755696 -244.441977) (xy 89.797367 -244.475208) (xy 89.833619 -244.514279)
			(xy 89.863643 -244.558316) (xy 89.886769 -244.606337) (xy 89.902479 -244.657267) (xy 89.910422 -244.709971)
			(xy 89.91092 -244.73662) (xy 89.910422 -244.763269) (xy 90.139256 -244.763269) (xy 90.139256 -244.709971)
			(xy 90.147199 -244.657267) (xy 90.162909 -244.606337) (xy 90.186035 -244.558316) (xy 90.216059 -244.514279)
			(xy 90.252311 -244.475208) (xy 90.293982 -244.441977) (xy 90.34014 -244.415328) (xy 90.389754 -244.395856)
			(xy 90.441716 -244.383996) (xy 90.494866 -244.380013) (xy 90.548016 -244.383996) (xy 90.599978 -244.395856)
			(xy 90.649592 -244.415328) (xy 90.69575 -244.441977) (xy 90.737421 -244.475208) (xy 90.773673 -244.514279)
			(xy 90.803697 -244.558316) (xy 90.826823 -244.606337) (xy 90.842533 -244.657267) (xy 90.850476 -244.709971)
			(xy 90.850974 -244.73662) (xy 90.850476 -244.763269) (xy 91.078802 -244.763269) (xy 91.078802 -244.709971)
			(xy 91.086745 -244.657267) (xy 91.102455 -244.606337) (xy 91.125581 -244.558316) (xy 91.155605 -244.514279)
			(xy 91.191857 -244.475208) (xy 91.233528 -244.441977) (xy 91.279686 -244.415328) (xy 91.3293 -244.395856)
			(xy 91.381262 -244.383996) (xy 91.434412 -244.380013) (xy 91.487562 -244.383996) (xy 91.539524 -244.395856)
			(xy 91.589138 -244.415328) (xy 91.635296 -244.441977) (xy 91.676967 -244.475208) (xy 91.713219 -244.514279)
			(xy 91.743243 -244.558316) (xy 91.766369 -244.606337) (xy 91.782079 -244.657267) (xy 91.790022 -244.709971)
			(xy 91.79052 -244.73662) (xy 91.790022 -244.763269) (xy 92.018856 -244.763269) (xy 92.018856 -244.709971)
			(xy 92.026799 -244.657267) (xy 92.042509 -244.606337) (xy 92.065635 -244.558316) (xy 92.095659 -244.514279)
			(xy 92.131911 -244.475208) (xy 92.173582 -244.441977) (xy 92.21974 -244.415328) (xy 92.269354 -244.395856)
			(xy 92.321316 -244.383996) (xy 92.374466 -244.380013) (xy 92.427616 -244.383996) (xy 92.479578 -244.395856)
			(xy 92.529192 -244.415328) (xy 92.57535 -244.441977) (xy 92.617021 -244.475208) (xy 92.653273 -244.514279)
			(xy 92.683297 -244.558316) (xy 92.706423 -244.606337) (xy 92.722133 -244.657267) (xy 92.730076 -244.709971)
			(xy 92.730574 -244.73662) (xy 92.730076 -244.763269) (xy 92.958402 -244.763269) (xy 92.958402 -244.709971)
			(xy 92.966345 -244.657267) (xy 92.982055 -244.606337) (xy 93.005181 -244.558316) (xy 93.035205 -244.514279)
			(xy 93.071457 -244.475208) (xy 93.113128 -244.441977) (xy 93.159286 -244.415328) (xy 93.2089 -244.395856)
			(xy 93.260862 -244.383996) (xy 93.314012 -244.380013) (xy 93.367162 -244.383996) (xy 93.419124 -244.395856)
			(xy 93.468738 -244.415328) (xy 93.514896 -244.441977) (xy 93.556567 -244.475208) (xy 93.592819 -244.514279)
			(xy 93.622843 -244.558316) (xy 93.645969 -244.606337) (xy 93.661679 -244.657267) (xy 93.669622 -244.709971)
			(xy 93.67012 -244.73662) (xy 93.669622 -244.763269) (xy 93.898202 -244.763269) (xy 93.898202 -244.709971)
			(xy 93.906145 -244.657267) (xy 93.921855 -244.606337) (xy 93.944981 -244.558316) (xy 93.975005 -244.514279)
			(xy 94.011257 -244.475208) (xy 94.052928 -244.441977) (xy 94.099086 -244.415328) (xy 94.1487 -244.395856)
			(xy 94.200662 -244.383996) (xy 94.253812 -244.380013) (xy 94.306962 -244.383996) (xy 94.358924 -244.395856)
			(xy 94.408538 -244.415328) (xy 94.454696 -244.441977) (xy 94.496367 -244.475208) (xy 94.532619 -244.514279)
			(xy 94.562643 -244.558316) (xy 94.585769 -244.606337) (xy 94.601479 -244.657267) (xy 94.609422 -244.709971)
			(xy 94.60992 -244.73662) (xy 94.609422 -244.763269) (xy 94.838002 -244.763269) (xy 94.838002 -244.709971)
			(xy 94.845945 -244.657267) (xy 94.861655 -244.606337) (xy 94.884781 -244.558316) (xy 94.914805 -244.514279)
			(xy 94.951057 -244.475208) (xy 94.992728 -244.441977) (xy 95.038886 -244.415328) (xy 95.0885 -244.395856)
			(xy 95.140462 -244.383996) (xy 95.193612 -244.380013) (xy 95.246762 -244.383996) (xy 95.298724 -244.395856)
			(xy 95.348338 -244.415328) (xy 95.394496 -244.441977) (xy 95.436167 -244.475208) (xy 95.472419 -244.514279)
			(xy 95.502443 -244.558316) (xy 95.525569 -244.606337) (xy 95.541279 -244.657267) (xy 95.549222 -244.709971)
			(xy 95.54972 -244.73662) (xy 95.549222 -244.763269) (xy 95.777802 -244.763269) (xy 95.777802 -244.709971)
			(xy 95.785745 -244.657267) (xy 95.801455 -244.606337) (xy 95.824581 -244.558316) (xy 95.854605 -244.514279)
			(xy 95.890857 -244.475208) (xy 95.932528 -244.441977) (xy 95.978686 -244.415328) (xy 96.0283 -244.395856)
			(xy 96.080262 -244.383996) (xy 96.133412 -244.380013) (xy 96.186562 -244.383996) (xy 96.238524 -244.395856)
			(xy 96.288138 -244.415328) (xy 96.334296 -244.441977) (xy 96.375967 -244.475208) (xy 96.412219 -244.514279)
			(xy 96.442243 -244.558316) (xy 96.465369 -244.606337) (xy 96.481079 -244.657267) (xy 96.489022 -244.709971)
			(xy 96.48952 -244.73662) (xy 96.489022 -244.763269) (xy 96.717856 -244.763269) (xy 96.717856 -244.709971)
			(xy 96.725799 -244.657267) (xy 96.741509 -244.606337) (xy 96.764635 -244.558316) (xy 96.794659 -244.514279)
			(xy 96.830911 -244.475208) (xy 96.872582 -244.441977) (xy 96.91874 -244.415328) (xy 96.968354 -244.395856)
			(xy 97.020316 -244.383996) (xy 97.073466 -244.380013) (xy 97.126616 -244.383996) (xy 97.178578 -244.395856)
			(xy 97.228192 -244.415328) (xy 97.27435 -244.441977) (xy 97.316021 -244.475208) (xy 97.352273 -244.514279)
			(xy 97.382297 -244.558316) (xy 97.405423 -244.606337) (xy 97.421133 -244.657267) (xy 97.429076 -244.709971)
			(xy 97.429574 -244.73662) (xy 97.429076 -244.763269) (xy 97.657402 -244.763269) (xy 97.657402 -244.709971)
			(xy 97.665345 -244.657267) (xy 97.681055 -244.606337) (xy 97.704181 -244.558316) (xy 97.734205 -244.514279)
			(xy 97.770457 -244.475208) (xy 97.812128 -244.441977) (xy 97.858286 -244.415328) (xy 97.9079 -244.395856)
			(xy 97.959862 -244.383996) (xy 98.013012 -244.380013) (xy 98.066162 -244.383996) (xy 98.118124 -244.395856)
			(xy 98.167738 -244.415328) (xy 98.213896 -244.441977) (xy 98.255567 -244.475208) (xy 98.291819 -244.514279)
			(xy 98.321843 -244.558316) (xy 98.344969 -244.606337) (xy 98.360679 -244.657267) (xy 98.368622 -244.709971)
			(xy 98.36912 -244.73662) (xy 98.368622 -244.763269) (xy 98.597202 -244.763269) (xy 98.597202 -244.709971)
			(xy 98.605145 -244.657267) (xy 98.620855 -244.606337) (xy 98.643981 -244.558316) (xy 98.674005 -244.514279)
			(xy 98.710257 -244.475208) (xy 98.751928 -244.441977) (xy 98.798086 -244.415328) (xy 98.8477 -244.395856)
			(xy 98.899662 -244.383996) (xy 98.952812 -244.380013) (xy 99.005962 -244.383996) (xy 99.057924 -244.395856)
			(xy 99.107538 -244.415328) (xy 99.153696 -244.441977) (xy 99.195367 -244.475208) (xy 99.231619 -244.514279)
			(xy 99.261643 -244.558316) (xy 99.284769 -244.606337) (xy 99.300479 -244.657267) (xy 99.308422 -244.709971)
			(xy 99.30892 -244.73662) (xy 99.308422 -244.763269) (xy 99.300479 -244.815973) (xy 99.284769 -244.866903)
			(xy 99.261643 -244.914924) (xy 99.231619 -244.958961) (xy 99.195367 -244.998032) (xy 99.153696 -245.031263)
			(xy 99.107538 -245.057912) (xy 99.057924 -245.077384) (xy 99.005962 -245.089244) (xy 98.952812 -245.093228)
			(xy 98.899662 -245.089244) (xy 98.8477 -245.077384) (xy 98.798086 -245.057912) (xy 98.751928 -245.031263)
			(xy 98.710257 -244.998032) (xy 98.674005 -244.958961) (xy 98.643981 -244.914924) (xy 98.620855 -244.866903)
			(xy 98.605145 -244.815973) (xy 98.597202 -244.763269) (xy 98.368622 -244.763269) (xy 98.360679 -244.815973)
			(xy 98.344969 -244.866903) (xy 98.321843 -244.914924) (xy 98.291819 -244.958961) (xy 98.255567 -244.998032)
			(xy 98.213896 -245.031263) (xy 98.167738 -245.057912) (xy 98.118124 -245.077384) (xy 98.066162 -245.089244)
			(xy 98.013012 -245.093228) (xy 97.959862 -245.089244) (xy 97.9079 -245.077384) (xy 97.858286 -245.057912)
			(xy 97.812128 -245.031263) (xy 97.770457 -244.998032) (xy 97.734205 -244.958961) (xy 97.704181 -244.914924)
			(xy 97.681055 -244.866903) (xy 97.665345 -244.815973) (xy 97.657402 -244.763269) (xy 97.429076 -244.763269)
			(xy 97.421133 -244.815973) (xy 97.405423 -244.866903) (xy 97.382297 -244.914924) (xy 97.352273 -244.958961)
			(xy 97.316021 -244.998032) (xy 97.27435 -245.031263) (xy 97.228192 -245.057912) (xy 97.178578 -245.077384)
			(xy 97.126616 -245.089244) (xy 97.073466 -245.093228) (xy 97.020316 -245.089244) (xy 96.968354 -245.077384)
			(xy 96.91874 -245.057912) (xy 96.872582 -245.031263) (xy 96.830911 -244.998032) (xy 96.794659 -244.958961)
			(xy 96.764635 -244.914924) (xy 96.741509 -244.866903) (xy 96.725799 -244.815973) (xy 96.717856 -244.763269)
			(xy 96.489022 -244.763269) (xy 96.481079 -244.815973) (xy 96.465369 -244.866903) (xy 96.442243 -244.914924)
			(xy 96.412219 -244.958961) (xy 96.375967 -244.998032) (xy 96.334296 -245.031263) (xy 96.288138 -245.057912)
			(xy 96.238524 -245.077384) (xy 96.186562 -245.089244) (xy 96.133412 -245.093228) (xy 96.080262 -245.089244)
			(xy 96.0283 -245.077384) (xy 95.978686 -245.057912) (xy 95.932528 -245.031263) (xy 95.890857 -244.998032)
			(xy 95.854605 -244.958961) (xy 95.824581 -244.914924) (xy 95.801455 -244.866903) (xy 95.785745 -244.815973)
			(xy 95.777802 -244.763269) (xy 95.549222 -244.763269) (xy 95.541279 -244.815973) (xy 95.525569 -244.866903)
			(xy 95.502443 -244.914924) (xy 95.472419 -244.958961) (xy 95.436167 -244.998032) (xy 95.394496 -245.031263)
			(xy 95.348338 -245.057912) (xy 95.298724 -245.077384) (xy 95.246762 -245.089244) (xy 95.193612 -245.093228)
			(xy 95.140462 -245.089244) (xy 95.0885 -245.077384) (xy 95.038886 -245.057912) (xy 94.992728 -245.031263)
			(xy 94.951057 -244.998032) (xy 94.914805 -244.958961) (xy 94.884781 -244.914924) (xy 94.861655 -244.866903)
			(xy 94.845945 -244.815973) (xy 94.838002 -244.763269) (xy 94.609422 -244.763269) (xy 94.601479 -244.815973)
			(xy 94.585769 -244.866903) (xy 94.562643 -244.914924) (xy 94.532619 -244.958961) (xy 94.496367 -244.998032)
			(xy 94.454696 -245.031263) (xy 94.408538 -245.057912) (xy 94.358924 -245.077384) (xy 94.306962 -245.089244)
			(xy 94.253812 -245.093228) (xy 94.200662 -245.089244) (xy 94.1487 -245.077384) (xy 94.099086 -245.057912)
			(xy 94.052928 -245.031263) (xy 94.011257 -244.998032) (xy 93.975005 -244.958961) (xy 93.944981 -244.914924)
			(xy 93.921855 -244.866903) (xy 93.906145 -244.815973) (xy 93.898202 -244.763269) (xy 93.669622 -244.763269)
			(xy 93.661679 -244.815973) (xy 93.645969 -244.866903) (xy 93.622843 -244.914924) (xy 93.592819 -244.958961)
			(xy 93.556567 -244.998032) (xy 93.514896 -245.031263) (xy 93.468738 -245.057912) (xy 93.419124 -245.077384)
			(xy 93.367162 -245.089244) (xy 93.314012 -245.093228) (xy 93.260862 -245.089244) (xy 93.2089 -245.077384)
			(xy 93.159286 -245.057912) (xy 93.113128 -245.031263) (xy 93.071457 -244.998032) (xy 93.035205 -244.958961)
			(xy 93.005181 -244.914924) (xy 92.982055 -244.866903) (xy 92.966345 -244.815973) (xy 92.958402 -244.763269)
			(xy 92.730076 -244.763269) (xy 92.722133 -244.815973) (xy 92.706423 -244.866903) (xy 92.683297 -244.914924)
			(xy 92.653273 -244.958961) (xy 92.617021 -244.998032) (xy 92.57535 -245.031263) (xy 92.529192 -245.057912)
			(xy 92.479578 -245.077384) (xy 92.427616 -245.089244) (xy 92.374466 -245.093228) (xy 92.321316 -245.089244)
			(xy 92.269354 -245.077384) (xy 92.21974 -245.057912) (xy 92.173582 -245.031263) (xy 92.131911 -244.998032)
			(xy 92.095659 -244.958961) (xy 92.065635 -244.914924) (xy 92.042509 -244.866903) (xy 92.026799 -244.815973)
			(xy 92.018856 -244.763269) (xy 91.790022 -244.763269) (xy 91.782079 -244.815973) (xy 91.766369 -244.866903)
			(xy 91.743243 -244.914924) (xy 91.713219 -244.958961) (xy 91.676967 -244.998032) (xy 91.635296 -245.031263)
			(xy 91.589138 -245.057912) (xy 91.539524 -245.077384) (xy 91.487562 -245.089244) (xy 91.434412 -245.093228)
			(xy 91.381262 -245.089244) (xy 91.3293 -245.077384) (xy 91.279686 -245.057912) (xy 91.233528 -245.031263)
			(xy 91.191857 -244.998032) (xy 91.155605 -244.958961) (xy 91.125581 -244.914924) (xy 91.102455 -244.866903)
			(xy 91.086745 -244.815973) (xy 91.078802 -244.763269) (xy 90.850476 -244.763269) (xy 90.842533 -244.815973)
			(xy 90.826823 -244.866903) (xy 90.803697 -244.914924) (xy 90.773673 -244.958961) (xy 90.737421 -244.998032)
			(xy 90.69575 -245.031263) (xy 90.649592 -245.057912) (xy 90.599978 -245.077384) (xy 90.548016 -245.089244)
			(xy 90.494866 -245.093228) (xy 90.441716 -245.089244) (xy 90.389754 -245.077384) (xy 90.34014 -245.057912)
			(xy 90.293982 -245.031263) (xy 90.252311 -244.998032) (xy 90.216059 -244.958961) (xy 90.186035 -244.914924)
			(xy 90.162909 -244.866903) (xy 90.147199 -244.815973) (xy 90.139256 -244.763269) (xy 89.910422 -244.763269)
			(xy 89.902479 -244.815973) (xy 89.886769 -244.866903) (xy 89.863643 -244.914924) (xy 89.833619 -244.958961)
			(xy 89.797367 -244.998032) (xy 89.755696 -245.031263) (xy 89.709538 -245.057912) (xy 89.659924 -245.077384)
			(xy 89.607962 -245.089244) (xy 89.554812 -245.093228) (xy 89.501662 -245.089244) (xy 89.4497 -245.077384)
			(xy 89.400086 -245.057912) (xy 89.353928 -245.031263) (xy 89.312257 -244.998032) (xy 89.276005 -244.958961)
			(xy 89.245981 -244.914924) (xy 89.222855 -244.866903) (xy 89.207145 -244.815973) (xy 89.199202 -244.763269)
			(xy 88.97064 -244.763269) (xy 88.97064 -244.763394) (xy 88.962624 -244.816342) (xy 88.946774 -244.867494)
			(xy 88.93556 -244.891814) (xy 88.93048 -244.902228) (xy 88.93048 -245.09603) (xy 88.930956 -245.110329)
			(xy 88.93888 -245.137805) (xy 88.954123 -245.162001) (xy 88.975487 -245.18101) (xy 89.00129 -245.193337)
			(xy 89.029502 -245.198013) (xy 89.043764 -245.196868) (xy 89.054078 -245.195764) (xy 89.074793 -245.19462)
			(xy 89.085166 -245.194582) (xy 89.11182 -245.195053) (xy 89.164532 -245.202993) (xy 89.215472 -245.218702)
			(xy 89.263501 -245.241828) (xy 89.307547 -245.271854) (xy 89.346626 -245.30811) (xy 89.379864 -245.349786)
			(xy 89.406519 -245.39595) (xy 89.425995 -245.445572) (xy 89.437858 -245.497542) (xy 89.441842 -245.5507)
			(xy 89.439846 -245.577339) (xy 89.669356 -245.577339) (xy 89.669356 -245.524041) (xy 89.677299 -245.471337)
			(xy 89.693009 -245.420407) (xy 89.716135 -245.372386) (xy 89.746159 -245.328349) (xy 89.782411 -245.289278)
			(xy 89.824082 -245.256047) (xy 89.87024 -245.229398) (xy 89.919854 -245.209926) (xy 89.971816 -245.198066)
			(xy 90.024966 -245.194083) (xy 90.078116 -245.198066) (xy 90.130078 -245.209926) (xy 90.179692 -245.229398)
			(xy 90.22585 -245.256047) (xy 90.267521 -245.289278) (xy 90.303773 -245.328349) (xy 90.333797 -245.372386)
			(xy 90.356923 -245.420407) (xy 90.372633 -245.471337) (xy 90.380576 -245.524041) (xy 90.381074 -245.55069)
			(xy 90.380576 -245.577339) (xy 90.608902 -245.577339) (xy 90.608902 -245.524041) (xy 90.616845 -245.471337)
			(xy 90.632555 -245.420407) (xy 90.655681 -245.372386) (xy 90.685705 -245.328349) (xy 90.721957 -245.289278)
			(xy 90.763628 -245.256047) (xy 90.809786 -245.229398) (xy 90.8594 -245.209926) (xy 90.911362 -245.198066)
			(xy 90.964512 -245.194083) (xy 91.017662 -245.198066) (xy 91.069624 -245.209926) (xy 91.119238 -245.229398)
			(xy 91.165396 -245.256047) (xy 91.207067 -245.289278) (xy 91.243319 -245.328349) (xy 91.273343 -245.372386)
			(xy 91.296469 -245.420407) (xy 91.312179 -245.471337) (xy 91.320122 -245.524041) (xy 91.32062 -245.55069)
			(xy 91.320122 -245.577339) (xy 91.548956 -245.577339) (xy 91.548956 -245.524041) (xy 91.556899 -245.471337)
			(xy 91.572609 -245.420407) (xy 91.595735 -245.372386) (xy 91.625759 -245.328349) (xy 91.662011 -245.289278)
			(xy 91.703682 -245.256047) (xy 91.74984 -245.229398) (xy 91.799454 -245.209926) (xy 91.851416 -245.198066)
			(xy 91.904566 -245.194083) (xy 91.957716 -245.198066) (xy 92.009678 -245.209926) (xy 92.059292 -245.229398)
			(xy 92.10545 -245.256047) (xy 92.147121 -245.289278) (xy 92.183373 -245.328349) (xy 92.213397 -245.372386)
			(xy 92.236523 -245.420407) (xy 92.252233 -245.471337) (xy 92.260176 -245.524041) (xy 92.260674 -245.55069)
			(xy 92.260176 -245.577339) (xy 92.488502 -245.577339) (xy 92.488502 -245.524041) (xy 92.496445 -245.471337)
			(xy 92.512155 -245.420407) (xy 92.535281 -245.372386) (xy 92.565305 -245.328349) (xy 92.601557 -245.289278)
			(xy 92.643228 -245.256047) (xy 92.689386 -245.229398) (xy 92.739 -245.209926) (xy 92.790962 -245.198066)
			(xy 92.844112 -245.194083) (xy 92.897262 -245.198066) (xy 92.949224 -245.209926) (xy 92.998838 -245.229398)
			(xy 93.044996 -245.256047) (xy 93.086667 -245.289278) (xy 93.122919 -245.328349) (xy 93.152943 -245.372386)
			(xy 93.176069 -245.420407) (xy 93.191779 -245.471337) (xy 93.199722 -245.524041) (xy 93.20022 -245.55069)
			(xy 93.199722 -245.577339) (xy 93.428556 -245.577339) (xy 93.428556 -245.524041) (xy 93.436499 -245.471337)
			(xy 93.452209 -245.420407) (xy 93.475335 -245.372386) (xy 93.505359 -245.328349) (xy 93.541611 -245.289278)
			(xy 93.583282 -245.256047) (xy 93.62944 -245.229398) (xy 93.679054 -245.209926) (xy 93.731016 -245.198066)
			(xy 93.784166 -245.194083) (xy 93.837316 -245.198066) (xy 93.889278 -245.209926) (xy 93.938892 -245.229398)
			(xy 93.98505 -245.256047) (xy 94.026721 -245.289278) (xy 94.062973 -245.328349) (xy 94.092997 -245.372386)
			(xy 94.116123 -245.420407) (xy 94.131833 -245.471337) (xy 94.139776 -245.524041) (xy 94.140274 -245.55069)
			(xy 94.139776 -245.577339) (xy 94.368356 -245.577339) (xy 94.368356 -245.524041) (xy 94.376299 -245.471337)
			(xy 94.392009 -245.420407) (xy 94.415135 -245.372386) (xy 94.445159 -245.328349) (xy 94.481411 -245.289278)
			(xy 94.523082 -245.256047) (xy 94.56924 -245.229398) (xy 94.618854 -245.209926) (xy 94.670816 -245.198066)
			(xy 94.723966 -245.194083) (xy 94.777116 -245.198066) (xy 94.829078 -245.209926) (xy 94.878692 -245.229398)
			(xy 94.92485 -245.256047) (xy 94.966521 -245.289278) (xy 95.002773 -245.328349) (xy 95.032797 -245.372386)
			(xy 95.055923 -245.420407) (xy 95.071633 -245.471337) (xy 95.079576 -245.524041) (xy 95.080074 -245.55069)
			(xy 95.079576 -245.577339) (xy 95.308156 -245.577339) (xy 95.308156 -245.524041) (xy 95.316099 -245.471337)
			(xy 95.331809 -245.420407) (xy 95.354935 -245.372386) (xy 95.384959 -245.328349) (xy 95.421211 -245.289278)
			(xy 95.462882 -245.256047) (xy 95.50904 -245.229398) (xy 95.558654 -245.209926) (xy 95.610616 -245.198066)
			(xy 95.663766 -245.194083) (xy 95.716916 -245.198066) (xy 95.768878 -245.209926) (xy 95.818492 -245.229398)
			(xy 95.86465 -245.256047) (xy 95.906321 -245.289278) (xy 95.942573 -245.328349) (xy 95.972597 -245.372386)
			(xy 95.995723 -245.420407) (xy 96.011433 -245.471337) (xy 96.019376 -245.524041) (xy 96.019874 -245.55069)
			(xy 96.019376 -245.577339) (xy 96.247956 -245.577339) (xy 96.247956 -245.524041) (xy 96.255899 -245.471337)
			(xy 96.271609 -245.420407) (xy 96.294735 -245.372386) (xy 96.324759 -245.328349) (xy 96.361011 -245.289278)
			(xy 96.402682 -245.256047) (xy 96.44884 -245.229398) (xy 96.498454 -245.209926) (xy 96.550416 -245.198066)
			(xy 96.603566 -245.194083) (xy 96.656716 -245.198066) (xy 96.708678 -245.209926) (xy 96.758292 -245.229398)
			(xy 96.80445 -245.256047) (xy 96.846121 -245.289278) (xy 96.882373 -245.328349) (xy 96.912397 -245.372386)
			(xy 96.935523 -245.420407) (xy 96.951233 -245.471337) (xy 96.959176 -245.524041) (xy 96.959674 -245.55069)
			(xy 96.959176 -245.577339) (xy 97.187502 -245.577339) (xy 97.187502 -245.524041) (xy 97.195445 -245.471337)
			(xy 97.211155 -245.420407) (xy 97.234281 -245.372386) (xy 97.264305 -245.328349) (xy 97.300557 -245.289278)
			(xy 97.342228 -245.256047) (xy 97.388386 -245.229398) (xy 97.438 -245.209926) (xy 97.489962 -245.198066)
			(xy 97.543112 -245.194083) (xy 97.596262 -245.198066) (xy 97.648224 -245.209926) (xy 97.697838 -245.229398)
			(xy 97.743996 -245.256047) (xy 97.785667 -245.289278) (xy 97.821919 -245.328349) (xy 97.851943 -245.372386)
			(xy 97.875069 -245.420407) (xy 97.890779 -245.471337) (xy 97.898722 -245.524041) (xy 97.89922 -245.55069)
			(xy 97.898722 -245.577339) (xy 98.127556 -245.577339) (xy 98.127556 -245.524041) (xy 98.135499 -245.471337)
			(xy 98.151209 -245.420407) (xy 98.174335 -245.372386) (xy 98.204359 -245.328349) (xy 98.240611 -245.289278)
			(xy 98.282282 -245.256047) (xy 98.32844 -245.229398) (xy 98.378054 -245.209926) (xy 98.430016 -245.198066)
			(xy 98.483166 -245.194083) (xy 98.536316 -245.198066) (xy 98.588278 -245.209926) (xy 98.637892 -245.229398)
			(xy 98.68405 -245.256047) (xy 98.725721 -245.289278) (xy 98.761973 -245.328349) (xy 98.791997 -245.372386)
			(xy 98.815123 -245.420407) (xy 98.830833 -245.471337) (xy 98.838776 -245.524041) (xy 98.839274 -245.55069)
			(xy 98.838776 -245.577339) (xy 98.830833 -245.630043) (xy 98.815123 -245.680973) (xy 98.791997 -245.728994)
			(xy 98.761973 -245.773031) (xy 98.725721 -245.812102) (xy 98.68405 -245.845333) (xy 98.637892 -245.871982)
			(xy 98.588278 -245.891454) (xy 98.536316 -245.903314) (xy 98.483166 -245.907298) (xy 98.430016 -245.903314)
			(xy 98.378054 -245.891454) (xy 98.32844 -245.871982) (xy 98.282282 -245.845333) (xy 98.240611 -245.812102)
			(xy 98.204359 -245.773031) (xy 98.174335 -245.728994) (xy 98.151209 -245.680973) (xy 98.135499 -245.630043)
			(xy 98.127556 -245.577339) (xy 97.898722 -245.577339) (xy 97.890779 -245.630043) (xy 97.875069 -245.680973)
			(xy 97.851943 -245.728994) (xy 97.821919 -245.773031) (xy 97.785667 -245.812102) (xy 97.743996 -245.845333)
			(xy 97.697838 -245.871982) (xy 97.648224 -245.891454) (xy 97.596262 -245.903314) (xy 97.543112 -245.907298)
			(xy 97.489962 -245.903314) (xy 97.438 -245.891454) (xy 97.388386 -245.871982) (xy 97.342228 -245.845333)
			(xy 97.300557 -245.812102) (xy 97.264305 -245.773031) (xy 97.234281 -245.728994) (xy 97.211155 -245.680973)
			(xy 97.195445 -245.630043) (xy 97.187502 -245.577339) (xy 96.959176 -245.577339) (xy 96.951233 -245.630043)
			(xy 96.935523 -245.680973) (xy 96.912397 -245.728994) (xy 96.882373 -245.773031) (xy 96.846121 -245.812102)
			(xy 96.80445 -245.845333) (xy 96.758292 -245.871982) (xy 96.708678 -245.891454) (xy 96.656716 -245.903314)
			(xy 96.603566 -245.907298) (xy 96.550416 -245.903314) (xy 96.498454 -245.891454) (xy 96.44884 -245.871982)
			(xy 96.402682 -245.845333) (xy 96.361011 -245.812102) (xy 96.324759 -245.773031) (xy 96.294735 -245.728994)
			(xy 96.271609 -245.680973) (xy 96.255899 -245.630043) (xy 96.247956 -245.577339) (xy 96.019376 -245.577339)
			(xy 96.011433 -245.630043) (xy 95.995723 -245.680973) (xy 95.972597 -245.728994) (xy 95.942573 -245.773031)
			(xy 95.906321 -245.812102) (xy 95.86465 -245.845333) (xy 95.818492 -245.871982) (xy 95.768878 -245.891454)
			(xy 95.716916 -245.903314) (xy 95.663766 -245.907298) (xy 95.610616 -245.903314) (xy 95.558654 -245.891454)
			(xy 95.50904 -245.871982) (xy 95.462882 -245.845333) (xy 95.421211 -245.812102) (xy 95.384959 -245.773031)
			(xy 95.354935 -245.728994) (xy 95.331809 -245.680973) (xy 95.316099 -245.630043) (xy 95.308156 -245.577339)
			(xy 95.079576 -245.577339) (xy 95.071633 -245.630043) (xy 95.055923 -245.680973) (xy 95.032797 -245.728994)
			(xy 95.002773 -245.773031) (xy 94.966521 -245.812102) (xy 94.92485 -245.845333) (xy 94.878692 -245.871982)
			(xy 94.829078 -245.891454) (xy 94.777116 -245.903314) (xy 94.723966 -245.907298) (xy 94.670816 -245.903314)
			(xy 94.618854 -245.891454) (xy 94.56924 -245.871982) (xy 94.523082 -245.845333) (xy 94.481411 -245.812102)
			(xy 94.445159 -245.773031) (xy 94.415135 -245.728994) (xy 94.392009 -245.680973) (xy 94.376299 -245.630043)
			(xy 94.368356 -245.577339) (xy 94.139776 -245.577339) (xy 94.131833 -245.630043) (xy 94.116123 -245.680973)
			(xy 94.092997 -245.728994) (xy 94.062973 -245.773031) (xy 94.026721 -245.812102) (xy 93.98505 -245.845333)
			(xy 93.938892 -245.871982) (xy 93.889278 -245.891454) (xy 93.837316 -245.903314) (xy 93.784166 -245.907298)
			(xy 93.731016 -245.903314) (xy 93.679054 -245.891454) (xy 93.62944 -245.871982) (xy 93.583282 -245.845333)
			(xy 93.541611 -245.812102) (xy 93.505359 -245.773031) (xy 93.475335 -245.728994) (xy 93.452209 -245.680973)
			(xy 93.436499 -245.630043) (xy 93.428556 -245.577339) (xy 93.199722 -245.577339) (xy 93.191779 -245.630043)
			(xy 93.176069 -245.680973) (xy 93.152943 -245.728994) (xy 93.122919 -245.773031) (xy 93.086667 -245.812102)
			(xy 93.044996 -245.845333) (xy 92.998838 -245.871982) (xy 92.949224 -245.891454) (xy 92.897262 -245.903314)
			(xy 92.844112 -245.907298) (xy 92.790962 -245.903314) (xy 92.739 -245.891454) (xy 92.689386 -245.871982)
			(xy 92.643228 -245.845333) (xy 92.601557 -245.812102) (xy 92.565305 -245.773031) (xy 92.535281 -245.728994)
			(xy 92.512155 -245.680973) (xy 92.496445 -245.630043) (xy 92.488502 -245.577339) (xy 92.260176 -245.577339)
			(xy 92.252233 -245.630043) (xy 92.236523 -245.680973) (xy 92.213397 -245.728994) (xy 92.183373 -245.773031)
			(xy 92.147121 -245.812102) (xy 92.10545 -245.845333) (xy 92.059292 -245.871982) (xy 92.009678 -245.891454)
			(xy 91.957716 -245.903314) (xy 91.904566 -245.907298) (xy 91.851416 -245.903314) (xy 91.799454 -245.891454)
			(xy 91.74984 -245.871982) (xy 91.703682 -245.845333) (xy 91.662011 -245.812102) (xy 91.625759 -245.773031)
			(xy 91.595735 -245.728994) (xy 91.572609 -245.680973) (xy 91.556899 -245.630043) (xy 91.548956 -245.577339)
			(xy 91.320122 -245.577339) (xy 91.312179 -245.630043) (xy 91.296469 -245.680973) (xy 91.273343 -245.728994)
			(xy 91.243319 -245.773031) (xy 91.207067 -245.812102) (xy 91.165396 -245.845333) (xy 91.119238 -245.871982)
			(xy 91.069624 -245.891454) (xy 91.017662 -245.903314) (xy 90.964512 -245.907298) (xy 90.911362 -245.903314)
			(xy 90.8594 -245.891454) (xy 90.809786 -245.871982) (xy 90.763628 -245.845333) (xy 90.721957 -245.812102)
			(xy 90.685705 -245.773031) (xy 90.655681 -245.728994) (xy 90.632555 -245.680973) (xy 90.616845 -245.630043)
			(xy 90.608902 -245.577339) (xy 90.380576 -245.577339) (xy 90.372633 -245.630043) (xy 90.356923 -245.680973)
			(xy 90.333797 -245.728994) (xy 90.303773 -245.773031) (xy 90.267521 -245.812102) (xy 90.22585 -245.845333)
			(xy 90.179692 -245.871982) (xy 90.130078 -245.891454) (xy 90.078116 -245.903314) (xy 90.024966 -245.907298)
			(xy 89.971816 -245.903314) (xy 89.919854 -245.891454) (xy 89.87024 -245.871982) (xy 89.824082 -245.845333)
			(xy 89.782411 -245.812102) (xy 89.746159 -245.773031) (xy 89.716135 -245.728994) (xy 89.693009 -245.680973)
			(xy 89.677299 -245.630043) (xy 89.669356 -245.577339) (xy 89.439846 -245.577339) (xy 89.437858 -245.603858)
			(xy 89.425995 -245.655828) (xy 89.406519 -245.70545) (xy 89.379864 -245.751614) (xy 89.346626 -245.79329)
			(xy 89.307547 -245.829546) (xy 89.263501 -245.859572) (xy 89.215472 -245.882698) (xy 89.164532 -245.898407)
			(xy 89.11182 -245.906347) (xy 89.085166 -245.906798) (xy 89.074793 -245.906752) (xy 89.054079 -245.90561)
			(xy 89.043764 -245.904512) (xy 89.029508 -245.903351) (xy 89.001309 -245.908068) (xy 88.975521 -245.920412)
			(xy 88.954163 -245.939417) (xy 88.938906 -245.963596) (xy 88.930944 -245.991056) (xy 88.93048 -246.00535)
			(xy 88.93048 -246.198898) (xy 88.93556 -246.209312) (xy 88.946788 -246.233625) (xy 88.962635 -246.284779)
			(xy 88.970648 -246.337729) (xy 88.970647 -246.391155) (xy 89.199202 -246.391155) (xy 89.199202 -246.337857)
			(xy 89.207145 -246.285153) (xy 89.222855 -246.234223) (xy 89.245981 -246.186202) (xy 89.276005 -246.142165)
			(xy 89.312257 -246.103094) (xy 89.353928 -246.069863) (xy 89.400086 -246.043214) (xy 89.4497 -246.023742)
			(xy 89.501662 -246.011882) (xy 89.554812 -246.007899) (xy 89.607962 -246.011882) (xy 89.659924 -246.023742)
			(xy 89.709538 -246.043214) (xy 89.755696 -246.069863) (xy 89.797367 -246.103094) (xy 89.833619 -246.142165)
			(xy 89.863643 -246.186202) (xy 89.886769 -246.234223) (xy 89.902479 -246.285153) (xy 89.910422 -246.337857)
			(xy 89.91092 -246.364506) (xy 89.910422 -246.391155) (xy 90.139002 -246.391155) (xy 90.139002 -246.337857)
			(xy 90.146945 -246.285153) (xy 90.162655 -246.234223) (xy 90.185781 -246.186202) (xy 90.215805 -246.142165)
			(xy 90.252057 -246.103094) (xy 90.293728 -246.069863) (xy 90.339886 -246.043214) (xy 90.3895 -246.023742)
			(xy 90.441462 -246.011882) (xy 90.494612 -246.007899) (xy 90.547762 -246.011882) (xy 90.599724 -246.023742)
			(xy 90.649338 -246.043214) (xy 90.695496 -246.069863) (xy 90.737167 -246.103094) (xy 90.773419 -246.142165)
			(xy 90.803443 -246.186202) (xy 90.826569 -246.234223) (xy 90.842279 -246.285153) (xy 90.850222 -246.337857)
			(xy 90.85072 -246.364506) (xy 90.850222 -246.391155) (xy 91.078802 -246.391155) (xy 91.078802 -246.337857)
			(xy 91.086745 -246.285153) (xy 91.102455 -246.234223) (xy 91.125581 -246.186202) (xy 91.155605 -246.142165)
			(xy 91.191857 -246.103094) (xy 91.233528 -246.069863) (xy 91.279686 -246.043214) (xy 91.3293 -246.023742)
			(xy 91.381262 -246.011882) (xy 91.434412 -246.007899) (xy 91.487562 -246.011882) (xy 91.539524 -246.023742)
			(xy 91.589138 -246.043214) (xy 91.635296 -246.069863) (xy 91.676967 -246.103094) (xy 91.713219 -246.142165)
			(xy 91.743243 -246.186202) (xy 91.766369 -246.234223) (xy 91.782079 -246.285153) (xy 91.790022 -246.337857)
			(xy 91.79052 -246.364506) (xy 91.790022 -246.391155) (xy 92.018602 -246.391155) (xy 92.018602 -246.337857)
			(xy 92.026545 -246.285153) (xy 92.042255 -246.234223) (xy 92.065381 -246.186202) (xy 92.095405 -246.142165)
			(xy 92.131657 -246.103094) (xy 92.173328 -246.069863) (xy 92.219486 -246.043214) (xy 92.2691 -246.023742)
			(xy 92.321062 -246.011882) (xy 92.374212 -246.007899) (xy 92.427362 -246.011882) (xy 92.479324 -246.023742)
			(xy 92.528938 -246.043214) (xy 92.575096 -246.069863) (xy 92.616767 -246.103094) (xy 92.653019 -246.142165)
			(xy 92.683043 -246.186202) (xy 92.706169 -246.234223) (xy 92.721879 -246.285153) (xy 92.729822 -246.337857)
			(xy 92.73032 -246.364506) (xy 92.729822 -246.391155) (xy 92.958402 -246.391155) (xy 92.958402 -246.337857)
			(xy 92.966345 -246.285153) (xy 92.982055 -246.234223) (xy 93.005181 -246.186202) (xy 93.035205 -246.142165)
			(xy 93.071457 -246.103094) (xy 93.113128 -246.069863) (xy 93.159286 -246.043214) (xy 93.2089 -246.023742)
			(xy 93.260862 -246.011882) (xy 93.314012 -246.007899) (xy 93.367162 -246.011882) (xy 93.419124 -246.023742)
			(xy 93.468738 -246.043214) (xy 93.514896 -246.069863) (xy 93.556567 -246.103094) (xy 93.592819 -246.142165)
			(xy 93.622843 -246.186202) (xy 93.645969 -246.234223) (xy 93.661679 -246.285153) (xy 93.669622 -246.337857)
			(xy 93.67012 -246.364506) (xy 93.669622 -246.391155) (xy 93.898456 -246.391155) (xy 93.898456 -246.337857)
			(xy 93.906399 -246.285153) (xy 93.922109 -246.234223) (xy 93.945235 -246.186202) (xy 93.975259 -246.142165)
			(xy 94.011511 -246.103094) (xy 94.053182 -246.069863) (xy 94.09934 -246.043214) (xy 94.148954 -246.023742)
			(xy 94.200916 -246.011882) (xy 94.254066 -246.007899) (xy 94.307216 -246.011882) (xy 94.359178 -246.023742)
			(xy 94.408792 -246.043214) (xy 94.45495 -246.069863) (xy 94.496621 -246.103094) (xy 94.532873 -246.142165)
			(xy 94.562897 -246.186202) (xy 94.586023 -246.234223) (xy 94.601733 -246.285153) (xy 94.609676 -246.337857)
			(xy 94.610174 -246.364506) (xy 94.609676 -246.391155) (xy 94.838002 -246.391155) (xy 94.838002 -246.337857)
			(xy 94.845945 -246.285153) (xy 94.861655 -246.234223) (xy 94.884781 -246.186202) (xy 94.914805 -246.142165)
			(xy 94.951057 -246.103094) (xy 94.992728 -246.069863) (xy 95.038886 -246.043214) (xy 95.0885 -246.023742)
			(xy 95.140462 -246.011882) (xy 95.193612 -246.007899) (xy 95.246762 -246.011882) (xy 95.298724 -246.023742)
			(xy 95.348338 -246.043214) (xy 95.394496 -246.069863) (xy 95.436167 -246.103094) (xy 95.472419 -246.142165)
			(xy 95.502443 -246.186202) (xy 95.525569 -246.234223) (xy 95.541279 -246.285153) (xy 95.549222 -246.337857)
			(xy 95.54972 -246.364506) (xy 95.549222 -246.391155) (xy 95.777802 -246.391155) (xy 95.777802 -246.337857)
			(xy 95.785745 -246.285153) (xy 95.801455 -246.234223) (xy 95.824581 -246.186202) (xy 95.854605 -246.142165)
			(xy 95.890857 -246.103094) (xy 95.932528 -246.069863) (xy 95.978686 -246.043214) (xy 96.0283 -246.023742)
			(xy 96.080262 -246.011882) (xy 96.133412 -246.007899) (xy 96.186562 -246.011882) (xy 96.238524 -246.023742)
			(xy 96.288138 -246.043214) (xy 96.334296 -246.069863) (xy 96.375967 -246.103094) (xy 96.412219 -246.142165)
			(xy 96.442243 -246.186202) (xy 96.465369 -246.234223) (xy 96.481079 -246.285153) (xy 96.489022 -246.337857)
			(xy 96.48952 -246.364506) (xy 96.489022 -246.391155) (xy 96.717602 -246.391155) (xy 96.717602 -246.337857)
			(xy 96.725545 -246.285153) (xy 96.741255 -246.234223) (xy 96.764381 -246.186202) (xy 96.794405 -246.142165)
			(xy 96.830657 -246.103094) (xy 96.872328 -246.069863) (xy 96.918486 -246.043214) (xy 96.9681 -246.023742)
			(xy 97.020062 -246.011882) (xy 97.073212 -246.007899) (xy 97.126362 -246.011882) (xy 97.178324 -246.023742)
			(xy 97.227938 -246.043214) (xy 97.274096 -246.069863) (xy 97.315767 -246.103094) (xy 97.352019 -246.142165)
			(xy 97.382043 -246.186202) (xy 97.405169 -246.234223) (xy 97.420879 -246.285153) (xy 97.428822 -246.337857)
			(xy 97.42932 -246.364506) (xy 97.428822 -246.391155) (xy 97.657402 -246.391155) (xy 97.657402 -246.337857)
			(xy 97.665345 -246.285153) (xy 97.681055 -246.234223) (xy 97.704181 -246.186202) (xy 97.734205 -246.142165)
			(xy 97.770457 -246.103094) (xy 97.812128 -246.069863) (xy 97.858286 -246.043214) (xy 97.9079 -246.023742)
			(xy 97.959862 -246.011882) (xy 98.013012 -246.007899) (xy 98.066162 -246.011882) (xy 98.118124 -246.023742)
			(xy 98.167738 -246.043214) (xy 98.213896 -246.069863) (xy 98.255567 -246.103094) (xy 98.291819 -246.142165)
			(xy 98.321843 -246.186202) (xy 98.344969 -246.234223) (xy 98.360679 -246.285153) (xy 98.368622 -246.337857)
			(xy 98.36912 -246.364506) (xy 98.368622 -246.391155) (xy 98.597202 -246.391155) (xy 98.597202 -246.337857)
			(xy 98.605145 -246.285153) (xy 98.620855 -246.234223) (xy 98.643981 -246.186202) (xy 98.674005 -246.142165)
			(xy 98.710257 -246.103094) (xy 98.751928 -246.069863) (xy 98.798086 -246.043214) (xy 98.8477 -246.023742)
			(xy 98.899662 -246.011882) (xy 98.952812 -246.007899) (xy 99.005962 -246.011882) (xy 99.057924 -246.023742)
			(xy 99.107538 -246.043214) (xy 99.153696 -246.069863) (xy 99.195367 -246.103094) (xy 99.231619 -246.142165)
			(xy 99.261643 -246.186202) (xy 99.284769 -246.234223) (xy 99.300479 -246.285153) (xy 99.308422 -246.337857)
			(xy 99.30892 -246.364506) (xy 99.308422 -246.391155) (xy 99.300479 -246.443859) (xy 99.284769 -246.494789)
			(xy 99.261643 -246.54281) (xy 99.231619 -246.586847) (xy 99.195367 -246.625918) (xy 99.153696 -246.659149)
			(xy 99.107538 -246.685798) (xy 99.057924 -246.70527) (xy 99.005962 -246.71713) (xy 98.952812 -246.721114)
			(xy 98.899662 -246.71713) (xy 98.8477 -246.70527) (xy 98.798086 -246.685798) (xy 98.751928 -246.659149)
			(xy 98.710257 -246.625918) (xy 98.674005 -246.586847) (xy 98.643981 -246.54281) (xy 98.620855 -246.494789)
			(xy 98.605145 -246.443859) (xy 98.597202 -246.391155) (xy 98.368622 -246.391155) (xy 98.360679 -246.443859)
			(xy 98.344969 -246.494789) (xy 98.321843 -246.54281) (xy 98.291819 -246.586847) (xy 98.255567 -246.625918)
			(xy 98.213896 -246.659149) (xy 98.167738 -246.685798) (xy 98.118124 -246.70527) (xy 98.066162 -246.71713)
			(xy 98.013012 -246.721114) (xy 97.959862 -246.71713) (xy 97.9079 -246.70527) (xy 97.858286 -246.685798)
			(xy 97.812128 -246.659149) (xy 97.770457 -246.625918) (xy 97.734205 -246.586847) (xy 97.704181 -246.54281)
			(xy 97.681055 -246.494789) (xy 97.665345 -246.443859) (xy 97.657402 -246.391155) (xy 97.428822 -246.391155)
			(xy 97.420879 -246.443859) (xy 97.405169 -246.494789) (xy 97.382043 -246.54281) (xy 97.352019 -246.586847)
			(xy 97.315767 -246.625918) (xy 97.274096 -246.659149) (xy 97.227938 -246.685798) (xy 97.178324 -246.70527)
			(xy 97.126362 -246.71713) (xy 97.073212 -246.721114) (xy 97.020062 -246.71713) (xy 96.9681 -246.70527)
			(xy 96.918486 -246.685798) (xy 96.872328 -246.659149) (xy 96.830657 -246.625918) (xy 96.794405 -246.586847)
			(xy 96.764381 -246.54281) (xy 96.741255 -246.494789) (xy 96.725545 -246.443859) (xy 96.717602 -246.391155)
			(xy 96.489022 -246.391155) (xy 96.481079 -246.443859) (xy 96.465369 -246.494789) (xy 96.442243 -246.54281)
			(xy 96.412219 -246.586847) (xy 96.375967 -246.625918) (xy 96.334296 -246.659149) (xy 96.288138 -246.685798)
			(xy 96.238524 -246.70527) (xy 96.186562 -246.71713) (xy 96.133412 -246.721114) (xy 96.080262 -246.71713)
			(xy 96.0283 -246.70527) (xy 95.978686 -246.685798) (xy 95.932528 -246.659149) (xy 95.890857 -246.625918)
			(xy 95.854605 -246.586847) (xy 95.824581 -246.54281) (xy 95.801455 -246.494789) (xy 95.785745 -246.443859)
			(xy 95.777802 -246.391155) (xy 95.549222 -246.391155) (xy 95.541279 -246.443859) (xy 95.525569 -246.494789)
			(xy 95.502443 -246.54281) (xy 95.472419 -246.586847) (xy 95.436167 -246.625918) (xy 95.394496 -246.659149)
			(xy 95.348338 -246.685798) (xy 95.298724 -246.70527) (xy 95.246762 -246.71713) (xy 95.193612 -246.721114)
			(xy 95.140462 -246.71713) (xy 95.0885 -246.70527) (xy 95.038886 -246.685798) (xy 94.992728 -246.659149)
			(xy 94.951057 -246.625918) (xy 94.914805 -246.586847) (xy 94.884781 -246.54281) (xy 94.861655 -246.494789)
			(xy 94.845945 -246.443859) (xy 94.838002 -246.391155) (xy 94.609676 -246.391155) (xy 94.601733 -246.443859)
			(xy 94.586023 -246.494789) (xy 94.562897 -246.54281) (xy 94.532873 -246.586847) (xy 94.496621 -246.625918)
			(xy 94.45495 -246.659149) (xy 94.408792 -246.685798) (xy 94.359178 -246.70527) (xy 94.307216 -246.71713)
			(xy 94.254066 -246.721114) (xy 94.200916 -246.71713) (xy 94.148954 -246.70527) (xy 94.09934 -246.685798)
			(xy 94.053182 -246.659149) (xy 94.011511 -246.625918) (xy 93.975259 -246.586847) (xy 93.945235 -246.54281)
			(xy 93.922109 -246.494789) (xy 93.906399 -246.443859) (xy 93.898456 -246.391155) (xy 93.669622 -246.391155)
			(xy 93.661679 -246.443859) (xy 93.645969 -246.494789) (xy 93.622843 -246.54281) (xy 93.592819 -246.586847)
			(xy 93.556567 -246.625918) (xy 93.514896 -246.659149) (xy 93.468738 -246.685798) (xy 93.419124 -246.70527)
			(xy 93.367162 -246.71713) (xy 93.314012 -246.721114) (xy 93.260862 -246.71713) (xy 93.2089 -246.70527)
			(xy 93.159286 -246.685798) (xy 93.113128 -246.659149) (xy 93.071457 -246.625918) (xy 93.035205 -246.586847)
			(xy 93.005181 -246.54281) (xy 92.982055 -246.494789) (xy 92.966345 -246.443859) (xy 92.958402 -246.391155)
			(xy 92.729822 -246.391155) (xy 92.721879 -246.443859) (xy 92.706169 -246.494789) (xy 92.683043 -246.54281)
			(xy 92.653019 -246.586847) (xy 92.616767 -246.625918) (xy 92.575096 -246.659149) (xy 92.528938 -246.685798)
			(xy 92.479324 -246.70527) (xy 92.427362 -246.71713) (xy 92.374212 -246.721114) (xy 92.321062 -246.71713)
			(xy 92.2691 -246.70527) (xy 92.219486 -246.685798) (xy 92.173328 -246.659149) (xy 92.131657 -246.625918)
			(xy 92.095405 -246.586847) (xy 92.065381 -246.54281) (xy 92.042255 -246.494789) (xy 92.026545 -246.443859)
			(xy 92.018602 -246.391155) (xy 91.790022 -246.391155) (xy 91.782079 -246.443859) (xy 91.766369 -246.494789)
			(xy 91.743243 -246.54281) (xy 91.713219 -246.586847) (xy 91.676967 -246.625918) (xy 91.635296 -246.659149)
			(xy 91.589138 -246.685798) (xy 91.539524 -246.70527) (xy 91.487562 -246.71713) (xy 91.434412 -246.721114)
			(xy 91.381262 -246.71713) (xy 91.3293 -246.70527) (xy 91.279686 -246.685798) (xy 91.233528 -246.659149)
			(xy 91.191857 -246.625918) (xy 91.155605 -246.586847) (xy 91.125581 -246.54281) (xy 91.102455 -246.494789)
			(xy 91.086745 -246.443859) (xy 91.078802 -246.391155) (xy 90.850222 -246.391155) (xy 90.842279 -246.443859)
			(xy 90.826569 -246.494789) (xy 90.803443 -246.54281) (xy 90.773419 -246.586847) (xy 90.737167 -246.625918)
			(xy 90.695496 -246.659149) (xy 90.649338 -246.685798) (xy 90.599724 -246.70527) (xy 90.547762 -246.71713)
			(xy 90.494612 -246.721114) (xy 90.441462 -246.71713) (xy 90.3895 -246.70527) (xy 90.339886 -246.685798)
			(xy 90.293728 -246.659149) (xy 90.252057 -246.625918) (xy 90.215805 -246.586847) (xy 90.185781 -246.54281)
			(xy 90.162655 -246.494789) (xy 90.146945 -246.443859) (xy 90.139002 -246.391155) (xy 89.910422 -246.391155)
			(xy 89.902479 -246.443859) (xy 89.886769 -246.494789) (xy 89.863643 -246.54281) (xy 89.833619 -246.586847)
			(xy 89.797367 -246.625918) (xy 89.755696 -246.659149) (xy 89.709538 -246.685798) (xy 89.659924 -246.70527)
			(xy 89.607962 -246.71713) (xy 89.554812 -246.721114) (xy 89.501662 -246.71713) (xy 89.4497 -246.70527)
			(xy 89.400086 -246.685798) (xy 89.353928 -246.659149) (xy 89.312257 -246.625918) (xy 89.276005 -246.586847)
			(xy 89.245981 -246.54281) (xy 89.222855 -246.494789) (xy 89.207145 -246.443859) (xy 89.199202 -246.391155)
			(xy 88.970647 -246.391155) (xy 88.970647 -246.391282) (xy 88.962632 -246.444231) (xy 88.946784 -246.495385)
			(xy 88.93556 -246.5197) (xy 88.93048 -246.530114) (xy 88.93048 -246.723662) (xy 88.93096 -246.737957)
			(xy 88.938889 -246.765427) (xy 88.954135 -246.789614) (xy 88.975497 -246.808616) (xy 89.001295 -246.820939)
			(xy 89.029501 -246.825613) (xy 89.043764 -246.8245) (xy 89.054078 -246.823397) (xy 89.074793 -246.822254)
			(xy 89.085166 -246.822214) (xy 89.111817 -246.822685) (xy 89.164525 -246.830624) (xy 89.21546 -246.846332)
			(xy 89.263485 -246.869455) (xy 89.307527 -246.899479) (xy 89.346603 -246.935732) (xy 89.379838 -246.977404)
			(xy 89.40649 -247.023564) (xy 89.425965 -247.073181) (xy 89.437826 -247.125147) (xy 89.44181 -247.1783)
			(xy 89.439811 -247.204971) (xy 89.669102 -247.204971) (xy 89.669102 -247.151673) (xy 89.677045 -247.098969)
			(xy 89.692755 -247.048039) (xy 89.715881 -247.000018) (xy 89.745905 -246.955981) (xy 89.782157 -246.91691)
			(xy 89.823828 -246.883679) (xy 89.869986 -246.85703) (xy 89.9196 -246.837558) (xy 89.971562 -246.825698)
			(xy 90.024712 -246.821715) (xy 90.077862 -246.825698) (xy 90.129824 -246.837558) (xy 90.179438 -246.85703)
			(xy 90.225596 -246.883679) (xy 90.267267 -246.91691) (xy 90.303519 -246.955981) (xy 90.333543 -247.000018)
			(xy 90.356669 -247.048039) (xy 90.372379 -247.098969) (xy 90.380322 -247.151673) (xy 90.38082 -247.178322)
			(xy 90.380322 -247.204971) (xy 90.609156 -247.204971) (xy 90.609156 -247.151673) (xy 90.617099 -247.098969)
			(xy 90.632809 -247.048039) (xy 90.655935 -247.000018) (xy 90.685959 -246.955981) (xy 90.722211 -246.91691)
			(xy 90.763882 -246.883679) (xy 90.81004 -246.85703) (xy 90.859654 -246.837558) (xy 90.911616 -246.825698)
			(xy 90.964766 -246.821715) (xy 91.017916 -246.825698) (xy 91.069878 -246.837558) (xy 91.119492 -246.85703)
			(xy 91.16565 -246.883679) (xy 91.207321 -246.91691) (xy 91.243573 -246.955981) (xy 91.273597 -247.000018)
			(xy 91.296723 -247.048039) (xy 91.312433 -247.098969) (xy 91.320376 -247.151673) (xy 91.320874 -247.178322)
			(xy 91.320376 -247.204971) (xy 91.548702 -247.204971) (xy 91.548702 -247.151673) (xy 91.556645 -247.098969)
			(xy 91.572355 -247.048039) (xy 91.595481 -247.000018) (xy 91.625505 -246.955981) (xy 91.661757 -246.91691)
			(xy 91.703428 -246.883679) (xy 91.749586 -246.85703) (xy 91.7992 -246.837558) (xy 91.851162 -246.825698)
			(xy 91.904312 -246.821715) (xy 91.957462 -246.825698) (xy 92.009424 -246.837558) (xy 92.059038 -246.85703)
			(xy 92.105196 -246.883679) (xy 92.146867 -246.91691) (xy 92.183119 -246.955981) (xy 92.213143 -247.000018)
			(xy 92.236269 -247.048039) (xy 92.251979 -247.098969) (xy 92.259922 -247.151673) (xy 92.26042 -247.178322)
			(xy 92.259922 -247.204971) (xy 92.488756 -247.204971) (xy 92.488756 -247.151673) (xy 92.496699 -247.098969)
			(xy 92.512409 -247.048039) (xy 92.535535 -247.000018) (xy 92.565559 -246.955981) (xy 92.601811 -246.91691)
			(xy 92.643482 -246.883679) (xy 92.68964 -246.85703) (xy 92.739254 -246.837558) (xy 92.791216 -246.825698)
			(xy 92.844366 -246.821715) (xy 92.897516 -246.825698) (xy 92.949478 -246.837558) (xy 92.999092 -246.85703)
			(xy 93.04525 -246.883679) (xy 93.086921 -246.91691) (xy 93.123173 -246.955981) (xy 93.153197 -247.000018)
			(xy 93.176323 -247.048039) (xy 93.192033 -247.098969) (xy 93.199976 -247.151673) (xy 93.200474 -247.178322)
			(xy 93.199976 -247.204971) (xy 93.428556 -247.204971) (xy 93.428556 -247.151673) (xy 93.436499 -247.098969)
			(xy 93.452209 -247.048039) (xy 93.475335 -247.000018) (xy 93.505359 -246.955981) (xy 93.541611 -246.91691)
			(xy 93.583282 -246.883679) (xy 93.62944 -246.85703) (xy 93.679054 -246.837558) (xy 93.731016 -246.825698)
			(xy 93.784166 -246.821715) (xy 93.837316 -246.825698) (xy 93.889278 -246.837558) (xy 93.938892 -246.85703)
			(xy 93.98505 -246.883679) (xy 94.026721 -246.91691) (xy 94.062973 -246.955981) (xy 94.092997 -247.000018)
			(xy 94.116123 -247.048039) (xy 94.131833 -247.098969) (xy 94.139776 -247.151673) (xy 94.140274 -247.178322)
			(xy 94.139776 -247.204971) (xy 94.368356 -247.204971) (xy 94.368356 -247.151673) (xy 94.376299 -247.098969)
			(xy 94.392009 -247.048039) (xy 94.415135 -247.000018) (xy 94.445159 -246.955981) (xy 94.481411 -246.91691)
			(xy 94.523082 -246.883679) (xy 94.56924 -246.85703) (xy 94.618854 -246.837558) (xy 94.670816 -246.825698)
			(xy 94.723966 -246.821715) (xy 94.777116 -246.825698) (xy 94.829078 -246.837558) (xy 94.878692 -246.85703)
			(xy 94.92485 -246.883679) (xy 94.966521 -246.91691) (xy 95.002773 -246.955981) (xy 95.032797 -247.000018)
			(xy 95.055923 -247.048039) (xy 95.071633 -247.098969) (xy 95.079576 -247.151673) (xy 95.080074 -247.178322)
			(xy 95.079576 -247.204971) (xy 95.308156 -247.204971) (xy 95.308156 -247.151673) (xy 95.316099 -247.098969)
			(xy 95.331809 -247.048039) (xy 95.354935 -247.000018) (xy 95.384959 -246.955981) (xy 95.421211 -246.91691)
			(xy 95.462882 -246.883679) (xy 95.50904 -246.85703) (xy 95.558654 -246.837558) (xy 95.610616 -246.825698)
			(xy 95.663766 -246.821715) (xy 95.716916 -246.825698) (xy 95.768878 -246.837558) (xy 95.818492 -246.85703)
			(xy 95.86465 -246.883679) (xy 95.906321 -246.91691) (xy 95.942573 -246.955981) (xy 95.972597 -247.000018)
			(xy 95.995723 -247.048039) (xy 96.011433 -247.098969) (xy 96.019376 -247.151673) (xy 96.019874 -247.178322)
			(xy 96.019376 -247.204971) (xy 96.247702 -247.204971) (xy 96.247702 -247.151673) (xy 96.255645 -247.098969)
			(xy 96.271355 -247.048039) (xy 96.294481 -247.000018) (xy 96.324505 -246.955981) (xy 96.360757 -246.91691)
			(xy 96.402428 -246.883679) (xy 96.448586 -246.85703) (xy 96.4982 -246.837558) (xy 96.550162 -246.825698)
			(xy 96.603312 -246.821715) (xy 96.656462 -246.825698) (xy 96.708424 -246.837558) (xy 96.758038 -246.85703)
			(xy 96.804196 -246.883679) (xy 96.845867 -246.91691) (xy 96.882119 -246.955981) (xy 96.912143 -247.000018)
			(xy 96.935269 -247.048039) (xy 96.950979 -247.098969) (xy 96.958922 -247.151673) (xy 96.95942 -247.178322)
			(xy 96.958922 -247.204971) (xy 97.187756 -247.204971) (xy 97.187756 -247.151673) (xy 97.195699 -247.098969)
			(xy 97.211409 -247.048039) (xy 97.234535 -247.000018) (xy 97.264559 -246.955981) (xy 97.300811 -246.91691)
			(xy 97.342482 -246.883679) (xy 97.38864 -246.85703) (xy 97.438254 -246.837558) (xy 97.490216 -246.825698)
			(xy 97.543366 -246.821715) (xy 97.596516 -246.825698) (xy 97.648478 -246.837558) (xy 97.698092 -246.85703)
			(xy 97.74425 -246.883679) (xy 97.785921 -246.91691) (xy 97.822173 -246.955981) (xy 97.852197 -247.000018)
			(xy 97.875323 -247.048039) (xy 97.891033 -247.098969) (xy 97.898976 -247.151673) (xy 97.899474 -247.178322)
			(xy 97.898976 -247.204971) (xy 98.127302 -247.204971) (xy 98.127302 -247.151673) (xy 98.135245 -247.098969)
			(xy 98.150955 -247.048039) (xy 98.174081 -247.000018) (xy 98.204105 -246.955981) (xy 98.240357 -246.91691)
			(xy 98.282028 -246.883679) (xy 98.328186 -246.85703) (xy 98.3778 -246.837558) (xy 98.429762 -246.825698)
			(xy 98.482912 -246.821715) (xy 98.536062 -246.825698) (xy 98.588024 -246.837558) (xy 98.637638 -246.85703)
			(xy 98.683796 -246.883679) (xy 98.725467 -246.91691) (xy 98.761719 -246.955981) (xy 98.791743 -247.000018)
			(xy 98.814869 -247.048039) (xy 98.830579 -247.098969) (xy 98.838522 -247.151673) (xy 98.83902 -247.178322)
			(xy 98.838522 -247.204971) (xy 98.830579 -247.257675) (xy 98.814869 -247.308605) (xy 98.791743 -247.356626)
			(xy 98.761719 -247.400663) (xy 98.725467 -247.439734) (xy 98.683796 -247.472965) (xy 98.637638 -247.499614)
			(xy 98.588024 -247.519086) (xy 98.536062 -247.530946) (xy 98.482912 -247.53493) (xy 98.429762 -247.530946)
			(xy 98.3778 -247.519086) (xy 98.328186 -247.499614) (xy 98.282028 -247.472965) (xy 98.240357 -247.439734)
			(xy 98.204105 -247.400663) (xy 98.174081 -247.356626) (xy 98.150955 -247.308605) (xy 98.135245 -247.257675)
			(xy 98.127302 -247.204971) (xy 97.898976 -247.204971) (xy 97.891033 -247.257675) (xy 97.875323 -247.308605)
			(xy 97.852197 -247.356626) (xy 97.822173 -247.400663) (xy 97.785921 -247.439734) (xy 97.74425 -247.472965)
			(xy 97.698092 -247.499614) (xy 97.648478 -247.519086) (xy 97.596516 -247.530946) (xy 97.543366 -247.53493)
			(xy 97.490216 -247.530946) (xy 97.438254 -247.519086) (xy 97.38864 -247.499614) (xy 97.342482 -247.472965)
			(xy 97.300811 -247.439734) (xy 97.264559 -247.400663) (xy 97.234535 -247.356626) (xy 97.211409 -247.308605)
			(xy 97.195699 -247.257675) (xy 97.187756 -247.204971) (xy 96.958922 -247.204971) (xy 96.950979 -247.257675)
			(xy 96.935269 -247.308605) (xy 96.912143 -247.356626) (xy 96.882119 -247.400663) (xy 96.845867 -247.439734)
			(xy 96.804196 -247.472965) (xy 96.758038 -247.499614) (xy 96.708424 -247.519086) (xy 96.656462 -247.530946)
			(xy 96.603312 -247.53493) (xy 96.550162 -247.530946) (xy 96.4982 -247.519086) (xy 96.448586 -247.499614)
			(xy 96.402428 -247.472965) (xy 96.360757 -247.439734) (xy 96.324505 -247.400663) (xy 96.294481 -247.356626)
			(xy 96.271355 -247.308605) (xy 96.255645 -247.257675) (xy 96.247702 -247.204971) (xy 96.019376 -247.204971)
			(xy 96.011433 -247.257675) (xy 95.995723 -247.308605) (xy 95.972597 -247.356626) (xy 95.942573 -247.400663)
			(xy 95.906321 -247.439734) (xy 95.86465 -247.472965) (xy 95.818492 -247.499614) (xy 95.768878 -247.519086)
			(xy 95.716916 -247.530946) (xy 95.663766 -247.53493) (xy 95.610616 -247.530946) (xy 95.558654 -247.519086)
			(xy 95.50904 -247.499614) (xy 95.462882 -247.472965) (xy 95.421211 -247.439734) (xy 95.384959 -247.400663)
			(xy 95.354935 -247.356626) (xy 95.331809 -247.308605) (xy 95.316099 -247.257675) (xy 95.308156 -247.204971)
			(xy 95.079576 -247.204971) (xy 95.071633 -247.257675) (xy 95.055923 -247.308605) (xy 95.032797 -247.356626)
			(xy 95.002773 -247.400663) (xy 94.966521 -247.439734) (xy 94.92485 -247.472965) (xy 94.878692 -247.499614)
			(xy 94.829078 -247.519086) (xy 94.777116 -247.530946) (xy 94.723966 -247.53493) (xy 94.670816 -247.530946)
			(xy 94.618854 -247.519086) (xy 94.56924 -247.499614) (xy 94.523082 -247.472965) (xy 94.481411 -247.439734)
			(xy 94.445159 -247.400663) (xy 94.415135 -247.356626) (xy 94.392009 -247.308605) (xy 94.376299 -247.257675)
			(xy 94.368356 -247.204971) (xy 94.139776 -247.204971) (xy 94.131833 -247.257675) (xy 94.116123 -247.308605)
			(xy 94.092997 -247.356626) (xy 94.062973 -247.400663) (xy 94.026721 -247.439734) (xy 93.98505 -247.472965)
			(xy 93.938892 -247.499614) (xy 93.889278 -247.519086) (xy 93.837316 -247.530946) (xy 93.784166 -247.53493)
			(xy 93.731016 -247.530946) (xy 93.679054 -247.519086) (xy 93.62944 -247.499614) (xy 93.583282 -247.472965)
			(xy 93.541611 -247.439734) (xy 93.505359 -247.400663) (xy 93.475335 -247.356626) (xy 93.452209 -247.308605)
			(xy 93.436499 -247.257675) (xy 93.428556 -247.204971) (xy 93.199976 -247.204971) (xy 93.192033 -247.257675)
			(xy 93.176323 -247.308605) (xy 93.153197 -247.356626) (xy 93.123173 -247.400663) (xy 93.086921 -247.439734)
			(xy 93.04525 -247.472965) (xy 92.999092 -247.499614) (xy 92.949478 -247.519086) (xy 92.897516 -247.530946)
			(xy 92.844366 -247.53493) (xy 92.791216 -247.530946) (xy 92.739254 -247.519086) (xy 92.68964 -247.499614)
			(xy 92.643482 -247.472965) (xy 92.601811 -247.439734) (xy 92.565559 -247.400663) (xy 92.535535 -247.356626)
			(xy 92.512409 -247.308605) (xy 92.496699 -247.257675) (xy 92.488756 -247.204971) (xy 92.259922 -247.204971)
			(xy 92.251979 -247.257675) (xy 92.236269 -247.308605) (xy 92.213143 -247.356626) (xy 92.183119 -247.400663)
			(xy 92.146867 -247.439734) (xy 92.105196 -247.472965) (xy 92.059038 -247.499614) (xy 92.009424 -247.519086)
			(xy 91.957462 -247.530946) (xy 91.904312 -247.53493) (xy 91.851162 -247.530946) (xy 91.7992 -247.519086)
			(xy 91.749586 -247.499614) (xy 91.703428 -247.472965) (xy 91.661757 -247.439734) (xy 91.625505 -247.400663)
			(xy 91.595481 -247.356626) (xy 91.572355 -247.308605) (xy 91.556645 -247.257675) (xy 91.548702 -247.204971)
			(xy 91.320376 -247.204971) (xy 91.312433 -247.257675) (xy 91.296723 -247.308605) (xy 91.273597 -247.356626)
			(xy 91.243573 -247.400663) (xy 91.207321 -247.439734) (xy 91.16565 -247.472965) (xy 91.119492 -247.499614)
			(xy 91.069878 -247.519086) (xy 91.017916 -247.530946) (xy 90.964766 -247.53493) (xy 90.911616 -247.530946)
			(xy 90.859654 -247.519086) (xy 90.81004 -247.499614) (xy 90.763882 -247.472965) (xy 90.722211 -247.439734)
			(xy 90.685959 -247.400663) (xy 90.655935 -247.356626) (xy 90.632809 -247.308605) (xy 90.617099 -247.257675)
			(xy 90.609156 -247.204971) (xy 90.380322 -247.204971) (xy 90.372379 -247.257675) (xy 90.356669 -247.308605)
			(xy 90.333543 -247.356626) (xy 90.303519 -247.400663) (xy 90.267267 -247.439734) (xy 90.225596 -247.472965)
			(xy 90.179438 -247.499614) (xy 90.129824 -247.519086) (xy 90.077862 -247.530946) (xy 90.024712 -247.53493)
			(xy 89.971562 -247.530946) (xy 89.9196 -247.519086) (xy 89.869986 -247.499614) (xy 89.823828 -247.472965)
			(xy 89.782157 -247.439734) (xy 89.745905 -247.400663) (xy 89.715881 -247.356626) (xy 89.692755 -247.308605)
			(xy 89.677045 -247.257675) (xy 89.669102 -247.204971) (xy 89.439811 -247.204971) (xy 89.437826 -247.231453)
			(xy 89.425965 -247.283419) (xy 89.40649 -247.333036) (xy 89.379838 -247.379196) (xy 89.346603 -247.420868)
			(xy 89.307527 -247.457121) (xy 89.263485 -247.487145) (xy 89.21546 -247.510268) (xy 89.164525 -247.525976)
			(xy 89.111817 -247.533915) (xy 89.085166 -247.53443) (xy 89.074793 -247.534384) (xy 89.054079 -247.533242)
			(xy 89.043764 -247.532144) (xy 89.029509 -247.530983) (xy 89.001314 -247.535699) (xy 88.97553 -247.548045)
			(xy 88.954176 -247.567051) (xy 88.938925 -247.59123) (xy 88.930972 -247.618689) (xy 88.93048 -247.632982)
			(xy 88.93048 -247.82653) (xy 88.93556 -247.836944) (xy 88.946786 -247.861257) (xy 88.962628 -247.912411)
			(xy 88.970636 -247.965359) (xy 88.970631 -248.018787) (xy 89.199456 -248.018787) (xy 89.199456 -247.965489)
			(xy 89.207399 -247.912785) (xy 89.223109 -247.861855) (xy 89.246235 -247.813834) (xy 89.276259 -247.769797)
			(xy 89.312511 -247.730726) (xy 89.354182 -247.697495) (xy 89.40034 -247.670846) (xy 89.449954 -247.651374)
			(xy 89.501916 -247.639514) (xy 89.555066 -247.635531) (xy 89.608216 -247.639514) (xy 89.660178 -247.651374)
			(xy 89.709792 -247.670846) (xy 89.75595 -247.697495) (xy 89.797621 -247.730726) (xy 89.833873 -247.769797)
			(xy 89.863897 -247.813834) (xy 89.887023 -247.861855) (xy 89.902733 -247.912785) (xy 89.910676 -247.965489)
			(xy 89.911174 -247.992138) (xy 89.910676 -248.018787) (xy 90.139002 -248.018787) (xy 90.139002 -247.965489)
			(xy 90.146945 -247.912785) (xy 90.162655 -247.861855) (xy 90.185781 -247.813834) (xy 90.215805 -247.769797)
			(xy 90.252057 -247.730726) (xy 90.293728 -247.697495) (xy 90.339886 -247.670846) (xy 90.3895 -247.651374)
			(xy 90.441462 -247.639514) (xy 90.494612 -247.635531) (xy 90.547762 -247.639514) (xy 90.599724 -247.651374)
			(xy 90.649338 -247.670846) (xy 90.695496 -247.697495) (xy 90.737167 -247.730726) (xy 90.773419 -247.769797)
			(xy 90.803443 -247.813834) (xy 90.826569 -247.861855) (xy 90.842279 -247.912785) (xy 90.850222 -247.965489)
			(xy 90.85072 -247.992138) (xy 90.850222 -248.018787) (xy 91.079056 -248.018787) (xy 91.079056 -247.965489)
			(xy 91.086999 -247.912785) (xy 91.102709 -247.861855) (xy 91.125835 -247.813834) (xy 91.155859 -247.769797)
			(xy 91.192111 -247.730726) (xy 91.233782 -247.697495) (xy 91.27994 -247.670846) (xy 91.329554 -247.651374)
			(xy 91.381516 -247.639514) (xy 91.434666 -247.635531) (xy 91.487816 -247.639514) (xy 91.539778 -247.651374)
			(xy 91.589392 -247.670846) (xy 91.63555 -247.697495) (xy 91.677221 -247.730726) (xy 91.713473 -247.769797)
			(xy 91.743497 -247.813834) (xy 91.766623 -247.861855) (xy 91.782333 -247.912785) (xy 91.790276 -247.965489)
			(xy 91.790774 -247.992138) (xy 91.790276 -248.018787) (xy 92.018602 -248.018787) (xy 92.018602 -247.965489)
			(xy 92.026545 -247.912785) (xy 92.042255 -247.861855) (xy 92.065381 -247.813834) (xy 92.095405 -247.769797)
			(xy 92.131657 -247.730726) (xy 92.173328 -247.697495) (xy 92.219486 -247.670846) (xy 92.2691 -247.651374)
			(xy 92.321062 -247.639514) (xy 92.374212 -247.635531) (xy 92.427362 -247.639514) (xy 92.479324 -247.651374)
			(xy 92.528938 -247.670846) (xy 92.575096 -247.697495) (xy 92.616767 -247.730726) (xy 92.653019 -247.769797)
			(xy 92.683043 -247.813834) (xy 92.706169 -247.861855) (xy 92.721879 -247.912785) (xy 92.729822 -247.965489)
			(xy 92.73032 -247.992138) (xy 92.729822 -248.018787) (xy 92.958402 -248.018787) (xy 92.958402 -247.965489)
			(xy 92.966345 -247.912785) (xy 92.982055 -247.861855) (xy 93.005181 -247.813834) (xy 93.035205 -247.769797)
			(xy 93.071457 -247.730726) (xy 93.113128 -247.697495) (xy 93.159286 -247.670846) (xy 93.2089 -247.651374)
			(xy 93.260862 -247.639514) (xy 93.314012 -247.635531) (xy 93.367162 -247.639514) (xy 93.419124 -247.651374)
			(xy 93.468738 -247.670846) (xy 93.514896 -247.697495) (xy 93.556567 -247.730726) (xy 93.592819 -247.769797)
			(xy 93.622843 -247.813834) (xy 93.645969 -247.861855) (xy 93.661679 -247.912785) (xy 93.669622 -247.965489)
			(xy 93.67012 -247.992138) (xy 93.669622 -248.018787) (xy 93.898202 -248.018787) (xy 93.898202 -247.965489)
			(xy 93.906145 -247.912785) (xy 93.921855 -247.861855) (xy 93.944981 -247.813834) (xy 93.975005 -247.769797)
			(xy 94.011257 -247.730726) (xy 94.052928 -247.697495) (xy 94.099086 -247.670846) (xy 94.1487 -247.651374)
			(xy 94.200662 -247.639514) (xy 94.253812 -247.635531) (xy 94.306962 -247.639514) (xy 94.358924 -247.651374)
			(xy 94.408538 -247.670846) (xy 94.454696 -247.697495) (xy 94.496367 -247.730726) (xy 94.532619 -247.769797)
			(xy 94.562643 -247.813834) (xy 94.585769 -247.861855) (xy 94.601479 -247.912785) (xy 94.609422 -247.965489)
			(xy 94.60992 -247.992138) (xy 94.609422 -248.018787) (xy 94.838002 -248.018787) (xy 94.838002 -247.965489)
			(xy 94.845945 -247.912785) (xy 94.861655 -247.861855) (xy 94.884781 -247.813834) (xy 94.914805 -247.769797)
			(xy 94.951057 -247.730726) (xy 94.992728 -247.697495) (xy 95.038886 -247.670846) (xy 95.0885 -247.651374)
			(xy 95.140462 -247.639514) (xy 95.193612 -247.635531) (xy 95.246762 -247.639514) (xy 95.298724 -247.651374)
			(xy 95.348338 -247.670846) (xy 95.394496 -247.697495) (xy 95.436167 -247.730726) (xy 95.472419 -247.769797)
			(xy 95.502443 -247.813834) (xy 95.525569 -247.861855) (xy 95.541279 -247.912785) (xy 95.549222 -247.965489)
			(xy 95.54972 -247.992138) (xy 95.549222 -248.018787) (xy 95.778056 -248.018787) (xy 95.778056 -247.965489)
			(xy 95.785999 -247.912785) (xy 95.801709 -247.861855) (xy 95.824835 -247.813834) (xy 95.854859 -247.769797)
			(xy 95.891111 -247.730726) (xy 95.932782 -247.697495) (xy 95.97894 -247.670846) (xy 96.028554 -247.651374)
			(xy 96.080516 -247.639514) (xy 96.133666 -247.635531) (xy 96.186816 -247.639514) (xy 96.238778 -247.651374)
			(xy 96.288392 -247.670846) (xy 96.33455 -247.697495) (xy 96.376221 -247.730726) (xy 96.412473 -247.769797)
			(xy 96.442497 -247.813834) (xy 96.465623 -247.861855) (xy 96.481333 -247.912785) (xy 96.489276 -247.965489)
			(xy 96.489774 -247.992138) (xy 96.489276 -248.018787) (xy 96.717602 -248.018787) (xy 96.717602 -247.965489)
			(xy 96.725545 -247.912785) (xy 96.741255 -247.861855) (xy 96.764381 -247.813834) (xy 96.794405 -247.769797)
			(xy 96.830657 -247.730726) (xy 96.872328 -247.697495) (xy 96.918486 -247.670846) (xy 96.9681 -247.651374)
			(xy 97.020062 -247.639514) (xy 97.073212 -247.635531) (xy 97.126362 -247.639514) (xy 97.178324 -247.651374)
			(xy 97.227938 -247.670846) (xy 97.274096 -247.697495) (xy 97.315767 -247.730726) (xy 97.352019 -247.769797)
			(xy 97.382043 -247.813834) (xy 97.405169 -247.861855) (xy 97.420879 -247.912785) (xy 97.428822 -247.965489)
			(xy 97.42932 -247.992138) (xy 97.428822 -248.018787) (xy 97.657656 -248.018787) (xy 97.657656 -247.965489)
			(xy 97.665599 -247.912785) (xy 97.681309 -247.861855) (xy 97.704435 -247.813834) (xy 97.734459 -247.769797)
			(xy 97.770711 -247.730726) (xy 97.812382 -247.697495) (xy 97.85854 -247.670846) (xy 97.908154 -247.651374)
			(xy 97.960116 -247.639514) (xy 98.013266 -247.635531) (xy 98.066416 -247.639514) (xy 98.118378 -247.651374)
			(xy 98.167992 -247.670846) (xy 98.21415 -247.697495) (xy 98.255821 -247.730726) (xy 98.292073 -247.769797)
			(xy 98.322097 -247.813834) (xy 98.345223 -247.861855) (xy 98.360933 -247.912785) (xy 98.368876 -247.965489)
			(xy 98.369374 -247.992138) (xy 98.368876 -248.018787) (xy 98.597456 -248.018787) (xy 98.597456 -247.965489)
			(xy 98.605399 -247.912785) (xy 98.621109 -247.861855) (xy 98.644235 -247.813834) (xy 98.674259 -247.769797)
			(xy 98.710511 -247.730726) (xy 98.752182 -247.697495) (xy 98.79834 -247.670846) (xy 98.847954 -247.651374)
			(xy 98.899916 -247.639514) (xy 98.953066 -247.635531) (xy 99.006216 -247.639514) (xy 99.058178 -247.651374)
			(xy 99.107792 -247.670846) (xy 99.15395 -247.697495) (xy 99.195621 -247.730726) (xy 99.231873 -247.769797)
			(xy 99.261897 -247.813834) (xy 99.285023 -247.861855) (xy 99.300733 -247.912785) (xy 99.308676 -247.965489)
			(xy 99.309174 -247.992138) (xy 99.308676 -248.018787) (xy 99.300733 -248.071491) (xy 99.285023 -248.122421)
			(xy 99.261897 -248.170442) (xy 99.231873 -248.214479) (xy 99.195621 -248.25355) (xy 99.15395 -248.286781)
			(xy 99.107792 -248.31343) (xy 99.058178 -248.332902) (xy 99.006216 -248.344762) (xy 98.953066 -248.348746)
			(xy 98.899916 -248.344762) (xy 98.847954 -248.332902) (xy 98.79834 -248.31343) (xy 98.752182 -248.286781)
			(xy 98.710511 -248.25355) (xy 98.674259 -248.214479) (xy 98.644235 -248.170442) (xy 98.621109 -248.122421)
			(xy 98.605399 -248.071491) (xy 98.597456 -248.018787) (xy 98.368876 -248.018787) (xy 98.360933 -248.071491)
			(xy 98.345223 -248.122421) (xy 98.322097 -248.170442) (xy 98.292073 -248.214479) (xy 98.255821 -248.25355)
			(xy 98.21415 -248.286781) (xy 98.167992 -248.31343) (xy 98.118378 -248.332902) (xy 98.066416 -248.344762)
			(xy 98.013266 -248.348746) (xy 97.960116 -248.344762) (xy 97.908154 -248.332902) (xy 97.85854 -248.31343)
			(xy 97.812382 -248.286781) (xy 97.770711 -248.25355) (xy 97.734459 -248.214479) (xy 97.704435 -248.170442)
			(xy 97.681309 -248.122421) (xy 97.665599 -248.071491) (xy 97.657656 -248.018787) (xy 97.428822 -248.018787)
			(xy 97.420879 -248.071491) (xy 97.405169 -248.122421) (xy 97.382043 -248.170442) (xy 97.352019 -248.214479)
			(xy 97.315767 -248.25355) (xy 97.274096 -248.286781) (xy 97.227938 -248.31343) (xy 97.178324 -248.332902)
			(xy 97.126362 -248.344762) (xy 97.073212 -248.348746) (xy 97.020062 -248.344762) (xy 96.9681 -248.332902)
			(xy 96.918486 -248.31343) (xy 96.872328 -248.286781) (xy 96.830657 -248.25355) (xy 96.794405 -248.214479)
			(xy 96.764381 -248.170442) (xy 96.741255 -248.122421) (xy 96.725545 -248.071491) (xy 96.717602 -248.018787)
			(xy 96.489276 -248.018787) (xy 96.481333 -248.071491) (xy 96.465623 -248.122421) (xy 96.442497 -248.170442)
			(xy 96.412473 -248.214479) (xy 96.376221 -248.25355) (xy 96.33455 -248.286781) (xy 96.288392 -248.31343)
			(xy 96.238778 -248.332902) (xy 96.186816 -248.344762) (xy 96.133666 -248.348746) (xy 96.080516 -248.344762)
			(xy 96.028554 -248.332902) (xy 95.97894 -248.31343) (xy 95.932782 -248.286781) (xy 95.891111 -248.25355)
			(xy 95.854859 -248.214479) (xy 95.824835 -248.170442) (xy 95.801709 -248.122421) (xy 95.785999 -248.071491)
			(xy 95.778056 -248.018787) (xy 95.549222 -248.018787) (xy 95.541279 -248.071491) (xy 95.525569 -248.122421)
			(xy 95.502443 -248.170442) (xy 95.472419 -248.214479) (xy 95.436167 -248.25355) (xy 95.394496 -248.286781)
			(xy 95.348338 -248.31343) (xy 95.298724 -248.332902) (xy 95.246762 -248.344762) (xy 95.193612 -248.348746)
			(xy 95.140462 -248.344762) (xy 95.0885 -248.332902) (xy 95.038886 -248.31343) (xy 94.992728 -248.286781)
			(xy 94.951057 -248.25355) (xy 94.914805 -248.214479) (xy 94.884781 -248.170442) (xy 94.861655 -248.122421)
			(xy 94.845945 -248.071491) (xy 94.838002 -248.018787) (xy 94.609422 -248.018787) (xy 94.601479 -248.071491)
			(xy 94.585769 -248.122421) (xy 94.562643 -248.170442) (xy 94.532619 -248.214479) (xy 94.496367 -248.25355)
			(xy 94.454696 -248.286781) (xy 94.408538 -248.31343) (xy 94.358924 -248.332902) (xy 94.306962 -248.344762)
			(xy 94.253812 -248.348746) (xy 94.200662 -248.344762) (xy 94.1487 -248.332902) (xy 94.099086 -248.31343)
			(xy 94.052928 -248.286781) (xy 94.011257 -248.25355) (xy 93.975005 -248.214479) (xy 93.944981 -248.170442)
			(xy 93.921855 -248.122421) (xy 93.906145 -248.071491) (xy 93.898202 -248.018787) (xy 93.669622 -248.018787)
			(xy 93.661679 -248.071491) (xy 93.645969 -248.122421) (xy 93.622843 -248.170442) (xy 93.592819 -248.214479)
			(xy 93.556567 -248.25355) (xy 93.514896 -248.286781) (xy 93.468738 -248.31343) (xy 93.419124 -248.332902)
			(xy 93.367162 -248.344762) (xy 93.314012 -248.348746) (xy 93.260862 -248.344762) (xy 93.2089 -248.332902)
			(xy 93.159286 -248.31343) (xy 93.113128 -248.286781) (xy 93.071457 -248.25355) (xy 93.035205 -248.214479)
			(xy 93.005181 -248.170442) (xy 92.982055 -248.122421) (xy 92.966345 -248.071491) (xy 92.958402 -248.018787)
			(xy 92.729822 -248.018787) (xy 92.721879 -248.071491) (xy 92.706169 -248.122421) (xy 92.683043 -248.170442)
			(xy 92.653019 -248.214479) (xy 92.616767 -248.25355) (xy 92.575096 -248.286781) (xy 92.528938 -248.31343)
			(xy 92.479324 -248.332902) (xy 92.427362 -248.344762) (xy 92.374212 -248.348746) (xy 92.321062 -248.344762)
			(xy 92.2691 -248.332902) (xy 92.219486 -248.31343) (xy 92.173328 -248.286781) (xy 92.131657 -248.25355)
			(xy 92.095405 -248.214479) (xy 92.065381 -248.170442) (xy 92.042255 -248.122421) (xy 92.026545 -248.071491)
			(xy 92.018602 -248.018787) (xy 91.790276 -248.018787) (xy 91.782333 -248.071491) (xy 91.766623 -248.122421)
			(xy 91.743497 -248.170442) (xy 91.713473 -248.214479) (xy 91.677221 -248.25355) (xy 91.63555 -248.286781)
			(xy 91.589392 -248.31343) (xy 91.539778 -248.332902) (xy 91.487816 -248.344762) (xy 91.434666 -248.348746)
			(xy 91.381516 -248.344762) (xy 91.329554 -248.332902) (xy 91.27994 -248.31343) (xy 91.233782 -248.286781)
			(xy 91.192111 -248.25355) (xy 91.155859 -248.214479) (xy 91.125835 -248.170442) (xy 91.102709 -248.122421)
			(xy 91.086999 -248.071491) (xy 91.079056 -248.018787) (xy 90.850222 -248.018787) (xy 90.842279 -248.071491)
			(xy 90.826569 -248.122421) (xy 90.803443 -248.170442) (xy 90.773419 -248.214479) (xy 90.737167 -248.25355)
			(xy 90.695496 -248.286781) (xy 90.649338 -248.31343) (xy 90.599724 -248.332902) (xy 90.547762 -248.344762)
			(xy 90.494612 -248.348746) (xy 90.441462 -248.344762) (xy 90.3895 -248.332902) (xy 90.339886 -248.31343)
			(xy 90.293728 -248.286781) (xy 90.252057 -248.25355) (xy 90.215805 -248.214479) (xy 90.185781 -248.170442)
			(xy 90.162655 -248.122421) (xy 90.146945 -248.071491) (xy 90.139002 -248.018787) (xy 89.910676 -248.018787)
			(xy 89.902733 -248.071491) (xy 89.887023 -248.122421) (xy 89.863897 -248.170442) (xy 89.833873 -248.214479)
			(xy 89.797621 -248.25355) (xy 89.75595 -248.286781) (xy 89.709792 -248.31343) (xy 89.660178 -248.332902)
			(xy 89.608216 -248.344762) (xy 89.555066 -248.348746) (xy 89.501916 -248.344762) (xy 89.449954 -248.332902)
			(xy 89.40034 -248.31343) (xy 89.354182 -248.286781) (xy 89.312511 -248.25355) (xy 89.276259 -248.214479)
			(xy 89.246235 -248.170442) (xy 89.223109 -248.122421) (xy 89.207399 -248.071491) (xy 89.199456 -248.018787)
			(xy 88.970631 -248.018787) (xy 88.970631 -248.018909) (xy 88.962612 -248.071856) (xy 88.946761 -248.123007)
			(xy 88.93556 -248.147332) (xy 88.93048 -248.157746) (xy 88.93048 -248.351548) (xy 88.930959 -248.365845)
			(xy 88.938885 -248.393317) (xy 88.95413 -248.417508) (xy 88.975492 -248.436513) (xy 89.001293 -248.448838)
			(xy 89.029501 -248.453513) (xy 89.043764 -248.452386) (xy 89.054078 -248.451283) (xy 89.074793 -248.45014)
			(xy 89.085166 -248.4501) (xy 89.111818 -248.450571) (xy 89.164528 -248.458511) (xy 89.215465 -248.474219)
			(xy 89.263492 -248.497343) (xy 89.307536 -248.527368) (xy 89.346613 -248.563622) (xy 89.379849 -248.605296)
			(xy 89.406503 -248.651458) (xy 89.425978 -248.701077) (xy 89.43784 -248.753045) (xy 89.441824 -248.8062)
			(xy 89.439826 -248.832857) (xy 89.669356 -248.832857) (xy 89.669356 -248.779559) (xy 89.677299 -248.726855)
			(xy 89.693009 -248.675925) (xy 89.716135 -248.627904) (xy 89.746159 -248.583867) (xy 89.782411 -248.544796)
			(xy 89.824082 -248.511565) (xy 89.87024 -248.484916) (xy 89.919854 -248.465444) (xy 89.971816 -248.453584)
			(xy 90.024966 -248.449601) (xy 90.078116 -248.453584) (xy 90.130078 -248.465444) (xy 90.179692 -248.484916)
			(xy 90.22585 -248.511565) (xy 90.267521 -248.544796) (xy 90.303773 -248.583867) (xy 90.333797 -248.627904)
			(xy 90.356923 -248.675925) (xy 90.372633 -248.726855) (xy 90.380576 -248.779559) (xy 90.381074 -248.806208)
			(xy 90.380576 -248.832857) (xy 90.609156 -248.832857) (xy 90.609156 -248.779559) (xy 90.617099 -248.726855)
			(xy 90.632809 -248.675925) (xy 90.655935 -248.627904) (xy 90.685959 -248.583867) (xy 90.722211 -248.544796)
			(xy 90.763882 -248.511565) (xy 90.81004 -248.484916) (xy 90.859654 -248.465444) (xy 90.911616 -248.453584)
			(xy 90.964766 -248.449601) (xy 91.017916 -248.453584) (xy 91.069878 -248.465444) (xy 91.119492 -248.484916)
			(xy 91.16565 -248.511565) (xy 91.207321 -248.544796) (xy 91.243573 -248.583867) (xy 91.273597 -248.627904)
			(xy 91.296723 -248.675925) (xy 91.312433 -248.726855) (xy 91.320376 -248.779559) (xy 91.320874 -248.806208)
			(xy 91.320376 -248.832857) (xy 91.548956 -248.832857) (xy 91.548956 -248.779559) (xy 91.556899 -248.726855)
			(xy 91.572609 -248.675925) (xy 91.595735 -248.627904) (xy 91.625759 -248.583867) (xy 91.662011 -248.544796)
			(xy 91.703682 -248.511565) (xy 91.74984 -248.484916) (xy 91.799454 -248.465444) (xy 91.851416 -248.453584)
			(xy 91.904566 -248.449601) (xy 91.957716 -248.453584) (xy 92.009678 -248.465444) (xy 92.059292 -248.484916)
			(xy 92.10545 -248.511565) (xy 92.147121 -248.544796) (xy 92.183373 -248.583867) (xy 92.213397 -248.627904)
			(xy 92.236523 -248.675925) (xy 92.252233 -248.726855) (xy 92.260176 -248.779559) (xy 92.260674 -248.806208)
			(xy 92.260176 -248.832857) (xy 92.488756 -248.832857) (xy 92.488756 -248.779559) (xy 92.496699 -248.726855)
			(xy 92.512409 -248.675925) (xy 92.535535 -248.627904) (xy 92.565559 -248.583867) (xy 92.601811 -248.544796)
			(xy 92.643482 -248.511565) (xy 92.68964 -248.484916) (xy 92.739254 -248.465444) (xy 92.791216 -248.453584)
			(xy 92.844366 -248.449601) (xy 92.897516 -248.453584) (xy 92.949478 -248.465444) (xy 92.999092 -248.484916)
			(xy 93.04525 -248.511565) (xy 93.086921 -248.544796) (xy 93.123173 -248.583867) (xy 93.153197 -248.627904)
			(xy 93.176323 -248.675925) (xy 93.192033 -248.726855) (xy 93.199976 -248.779559) (xy 93.200474 -248.806208)
			(xy 93.199976 -248.832857) (xy 93.428556 -248.832857) (xy 93.428556 -248.779559) (xy 93.436499 -248.726855)
			(xy 93.452209 -248.675925) (xy 93.475335 -248.627904) (xy 93.505359 -248.583867) (xy 93.541611 -248.544796)
			(xy 93.583282 -248.511565) (xy 93.62944 -248.484916) (xy 93.679054 -248.465444) (xy 93.731016 -248.453584)
			(xy 93.784166 -248.449601) (xy 93.837316 -248.453584) (xy 93.889278 -248.465444) (xy 93.938892 -248.484916)
			(xy 93.98505 -248.511565) (xy 94.026721 -248.544796) (xy 94.062973 -248.583867) (xy 94.092997 -248.627904)
			(xy 94.116123 -248.675925) (xy 94.131833 -248.726855) (xy 94.139776 -248.779559) (xy 94.140274 -248.806208)
			(xy 94.139776 -248.832857) (xy 94.368102 -248.832857) (xy 94.368102 -248.779559) (xy 94.376045 -248.726855)
			(xy 94.391755 -248.675925) (xy 94.414881 -248.627904) (xy 94.444905 -248.583867) (xy 94.481157 -248.544796)
			(xy 94.522828 -248.511565) (xy 94.568986 -248.484916) (xy 94.6186 -248.465444) (xy 94.670562 -248.453584)
			(xy 94.723712 -248.449601) (xy 94.776862 -248.453584) (xy 94.828824 -248.465444) (xy 94.878438 -248.484916)
			(xy 94.924596 -248.511565) (xy 94.966267 -248.544796) (xy 95.002519 -248.583867) (xy 95.032543 -248.627904)
			(xy 95.055669 -248.675925) (xy 95.071379 -248.726855) (xy 95.079322 -248.779559) (xy 95.07982 -248.806208)
			(xy 95.079322 -248.832857) (xy 95.308156 -248.832857) (xy 95.308156 -248.779559) (xy 95.316099 -248.726855)
			(xy 95.331809 -248.675925) (xy 95.354935 -248.627904) (xy 95.384959 -248.583867) (xy 95.421211 -248.544796)
			(xy 95.462882 -248.511565) (xy 95.50904 -248.484916) (xy 95.558654 -248.465444) (xy 95.610616 -248.453584)
			(xy 95.663766 -248.449601) (xy 95.716916 -248.453584) (xy 95.768878 -248.465444) (xy 95.818492 -248.484916)
			(xy 95.86465 -248.511565) (xy 95.906321 -248.544796) (xy 95.942573 -248.583867) (xy 95.972597 -248.627904)
			(xy 95.995723 -248.675925) (xy 96.011433 -248.726855) (xy 96.019376 -248.779559) (xy 96.019874 -248.806208)
			(xy 96.019376 -248.832857) (xy 96.247956 -248.832857) (xy 96.247956 -248.779559) (xy 96.255899 -248.726855)
			(xy 96.271609 -248.675925) (xy 96.294735 -248.627904) (xy 96.324759 -248.583867) (xy 96.361011 -248.544796)
			(xy 96.402682 -248.511565) (xy 96.44884 -248.484916) (xy 96.498454 -248.465444) (xy 96.550416 -248.453584)
			(xy 96.603566 -248.449601) (xy 96.656716 -248.453584) (xy 96.708678 -248.465444) (xy 96.758292 -248.484916)
			(xy 96.80445 -248.511565) (xy 96.846121 -248.544796) (xy 96.882373 -248.583867) (xy 96.912397 -248.627904)
			(xy 96.935523 -248.675925) (xy 96.951233 -248.726855) (xy 96.959176 -248.779559) (xy 96.959674 -248.806208)
			(xy 96.959176 -248.832857) (xy 97.187756 -248.832857) (xy 97.187756 -248.779559) (xy 97.195699 -248.726855)
			(xy 97.211409 -248.675925) (xy 97.234535 -248.627904) (xy 97.264559 -248.583867) (xy 97.300811 -248.544796)
			(xy 97.342482 -248.511565) (xy 97.38864 -248.484916) (xy 97.438254 -248.465444) (xy 97.490216 -248.453584)
			(xy 97.543366 -248.449601) (xy 97.596516 -248.453584) (xy 97.648478 -248.465444) (xy 97.698092 -248.484916)
			(xy 97.74425 -248.511565) (xy 97.785921 -248.544796) (xy 97.822173 -248.583867) (xy 97.852197 -248.627904)
			(xy 97.875323 -248.675925) (xy 97.891033 -248.726855) (xy 97.898976 -248.779559) (xy 97.899474 -248.806208)
			(xy 97.898976 -248.832857) (xy 98.127556 -248.832857) (xy 98.127556 -248.779559) (xy 98.135499 -248.726855)
			(xy 98.151209 -248.675925) (xy 98.174335 -248.627904) (xy 98.204359 -248.583867) (xy 98.240611 -248.544796)
			(xy 98.282282 -248.511565) (xy 98.32844 -248.484916) (xy 98.378054 -248.465444) (xy 98.430016 -248.453584)
			(xy 98.483166 -248.449601) (xy 98.536316 -248.453584) (xy 98.588278 -248.465444) (xy 98.637892 -248.484916)
			(xy 98.68405 -248.511565) (xy 98.725721 -248.544796) (xy 98.761973 -248.583867) (xy 98.791997 -248.627904)
			(xy 98.815123 -248.675925) (xy 98.830833 -248.726855) (xy 98.838776 -248.779559) (xy 98.839274 -248.806208)
			(xy 98.838776 -248.832857) (xy 98.830833 -248.885561) (xy 98.815123 -248.936491) (xy 98.791997 -248.984512)
			(xy 98.761973 -249.028549) (xy 98.725721 -249.06762) (xy 98.68405 -249.100851) (xy 98.637892 -249.1275)
			(xy 98.588278 -249.146972) (xy 98.536316 -249.158832) (xy 98.483166 -249.162816) (xy 98.430016 -249.158832)
			(xy 98.378054 -249.146972) (xy 98.32844 -249.1275) (xy 98.282282 -249.100851) (xy 98.240611 -249.06762)
			(xy 98.204359 -249.028549) (xy 98.174335 -248.984512) (xy 98.151209 -248.936491) (xy 98.135499 -248.885561)
			(xy 98.127556 -248.832857) (xy 97.898976 -248.832857) (xy 97.891033 -248.885561) (xy 97.875323 -248.936491)
			(xy 97.852197 -248.984512) (xy 97.822173 -249.028549) (xy 97.785921 -249.06762) (xy 97.74425 -249.100851)
			(xy 97.698092 -249.1275) (xy 97.648478 -249.146972) (xy 97.596516 -249.158832) (xy 97.543366 -249.162816)
			(xy 97.490216 -249.158832) (xy 97.438254 -249.146972) (xy 97.38864 -249.1275) (xy 97.342482 -249.100851)
			(xy 97.300811 -249.06762) (xy 97.264559 -249.028549) (xy 97.234535 -248.984512) (xy 97.211409 -248.936491)
			(xy 97.195699 -248.885561) (xy 97.187756 -248.832857) (xy 96.959176 -248.832857) (xy 96.951233 -248.885561)
			(xy 96.935523 -248.936491) (xy 96.912397 -248.984512) (xy 96.882373 -249.028549) (xy 96.846121 -249.06762)
			(xy 96.80445 -249.100851) (xy 96.758292 -249.1275) (xy 96.708678 -249.146972) (xy 96.656716 -249.158832)
			(xy 96.603566 -249.162816) (xy 96.550416 -249.158832) (xy 96.498454 -249.146972) (xy 96.44884 -249.1275)
			(xy 96.402682 -249.100851) (xy 96.361011 -249.06762) (xy 96.324759 -249.028549) (xy 96.294735 -248.984512)
			(xy 96.271609 -248.936491) (xy 96.255899 -248.885561) (xy 96.247956 -248.832857) (xy 96.019376 -248.832857)
			(xy 96.011433 -248.885561) (xy 95.995723 -248.936491) (xy 95.972597 -248.984512) (xy 95.942573 -249.028549)
			(xy 95.906321 -249.06762) (xy 95.86465 -249.100851) (xy 95.818492 -249.1275) (xy 95.768878 -249.146972)
			(xy 95.716916 -249.158832) (xy 95.663766 -249.162816) (xy 95.610616 -249.158832) (xy 95.558654 -249.146972)
			(xy 95.50904 -249.1275) (xy 95.462882 -249.100851) (xy 95.421211 -249.06762) (xy 95.384959 -249.028549)
			(xy 95.354935 -248.984512) (xy 95.331809 -248.936491) (xy 95.316099 -248.885561) (xy 95.308156 -248.832857)
			(xy 95.079322 -248.832857) (xy 95.071379 -248.885561) (xy 95.055669 -248.936491) (xy 95.032543 -248.984512)
			(xy 95.002519 -249.028549) (xy 94.966267 -249.06762) (xy 94.924596 -249.100851) (xy 94.878438 -249.1275)
			(xy 94.828824 -249.146972) (xy 94.776862 -249.158832) (xy 94.723712 -249.162816) (xy 94.670562 -249.158832)
			(xy 94.6186 -249.146972) (xy 94.568986 -249.1275) (xy 94.522828 -249.100851) (xy 94.481157 -249.06762)
			(xy 94.444905 -249.028549) (xy 94.414881 -248.984512) (xy 94.391755 -248.936491) (xy 94.376045 -248.885561)
			(xy 94.368102 -248.832857) (xy 94.139776 -248.832857) (xy 94.131833 -248.885561) (xy 94.116123 -248.936491)
			(xy 94.092997 -248.984512) (xy 94.062973 -249.028549) (xy 94.026721 -249.06762) (xy 93.98505 -249.100851)
			(xy 93.938892 -249.1275) (xy 93.889278 -249.146972) (xy 93.837316 -249.158832) (xy 93.784166 -249.162816)
			(xy 93.731016 -249.158832) (xy 93.679054 -249.146972) (xy 93.62944 -249.1275) (xy 93.583282 -249.100851)
			(xy 93.541611 -249.06762) (xy 93.505359 -249.028549) (xy 93.475335 -248.984512) (xy 93.452209 -248.936491)
			(xy 93.436499 -248.885561) (xy 93.428556 -248.832857) (xy 93.199976 -248.832857) (xy 93.192033 -248.885561)
			(xy 93.176323 -248.936491) (xy 93.153197 -248.984512) (xy 93.123173 -249.028549) (xy 93.086921 -249.06762)
			(xy 93.04525 -249.100851) (xy 92.999092 -249.1275) (xy 92.949478 -249.146972) (xy 92.897516 -249.158832)
			(xy 92.844366 -249.162816) (xy 92.791216 -249.158832) (xy 92.739254 -249.146972) (xy 92.68964 -249.1275)
			(xy 92.643482 -249.100851) (xy 92.601811 -249.06762) (xy 92.565559 -249.028549) (xy 92.535535 -248.984512)
			(xy 92.512409 -248.936491) (xy 92.496699 -248.885561) (xy 92.488756 -248.832857) (xy 92.260176 -248.832857)
			(xy 92.252233 -248.885561) (xy 92.236523 -248.936491) (xy 92.213397 -248.984512) (xy 92.183373 -249.028549)
			(xy 92.147121 -249.06762) (xy 92.10545 -249.100851) (xy 92.059292 -249.1275) (xy 92.009678 -249.146972)
			(xy 91.957716 -249.158832) (xy 91.904566 -249.162816) (xy 91.851416 -249.158832) (xy 91.799454 -249.146972)
			(xy 91.74984 -249.1275) (xy 91.703682 -249.100851) (xy 91.662011 -249.06762) (xy 91.625759 -249.028549)
			(xy 91.595735 -248.984512) (xy 91.572609 -248.936491) (xy 91.556899 -248.885561) (xy 91.548956 -248.832857)
			(xy 91.320376 -248.832857) (xy 91.312433 -248.885561) (xy 91.296723 -248.936491) (xy 91.273597 -248.984512)
			(xy 91.243573 -249.028549) (xy 91.207321 -249.06762) (xy 91.16565 -249.100851) (xy 91.119492 -249.1275)
			(xy 91.069878 -249.146972) (xy 91.017916 -249.158832) (xy 90.964766 -249.162816) (xy 90.911616 -249.158832)
			(xy 90.859654 -249.146972) (xy 90.81004 -249.1275) (xy 90.763882 -249.100851) (xy 90.722211 -249.06762)
			(xy 90.685959 -249.028549) (xy 90.655935 -248.984512) (xy 90.632809 -248.936491) (xy 90.617099 -248.885561)
			(xy 90.609156 -248.832857) (xy 90.380576 -248.832857) (xy 90.372633 -248.885561) (xy 90.356923 -248.936491)
			(xy 90.333797 -248.984512) (xy 90.303773 -249.028549) (xy 90.267521 -249.06762) (xy 90.22585 -249.100851)
			(xy 90.179692 -249.1275) (xy 90.130078 -249.146972) (xy 90.078116 -249.158832) (xy 90.024966 -249.162816)
			(xy 89.971816 -249.158832) (xy 89.919854 -249.146972) (xy 89.87024 -249.1275) (xy 89.824082 -249.100851)
			(xy 89.782411 -249.06762) (xy 89.746159 -249.028549) (xy 89.716135 -248.984512) (xy 89.693009 -248.936491)
			(xy 89.677299 -248.885561) (xy 89.669356 -248.832857) (xy 89.439826 -248.832857) (xy 89.43784 -248.859355)
			(xy 89.425978 -248.911323) (xy 89.406503 -248.960942) (xy 89.379849 -249.007104) (xy 89.346613 -249.048778)
			(xy 89.307536 -249.085032) (xy 89.263492 -249.115057) (xy 89.215465 -249.138181) (xy 89.164528 -249.153889)
			(xy 89.111818 -249.161829) (xy 89.085166 -249.162316) (xy 89.074793 -249.16227) (xy 89.054079 -249.161128)
			(xy 89.043764 -249.16003) (xy 89.029509 -249.158869) (xy 89.001312 -249.163586) (xy 88.975526 -249.17593)
			(xy 88.95417 -249.194936) (xy 88.938917 -249.219115) (xy 88.93096 -249.246574) (xy 88.93048 -249.260868)
			(xy 88.93048 -249.454416) (xy 88.93556 -249.46483) (xy 88.946787 -249.489143) (xy 88.962631 -249.540297)
			(xy 88.970641 -249.593246) (xy 88.970638 -249.646673) (xy 89.199202 -249.646673) (xy 89.199202 -249.593375)
			(xy 89.207145 -249.540671) (xy 89.222855 -249.489741) (xy 89.245981 -249.44172) (xy 89.276005 -249.397683)
			(xy 89.312257 -249.358612) (xy 89.353928 -249.325381) (xy 89.400086 -249.298732) (xy 89.4497 -249.27926)
			(xy 89.501662 -249.2674) (xy 89.554812 -249.263417) (xy 89.607962 -249.2674) (xy 89.659924 -249.27926)
			(xy 89.709538 -249.298732) (xy 89.755696 -249.325381) (xy 89.797367 -249.358612) (xy 89.833619 -249.397683)
			(xy 89.863643 -249.44172) (xy 89.886769 -249.489741) (xy 89.902479 -249.540671) (xy 89.910422 -249.593375)
			(xy 89.91092 -249.620024) (xy 89.910422 -249.646673) (xy 90.139256 -249.646673) (xy 90.139256 -249.593375)
			(xy 90.147199 -249.540671) (xy 90.162909 -249.489741) (xy 90.186035 -249.44172) (xy 90.216059 -249.397683)
			(xy 90.252311 -249.358612) (xy 90.293982 -249.325381) (xy 90.34014 -249.298732) (xy 90.389754 -249.27926)
			(xy 90.441716 -249.2674) (xy 90.494866 -249.263417) (xy 90.548016 -249.2674) (xy 90.599978 -249.27926)
			(xy 90.649592 -249.298732) (xy 90.69575 -249.325381) (xy 90.737421 -249.358612) (xy 90.773673 -249.397683)
			(xy 90.803697 -249.44172) (xy 90.826823 -249.489741) (xy 90.842533 -249.540671) (xy 90.850476 -249.593375)
			(xy 90.850974 -249.620024) (xy 90.850476 -249.646673) (xy 91.078802 -249.646673) (xy 91.078802 -249.593375)
			(xy 91.086745 -249.540671) (xy 91.102455 -249.489741) (xy 91.125581 -249.44172) (xy 91.155605 -249.397683)
			(xy 91.191857 -249.358612) (xy 91.233528 -249.325381) (xy 91.279686 -249.298732) (xy 91.3293 -249.27926)
			(xy 91.381262 -249.2674) (xy 91.434412 -249.263417) (xy 91.487562 -249.2674) (xy 91.539524 -249.27926)
			(xy 91.589138 -249.298732) (xy 91.635296 -249.325381) (xy 91.676967 -249.358612) (xy 91.713219 -249.397683)
			(xy 91.743243 -249.44172) (xy 91.766369 -249.489741) (xy 91.782079 -249.540671) (xy 91.790022 -249.593375)
			(xy 91.79052 -249.620024) (xy 91.790022 -249.646673) (xy 92.018602 -249.646673) (xy 92.018602 -249.593375)
			(xy 92.026545 -249.540671) (xy 92.042255 -249.489741) (xy 92.065381 -249.44172) (xy 92.095405 -249.397683)
			(xy 92.131657 -249.358612) (xy 92.173328 -249.325381) (xy 92.219486 -249.298732) (xy 92.2691 -249.27926)
			(xy 92.321062 -249.2674) (xy 92.374212 -249.263417) (xy 92.427362 -249.2674) (xy 92.479324 -249.27926)
			(xy 92.528938 -249.298732) (xy 92.575096 -249.325381) (xy 92.616767 -249.358612) (xy 92.653019 -249.397683)
			(xy 92.683043 -249.44172) (xy 92.706169 -249.489741) (xy 92.721879 -249.540671) (xy 92.729822 -249.593375)
			(xy 92.73032 -249.620024) (xy 92.729822 -249.646673) (xy 92.958402 -249.646673) (xy 92.958402 -249.593375)
			(xy 92.966345 -249.540671) (xy 92.982055 -249.489741) (xy 93.005181 -249.44172) (xy 93.035205 -249.397683)
			(xy 93.071457 -249.358612) (xy 93.113128 -249.325381) (xy 93.159286 -249.298732) (xy 93.2089 -249.27926)
			(xy 93.260862 -249.2674) (xy 93.314012 -249.263417) (xy 93.367162 -249.2674) (xy 93.419124 -249.27926)
			(xy 93.468738 -249.298732) (xy 93.514896 -249.325381) (xy 93.556567 -249.358612) (xy 93.592819 -249.397683)
			(xy 93.622843 -249.44172) (xy 93.645969 -249.489741) (xy 93.661679 -249.540671) (xy 93.669622 -249.593375)
			(xy 93.67012 -249.620024) (xy 93.669622 -249.646673) (xy 93.898202 -249.646673) (xy 93.898202 -249.593375)
			(xy 93.906145 -249.540671) (xy 93.921855 -249.489741) (xy 93.944981 -249.44172) (xy 93.975005 -249.397683)
			(xy 94.011257 -249.358612) (xy 94.052928 -249.325381) (xy 94.099086 -249.298732) (xy 94.1487 -249.27926)
			(xy 94.200662 -249.2674) (xy 94.253812 -249.263417) (xy 94.306962 -249.2674) (xy 94.358924 -249.27926)
			(xy 94.408538 -249.298732) (xy 94.454696 -249.325381) (xy 94.496367 -249.358612) (xy 94.532619 -249.397683)
			(xy 94.562643 -249.44172) (xy 94.585769 -249.489741) (xy 94.601479 -249.540671) (xy 94.609422 -249.593375)
			(xy 94.60992 -249.620024) (xy 94.609422 -249.646673) (xy 94.838002 -249.646673) (xy 94.838002 -249.593375)
			(xy 94.845945 -249.540671) (xy 94.861655 -249.489741) (xy 94.884781 -249.44172) (xy 94.914805 -249.397683)
			(xy 94.951057 -249.358612) (xy 94.992728 -249.325381) (xy 95.038886 -249.298732) (xy 95.0885 -249.27926)
			(xy 95.140462 -249.2674) (xy 95.193612 -249.263417) (xy 95.246762 -249.2674) (xy 95.298724 -249.27926)
			(xy 95.348338 -249.298732) (xy 95.394496 -249.325381) (xy 95.436167 -249.358612) (xy 95.472419 -249.397683)
			(xy 95.502443 -249.44172) (xy 95.525569 -249.489741) (xy 95.541279 -249.540671) (xy 95.549222 -249.593375)
			(xy 95.54972 -249.620024) (xy 95.549222 -249.646673) (xy 95.777802 -249.646673) (xy 95.777802 -249.593375)
			(xy 95.785745 -249.540671) (xy 95.801455 -249.489741) (xy 95.824581 -249.44172) (xy 95.854605 -249.397683)
			(xy 95.890857 -249.358612) (xy 95.932528 -249.325381) (xy 95.978686 -249.298732) (xy 96.0283 -249.27926)
			(xy 96.080262 -249.2674) (xy 96.133412 -249.263417) (xy 96.186562 -249.2674) (xy 96.238524 -249.27926)
			(xy 96.288138 -249.298732) (xy 96.334296 -249.325381) (xy 96.375967 -249.358612) (xy 96.412219 -249.397683)
			(xy 96.442243 -249.44172) (xy 96.465369 -249.489741) (xy 96.481079 -249.540671) (xy 96.489022 -249.593375)
			(xy 96.48952 -249.620024) (xy 96.489022 -249.646673) (xy 96.717856 -249.646673) (xy 96.717856 -249.593375)
			(xy 96.725799 -249.540671) (xy 96.741509 -249.489741) (xy 96.764635 -249.44172) (xy 96.794659 -249.397683)
			(xy 96.830911 -249.358612) (xy 96.872582 -249.325381) (xy 96.91874 -249.298732) (xy 96.968354 -249.27926)
			(xy 97.020316 -249.2674) (xy 97.073466 -249.263417) (xy 97.126616 -249.2674) (xy 97.178578 -249.27926)
			(xy 97.228192 -249.298732) (xy 97.27435 -249.325381) (xy 97.316021 -249.358612) (xy 97.352273 -249.397683)
			(xy 97.382297 -249.44172) (xy 97.405423 -249.489741) (xy 97.421133 -249.540671) (xy 97.429076 -249.593375)
			(xy 97.429574 -249.620024) (xy 97.429076 -249.646673) (xy 97.657402 -249.646673) (xy 97.657402 -249.593375)
			(xy 97.665345 -249.540671) (xy 97.681055 -249.489741) (xy 97.704181 -249.44172) (xy 97.734205 -249.397683)
			(xy 97.770457 -249.358612) (xy 97.812128 -249.325381) (xy 97.858286 -249.298732) (xy 97.9079 -249.27926)
			(xy 97.959862 -249.2674) (xy 98.013012 -249.263417) (xy 98.066162 -249.2674) (xy 98.118124 -249.27926)
			(xy 98.167738 -249.298732) (xy 98.213896 -249.325381) (xy 98.255567 -249.358612) (xy 98.291819 -249.397683)
			(xy 98.321843 -249.44172) (xy 98.344969 -249.489741) (xy 98.360679 -249.540671) (xy 98.368622 -249.593375)
			(xy 98.36912 -249.620024) (xy 98.368622 -249.646673) (xy 98.597202 -249.646673) (xy 98.597202 -249.593375)
			(xy 98.605145 -249.540671) (xy 98.620855 -249.489741) (xy 98.643981 -249.44172) (xy 98.674005 -249.397683)
			(xy 98.710257 -249.358612) (xy 98.751928 -249.325381) (xy 98.798086 -249.298732) (xy 98.8477 -249.27926)
			(xy 98.899662 -249.2674) (xy 98.952812 -249.263417) (xy 99.005962 -249.2674) (xy 99.057924 -249.27926)
			(xy 99.107538 -249.298732) (xy 99.153696 -249.325381) (xy 99.195367 -249.358612) (xy 99.231619 -249.397683)
			(xy 99.261643 -249.44172) (xy 99.284769 -249.489741) (xy 99.300479 -249.540671) (xy 99.308422 -249.593375)
			(xy 99.30892 -249.620024) (xy 99.308422 -249.646673) (xy 99.300479 -249.699377) (xy 99.284769 -249.750307)
			(xy 99.261643 -249.798328) (xy 99.231619 -249.842365) (xy 99.195367 -249.881436) (xy 99.153696 -249.914667)
			(xy 99.107538 -249.941316) (xy 99.057924 -249.960788) (xy 99.005962 -249.972648) (xy 98.952812 -249.976632)
			(xy 98.899662 -249.972648) (xy 98.8477 -249.960788) (xy 98.798086 -249.941316) (xy 98.751928 -249.914667)
			(xy 98.710257 -249.881436) (xy 98.674005 -249.842365) (xy 98.643981 -249.798328) (xy 98.620855 -249.750307)
			(xy 98.605145 -249.699377) (xy 98.597202 -249.646673) (xy 98.368622 -249.646673) (xy 98.360679 -249.699377)
			(xy 98.344969 -249.750307) (xy 98.321843 -249.798328) (xy 98.291819 -249.842365) (xy 98.255567 -249.881436)
			(xy 98.213896 -249.914667) (xy 98.167738 -249.941316) (xy 98.118124 -249.960788) (xy 98.066162 -249.972648)
			(xy 98.013012 -249.976632) (xy 97.959862 -249.972648) (xy 97.9079 -249.960788) (xy 97.858286 -249.941316)
			(xy 97.812128 -249.914667) (xy 97.770457 -249.881436) (xy 97.734205 -249.842365) (xy 97.704181 -249.798328)
			(xy 97.681055 -249.750307) (xy 97.665345 -249.699377) (xy 97.657402 -249.646673) (xy 97.429076 -249.646673)
			(xy 97.421133 -249.699377) (xy 97.405423 -249.750307) (xy 97.382297 -249.798328) (xy 97.352273 -249.842365)
			(xy 97.316021 -249.881436) (xy 97.27435 -249.914667) (xy 97.228192 -249.941316) (xy 97.178578 -249.960788)
			(xy 97.126616 -249.972648) (xy 97.073466 -249.976632) (xy 97.020316 -249.972648) (xy 96.968354 -249.960788)
			(xy 96.91874 -249.941316) (xy 96.872582 -249.914667) (xy 96.830911 -249.881436) (xy 96.794659 -249.842365)
			(xy 96.764635 -249.798328) (xy 96.741509 -249.750307) (xy 96.725799 -249.699377) (xy 96.717856 -249.646673)
			(xy 96.489022 -249.646673) (xy 96.481079 -249.699377) (xy 96.465369 -249.750307) (xy 96.442243 -249.798328)
			(xy 96.412219 -249.842365) (xy 96.375967 -249.881436) (xy 96.334296 -249.914667) (xy 96.288138 -249.941316)
			(xy 96.238524 -249.960788) (xy 96.186562 -249.972648) (xy 96.133412 -249.976632) (xy 96.080262 -249.972648)
			(xy 96.0283 -249.960788) (xy 95.978686 -249.941316) (xy 95.932528 -249.914667) (xy 95.890857 -249.881436)
			(xy 95.854605 -249.842365) (xy 95.824581 -249.798328) (xy 95.801455 -249.750307) (xy 95.785745 -249.699377)
			(xy 95.777802 -249.646673) (xy 95.549222 -249.646673) (xy 95.541279 -249.699377) (xy 95.525569 -249.750307)
			(xy 95.502443 -249.798328) (xy 95.472419 -249.842365) (xy 95.436167 -249.881436) (xy 95.394496 -249.914667)
			(xy 95.348338 -249.941316) (xy 95.298724 -249.960788) (xy 95.246762 -249.972648) (xy 95.193612 -249.976632)
			(xy 95.140462 -249.972648) (xy 95.0885 -249.960788) (xy 95.038886 -249.941316) (xy 94.992728 -249.914667)
			(xy 94.951057 -249.881436) (xy 94.914805 -249.842365) (xy 94.884781 -249.798328) (xy 94.861655 -249.750307)
			(xy 94.845945 -249.699377) (xy 94.838002 -249.646673) (xy 94.609422 -249.646673) (xy 94.601479 -249.699377)
			(xy 94.585769 -249.750307) (xy 94.562643 -249.798328) (xy 94.532619 -249.842365) (xy 94.496367 -249.881436)
			(xy 94.454696 -249.914667) (xy 94.408538 -249.941316) (xy 94.358924 -249.960788) (xy 94.306962 -249.972648)
			(xy 94.253812 -249.976632) (xy 94.200662 -249.972648) (xy 94.1487 -249.960788) (xy 94.099086 -249.941316)
			(xy 94.052928 -249.914667) (xy 94.011257 -249.881436) (xy 93.975005 -249.842365) (xy 93.944981 -249.798328)
			(xy 93.921855 -249.750307) (xy 93.906145 -249.699377) (xy 93.898202 -249.646673) (xy 93.669622 -249.646673)
			(xy 93.661679 -249.699377) (xy 93.645969 -249.750307) (xy 93.622843 -249.798328) (xy 93.592819 -249.842365)
			(xy 93.556567 -249.881436) (xy 93.514896 -249.914667) (xy 93.468738 -249.941316) (xy 93.419124 -249.960788)
			(xy 93.367162 -249.972648) (xy 93.314012 -249.976632) (xy 93.260862 -249.972648) (xy 93.2089 -249.960788)
			(xy 93.159286 -249.941316) (xy 93.113128 -249.914667) (xy 93.071457 -249.881436) (xy 93.035205 -249.842365)
			(xy 93.005181 -249.798328) (xy 92.982055 -249.750307) (xy 92.966345 -249.699377) (xy 92.958402 -249.646673)
			(xy 92.729822 -249.646673) (xy 92.721879 -249.699377) (xy 92.706169 -249.750307) (xy 92.683043 -249.798328)
			(xy 92.653019 -249.842365) (xy 92.616767 -249.881436) (xy 92.575096 -249.914667) (xy 92.528938 -249.941316)
			(xy 92.479324 -249.960788) (xy 92.427362 -249.972648) (xy 92.374212 -249.976632) (xy 92.321062 -249.972648)
			(xy 92.2691 -249.960788) (xy 92.219486 -249.941316) (xy 92.173328 -249.914667) (xy 92.131657 -249.881436)
			(xy 92.095405 -249.842365) (xy 92.065381 -249.798328) (xy 92.042255 -249.750307) (xy 92.026545 -249.699377)
			(xy 92.018602 -249.646673) (xy 91.790022 -249.646673) (xy 91.782079 -249.699377) (xy 91.766369 -249.750307)
			(xy 91.743243 -249.798328) (xy 91.713219 -249.842365) (xy 91.676967 -249.881436) (xy 91.635296 -249.914667)
			(xy 91.589138 -249.941316) (xy 91.539524 -249.960788) (xy 91.487562 -249.972648) (xy 91.434412 -249.976632)
			(xy 91.381262 -249.972648) (xy 91.3293 -249.960788) (xy 91.279686 -249.941316) (xy 91.233528 -249.914667)
			(xy 91.191857 -249.881436) (xy 91.155605 -249.842365) (xy 91.125581 -249.798328) (xy 91.102455 -249.750307)
			(xy 91.086745 -249.699377) (xy 91.078802 -249.646673) (xy 90.850476 -249.646673) (xy 90.842533 -249.699377)
			(xy 90.826823 -249.750307) (xy 90.803697 -249.798328) (xy 90.773673 -249.842365) (xy 90.737421 -249.881436)
			(xy 90.69575 -249.914667) (xy 90.649592 -249.941316) (xy 90.599978 -249.960788) (xy 90.548016 -249.972648)
			(xy 90.494866 -249.976632) (xy 90.441716 -249.972648) (xy 90.389754 -249.960788) (xy 90.34014 -249.941316)
			(xy 90.293982 -249.914667) (xy 90.252311 -249.881436) (xy 90.216059 -249.842365) (xy 90.186035 -249.798328)
			(xy 90.162909 -249.750307) (xy 90.147199 -249.699377) (xy 90.139256 -249.646673) (xy 89.910422 -249.646673)
			(xy 89.902479 -249.699377) (xy 89.886769 -249.750307) (xy 89.863643 -249.798328) (xy 89.833619 -249.842365)
			(xy 89.797367 -249.881436) (xy 89.755696 -249.914667) (xy 89.709538 -249.941316) (xy 89.659924 -249.960788)
			(xy 89.607962 -249.972648) (xy 89.554812 -249.976632) (xy 89.501662 -249.972648) (xy 89.4497 -249.960788)
			(xy 89.400086 -249.941316) (xy 89.353928 -249.914667) (xy 89.312257 -249.881436) (xy 89.276005 -249.842365)
			(xy 89.245981 -249.798328) (xy 89.222855 -249.750307) (xy 89.207145 -249.699377) (xy 89.199202 -249.646673)
			(xy 88.970638 -249.646673) (xy 88.970638 -249.646797) (xy 88.962621 -249.699745) (xy 88.946771 -249.750897)
			(xy 88.93556 -249.775218) (xy 88.93048 -249.785632) (xy 88.93048 -253.132569) (xy 94.94773 -253.132569)
			(xy 94.94773 -253.079271) (xy 94.955673 -253.026567) (xy 94.971383 -252.975637) (xy 94.994509 -252.927616)
			(xy 95.024533 -252.883579) (xy 95.060785 -252.844508) (xy 95.102456 -252.811277) (xy 95.148614 -252.784628)
			(xy 95.198228 -252.765156) (xy 95.25019 -252.753296) (xy 95.30334 -252.749313) (xy 95.35649 -252.753296)
			(xy 95.408452 -252.765156) (xy 95.458066 -252.784628) (xy 95.504224 -252.811277) (xy 95.545895 -252.844508)
			(xy 95.582147 -252.883579) (xy 95.612171 -252.927616) (xy 95.635297 -252.975637) (xy 95.651007 -253.026567)
			(xy 95.65895 -253.079271) (xy 95.659448 -253.10592) (xy 95.65895 -253.132569) (xy 95.651007 -253.185273)
			(xy 95.635297 -253.236203) (xy 95.612171 -253.284224) (xy 95.582147 -253.328261) (xy 95.545895 -253.367332)
			(xy 95.504224 -253.400563) (xy 95.458066 -253.427212) (xy 95.408452 -253.446684) (xy 95.35649 -253.458544)
			(xy 95.30334 -253.462528) (xy 95.25019 -253.458544) (xy 95.198228 -253.446684) (xy 95.148614 -253.427212)
			(xy 95.102456 -253.400563) (xy 95.060785 -253.367332) (xy 95.024533 -253.328261) (xy 94.994509 -253.284224)
			(xy 94.971383 -253.236203) (xy 94.955673 -253.185273) (xy 94.94773 -253.132569) (xy 88.93048 -253.132569)
			(xy 88.93048 -253.492) (xy 88.93093 -253.506062) (xy 88.9386 -253.533119) (xy 88.953357 -253.557059)
			(xy 88.974084 -253.576067) (xy 88.99921 -253.588702) (xy 89.026828 -253.594006) (xy 89.054847 -253.591578)
			(xy 89.068148 -253.586996) (xy 89.098701 -253.576122) (xy 89.162472 -253.56436) (xy 89.194894 -253.563628)
			(xy 89.221543 -253.564101) (xy 89.274245 -253.572043) (xy 89.325175 -253.587752) (xy 89.373195 -253.610877)
			(xy 89.417231 -253.6409) (xy 89.456301 -253.677151) (xy 89.489532 -253.71882) (xy 89.516181 -253.764977)
			(xy 89.535653 -253.81459) (xy 89.547513 -253.866552) (xy 89.551496 -253.9197) (xy 89.549496 -253.946385)
			(xy 89.779084 -253.946385) (xy 89.779084 -253.893087) (xy 89.787027 -253.840383) (xy 89.802737 -253.789453)
			(xy 89.825863 -253.741432) (xy 89.855887 -253.697395) (xy 89.892139 -253.658324) (xy 89.93381 -253.625093)
			(xy 89.979968 -253.598444) (xy 90.029582 -253.578972) (xy 90.081544 -253.567112) (xy 90.134694 -253.563129)
			(xy 90.187844 -253.567112) (xy 90.239806 -253.578972) (xy 90.28942 -253.598444) (xy 90.335578 -253.625093)
			(xy 90.377249 -253.658324) (xy 90.413501 -253.697395) (xy 90.443525 -253.741432) (xy 90.466651 -253.789453)
			(xy 90.482361 -253.840383) (xy 90.490304 -253.893087) (xy 90.490802 -253.919736) (xy 90.490304 -253.946385)
			(xy 90.719138 -253.946385) (xy 90.719138 -253.893087) (xy 90.727081 -253.840383) (xy 90.742791 -253.789453)
			(xy 90.765917 -253.741432) (xy 90.795941 -253.697395) (xy 90.832193 -253.658324) (xy 90.873864 -253.625093)
			(xy 90.920022 -253.598444) (xy 90.969636 -253.578972) (xy 91.021598 -253.567112) (xy 91.074748 -253.563129)
			(xy 91.127898 -253.567112) (xy 91.17986 -253.578972) (xy 91.229474 -253.598444) (xy 91.275632 -253.625093)
			(xy 91.317303 -253.658324) (xy 91.353555 -253.697395) (xy 91.383579 -253.741432) (xy 91.406705 -253.789453)
			(xy 91.422415 -253.840383) (xy 91.430358 -253.893087) (xy 91.430856 -253.919736) (xy 91.430358 -253.946385)
			(xy 91.658938 -253.946385) (xy 91.658938 -253.893087) (xy 91.666881 -253.840383) (xy 91.682591 -253.789453)
			(xy 91.705717 -253.741432) (xy 91.735741 -253.697395) (xy 91.771993 -253.658324) (xy 91.813664 -253.625093)
			(xy 91.859822 -253.598444) (xy 91.909436 -253.578972) (xy 91.961398 -253.567112) (xy 92.014548 -253.563129)
			(xy 92.067698 -253.567112) (xy 92.11966 -253.578972) (xy 92.169274 -253.598444) (xy 92.215432 -253.625093)
			(xy 92.257103 -253.658324) (xy 92.293355 -253.697395) (xy 92.323379 -253.741432) (xy 92.346505 -253.789453)
			(xy 92.362215 -253.840383) (xy 92.370158 -253.893087) (xy 92.370656 -253.919736) (xy 92.370158 -253.946385)
			(xy 92.598738 -253.946385) (xy 92.598738 -253.893087) (xy 92.606681 -253.840383) (xy 92.622391 -253.789453)
			(xy 92.645517 -253.741432) (xy 92.675541 -253.697395) (xy 92.711793 -253.658324) (xy 92.753464 -253.625093)
			(xy 92.799622 -253.598444) (xy 92.849236 -253.578972) (xy 92.901198 -253.567112) (xy 92.954348 -253.563129)
			(xy 93.007498 -253.567112) (xy 93.05946 -253.578972) (xy 93.109074 -253.598444) (xy 93.155232 -253.625093)
			(xy 93.196903 -253.658324) (xy 93.233155 -253.697395) (xy 93.263179 -253.741432) (xy 93.286305 -253.789453)
			(xy 93.302015 -253.840383) (xy 93.309958 -253.893087) (xy 93.310456 -253.919736) (xy 93.309958 -253.946385)
			(xy 93.538538 -253.946385) (xy 93.538538 -253.893087) (xy 93.546481 -253.840383) (xy 93.562191 -253.789453)
			(xy 93.585317 -253.741432) (xy 93.615341 -253.697395) (xy 93.651593 -253.658324) (xy 93.693264 -253.625093)
			(xy 93.739422 -253.598444) (xy 93.789036 -253.578972) (xy 93.840998 -253.567112) (xy 93.894148 -253.563129)
			(xy 93.947298 -253.567112) (xy 93.99926 -253.578972) (xy 94.048874 -253.598444) (xy 94.095032 -253.625093)
			(xy 94.136703 -253.658324) (xy 94.172955 -253.697395) (xy 94.202979 -253.741432) (xy 94.226105 -253.789453)
			(xy 94.241815 -253.840383) (xy 94.249758 -253.893087) (xy 94.250256 -253.919736) (xy 94.249758 -253.946385)
			(xy 94.478084 -253.946385) (xy 94.478084 -253.893087) (xy 94.486027 -253.840383) (xy 94.501737 -253.789453)
			(xy 94.524863 -253.741432) (xy 94.554887 -253.697395) (xy 94.591139 -253.658324) (xy 94.63281 -253.625093)
			(xy 94.678968 -253.598444) (xy 94.728582 -253.578972) (xy 94.780544 -253.567112) (xy 94.833694 -253.563129)
			(xy 94.886844 -253.567112) (xy 94.938806 -253.578972) (xy 94.98842 -253.598444) (xy 95.034578 -253.625093)
			(xy 95.076249 -253.658324) (xy 95.112501 -253.697395) (xy 95.142525 -253.741432) (xy 95.165651 -253.789453)
			(xy 95.181361 -253.840383) (xy 95.189304 -253.893087) (xy 95.189802 -253.919736) (xy 95.189304 -253.946385)
			(xy 95.418138 -253.946385) (xy 95.418138 -253.893087) (xy 95.426081 -253.840383) (xy 95.441791 -253.789453)
			(xy 95.464917 -253.741432) (xy 95.494941 -253.697395) (xy 95.531193 -253.658324) (xy 95.572864 -253.625093)
			(xy 95.619022 -253.598444) (xy 95.668636 -253.578972) (xy 95.720598 -253.567112) (xy 95.773748 -253.563129)
			(xy 95.826898 -253.567112) (xy 95.87886 -253.578972) (xy 95.928474 -253.598444) (xy 95.974632 -253.625093)
			(xy 96.016303 -253.658324) (xy 96.052555 -253.697395) (xy 96.082579 -253.741432) (xy 96.105705 -253.789453)
			(xy 96.121415 -253.840383) (xy 96.129358 -253.893087) (xy 96.129856 -253.919736) (xy 96.129358 -253.946385)
			(xy 96.357938 -253.946385) (xy 96.357938 -253.893087) (xy 96.365881 -253.840383) (xy 96.381591 -253.789453)
			(xy 96.404717 -253.741432) (xy 96.434741 -253.697395) (xy 96.470993 -253.658324) (xy 96.512664 -253.625093)
			(xy 96.558822 -253.598444) (xy 96.608436 -253.578972) (xy 96.660398 -253.567112) (xy 96.713548 -253.563129)
			(xy 96.766698 -253.567112) (xy 96.81866 -253.578972) (xy 96.868274 -253.598444) (xy 96.914432 -253.625093)
			(xy 96.956103 -253.658324) (xy 96.992355 -253.697395) (xy 97.022379 -253.741432) (xy 97.045505 -253.789453)
			(xy 97.061215 -253.840383) (xy 97.069158 -253.893087) (xy 97.069656 -253.919736) (xy 97.069158 -253.946385)
			(xy 97.297738 -253.946385) (xy 97.297738 -253.893087) (xy 97.305681 -253.840383) (xy 97.321391 -253.789453)
			(xy 97.344517 -253.741432) (xy 97.374541 -253.697395) (xy 97.410793 -253.658324) (xy 97.452464 -253.625093)
			(xy 97.498622 -253.598444) (xy 97.548236 -253.578972) (xy 97.600198 -253.567112) (xy 97.653348 -253.563129)
			(xy 97.706498 -253.567112) (xy 97.75846 -253.578972) (xy 97.808074 -253.598444) (xy 97.854232 -253.625093)
			(xy 97.895903 -253.658324) (xy 97.932155 -253.697395) (xy 97.962179 -253.741432) (xy 97.985305 -253.789453)
			(xy 98.001015 -253.840383) (xy 98.008958 -253.893087) (xy 98.009456 -253.919736) (xy 98.008958 -253.946385)
			(xy 98.237538 -253.946385) (xy 98.237538 -253.893087) (xy 98.245481 -253.840383) (xy 98.261191 -253.789453)
			(xy 98.284317 -253.741432) (xy 98.314341 -253.697395) (xy 98.350593 -253.658324) (xy 98.392264 -253.625093)
			(xy 98.438422 -253.598444) (xy 98.488036 -253.578972) (xy 98.539998 -253.567112) (xy 98.593148 -253.563129)
			(xy 98.646298 -253.567112) (xy 98.69826 -253.578972) (xy 98.747874 -253.598444) (xy 98.794032 -253.625093)
			(xy 98.835703 -253.658324) (xy 98.871955 -253.697395) (xy 98.901979 -253.741432) (xy 98.925105 -253.789453)
			(xy 98.940815 -253.840383) (xy 98.948758 -253.893087) (xy 98.949256 -253.919736) (xy 98.948758 -253.946385)
			(xy 98.940815 -253.999089) (xy 98.925105 -254.050019) (xy 98.901979 -254.09804) (xy 98.871955 -254.142077)
			(xy 98.835703 -254.181148) (xy 98.794032 -254.214379) (xy 98.747874 -254.241028) (xy 98.69826 -254.2605)
			(xy 98.646298 -254.27236) (xy 98.593148 -254.276344) (xy 98.539998 -254.27236) (xy 98.488036 -254.2605)
			(xy 98.438422 -254.241028) (xy 98.392264 -254.214379) (xy 98.350593 -254.181148) (xy 98.314341 -254.142077)
			(xy 98.284317 -254.09804) (xy 98.261191 -254.050019) (xy 98.245481 -253.999089) (xy 98.237538 -253.946385)
			(xy 98.008958 -253.946385) (xy 98.001015 -253.999089) (xy 97.985305 -254.050019) (xy 97.962179 -254.09804)
			(xy 97.932155 -254.142077) (xy 97.895903 -254.181148) (xy 97.854232 -254.214379) (xy 97.808074 -254.241028)
			(xy 97.75846 -254.2605) (xy 97.706498 -254.27236) (xy 97.653348 -254.276344) (xy 97.600198 -254.27236)
			(xy 97.548236 -254.2605) (xy 97.498622 -254.241028) (xy 97.452464 -254.214379) (xy 97.410793 -254.181148)
			(xy 97.374541 -254.142077) (xy 97.344517 -254.09804) (xy 97.321391 -254.050019) (xy 97.305681 -253.999089)
			(xy 97.297738 -253.946385) (xy 97.069158 -253.946385) (xy 97.061215 -253.999089) (xy 97.045505 -254.050019)
			(xy 97.022379 -254.09804) (xy 96.992355 -254.142077) (xy 96.956103 -254.181148) (xy 96.914432 -254.214379)
			(xy 96.868274 -254.241028) (xy 96.81866 -254.2605) (xy 96.766698 -254.27236) (xy 96.713548 -254.276344)
			(xy 96.660398 -254.27236) (xy 96.608436 -254.2605) (xy 96.558822 -254.241028) (xy 96.512664 -254.214379)
			(xy 96.470993 -254.181148) (xy 96.434741 -254.142077) (xy 96.404717 -254.09804) (xy 96.381591 -254.050019)
			(xy 96.365881 -253.999089) (xy 96.357938 -253.946385) (xy 96.129358 -253.946385) (xy 96.121415 -253.999089)
			(xy 96.105705 -254.050019) (xy 96.082579 -254.09804) (xy 96.052555 -254.142077) (xy 96.016303 -254.181148)
			(xy 95.974632 -254.214379) (xy 95.928474 -254.241028) (xy 95.87886 -254.2605) (xy 95.826898 -254.27236)
			(xy 95.773748 -254.276344) (xy 95.720598 -254.27236) (xy 95.668636 -254.2605) (xy 95.619022 -254.241028)
			(xy 95.572864 -254.214379) (xy 95.531193 -254.181148) (xy 95.494941 -254.142077) (xy 95.464917 -254.09804)
			(xy 95.441791 -254.050019) (xy 95.426081 -253.999089) (xy 95.418138 -253.946385) (xy 95.189304 -253.946385)
			(xy 95.181361 -253.999089) (xy 95.165651 -254.050019) (xy 95.142525 -254.09804) (xy 95.112501 -254.142077)
			(xy 95.076249 -254.181148) (xy 95.034578 -254.214379) (xy 94.98842 -254.241028) (xy 94.938806 -254.2605)
			(xy 94.886844 -254.27236) (xy 94.833694 -254.276344) (xy 94.780544 -254.27236) (xy 94.728582 -254.2605)
			(xy 94.678968 -254.241028) (xy 94.63281 -254.214379) (xy 94.591139 -254.181148) (xy 94.554887 -254.142077)
			(xy 94.524863 -254.09804) (xy 94.501737 -254.050019) (xy 94.486027 -253.999089) (xy 94.478084 -253.946385)
			(xy 94.249758 -253.946385) (xy 94.241815 -253.999089) (xy 94.226105 -254.050019) (xy 94.202979 -254.09804)
			(xy 94.172955 -254.142077) (xy 94.136703 -254.181148) (xy 94.095032 -254.214379) (xy 94.048874 -254.241028)
			(xy 93.99926 -254.2605) (xy 93.947298 -254.27236) (xy 93.894148 -254.276344) (xy 93.840998 -254.27236)
			(xy 93.789036 -254.2605) (xy 93.739422 -254.241028) (xy 93.693264 -254.214379) (xy 93.651593 -254.181148)
			(xy 93.615341 -254.142077) (xy 93.585317 -254.09804) (xy 93.562191 -254.050019) (xy 93.546481 -253.999089)
			(xy 93.538538 -253.946385) (xy 93.309958 -253.946385) (xy 93.302015 -253.999089) (xy 93.286305 -254.050019)
			(xy 93.263179 -254.09804) (xy 93.233155 -254.142077) (xy 93.196903 -254.181148) (xy 93.155232 -254.214379)
			(xy 93.109074 -254.241028) (xy 93.05946 -254.2605) (xy 93.007498 -254.27236) (xy 92.954348 -254.276344)
			(xy 92.901198 -254.27236) (xy 92.849236 -254.2605) (xy 92.799622 -254.241028) (xy 92.753464 -254.214379)
			(xy 92.711793 -254.181148) (xy 92.675541 -254.142077) (xy 92.645517 -254.09804) (xy 92.622391 -254.050019)
			(xy 92.606681 -253.999089) (xy 92.598738 -253.946385) (xy 92.370158 -253.946385) (xy 92.362215 -253.999089)
			(xy 92.346505 -254.050019) (xy 92.323379 -254.09804) (xy 92.293355 -254.142077) (xy 92.257103 -254.181148)
			(xy 92.215432 -254.214379) (xy 92.169274 -254.241028) (xy 92.11966 -254.2605) (xy 92.067698 -254.27236)
			(xy 92.014548 -254.276344) (xy 91.961398 -254.27236) (xy 91.909436 -254.2605) (xy 91.859822 -254.241028)
			(xy 91.813664 -254.214379) (xy 91.771993 -254.181148) (xy 91.735741 -254.142077) (xy 91.705717 -254.09804)
			(xy 91.682591 -254.050019) (xy 91.666881 -253.999089) (xy 91.658938 -253.946385) (xy 91.430358 -253.946385)
			(xy 91.422415 -253.999089) (xy 91.406705 -254.050019) (xy 91.383579 -254.09804) (xy 91.353555 -254.142077)
			(xy 91.317303 -254.181148) (xy 91.275632 -254.214379) (xy 91.229474 -254.241028) (xy 91.17986 -254.2605)
			(xy 91.127898 -254.27236) (xy 91.074748 -254.276344) (xy 91.021598 -254.27236) (xy 90.969636 -254.2605)
			(xy 90.920022 -254.241028) (xy 90.873864 -254.214379) (xy 90.832193 -254.181148) (xy 90.795941 -254.142077)
			(xy 90.765917 -254.09804) (xy 90.742791 -254.050019) (xy 90.727081 -253.999089) (xy 90.719138 -253.946385)
			(xy 90.490304 -253.946385) (xy 90.482361 -253.999089) (xy 90.466651 -254.050019) (xy 90.443525 -254.09804)
			(xy 90.413501 -254.142077) (xy 90.377249 -254.181148) (xy 90.335578 -254.214379) (xy 90.28942 -254.241028)
			(xy 90.239806 -254.2605) (xy 90.187844 -254.27236) (xy 90.134694 -254.276344) (xy 90.081544 -254.27236)
			(xy 90.029582 -254.2605) (xy 89.979968 -254.241028) (xy 89.93381 -254.214379) (xy 89.892139 -254.181148)
			(xy 89.855887 -254.142077) (xy 89.825863 -254.09804) (xy 89.802737 -254.050019) (xy 89.787027 -253.999089)
			(xy 89.779084 -253.946385) (xy 89.549496 -253.946385) (xy 89.547513 -253.972848) (xy 89.535653 -254.02481)
			(xy 89.516181 -254.074423) (xy 89.489532 -254.12058) (xy 89.456301 -254.162249) (xy 89.417231 -254.1985)
			(xy 89.373195 -254.228523) (xy 89.325175 -254.251648) (xy 89.274245 -254.267357) (xy 89.221543 -254.275299)
			(xy 89.194894 -254.275844) (xy 89.16247 -254.275131) (xy 89.098697 -254.263368) (xy 89.068148 -254.252476)
			(xy 89.054842 -254.247909) (xy 89.026826 -254.245482) (xy 88.999209 -254.250785) (xy 88.974085 -254.263418)
			(xy 88.953358 -254.282422) (xy 88.938597 -254.306358) (xy 88.930922 -254.333412) (xy 88.93048 -254.347472)
			(xy 88.93048 -254.442722) (xy 88.951607 -254.458214) (xy 88.989507 -254.494384) (xy 89.021698 -254.535716)
			(xy 89.047487 -254.581318) (xy 89.066318 -254.630206) (xy 89.077782 -254.681325) (xy 89.081634 -254.733572)
			(xy 89.079675 -254.760201) (xy 89.309184 -254.760201) (xy 89.309184 -254.706903) (xy 89.317127 -254.654199)
			(xy 89.332837 -254.603269) (xy 89.355963 -254.555248) (xy 89.385987 -254.511211) (xy 89.422239 -254.47214)
			(xy 89.46391 -254.438909) (xy 89.510068 -254.41226) (xy 89.559682 -254.392788) (xy 89.611644 -254.380928)
			(xy 89.664794 -254.376945) (xy 89.717944 -254.380928) (xy 89.769906 -254.392788) (xy 89.81952 -254.41226)
			(xy 89.865678 -254.438909) (xy 89.907349 -254.47214) (xy 89.943601 -254.511211) (xy 89.973625 -254.555248)
			(xy 89.996751 -254.603269) (xy 90.012461 -254.654199) (xy 90.020404 -254.706903) (xy 90.020902 -254.733552)
			(xy 90.020404 -254.760201) (xy 90.248984 -254.760201) (xy 90.248984 -254.706903) (xy 90.256927 -254.654199)
			(xy 90.272637 -254.603269) (xy 90.295763 -254.555248) (xy 90.325787 -254.511211) (xy 90.362039 -254.47214)
			(xy 90.40371 -254.438909) (xy 90.449868 -254.41226) (xy 90.499482 -254.392788) (xy 90.551444 -254.380928)
			(xy 90.604594 -254.376945) (xy 90.657744 -254.380928) (xy 90.709706 -254.392788) (xy 90.75932 -254.41226)
			(xy 90.805478 -254.438909) (xy 90.847149 -254.47214) (xy 90.883401 -254.511211) (xy 90.913425 -254.555248)
			(xy 90.936551 -254.603269) (xy 90.952261 -254.654199) (xy 90.960204 -254.706903) (xy 90.960702 -254.733552)
			(xy 90.960204 -254.760201) (xy 91.189038 -254.760201) (xy 91.189038 -254.706903) (xy 91.196981 -254.654199)
			(xy 91.212691 -254.603269) (xy 91.235817 -254.555248) (xy 91.265841 -254.511211) (xy 91.302093 -254.47214)
			(xy 91.343764 -254.438909) (xy 91.389922 -254.41226) (xy 91.439536 -254.392788) (xy 91.491498 -254.380928)
			(xy 91.544648 -254.376945) (xy 91.597798 -254.380928) (xy 91.64976 -254.392788) (xy 91.699374 -254.41226)
			(xy 91.745532 -254.438909) (xy 91.787203 -254.47214) (xy 91.823455 -254.511211) (xy 91.853479 -254.555248)
			(xy 91.876605 -254.603269) (xy 91.892315 -254.654199) (xy 91.900258 -254.706903) (xy 91.900756 -254.733552)
			(xy 91.900258 -254.760201) (xy 92.128584 -254.760201) (xy 92.128584 -254.706903) (xy 92.136527 -254.654199)
			(xy 92.152237 -254.603269) (xy 92.175363 -254.555248) (xy 92.205387 -254.511211) (xy 92.241639 -254.47214)
			(xy 92.28331 -254.438909) (xy 92.329468 -254.41226) (xy 92.379082 -254.392788) (xy 92.431044 -254.380928)
			(xy 92.484194 -254.376945) (xy 92.537344 -254.380928) (xy 92.589306 -254.392788) (xy 92.63892 -254.41226)
			(xy 92.685078 -254.438909) (xy 92.726749 -254.47214) (xy 92.763001 -254.511211) (xy 92.793025 -254.555248)
			(xy 92.816151 -254.603269) (xy 92.831861 -254.654199) (xy 92.839804 -254.706903) (xy 92.840302 -254.733552)
			(xy 93.080081 -254.733552) (xy 93.084111 -254.681054) (xy 93.096108 -254.629786) (xy 93.115791 -254.580951)
			(xy 93.142697 -254.535692) (xy 93.176197 -254.495071) (xy 93.215505 -254.46004) (xy 93.2597 -254.43142)
			(xy 93.307745 -254.409881) (xy 93.358516 -254.395929) (xy 93.410821 -254.389891) (xy 93.463435 -254.391908)
			(xy 93.515125 -254.401932) (xy 93.564678 -254.41973) (xy 93.610934 -254.444883) (xy 93.652808 -254.476802)
			(xy 93.68932 -254.51474) (xy 93.719612 -254.557806) (xy 93.742975 -254.604991) (xy 93.758861 -254.65519)
			(xy 93.766898 -254.707226) (xy 93.767402 -254.733552) (xy 94.019881 -254.733552) (xy 94.023911 -254.681054)
			(xy 94.035908 -254.629786) (xy 94.055591 -254.580951) (xy 94.082497 -254.535692) (xy 94.115997 -254.495071)
			(xy 94.155305 -254.46004) (xy 94.1995 -254.43142) (xy 94.247545 -254.409881) (xy 94.298316 -254.395929)
			(xy 94.350621 -254.389891) (xy 94.403235 -254.391908) (xy 94.454925 -254.401932) (xy 94.504478 -254.41973)
			(xy 94.550734 -254.444883) (xy 94.592608 -254.476802) (xy 94.62912 -254.51474) (xy 94.659412 -254.557806)
			(xy 94.682775 -254.604991) (xy 94.698661 -254.65519) (xy 94.706698 -254.707226) (xy 94.707202 -254.733552)
			(xy 94.706698 -254.759878) (xy 94.706648 -254.760201) (xy 94.947984 -254.760201) (xy 94.947984 -254.706903)
			(xy 94.955927 -254.654199) (xy 94.971637 -254.603269) (xy 94.994763 -254.555248) (xy 95.024787 -254.511211)
			(xy 95.061039 -254.47214) (xy 95.10271 -254.438909) (xy 95.148868 -254.41226) (xy 95.198482 -254.392788)
			(xy 95.250444 -254.380928) (xy 95.303594 -254.376945) (xy 95.356744 -254.380928) (xy 95.408706 -254.392788)
			(xy 95.45832 -254.41226) (xy 95.504478 -254.438909) (xy 95.546149 -254.47214) (xy 95.582401 -254.511211)
			(xy 95.612425 -254.555248) (xy 95.635551 -254.603269) (xy 95.651261 -254.654199) (xy 95.659204 -254.706903)
			(xy 95.659702 -254.733552) (xy 95.659204 -254.760201) (xy 95.887784 -254.760201) (xy 95.887784 -254.706903)
			(xy 95.895727 -254.654199) (xy 95.911437 -254.603269) (xy 95.934563 -254.555248) (xy 95.964587 -254.511211)
			(xy 96.000839 -254.47214) (xy 96.04251 -254.438909) (xy 96.088668 -254.41226) (xy 96.138282 -254.392788)
			(xy 96.190244 -254.380928) (xy 96.243394 -254.376945) (xy 96.296544 -254.380928) (xy 96.348506 -254.392788)
			(xy 96.39812 -254.41226) (xy 96.444278 -254.438909) (xy 96.485949 -254.47214) (xy 96.522201 -254.511211)
			(xy 96.552225 -254.555248) (xy 96.575351 -254.603269) (xy 96.591061 -254.654199) (xy 96.599004 -254.706903)
			(xy 96.599502 -254.733552) (xy 96.599004 -254.760201) (xy 96.827584 -254.760201) (xy 96.827584 -254.706903)
			(xy 96.835527 -254.654199) (xy 96.851237 -254.603269) (xy 96.874363 -254.555248) (xy 96.904387 -254.511211)
			(xy 96.940639 -254.47214) (xy 96.98231 -254.438909) (xy 97.028468 -254.41226) (xy 97.078082 -254.392788)
			(xy 97.130044 -254.380928) (xy 97.183194 -254.376945) (xy 97.236344 -254.380928) (xy 97.288306 -254.392788)
			(xy 97.33792 -254.41226) (xy 97.384078 -254.438909) (xy 97.425749 -254.47214) (xy 97.462001 -254.511211)
			(xy 97.492025 -254.555248) (xy 97.515151 -254.603269) (xy 97.530861 -254.654199) (xy 97.538804 -254.706903)
			(xy 97.539302 -254.733552) (xy 97.538804 -254.760201) (xy 97.767638 -254.760201) (xy 97.767638 -254.706903)
			(xy 97.775581 -254.654199) (xy 97.791291 -254.603269) (xy 97.814417 -254.555248) (xy 97.844441 -254.511211)
			(xy 97.880693 -254.47214) (xy 97.922364 -254.438909) (xy 97.968522 -254.41226) (xy 98.018136 -254.392788)
			(xy 98.070098 -254.380928) (xy 98.123248 -254.376945) (xy 98.176398 -254.380928) (xy 98.22836 -254.392788)
			(xy 98.277974 -254.41226) (xy 98.324132 -254.438909) (xy 98.365803 -254.47214) (xy 98.402055 -254.511211)
			(xy 98.432079 -254.555248) (xy 98.455205 -254.603269) (xy 98.470915 -254.654199) (xy 98.478858 -254.706903)
			(xy 98.479356 -254.733552) (xy 98.478858 -254.760201) (xy 98.470915 -254.812905) (xy 98.455205 -254.863835)
			(xy 98.432079 -254.911856) (xy 98.402055 -254.955893) (xy 98.365803 -254.994964) (xy 98.324132 -255.028195)
			(xy 98.277974 -255.054844) (xy 98.22836 -255.074316) (xy 98.176398 -255.086176) (xy 98.123248 -255.09016)
			(xy 98.070098 -255.086176) (xy 98.018136 -255.074316) (xy 97.968522 -255.054844) (xy 97.922364 -255.028195)
			(xy 97.880693 -254.994964) (xy 97.844441 -254.955893) (xy 97.814417 -254.911856) (xy 97.791291 -254.863835)
			(xy 97.775581 -254.812905) (xy 97.767638 -254.760201) (xy 97.538804 -254.760201) (xy 97.530861 -254.812905)
			(xy 97.515151 -254.863835) (xy 97.492025 -254.911856) (xy 97.462001 -254.955893) (xy 97.425749 -254.994964)
			(xy 97.384078 -255.028195) (xy 97.33792 -255.054844) (xy 97.288306 -255.074316) (xy 97.236344 -255.086176)
			(xy 97.183194 -255.09016) (xy 97.130044 -255.086176) (xy 97.078082 -255.074316) (xy 97.028468 -255.054844)
			(xy 96.98231 -255.028195) (xy 96.940639 -254.994964) (xy 96.904387 -254.955893) (xy 96.874363 -254.911856)
			(xy 96.851237 -254.863835) (xy 96.835527 -254.812905) (xy 96.827584 -254.760201) (xy 96.599004 -254.760201)
			(xy 96.591061 -254.812905) (xy 96.575351 -254.863835) (xy 96.552225 -254.911856) (xy 96.522201 -254.955893)
			(xy 96.485949 -254.994964) (xy 96.444278 -255.028195) (xy 96.39812 -255.054844) (xy 96.348506 -255.074316)
			(xy 96.296544 -255.086176) (xy 96.243394 -255.09016) (xy 96.190244 -255.086176) (xy 96.138282 -255.074316)
			(xy 96.088668 -255.054844) (xy 96.04251 -255.028195) (xy 96.000839 -254.994964) (xy 95.964587 -254.955893)
			(xy 95.934563 -254.911856) (xy 95.911437 -254.863835) (xy 95.895727 -254.812905) (xy 95.887784 -254.760201)
			(xy 95.659204 -254.760201) (xy 95.651261 -254.812905) (xy 95.635551 -254.863835) (xy 95.612425 -254.911856)
			(xy 95.582401 -254.955893) (xy 95.546149 -254.994964) (xy 95.504478 -255.028195) (xy 95.45832 -255.054844)
			(xy 95.408706 -255.074316) (xy 95.356744 -255.086176) (xy 95.303594 -255.09016) (xy 95.250444 -255.086176)
			(xy 95.198482 -255.074316) (xy 95.148868 -255.054844) (xy 95.10271 -255.028195) (xy 95.061039 -254.994964)
			(xy 95.024787 -254.955893) (xy 94.994763 -254.911856) (xy 94.971637 -254.863835) (xy 94.955927 -254.812905)
			(xy 94.947984 -254.760201) (xy 94.706648 -254.760201) (xy 94.698661 -254.811914) (xy 94.682775 -254.862113)
			(xy 94.659412 -254.909298) (xy 94.62912 -254.952364) (xy 94.592608 -254.990302) (xy 94.550734 -255.022221)
			(xy 94.504478 -255.047374) (xy 94.454925 -255.065172) (xy 94.403235 -255.075196) (xy 94.350621 -255.077213)
			(xy 94.298316 -255.071175) (xy 94.247545 -255.057223) (xy 94.1995 -255.035684) (xy 94.155305 -255.007064)
			(xy 94.115997 -254.972033) (xy 94.082497 -254.931412) (xy 94.055591 -254.886153) (xy 94.035908 -254.837318)
			(xy 94.023911 -254.78605) (xy 94.019881 -254.733552) (xy 93.767402 -254.733552) (xy 93.766898 -254.759878)
			(xy 93.758861 -254.811914) (xy 93.742975 -254.862113) (xy 93.719612 -254.909298) (xy 93.68932 -254.952364)
			(xy 93.652808 -254.990302) (xy 93.610934 -255.022221) (xy 93.564678 -255.047374) (xy 93.515125 -255.065172)
			(xy 93.463435 -255.075196) (xy 93.410821 -255.077213) (xy 93.358516 -255.071175) (xy 93.307745 -255.057223)
			(xy 93.2597 -255.035684) (xy 93.215505 -255.007064) (xy 93.176197 -254.972033) (xy 93.142697 -254.931412)
			(xy 93.115791 -254.886153) (xy 93.096108 -254.837318) (xy 93.084111 -254.78605) (xy 93.080081 -254.733552)
			(xy 92.840302 -254.733552) (xy 92.839804 -254.760201) (xy 92.831861 -254.812905) (xy 92.816151 -254.863835)
			(xy 92.793025 -254.911856) (xy 92.763001 -254.955893) (xy 92.726749 -254.994964) (xy 92.685078 -255.028195)
			(xy 92.63892 -255.054844) (xy 92.589306 -255.074316) (xy 92.537344 -255.086176) (xy 92.484194 -255.09016)
			(xy 92.431044 -255.086176) (xy 92.379082 -255.074316) (xy 92.329468 -255.054844) (xy 92.28331 -255.028195)
			(xy 92.241639 -254.994964) (xy 92.205387 -254.955893) (xy 92.175363 -254.911856) (xy 92.152237 -254.863835)
			(xy 92.136527 -254.812905) (xy 92.128584 -254.760201) (xy 91.900258 -254.760201) (xy 91.892315 -254.812905)
			(xy 91.876605 -254.863835) (xy 91.853479 -254.911856) (xy 91.823455 -254.955893) (xy 91.787203 -254.994964)
			(xy 91.745532 -255.028195) (xy 91.699374 -255.054844) (xy 91.64976 -255.074316) (xy 91.597798 -255.086176)
			(xy 91.544648 -255.09016) (xy 91.491498 -255.086176) (xy 91.439536 -255.074316) (xy 91.389922 -255.054844)
			(xy 91.343764 -255.028195) (xy 91.302093 -254.994964) (xy 91.265841 -254.955893) (xy 91.235817 -254.911856)
			(xy 91.212691 -254.863835) (xy 91.196981 -254.812905) (xy 91.189038 -254.760201) (xy 90.960204 -254.760201)
			(xy 90.952261 -254.812905) (xy 90.936551 -254.863835) (xy 90.913425 -254.911856) (xy 90.883401 -254.955893)
			(xy 90.847149 -254.994964) (xy 90.805478 -255.028195) (xy 90.75932 -255.054844) (xy 90.709706 -255.074316)
			(xy 90.657744 -255.086176) (xy 90.604594 -255.09016) (xy 90.551444 -255.086176) (xy 90.499482 -255.074316)
			(xy 90.449868 -255.054844) (xy 90.40371 -255.028195) (xy 90.362039 -254.994964) (xy 90.325787 -254.955893)
			(xy 90.295763 -254.911856) (xy 90.272637 -254.863835) (xy 90.256927 -254.812905) (xy 90.248984 -254.760201)
			(xy 90.020404 -254.760201) (xy 90.012461 -254.812905) (xy 89.996751 -254.863835) (xy 89.973625 -254.911856)
			(xy 89.943601 -254.955893) (xy 89.907349 -254.994964) (xy 89.865678 -255.028195) (xy 89.81952 -255.054844)
			(xy 89.769906 -255.074316) (xy 89.717944 -255.086176) (xy 89.664794 -255.09016) (xy 89.611644 -255.086176)
			(xy 89.559682 -255.074316) (xy 89.510068 -255.054844) (xy 89.46391 -255.028195) (xy 89.422239 -254.994964)
			(xy 89.385987 -254.955893) (xy 89.355963 -254.911856) (xy 89.332837 -254.863835) (xy 89.317127 -254.812905)
			(xy 89.309184 -254.760201) (xy 89.079675 -254.760201) (xy 89.07779 -254.78582) (xy 89.066334 -254.836941)
			(xy 89.047511 -254.885832) (xy 89.021729 -254.931438) (xy 88.989544 -254.972775) (xy 88.95165 -255.00895)
			(xy 88.93048 -255.024382) (xy 88.93048 -255.119886) (xy 88.930928 -255.133949) (xy 88.938596 -255.16101)
			(xy 88.953353 -255.184954) (xy 88.974081 -255.203965) (xy 88.999208 -255.216602) (xy 89.026829 -255.221906)
			(xy 89.05485 -255.219477) (xy 89.068148 -255.214882) (xy 89.098694 -255.203981) (xy 89.162469 -255.192219)
			(xy 89.194894 -255.191514) (xy 89.195148 -255.191514) (xy 89.221793 -255.192016) (xy 89.274488 -255.199964)
			(xy 89.325409 -255.215678) (xy 89.37342 -255.238804) (xy 89.417449 -255.268828) (xy 89.456511 -255.305077)
			(xy 89.489735 -255.346744) (xy 89.516378 -255.392896) (xy 89.535846 -255.442503) (xy 89.547703 -255.494458)
			(xy 89.551685 -255.5476) (xy 89.549687 -255.574271) (xy 89.779084 -255.574271) (xy 89.779084 -255.520973)
			(xy 89.787027 -255.468269) (xy 89.802737 -255.417339) (xy 89.825863 -255.369318) (xy 89.855887 -255.325281)
			(xy 89.892139 -255.28621) (xy 89.93381 -255.252979) (xy 89.979968 -255.22633) (xy 90.029582 -255.206858)
			(xy 90.081544 -255.194998) (xy 90.134694 -255.191015) (xy 90.187844 -255.194998) (xy 90.239806 -255.206858)
			(xy 90.28942 -255.22633) (xy 90.335578 -255.252979) (xy 90.377249 -255.28621) (xy 90.413501 -255.325281)
			(xy 90.443525 -255.369318) (xy 90.466651 -255.417339) (xy 90.482361 -255.468269) (xy 90.490304 -255.520973)
			(xy 90.490802 -255.547622) (xy 90.490304 -255.574271) (xy 90.719138 -255.574271) (xy 90.719138 -255.520973)
			(xy 90.727081 -255.468269) (xy 90.742791 -255.417339) (xy 90.765917 -255.369318) (xy 90.795941 -255.325281)
			(xy 90.832193 -255.28621) (xy 90.873864 -255.252979) (xy 90.920022 -255.22633) (xy 90.969636 -255.206858)
			(xy 91.021598 -255.194998) (xy 91.074748 -255.191015) (xy 91.127898 -255.194998) (xy 91.17986 -255.206858)
			(xy 91.229474 -255.22633) (xy 91.275632 -255.252979) (xy 91.317303 -255.28621) (xy 91.353555 -255.325281)
			(xy 91.383579 -255.369318) (xy 91.406705 -255.417339) (xy 91.422415 -255.468269) (xy 91.430358 -255.520973)
			(xy 91.430856 -255.547622) (xy 91.430358 -255.574271) (xy 91.658684 -255.574271) (xy 91.658684 -255.520973)
			(xy 91.666627 -255.468269) (xy 91.682337 -255.417339) (xy 91.705463 -255.369318) (xy 91.735487 -255.325281)
			(xy 91.771739 -255.28621) (xy 91.81341 -255.252979) (xy 91.859568 -255.22633) (xy 91.909182 -255.206858)
			(xy 91.961144 -255.194998) (xy 92.014294 -255.191015) (xy 92.067444 -255.194998) (xy 92.119406 -255.206858)
			(xy 92.16902 -255.22633) (xy 92.215178 -255.252979) (xy 92.256849 -255.28621) (xy 92.293101 -255.325281)
			(xy 92.323125 -255.369318) (xy 92.346251 -255.417339) (xy 92.361961 -255.468269) (xy 92.369904 -255.520973)
			(xy 92.370402 -255.547622) (xy 92.369904 -255.574271) (xy 92.598738 -255.574271) (xy 92.598738 -255.520973)
			(xy 92.606681 -255.468269) (xy 92.622391 -255.417339) (xy 92.645517 -255.369318) (xy 92.675541 -255.325281)
			(xy 92.711793 -255.28621) (xy 92.753464 -255.252979) (xy 92.799622 -255.22633) (xy 92.849236 -255.206858)
			(xy 92.901198 -255.194998) (xy 92.954348 -255.191015) (xy 93.007498 -255.194998) (xy 93.05946 -255.206858)
			(xy 93.109074 -255.22633) (xy 93.155232 -255.252979) (xy 93.196903 -255.28621) (xy 93.233155 -255.325281)
			(xy 93.263179 -255.369318) (xy 93.286305 -255.417339) (xy 93.302015 -255.468269) (xy 93.309958 -255.520973)
			(xy 93.310456 -255.547622) (xy 93.309958 -255.574271) (xy 93.538538 -255.574271) (xy 93.538538 -255.520973)
			(xy 93.546481 -255.468269) (xy 93.562191 -255.417339) (xy 93.585317 -255.369318) (xy 93.615341 -255.325281)
			(xy 93.651593 -255.28621) (xy 93.693264 -255.252979) (xy 93.739422 -255.22633) (xy 93.789036 -255.206858)
			(xy 93.840998 -255.194998) (xy 93.894148 -255.191015) (xy 93.947298 -255.194998) (xy 93.99926 -255.206858)
			(xy 94.048874 -255.22633) (xy 94.095032 -255.252979) (xy 94.136703 -255.28621) (xy 94.172955 -255.325281)
			(xy 94.202979 -255.369318) (xy 94.226105 -255.417339) (xy 94.241815 -255.468269) (xy 94.249758 -255.520973)
			(xy 94.250256 -255.547622) (xy 94.249758 -255.574271) (xy 94.478338 -255.574271) (xy 94.478338 -255.520973)
			(xy 94.486281 -255.468269) (xy 94.501991 -255.417339) (xy 94.525117 -255.369318) (xy 94.555141 -255.325281)
			(xy 94.591393 -255.28621) (xy 94.633064 -255.252979) (xy 94.679222 -255.22633) (xy 94.728836 -255.206858)
			(xy 94.780798 -255.194998) (xy 94.833948 -255.191015) (xy 94.887098 -255.194998) (xy 94.93906 -255.206858)
			(xy 94.988674 -255.22633) (xy 95.034832 -255.252979) (xy 95.076503 -255.28621) (xy 95.112755 -255.325281)
			(xy 95.142779 -255.369318) (xy 95.165905 -255.417339) (xy 95.181615 -255.468269) (xy 95.189558 -255.520973)
			(xy 95.190056 -255.547622) (xy 95.189558 -255.574271) (xy 95.418138 -255.574271) (xy 95.418138 -255.520973)
			(xy 95.426081 -255.468269) (xy 95.441791 -255.417339) (xy 95.464917 -255.369318) (xy 95.494941 -255.325281)
			(xy 95.531193 -255.28621) (xy 95.572864 -255.252979) (xy 95.619022 -255.22633) (xy 95.668636 -255.206858)
			(xy 95.720598 -255.194998) (xy 95.773748 -255.191015) (xy 95.826898 -255.194998) (xy 95.87886 -255.206858)
			(xy 95.928474 -255.22633) (xy 95.974632 -255.252979) (xy 96.016303 -255.28621) (xy 96.052555 -255.325281)
			(xy 96.082579 -255.369318) (xy 96.105705 -255.417339) (xy 96.121415 -255.468269) (xy 96.129358 -255.520973)
			(xy 96.129856 -255.547622) (xy 96.129358 -255.574271) (xy 96.357938 -255.574271) (xy 96.357938 -255.520973)
			(xy 96.365881 -255.468269) (xy 96.381591 -255.417339) (xy 96.404717 -255.369318) (xy 96.434741 -255.325281)
			(xy 96.470993 -255.28621) (xy 96.512664 -255.252979) (xy 96.558822 -255.22633) (xy 96.608436 -255.206858)
			(xy 96.660398 -255.194998) (xy 96.713548 -255.191015) (xy 96.766698 -255.194998) (xy 96.81866 -255.206858)
			(xy 96.868274 -255.22633) (xy 96.914432 -255.252979) (xy 96.956103 -255.28621) (xy 96.992355 -255.325281)
			(xy 97.022379 -255.369318) (xy 97.045505 -255.417339) (xy 97.061215 -255.468269) (xy 97.069158 -255.520973)
			(xy 97.069656 -255.547622) (xy 97.069158 -255.574271) (xy 97.297738 -255.574271) (xy 97.297738 -255.520973)
			(xy 97.305681 -255.468269) (xy 97.321391 -255.417339) (xy 97.344517 -255.369318) (xy 97.374541 -255.325281)
			(xy 97.410793 -255.28621) (xy 97.452464 -255.252979) (xy 97.498622 -255.22633) (xy 97.548236 -255.206858)
			(xy 97.600198 -255.194998) (xy 97.653348 -255.191015) (xy 97.706498 -255.194998) (xy 97.75846 -255.206858)
			(xy 97.808074 -255.22633) (xy 97.854232 -255.252979) (xy 97.895903 -255.28621) (xy 97.932155 -255.325281)
			(xy 97.962179 -255.369318) (xy 97.985305 -255.417339) (xy 98.001015 -255.468269) (xy 98.008958 -255.520973)
			(xy 98.009456 -255.547622) (xy 98.008958 -255.574271) (xy 98.237284 -255.574271) (xy 98.237284 -255.520973)
			(xy 98.245227 -255.468269) (xy 98.260937 -255.417339) (xy 98.284063 -255.369318) (xy 98.314087 -255.325281)
			(xy 98.350339 -255.28621) (xy 98.39201 -255.252979) (xy 98.438168 -255.22633) (xy 98.487782 -255.206858)
			(xy 98.539744 -255.194998) (xy 98.592894 -255.191015) (xy 98.646044 -255.194998) (xy 98.698006 -255.206858)
			(xy 98.74762 -255.22633) (xy 98.793778 -255.252979) (xy 98.835449 -255.28621) (xy 98.871701 -255.325281)
			(xy 98.901725 -255.369318) (xy 98.924851 -255.417339) (xy 98.940561 -255.468269) (xy 98.948504 -255.520973)
			(xy 98.949002 -255.547622) (xy 98.948504 -255.574271) (xy 98.940561 -255.626975) (xy 98.924851 -255.677905)
			(xy 98.901725 -255.725926) (xy 98.871701 -255.769963) (xy 98.835449 -255.809034) (xy 98.793778 -255.842265)
			(xy 98.74762 -255.868914) (xy 98.698006 -255.888386) (xy 98.646044 -255.900246) (xy 98.592894 -255.90423)
			(xy 98.539744 -255.900246) (xy 98.487782 -255.888386) (xy 98.438168 -255.868914) (xy 98.39201 -255.842265)
			(xy 98.350339 -255.809034) (xy 98.314087 -255.769963) (xy 98.284063 -255.725926) (xy 98.260937 -255.677905)
			(xy 98.245227 -255.626975) (xy 98.237284 -255.574271) (xy 98.008958 -255.574271) (xy 98.001015 -255.626975)
			(xy 97.985305 -255.677905) (xy 97.962179 -255.725926) (xy 97.932155 -255.769963) (xy 97.895903 -255.809034)
			(xy 97.854232 -255.842265) (xy 97.808074 -255.868914) (xy 97.75846 -255.888386) (xy 97.706498 -255.900246)
			(xy 97.653348 -255.90423) (xy 97.600198 -255.900246) (xy 97.548236 -255.888386) (xy 97.498622 -255.868914)
			(xy 97.452464 -255.842265) (xy 97.410793 -255.809034) (xy 97.374541 -255.769963) (xy 97.344517 -255.725926)
			(xy 97.321391 -255.677905) (xy 97.305681 -255.626975) (xy 97.297738 -255.574271) (xy 97.069158 -255.574271)
			(xy 97.061215 -255.626975) (xy 97.045505 -255.677905) (xy 97.022379 -255.725926) (xy 96.992355 -255.769963)
			(xy 96.956103 -255.809034) (xy 96.914432 -255.842265) (xy 96.868274 -255.868914) (xy 96.81866 -255.888386)
			(xy 96.766698 -255.900246) (xy 96.713548 -255.90423) (xy 96.660398 -255.900246) (xy 96.608436 -255.888386)
			(xy 96.558822 -255.868914) (xy 96.512664 -255.842265) (xy 96.470993 -255.809034) (xy 96.434741 -255.769963)
			(xy 96.404717 -255.725926) (xy 96.381591 -255.677905) (xy 96.365881 -255.626975) (xy 96.357938 -255.574271)
			(xy 96.129358 -255.574271) (xy 96.121415 -255.626975) (xy 96.105705 -255.677905) (xy 96.082579 -255.725926)
			(xy 96.052555 -255.769963) (xy 96.016303 -255.809034) (xy 95.974632 -255.842265) (xy 95.928474 -255.868914)
			(xy 95.87886 -255.888386) (xy 95.826898 -255.900246) (xy 95.773748 -255.90423) (xy 95.720598 -255.900246)
			(xy 95.668636 -255.888386) (xy 95.619022 -255.868914) (xy 95.572864 -255.842265) (xy 95.531193 -255.809034)
			(xy 95.494941 -255.769963) (xy 95.464917 -255.725926) (xy 95.441791 -255.677905) (xy 95.426081 -255.626975)
			(xy 95.418138 -255.574271) (xy 95.189558 -255.574271) (xy 95.181615 -255.626975) (xy 95.165905 -255.677905)
			(xy 95.142779 -255.725926) (xy 95.112755 -255.769963) (xy 95.076503 -255.809034) (xy 95.034832 -255.842265)
			(xy 94.988674 -255.868914) (xy 94.93906 -255.888386) (xy 94.887098 -255.900246) (xy 94.833948 -255.90423)
			(xy 94.780798 -255.900246) (xy 94.728836 -255.888386) (xy 94.679222 -255.868914) (xy 94.633064 -255.842265)
			(xy 94.591393 -255.809034) (xy 94.555141 -255.769963) (xy 94.525117 -255.725926) (xy 94.501991 -255.677905)
			(xy 94.486281 -255.626975) (xy 94.478338 -255.574271) (xy 94.249758 -255.574271) (xy 94.241815 -255.626975)
			(xy 94.226105 -255.677905) (xy 94.202979 -255.725926) (xy 94.172955 -255.769963) (xy 94.136703 -255.809034)
			(xy 94.095032 -255.842265) (xy 94.048874 -255.868914) (xy 93.99926 -255.888386) (xy 93.947298 -255.900246)
			(xy 93.894148 -255.90423) (xy 93.840998 -255.900246) (xy 93.789036 -255.888386) (xy 93.739422 -255.868914)
			(xy 93.693264 -255.842265) (xy 93.651593 -255.809034) (xy 93.615341 -255.769963) (xy 93.585317 -255.725926)
			(xy 93.562191 -255.677905) (xy 93.546481 -255.626975) (xy 93.538538 -255.574271) (xy 93.309958 -255.574271)
			(xy 93.302015 -255.626975) (xy 93.286305 -255.677905) (xy 93.263179 -255.725926) (xy 93.233155 -255.769963)
			(xy 93.196903 -255.809034) (xy 93.155232 -255.842265) (xy 93.109074 -255.868914) (xy 93.05946 -255.888386)
			(xy 93.007498 -255.900246) (xy 92.954348 -255.90423) (xy 92.901198 -255.900246) (xy 92.849236 -255.888386)
			(xy 92.799622 -255.868914) (xy 92.753464 -255.842265) (xy 92.711793 -255.809034) (xy 92.675541 -255.769963)
			(xy 92.645517 -255.725926) (xy 92.622391 -255.677905) (xy 92.606681 -255.626975) (xy 92.598738 -255.574271)
			(xy 92.369904 -255.574271) (xy 92.361961 -255.626975) (xy 92.346251 -255.677905) (xy 92.323125 -255.725926)
			(xy 92.293101 -255.769963) (xy 92.256849 -255.809034) (xy 92.215178 -255.842265) (xy 92.16902 -255.868914)
			(xy 92.119406 -255.888386) (xy 92.067444 -255.900246) (xy 92.014294 -255.90423) (xy 91.961144 -255.900246)
			(xy 91.909182 -255.888386) (xy 91.859568 -255.868914) (xy 91.81341 -255.842265) (xy 91.771739 -255.809034)
			(xy 91.735487 -255.769963) (xy 91.705463 -255.725926) (xy 91.682337 -255.677905) (xy 91.666627 -255.626975)
			(xy 91.658684 -255.574271) (xy 91.430358 -255.574271) (xy 91.422415 -255.626975) (xy 91.406705 -255.677905)
			(xy 91.383579 -255.725926) (xy 91.353555 -255.769963) (xy 91.317303 -255.809034) (xy 91.275632 -255.842265)
			(xy 91.229474 -255.868914) (xy 91.17986 -255.888386) (xy 91.127898 -255.900246) (xy 91.074748 -255.90423)
			(xy 91.021598 -255.900246) (xy 90.969636 -255.888386) (xy 90.920022 -255.868914) (xy 90.873864 -255.842265)
			(xy 90.832193 -255.809034) (xy 90.795941 -255.769963) (xy 90.765917 -255.725926) (xy 90.742791 -255.677905)
			(xy 90.727081 -255.626975) (xy 90.719138 -255.574271) (xy 90.490304 -255.574271) (xy 90.482361 -255.626975)
			(xy 90.466651 -255.677905) (xy 90.443525 -255.725926) (xy 90.413501 -255.769963) (xy 90.377249 -255.809034)
			(xy 90.335578 -255.842265) (xy 90.28942 -255.868914) (xy 90.239806 -255.888386) (xy 90.187844 -255.900246)
			(xy 90.134694 -255.90423) (xy 90.081544 -255.900246) (xy 90.029582 -255.888386) (xy 89.979968 -255.868914)
			(xy 89.93381 -255.842265) (xy 89.892139 -255.809034) (xy 89.855887 -255.769963) (xy 89.825863 -255.725926)
			(xy 89.802737 -255.677905) (xy 89.787027 -255.626975) (xy 89.779084 -255.574271) (xy 89.549687 -255.574271)
			(xy 89.547703 -255.600742) (xy 89.535846 -255.652697) (xy 89.516378 -255.702304) (xy 89.489735 -255.748456)
			(xy 89.456511 -255.790123) (xy 89.417449 -255.826372) (xy 89.37342 -255.856396) (xy 89.325409 -255.879522)
			(xy 89.274488 -255.895236) (xy 89.221793 -255.903184) (xy 89.195148 -255.90373) (xy 89.194894 -255.90373)
			(xy 89.162473 -255.902988) (xy 89.098704 -255.891225) (xy 89.068148 -255.880362) (xy 89.054846 -255.875793)
			(xy 89.026836 -255.873362) (xy 88.999225 -255.878666) (xy 88.974108 -255.8913) (xy 88.953391 -255.910308)
			(xy 88.938646 -255.934247) (xy 88.930991 -255.9613) (xy 88.93048 -255.975358) (xy 88.93048 -256.070608)
			(xy 88.951601 -256.086101) (xy 88.989488 -256.122268) (xy 89.021667 -256.163596) (xy 89.047445 -256.209193)
			(xy 89.066264 -256.258074) (xy 89.07772 -256.309184) (xy 89.081564 -256.361422) (xy 89.079598 -256.388087)
			(xy 89.309184 -256.388087) (xy 89.309184 -256.334789) (xy 89.317127 -256.282085) (xy 89.332837 -256.231155)
			(xy 89.355963 -256.183134) (xy 89.385987 -256.139097) (xy 89.422239 -256.100026) (xy 89.46391 -256.066795)
			(xy 89.510068 -256.040146) (xy 89.559682 -256.020674) (xy 89.611644 -256.008814) (xy 89.664794 -256.004831)
			(xy 89.717944 -256.008814) (xy 89.769906 -256.020674) (xy 89.81952 -256.040146) (xy 89.865678 -256.066795)
			(xy 89.907349 -256.100026) (xy 89.943601 -256.139097) (xy 89.973625 -256.183134) (xy 89.996751 -256.231155)
			(xy 90.012461 -256.282085) (xy 90.020404 -256.334789) (xy 90.020902 -256.361438) (xy 90.020404 -256.388087)
			(xy 90.248984 -256.388087) (xy 90.248984 -256.334789) (xy 90.256927 -256.282085) (xy 90.272637 -256.231155)
			(xy 90.295763 -256.183134) (xy 90.325787 -256.139097) (xy 90.362039 -256.100026) (xy 90.40371 -256.066795)
			(xy 90.449868 -256.040146) (xy 90.499482 -256.020674) (xy 90.551444 -256.008814) (xy 90.604594 -256.004831)
			(xy 90.657744 -256.008814) (xy 90.709706 -256.020674) (xy 90.75932 -256.040146) (xy 90.805478 -256.066795)
			(xy 90.847149 -256.100026) (xy 90.883401 -256.139097) (xy 90.913425 -256.183134) (xy 90.936551 -256.231155)
			(xy 90.952261 -256.282085) (xy 90.960204 -256.334789) (xy 90.960702 -256.361438) (xy 90.960204 -256.388087)
			(xy 91.188784 -256.388087) (xy 91.188784 -256.334789) (xy 91.196727 -256.282085) (xy 91.212437 -256.231155)
			(xy 91.235563 -256.183134) (xy 91.265587 -256.139097) (xy 91.301839 -256.100026) (xy 91.34351 -256.066795)
			(xy 91.389668 -256.040146) (xy 91.439282 -256.020674) (xy 91.491244 -256.008814) (xy 91.544394 -256.004831)
			(xy 91.597544 -256.008814) (xy 91.649506 -256.020674) (xy 91.69912 -256.040146) (xy 91.745278 -256.066795)
			(xy 91.786949 -256.100026) (xy 91.823201 -256.139097) (xy 91.853225 -256.183134) (xy 91.876351 -256.231155)
			(xy 91.892061 -256.282085) (xy 91.900004 -256.334789) (xy 91.900502 -256.361438) (xy 91.900004 -256.388087)
			(xy 92.128584 -256.388087) (xy 92.128584 -256.334789) (xy 92.136527 -256.282085) (xy 92.152237 -256.231155)
			(xy 92.175363 -256.183134) (xy 92.205387 -256.139097) (xy 92.241639 -256.100026) (xy 92.28331 -256.066795)
			(xy 92.329468 -256.040146) (xy 92.379082 -256.020674) (xy 92.431044 -256.008814) (xy 92.484194 -256.004831)
			(xy 92.537344 -256.008814) (xy 92.589306 -256.020674) (xy 92.63892 -256.040146) (xy 92.685078 -256.066795)
			(xy 92.726749 -256.100026) (xy 92.763001 -256.139097) (xy 92.793025 -256.183134) (xy 92.816151 -256.231155)
			(xy 92.831861 -256.282085) (xy 92.839804 -256.334789) (xy 92.840302 -256.361438) (xy 92.839804 -256.388087)
			(xy 93.068384 -256.388087) (xy 93.068384 -256.334789) (xy 93.076327 -256.282085) (xy 93.092037 -256.231155)
			(xy 93.115163 -256.183134) (xy 93.145187 -256.139097) (xy 93.181439 -256.100026) (xy 93.22311 -256.066795)
			(xy 93.269268 -256.040146) (xy 93.318882 -256.020674) (xy 93.370844 -256.008814) (xy 93.423994 -256.004831)
			(xy 93.477144 -256.008814) (xy 93.529106 -256.020674) (xy 93.57872 -256.040146) (xy 93.624878 -256.066795)
			(xy 93.666549 -256.100026) (xy 93.702801 -256.139097) (xy 93.732825 -256.183134) (xy 93.755951 -256.231155)
			(xy 93.771661 -256.282085) (xy 93.779604 -256.334789) (xy 93.780102 -256.361438) (xy 93.779604 -256.388087)
			(xy 94.008438 -256.388087) (xy 94.008438 -256.334789) (xy 94.016381 -256.282085) (xy 94.032091 -256.231155)
			(xy 94.055217 -256.183134) (xy 94.085241 -256.139097) (xy 94.121493 -256.100026) (xy 94.163164 -256.066795)
			(xy 94.209322 -256.040146) (xy 94.258936 -256.020674) (xy 94.310898 -256.008814) (xy 94.364048 -256.004831)
			(xy 94.417198 -256.008814) (xy 94.46916 -256.020674) (xy 94.518774 -256.040146) (xy 94.564932 -256.066795)
			(xy 94.606603 -256.100026) (xy 94.642855 -256.139097) (xy 94.672879 -256.183134) (xy 94.696005 -256.231155)
			(xy 94.711715 -256.282085) (xy 94.719658 -256.334789) (xy 94.720156 -256.361438) (xy 94.719658 -256.388087)
			(xy 94.947984 -256.388087) (xy 94.947984 -256.334789) (xy 94.955927 -256.282085) (xy 94.971637 -256.231155)
			(xy 94.994763 -256.183134) (xy 95.024787 -256.139097) (xy 95.061039 -256.100026) (xy 95.10271 -256.066795)
			(xy 95.148868 -256.040146) (xy 95.198482 -256.020674) (xy 95.250444 -256.008814) (xy 95.303594 -256.004831)
			(xy 95.356744 -256.008814) (xy 95.408706 -256.020674) (xy 95.45832 -256.040146) (xy 95.504478 -256.066795)
			(xy 95.546149 -256.100026) (xy 95.582401 -256.139097) (xy 95.612425 -256.183134) (xy 95.635551 -256.231155)
			(xy 95.651261 -256.282085) (xy 95.659204 -256.334789) (xy 95.659702 -256.361438) (xy 95.659204 -256.388087)
			(xy 95.887784 -256.388087) (xy 95.887784 -256.334789) (xy 95.895727 -256.282085) (xy 95.911437 -256.231155)
			(xy 95.934563 -256.183134) (xy 95.964587 -256.139097) (xy 96.000839 -256.100026) (xy 96.04251 -256.066795)
			(xy 96.088668 -256.040146) (xy 96.138282 -256.020674) (xy 96.190244 -256.008814) (xy 96.243394 -256.004831)
			(xy 96.296544 -256.008814) (xy 96.348506 -256.020674) (xy 96.39812 -256.040146) (xy 96.444278 -256.066795)
			(xy 96.485949 -256.100026) (xy 96.522201 -256.139097) (xy 96.552225 -256.183134) (xy 96.575351 -256.231155)
			(xy 96.591061 -256.282085) (xy 96.599004 -256.334789) (xy 96.599502 -256.361438) (xy 96.599004 -256.388087)
			(xy 96.827584 -256.388087) (xy 96.827584 -256.334789) (xy 96.835527 -256.282085) (xy 96.851237 -256.231155)
			(xy 96.874363 -256.183134) (xy 96.904387 -256.139097) (xy 96.940639 -256.100026) (xy 96.98231 -256.066795)
			(xy 97.028468 -256.040146) (xy 97.078082 -256.020674) (xy 97.130044 -256.008814) (xy 97.183194 -256.004831)
			(xy 97.236344 -256.008814) (xy 97.288306 -256.020674) (xy 97.33792 -256.040146) (xy 97.384078 -256.066795)
			(xy 97.425749 -256.100026) (xy 97.462001 -256.139097) (xy 97.492025 -256.183134) (xy 97.515151 -256.231155)
			(xy 97.530861 -256.282085) (xy 97.538804 -256.334789) (xy 97.539302 -256.361438) (xy 97.538804 -256.388087)
			(xy 97.767384 -256.388087) (xy 97.767384 -256.334789) (xy 97.775327 -256.282085) (xy 97.791037 -256.231155)
			(xy 97.814163 -256.183134) (xy 97.844187 -256.139097) (xy 97.880439 -256.100026) (xy 97.92211 -256.066795)
			(xy 97.968268 -256.040146) (xy 98.017882 -256.020674) (xy 98.069844 -256.008814) (xy 98.122994 -256.004831)
			(xy 98.176144 -256.008814) (xy 98.228106 -256.020674) (xy 98.27772 -256.040146) (xy 98.323878 -256.066795)
			(xy 98.365549 -256.100026) (xy 98.401801 -256.139097) (xy 98.431825 -256.183134) (xy 98.454951 -256.231155)
			(xy 98.470661 -256.282085) (xy 98.478604 -256.334789) (xy 98.479102 -256.361438) (xy 98.478604 -256.388087)
			(xy 98.470661 -256.440791) (xy 98.454951 -256.491721) (xy 98.431825 -256.539742) (xy 98.401801 -256.583779)
			(xy 98.365549 -256.62285) (xy 98.323878 -256.656081) (xy 98.27772 -256.68273) (xy 98.228106 -256.702202)
			(xy 98.176144 -256.714062) (xy 98.122994 -256.718046) (xy 98.069844 -256.714062) (xy 98.017882 -256.702202)
			(xy 97.968268 -256.68273) (xy 97.92211 -256.656081) (xy 97.880439 -256.62285) (xy 97.844187 -256.583779)
			(xy 97.814163 -256.539742) (xy 97.791037 -256.491721) (xy 97.775327 -256.440791) (xy 97.767384 -256.388087)
			(xy 97.538804 -256.388087) (xy 97.530861 -256.440791) (xy 97.515151 -256.491721) (xy 97.492025 -256.539742)
			(xy 97.462001 -256.583779) (xy 97.425749 -256.62285) (xy 97.384078 -256.656081) (xy 97.33792 -256.68273)
			(xy 97.288306 -256.702202) (xy 97.236344 -256.714062) (xy 97.183194 -256.718046) (xy 97.130044 -256.714062)
			(xy 97.078082 -256.702202) (xy 97.028468 -256.68273) (xy 96.98231 -256.656081) (xy 96.940639 -256.62285)
			(xy 96.904387 -256.583779) (xy 96.874363 -256.539742) (xy 96.851237 -256.491721) (xy 96.835527 -256.440791)
			(xy 96.827584 -256.388087) (xy 96.599004 -256.388087) (xy 96.591061 -256.440791) (xy 96.575351 -256.491721)
			(xy 96.552225 -256.539742) (xy 96.522201 -256.583779) (xy 96.485949 -256.62285) (xy 96.444278 -256.656081)
			(xy 96.39812 -256.68273) (xy 96.348506 -256.702202) (xy 96.296544 -256.714062) (xy 96.243394 -256.718046)
			(xy 96.190244 -256.714062) (xy 96.138282 -256.702202) (xy 96.088668 -256.68273) (xy 96.04251 -256.656081)
			(xy 96.000839 -256.62285) (xy 95.964587 -256.583779) (xy 95.934563 -256.539742) (xy 95.911437 -256.491721)
			(xy 95.895727 -256.440791) (xy 95.887784 -256.388087) (xy 95.659204 -256.388087) (xy 95.651261 -256.440791)
			(xy 95.635551 -256.491721) (xy 95.612425 -256.539742) (xy 95.582401 -256.583779) (xy 95.546149 -256.62285)
			(xy 95.504478 -256.656081) (xy 95.45832 -256.68273) (xy 95.408706 -256.702202) (xy 95.356744 -256.714062)
			(xy 95.303594 -256.718046) (xy 95.250444 -256.714062) (xy 95.198482 -256.702202) (xy 95.148868 -256.68273)
			(xy 95.10271 -256.656081) (xy 95.061039 -256.62285) (xy 95.024787 -256.583779) (xy 94.994763 -256.539742)
			(xy 94.971637 -256.491721) (xy 94.955927 -256.440791) (xy 94.947984 -256.388087) (xy 94.719658 -256.388087)
			(xy 94.711715 -256.440791) (xy 94.696005 -256.491721) (xy 94.672879 -256.539742) (xy 94.642855 -256.583779)
			(xy 94.606603 -256.62285) (xy 94.564932 -256.656081) (xy 94.518774 -256.68273) (xy 94.46916 -256.702202)
			(xy 94.417198 -256.714062) (xy 94.364048 -256.718046) (xy 94.310898 -256.714062) (xy 94.258936 -256.702202)
			(xy 94.209322 -256.68273) (xy 94.163164 -256.656081) (xy 94.121493 -256.62285) (xy 94.085241 -256.583779)
			(xy 94.055217 -256.539742) (xy 94.032091 -256.491721) (xy 94.016381 -256.440791) (xy 94.008438 -256.388087)
			(xy 93.779604 -256.388087) (xy 93.771661 -256.440791) (xy 93.755951 -256.491721) (xy 93.732825 -256.539742)
			(xy 93.702801 -256.583779) (xy 93.666549 -256.62285) (xy 93.624878 -256.656081) (xy 93.57872 -256.68273)
			(xy 93.529106 -256.702202) (xy 93.477144 -256.714062) (xy 93.423994 -256.718046) (xy 93.370844 -256.714062)
			(xy 93.318882 -256.702202) (xy 93.269268 -256.68273) (xy 93.22311 -256.656081) (xy 93.181439 -256.62285)
			(xy 93.145187 -256.583779) (xy 93.115163 -256.539742) (xy 93.092037 -256.491721) (xy 93.076327 -256.440791)
			(xy 93.068384 -256.388087) (xy 92.839804 -256.388087) (xy 92.831861 -256.440791) (xy 92.816151 -256.491721)
			(xy 92.793025 -256.539742) (xy 92.763001 -256.583779) (xy 92.726749 -256.62285) (xy 92.685078 -256.656081)
			(xy 92.63892 -256.68273) (xy 92.589306 -256.702202) (xy 92.537344 -256.714062) (xy 92.484194 -256.718046)
			(xy 92.431044 -256.714062) (xy 92.379082 -256.702202) (xy 92.329468 -256.68273) (xy 92.28331 -256.656081)
			(xy 92.241639 -256.62285) (xy 92.205387 -256.583779) (xy 92.175363 -256.539742) (xy 92.152237 -256.491721)
			(xy 92.136527 -256.440791) (xy 92.128584 -256.388087) (xy 91.900004 -256.388087) (xy 91.892061 -256.440791)
			(xy 91.876351 -256.491721) (xy 91.853225 -256.539742) (xy 91.823201 -256.583779) (xy 91.786949 -256.62285)
			(xy 91.745278 -256.656081) (xy 91.69912 -256.68273) (xy 91.649506 -256.702202) (xy 91.597544 -256.714062)
			(xy 91.544394 -256.718046) (xy 91.491244 -256.714062) (xy 91.439282 -256.702202) (xy 91.389668 -256.68273)
			(xy 91.34351 -256.656081) (xy 91.301839 -256.62285) (xy 91.265587 -256.583779) (xy 91.235563 -256.539742)
			(xy 91.212437 -256.491721) (xy 91.196727 -256.440791) (xy 91.188784 -256.388087) (xy 90.960204 -256.388087)
			(xy 90.952261 -256.440791) (xy 90.936551 -256.491721) (xy 90.913425 -256.539742) (xy 90.883401 -256.583779)
			(xy 90.847149 -256.62285) (xy 90.805478 -256.656081) (xy 90.75932 -256.68273) (xy 90.709706 -256.702202)
			(xy 90.657744 -256.714062) (xy 90.604594 -256.718046) (xy 90.551444 -256.714062) (xy 90.499482 -256.702202)
			(xy 90.449868 -256.68273) (xy 90.40371 -256.656081) (xy 90.362039 -256.62285) (xy 90.325787 -256.583779)
			(xy 90.295763 -256.539742) (xy 90.272637 -256.491721) (xy 90.256927 -256.440791) (xy 90.248984 -256.388087)
			(xy 90.020404 -256.388087) (xy 90.012461 -256.440791) (xy 89.996751 -256.491721) (xy 89.973625 -256.539742)
			(xy 89.943601 -256.583779) (xy 89.907349 -256.62285) (xy 89.865678 -256.656081) (xy 89.81952 -256.68273)
			(xy 89.769906 -256.702202) (xy 89.717944 -256.714062) (xy 89.664794 -256.718046) (xy 89.611644 -256.714062)
			(xy 89.559682 -256.702202) (xy 89.510068 -256.68273) (xy 89.46391 -256.656081) (xy 89.422239 -256.62285)
			(xy 89.385987 -256.583779) (xy 89.355963 -256.539742) (xy 89.332837 -256.491721) (xy 89.317127 -256.440791)
			(xy 89.309184 -256.388087) (xy 89.079598 -256.388087) (xy 89.077713 -256.413659) (xy 89.066252 -256.464768)
			(xy 89.047426 -256.513647) (xy 89.021643 -256.55924) (xy 88.989458 -256.600564) (xy 88.951567 -256.636727)
			(xy 88.93048 -256.652268) (xy 88.93048 -256.747518) (xy 88.930932 -256.761578) (xy 88.938605 -256.788631)
			(xy 88.953363 -256.812566) (xy 88.974089 -256.83157) (xy 88.999212 -256.844203) (xy 89.026827 -256.849506)
			(xy 89.054842 -256.847079) (xy 89.068148 -256.842514) (xy 89.098701 -256.83164) (xy 89.162472 -256.819877)
			(xy 89.194894 -256.819146) (xy 89.221549 -256.819619) (xy 89.274263 -256.827564) (xy 89.325205 -256.843276)
			(xy 89.373236 -256.866406) (xy 89.417282 -256.896436) (xy 89.456362 -256.932695) (xy 89.4896 -256.974374)
			(xy 89.516255 -257.020542) (xy 89.535731 -257.070166) (xy 89.547594 -257.122139) (xy 89.551578 -257.1753)
			(xy 89.549584 -257.201903) (xy 89.779084 -257.201903) (xy 89.779084 -257.148605) (xy 89.787027 -257.095901)
			(xy 89.802737 -257.044971) (xy 89.825863 -256.99695) (xy 89.855887 -256.952913) (xy 89.892139 -256.913842)
			(xy 89.93381 -256.880611) (xy 89.979968 -256.853962) (xy 90.029582 -256.83449) (xy 90.081544 -256.82263)
			(xy 90.134694 -256.818647) (xy 90.187844 -256.82263) (xy 90.239806 -256.83449) (xy 90.28942 -256.853962)
			(xy 90.335578 -256.880611) (xy 90.377249 -256.913842) (xy 90.413501 -256.952913) (xy 90.443525 -256.99695)
			(xy 90.466651 -257.044971) (xy 90.482361 -257.095901) (xy 90.490304 -257.148605) (xy 90.490802 -257.175254)
			(xy 90.490304 -257.201903) (xy 90.718884 -257.201903) (xy 90.718884 -257.148605) (xy 90.726827 -257.095901)
			(xy 90.742537 -257.044971) (xy 90.765663 -256.99695) (xy 90.795687 -256.952913) (xy 90.831939 -256.913842)
			(xy 90.87361 -256.880611) (xy 90.919768 -256.853962) (xy 90.969382 -256.83449) (xy 91.021344 -256.82263)
			(xy 91.074494 -256.818647) (xy 91.127644 -256.82263) (xy 91.179606 -256.83449) (xy 91.22922 -256.853962)
			(xy 91.275378 -256.880611) (xy 91.317049 -256.913842) (xy 91.353301 -256.952913) (xy 91.383325 -256.99695)
			(xy 91.406451 -257.044971) (xy 91.422161 -257.095901) (xy 91.430104 -257.148605) (xy 91.430602 -257.175254)
			(xy 91.430104 -257.201903) (xy 91.658938 -257.201903) (xy 91.658938 -257.148605) (xy 91.666881 -257.095901)
			(xy 91.682591 -257.044971) (xy 91.705717 -256.99695) (xy 91.735741 -256.952913) (xy 91.771993 -256.913842)
			(xy 91.813664 -256.880611) (xy 91.859822 -256.853962) (xy 91.909436 -256.83449) (xy 91.961398 -256.82263)
			(xy 92.014548 -256.818647) (xy 92.067698 -256.82263) (xy 92.11966 -256.83449) (xy 92.169274 -256.853962)
			(xy 92.215432 -256.880611) (xy 92.257103 -256.913842) (xy 92.293355 -256.952913) (xy 92.323379 -256.99695)
			(xy 92.346505 -257.044971) (xy 92.362215 -257.095901) (xy 92.370158 -257.148605) (xy 92.370656 -257.175254)
			(xy 92.370158 -257.201903) (xy 92.598484 -257.201903) (xy 92.598484 -257.148605) (xy 92.606427 -257.095901)
			(xy 92.622137 -257.044971) (xy 92.645263 -256.99695) (xy 92.675287 -256.952913) (xy 92.711539 -256.913842)
			(xy 92.75321 -256.880611) (xy 92.799368 -256.853962) (xy 92.848982 -256.83449) (xy 92.900944 -256.82263)
			(xy 92.954094 -256.818647) (xy 93.007244 -256.82263) (xy 93.059206 -256.83449) (xy 93.10882 -256.853962)
			(xy 93.154978 -256.880611) (xy 93.196649 -256.913842) (xy 93.232901 -256.952913) (xy 93.262925 -256.99695)
			(xy 93.286051 -257.044971) (xy 93.301761 -257.095901) (xy 93.309704 -257.148605) (xy 93.310202 -257.175254)
			(xy 93.309704 -257.201903) (xy 93.538538 -257.201903) (xy 93.538538 -257.148605) (xy 93.546481 -257.095901)
			(xy 93.562191 -257.044971) (xy 93.585317 -256.99695) (xy 93.615341 -256.952913) (xy 93.651593 -256.913842)
			(xy 93.693264 -256.880611) (xy 93.739422 -256.853962) (xy 93.789036 -256.83449) (xy 93.840998 -256.82263)
			(xy 93.894148 -256.818647) (xy 93.947298 -256.82263) (xy 93.99926 -256.83449) (xy 94.048874 -256.853962)
			(xy 94.095032 -256.880611) (xy 94.136703 -256.913842) (xy 94.172955 -256.952913) (xy 94.202979 -256.99695)
			(xy 94.226105 -257.044971) (xy 94.241815 -257.095901) (xy 94.249758 -257.148605) (xy 94.250256 -257.175254)
			(xy 94.249758 -257.201903) (xy 94.478338 -257.201903) (xy 94.478338 -257.148605) (xy 94.486281 -257.095901)
			(xy 94.501991 -257.044971) (xy 94.525117 -256.99695) (xy 94.555141 -256.952913) (xy 94.591393 -256.913842)
			(xy 94.633064 -256.880611) (xy 94.679222 -256.853962) (xy 94.728836 -256.83449) (xy 94.780798 -256.82263)
			(xy 94.833948 -256.818647) (xy 94.887098 -256.82263) (xy 94.93906 -256.83449) (xy 94.988674 -256.853962)
			(xy 95.034832 -256.880611) (xy 95.076503 -256.913842) (xy 95.112755 -256.952913) (xy 95.142779 -256.99695)
			(xy 95.165905 -257.044971) (xy 95.181615 -257.095901) (xy 95.189558 -257.148605) (xy 95.190056 -257.175254)
			(xy 95.189558 -257.201903) (xy 95.418138 -257.201903) (xy 95.418138 -257.148605) (xy 95.426081 -257.095901)
			(xy 95.441791 -257.044971) (xy 95.464917 -256.99695) (xy 95.494941 -256.952913) (xy 95.531193 -256.913842)
			(xy 95.572864 -256.880611) (xy 95.619022 -256.853962) (xy 95.668636 -256.83449) (xy 95.720598 -256.82263)
			(xy 95.773748 -256.818647) (xy 95.826898 -256.82263) (xy 95.87886 -256.83449) (xy 95.928474 -256.853962)
			(xy 95.974632 -256.880611) (xy 96.016303 -256.913842) (xy 96.052555 -256.952913) (xy 96.082579 -256.99695)
			(xy 96.105705 -257.044971) (xy 96.121415 -257.095901) (xy 96.129358 -257.148605) (xy 96.129856 -257.175254)
			(xy 96.129358 -257.201903) (xy 96.357938 -257.201903) (xy 96.357938 -257.148605) (xy 96.365881 -257.095901)
			(xy 96.381591 -257.044971) (xy 96.404717 -256.99695) (xy 96.434741 -256.952913) (xy 96.470993 -256.913842)
			(xy 96.512664 -256.880611) (xy 96.558822 -256.853962) (xy 96.608436 -256.83449) (xy 96.660398 -256.82263)
			(xy 96.713548 -256.818647) (xy 96.766698 -256.82263) (xy 96.81866 -256.83449) (xy 96.868274 -256.853962)
			(xy 96.914432 -256.880611) (xy 96.956103 -256.913842) (xy 96.992355 -256.952913) (xy 97.022379 -256.99695)
			(xy 97.045505 -257.044971) (xy 97.061215 -257.095901) (xy 97.069158 -257.148605) (xy 97.069656 -257.175254)
			(xy 97.069158 -257.201903) (xy 97.297484 -257.201903) (xy 97.297484 -257.148605) (xy 97.305427 -257.095901)
			(xy 97.321137 -257.044971) (xy 97.344263 -256.99695) (xy 97.374287 -256.952913) (xy 97.410539 -256.913842)
			(xy 97.45221 -256.880611) (xy 97.498368 -256.853962) (xy 97.547982 -256.83449) (xy 97.599944 -256.82263)
			(xy 97.653094 -256.818647) (xy 97.706244 -256.82263) (xy 97.758206 -256.83449) (xy 97.80782 -256.853962)
			(xy 97.853978 -256.880611) (xy 97.895649 -256.913842) (xy 97.931901 -256.952913) (xy 97.961925 -256.99695)
			(xy 97.985051 -257.044971) (xy 98.000761 -257.095901) (xy 98.008704 -257.148605) (xy 98.009202 -257.175254)
			(xy 98.008704 -257.201903) (xy 98.237538 -257.201903) (xy 98.237538 -257.148605) (xy 98.245481 -257.095901)
			(xy 98.261191 -257.044971) (xy 98.284317 -256.99695) (xy 98.314341 -256.952913) (xy 98.350593 -256.913842)
			(xy 98.392264 -256.880611) (xy 98.438422 -256.853962) (xy 98.488036 -256.83449) (xy 98.539998 -256.82263)
			(xy 98.593148 -256.818647) (xy 98.646298 -256.82263) (xy 98.69826 -256.83449) (xy 98.747874 -256.853962)
			(xy 98.794032 -256.880611) (xy 98.835703 -256.913842) (xy 98.871955 -256.952913) (xy 98.901979 -256.99695)
			(xy 98.925105 -257.044971) (xy 98.940815 -257.095901) (xy 98.948758 -257.148605) (xy 98.949256 -257.175254)
			(xy 98.948758 -257.201903) (xy 98.940815 -257.254607) (xy 98.925105 -257.305537) (xy 98.901979 -257.353558)
			(xy 98.871955 -257.397595) (xy 98.835703 -257.436666) (xy 98.794032 -257.469897) (xy 98.747874 -257.496546)
			(xy 98.69826 -257.516018) (xy 98.646298 -257.527878) (xy 98.593148 -257.531862) (xy 98.539998 -257.527878)
			(xy 98.488036 -257.516018) (xy 98.438422 -257.496546) (xy 98.392264 -257.469897) (xy 98.350593 -257.436666)
			(xy 98.314341 -257.397595) (xy 98.284317 -257.353558) (xy 98.261191 -257.305537) (xy 98.245481 -257.254607)
			(xy 98.237538 -257.201903) (xy 98.008704 -257.201903) (xy 98.000761 -257.254607) (xy 97.985051 -257.305537)
			(xy 97.961925 -257.353558) (xy 97.931901 -257.397595) (xy 97.895649 -257.436666) (xy 97.853978 -257.469897)
			(xy 97.80782 -257.496546) (xy 97.758206 -257.516018) (xy 97.706244 -257.527878) (xy 97.653094 -257.531862)
			(xy 97.599944 -257.527878) (xy 97.547982 -257.516018) (xy 97.498368 -257.496546) (xy 97.45221 -257.469897)
			(xy 97.410539 -257.436666) (xy 97.374287 -257.397595) (xy 97.344263 -257.353558) (xy 97.321137 -257.305537)
			(xy 97.305427 -257.254607) (xy 97.297484 -257.201903) (xy 97.069158 -257.201903) (xy 97.061215 -257.254607)
			(xy 97.045505 -257.305537) (xy 97.022379 -257.353558) (xy 96.992355 -257.397595) (xy 96.956103 -257.436666)
			(xy 96.914432 -257.469897) (xy 96.868274 -257.496546) (xy 96.81866 -257.516018) (xy 96.766698 -257.527878)
			(xy 96.713548 -257.531862) (xy 96.660398 -257.527878) (xy 96.608436 -257.516018) (xy 96.558822 -257.496546)
			(xy 96.512664 -257.469897) (xy 96.470993 -257.436666) (xy 96.434741 -257.397595) (xy 96.404717 -257.353558)
			(xy 96.381591 -257.305537) (xy 96.365881 -257.254607) (xy 96.357938 -257.201903) (xy 96.129358 -257.201903)
			(xy 96.121415 -257.254607) (xy 96.105705 -257.305537) (xy 96.082579 -257.353558) (xy 96.052555 -257.397595)
			(xy 96.016303 -257.436666) (xy 95.974632 -257.469897) (xy 95.928474 -257.496546) (xy 95.87886 -257.516018)
			(xy 95.826898 -257.527878) (xy 95.773748 -257.531862) (xy 95.720598 -257.527878) (xy 95.668636 -257.516018)
			(xy 95.619022 -257.496546) (xy 95.572864 -257.469897) (xy 95.531193 -257.436666) (xy 95.494941 -257.397595)
			(xy 95.464917 -257.353558) (xy 95.441791 -257.305537) (xy 95.426081 -257.254607) (xy 95.418138 -257.201903)
			(xy 95.189558 -257.201903) (xy 95.181615 -257.254607) (xy 95.165905 -257.305537) (xy 95.142779 -257.353558)
			(xy 95.112755 -257.397595) (xy 95.076503 -257.436666) (xy 95.034832 -257.469897) (xy 94.988674 -257.496546)
			(xy 94.93906 -257.516018) (xy 94.887098 -257.527878) (xy 94.833948 -257.531862) (xy 94.780798 -257.527878)
			(xy 94.728836 -257.516018) (xy 94.679222 -257.496546) (xy 94.633064 -257.469897) (xy 94.591393 -257.436666)
			(xy 94.555141 -257.397595) (xy 94.525117 -257.353558) (xy 94.501991 -257.305537) (xy 94.486281 -257.254607)
			(xy 94.478338 -257.201903) (xy 94.249758 -257.201903) (xy 94.241815 -257.254607) (xy 94.226105 -257.305537)
			(xy 94.202979 -257.353558) (xy 94.172955 -257.397595) (xy 94.136703 -257.436666) (xy 94.095032 -257.469897)
			(xy 94.048874 -257.496546) (xy 93.99926 -257.516018) (xy 93.947298 -257.527878) (xy 93.894148 -257.531862)
			(xy 93.840998 -257.527878) (xy 93.789036 -257.516018) (xy 93.739422 -257.496546) (xy 93.693264 -257.469897)
			(xy 93.651593 -257.436666) (xy 93.615341 -257.397595) (xy 93.585317 -257.353558) (xy 93.562191 -257.305537)
			(xy 93.546481 -257.254607) (xy 93.538538 -257.201903) (xy 93.309704 -257.201903) (xy 93.301761 -257.254607)
			(xy 93.286051 -257.305537) (xy 93.262925 -257.353558) (xy 93.232901 -257.397595) (xy 93.196649 -257.436666)
			(xy 93.154978 -257.469897) (xy 93.10882 -257.496546) (xy 93.059206 -257.516018) (xy 93.007244 -257.527878)
			(xy 92.954094 -257.531862) (xy 92.900944 -257.527878) (xy 92.848982 -257.516018) (xy 92.799368 -257.496546)
			(xy 92.75321 -257.469897) (xy 92.711539 -257.436666) (xy 92.675287 -257.397595) (xy 92.645263 -257.353558)
			(xy 92.622137 -257.305537) (xy 92.606427 -257.254607) (xy 92.598484 -257.201903) (xy 92.370158 -257.201903)
			(xy 92.362215 -257.254607) (xy 92.346505 -257.305537) (xy 92.323379 -257.353558) (xy 92.293355 -257.397595)
			(xy 92.257103 -257.436666) (xy 92.215432 -257.469897) (xy 92.169274 -257.496546) (xy 92.11966 -257.516018)
			(xy 92.067698 -257.527878) (xy 92.014548 -257.531862) (xy 91.961398 -257.527878) (xy 91.909436 -257.516018)
			(xy 91.859822 -257.496546) (xy 91.813664 -257.469897) (xy 91.771993 -257.436666) (xy 91.735741 -257.397595)
			(xy 91.705717 -257.353558) (xy 91.682591 -257.305537) (xy 91.666881 -257.254607) (xy 91.658938 -257.201903)
			(xy 91.430104 -257.201903) (xy 91.422161 -257.254607) (xy 91.406451 -257.305537) (xy 91.383325 -257.353558)
			(xy 91.353301 -257.397595) (xy 91.317049 -257.436666) (xy 91.275378 -257.469897) (xy 91.22922 -257.496546)
			(xy 91.179606 -257.516018) (xy 91.127644 -257.527878) (xy 91.074494 -257.531862) (xy 91.021344 -257.527878)
			(xy 90.969382 -257.516018) (xy 90.919768 -257.496546) (xy 90.87361 -257.469897) (xy 90.831939 -257.436666)
			(xy 90.795687 -257.397595) (xy 90.765663 -257.353558) (xy 90.742537 -257.305537) (xy 90.726827 -257.254607)
			(xy 90.718884 -257.201903) (xy 90.490304 -257.201903) (xy 90.482361 -257.254607) (xy 90.466651 -257.305537)
			(xy 90.443525 -257.353558) (xy 90.413501 -257.397595) (xy 90.377249 -257.436666) (xy 90.335578 -257.469897)
			(xy 90.28942 -257.496546) (xy 90.239806 -257.516018) (xy 90.187844 -257.527878) (xy 90.134694 -257.531862)
			(xy 90.081544 -257.527878) (xy 90.029582 -257.516018) (xy 89.979968 -257.496546) (xy 89.93381 -257.469897)
			(xy 89.892139 -257.436666) (xy 89.855887 -257.397595) (xy 89.825863 -257.353558) (xy 89.802737 -257.305537)
			(xy 89.787027 -257.254607) (xy 89.779084 -257.201903) (xy 89.549584 -257.201903) (xy 89.547594 -257.228461)
			(xy 89.535731 -257.280434) (xy 89.516255 -257.330058) (xy 89.4896 -257.376226) (xy 89.456362 -257.417905)
			(xy 89.417282 -257.454164) (xy 89.373236 -257.484194) (xy 89.325205 -257.507324) (xy 89.274263 -257.523036)
			(xy 89.221549 -257.530981) (xy 89.194894 -257.531362) (xy 89.16247 -257.530649) (xy 89.098697 -257.518887)
			(xy 89.068148 -257.507994) (xy 89.054843 -257.503427) (xy 89.026828 -257.500999) (xy 88.999213 -257.506302)
			(xy 88.97409 -257.518935) (xy 88.953365 -257.53794) (xy 88.938607 -257.561877) (xy 88.930936 -257.58893)
			(xy 88.93048 -257.60299) (xy 88.93048 -257.69824) (xy 88.951606 -257.713732) (xy 88.989503 -257.749902)
			(xy 89.021692 -257.791233) (xy 89.047479 -257.836833) (xy 89.066307 -257.88572) (xy 89.077769 -257.936837)
			(xy 89.08162 -257.989083) (xy 89.079659 -258.015719) (xy 89.309184 -258.015719) (xy 89.309184 -257.962421)
			(xy 89.317127 -257.909717) (xy 89.332837 -257.858787) (xy 89.355963 -257.810766) (xy 89.385987 -257.766729)
			(xy 89.422239 -257.727658) (xy 89.46391 -257.694427) (xy 89.510068 -257.667778) (xy 89.559682 -257.648306)
			(xy 89.611644 -257.636446) (xy 89.664794 -257.632463) (xy 89.717944 -257.636446) (xy 89.769906 -257.648306)
			(xy 89.81952 -257.667778) (xy 89.865678 -257.694427) (xy 89.907349 -257.727658) (xy 89.943601 -257.766729)
			(xy 89.973625 -257.810766) (xy 89.996751 -257.858787) (xy 90.012461 -257.909717) (xy 90.020404 -257.962421)
			(xy 90.020902 -257.98907) (xy 90.020404 -258.015719) (xy 90.249238 -258.015719) (xy 90.249238 -257.962421)
			(xy 90.257181 -257.909717) (xy 90.272891 -257.858787) (xy 90.296017 -257.810766) (xy 90.326041 -257.766729)
			(xy 90.362293 -257.727658) (xy 90.403964 -257.694427) (xy 90.450122 -257.667778) (xy 90.499736 -257.648306)
			(xy 90.551698 -257.636446) (xy 90.604848 -257.632463) (xy 90.657998 -257.636446) (xy 90.70996 -257.648306)
			(xy 90.759574 -257.667778) (xy 90.805732 -257.694427) (xy 90.847403 -257.727658) (xy 90.883655 -257.766729)
			(xy 90.913679 -257.810766) (xy 90.936805 -257.858787) (xy 90.952515 -257.909717) (xy 90.960458 -257.962421)
			(xy 90.960956 -257.98907) (xy 90.960458 -258.015719) (xy 91.188784 -258.015719) (xy 91.188784 -257.962421)
			(xy 91.196727 -257.909717) (xy 91.212437 -257.858787) (xy 91.235563 -257.810766) (xy 91.265587 -257.766729)
			(xy 91.301839 -257.727658) (xy 91.34351 -257.694427) (xy 91.389668 -257.667778) (xy 91.439282 -257.648306)
			(xy 91.491244 -257.636446) (xy 91.544394 -257.632463) (xy 91.597544 -257.636446) (xy 91.649506 -257.648306)
			(xy 91.69912 -257.667778) (xy 91.745278 -257.694427) (xy 91.786949 -257.727658) (xy 91.823201 -257.766729)
			(xy 91.853225 -257.810766) (xy 91.876351 -257.858787) (xy 91.892061 -257.909717) (xy 91.900004 -257.962421)
			(xy 91.900502 -257.98907) (xy 91.900004 -258.015719) (xy 92.128838 -258.015719) (xy 92.128838 -257.962421)
			(xy 92.136781 -257.909717) (xy 92.152491 -257.858787) (xy 92.175617 -257.810766) (xy 92.205641 -257.766729)
			(xy 92.241893 -257.727658) (xy 92.283564 -257.694427) (xy 92.329722 -257.667778) (xy 92.379336 -257.648306)
			(xy 92.431298 -257.636446) (xy 92.484448 -257.632463) (xy 92.537598 -257.636446) (xy 92.58956 -257.648306)
			(xy 92.639174 -257.667778) (xy 92.685332 -257.694427) (xy 92.727003 -257.727658) (xy 92.763255 -257.766729)
			(xy 92.793279 -257.810766) (xy 92.816405 -257.858787) (xy 92.832115 -257.909717) (xy 92.840058 -257.962421)
			(xy 92.840556 -257.98907) (xy 92.840058 -258.015719) (xy 93.068384 -258.015719) (xy 93.068384 -257.962421)
			(xy 93.076327 -257.909717) (xy 93.092037 -257.858787) (xy 93.115163 -257.810766) (xy 93.145187 -257.766729)
			(xy 93.181439 -257.727658) (xy 93.22311 -257.694427) (xy 93.269268 -257.667778) (xy 93.318882 -257.648306)
			(xy 93.370844 -257.636446) (xy 93.423994 -257.632463) (xy 93.477144 -257.636446) (xy 93.529106 -257.648306)
			(xy 93.57872 -257.667778) (xy 93.624878 -257.694427) (xy 93.666549 -257.727658) (xy 93.702801 -257.766729)
			(xy 93.732825 -257.810766) (xy 93.755951 -257.858787) (xy 93.771661 -257.909717) (xy 93.779604 -257.962421)
			(xy 93.780102 -257.98907) (xy 93.779604 -258.015719) (xy 94.008184 -258.015719) (xy 94.008184 -257.962421)
			(xy 94.016127 -257.909717) (xy 94.031837 -257.858787) (xy 94.054963 -257.810766) (xy 94.084987 -257.766729)
			(xy 94.121239 -257.727658) (xy 94.16291 -257.694427) (xy 94.209068 -257.667778) (xy 94.258682 -257.648306)
			(xy 94.310644 -257.636446) (xy 94.363794 -257.632463) (xy 94.416944 -257.636446) (xy 94.468906 -257.648306)
			(xy 94.51852 -257.667778) (xy 94.564678 -257.694427) (xy 94.606349 -257.727658) (xy 94.642601 -257.766729)
			(xy 94.672625 -257.810766) (xy 94.695751 -257.858787) (xy 94.711461 -257.909717) (xy 94.719404 -257.962421)
			(xy 94.719902 -257.98907) (xy 94.719404 -258.015719) (xy 94.947984 -258.015719) (xy 94.947984 -257.962421)
			(xy 94.955927 -257.909717) (xy 94.971637 -257.858787) (xy 94.994763 -257.810766) (xy 95.024787 -257.766729)
			(xy 95.061039 -257.727658) (xy 95.10271 -257.694427) (xy 95.148868 -257.667778) (xy 95.198482 -257.648306)
			(xy 95.250444 -257.636446) (xy 95.303594 -257.632463) (xy 95.356744 -257.636446) (xy 95.408706 -257.648306)
			(xy 95.45832 -257.667778) (xy 95.504478 -257.694427) (xy 95.546149 -257.727658) (xy 95.582401 -257.766729)
			(xy 95.612425 -257.810766) (xy 95.635551 -257.858787) (xy 95.651261 -257.909717) (xy 95.659204 -257.962421)
			(xy 95.659702 -257.98907) (xy 95.659204 -258.015719) (xy 95.887784 -258.015719) (xy 95.887784 -257.962421)
			(xy 95.895727 -257.909717) (xy 95.911437 -257.858787) (xy 95.934563 -257.810766) (xy 95.964587 -257.766729)
			(xy 96.000839 -257.727658) (xy 96.04251 -257.694427) (xy 96.088668 -257.667778) (xy 96.138282 -257.648306)
			(xy 96.190244 -257.636446) (xy 96.243394 -257.632463) (xy 96.296544 -257.636446) (xy 96.348506 -257.648306)
			(xy 96.39812 -257.667778) (xy 96.444278 -257.694427) (xy 96.485949 -257.727658) (xy 96.522201 -257.766729)
			(xy 96.552225 -257.810766) (xy 96.575351 -257.858787) (xy 96.591061 -257.909717) (xy 96.599004 -257.962421)
			(xy 96.599502 -257.98907) (xy 96.599004 -258.015719) (xy 96.827838 -258.015719) (xy 96.827838 -257.962421)
			(xy 96.835781 -257.909717) (xy 96.851491 -257.858787) (xy 96.874617 -257.810766) (xy 96.904641 -257.766729)
			(xy 96.940893 -257.727658) (xy 96.982564 -257.694427) (xy 97.028722 -257.667778) (xy 97.078336 -257.648306)
			(xy 97.130298 -257.636446) (xy 97.183448 -257.632463) (xy 97.236598 -257.636446) (xy 97.28856 -257.648306)
			(xy 97.338174 -257.667778) (xy 97.384332 -257.694427) (xy 97.426003 -257.727658) (xy 97.462255 -257.766729)
			(xy 97.492279 -257.810766) (xy 97.515405 -257.858787) (xy 97.531115 -257.909717) (xy 97.539058 -257.962421)
			(xy 97.539556 -257.98907) (xy 97.539058 -258.015719) (xy 97.767384 -258.015719) (xy 97.767384 -257.962421)
			(xy 97.775327 -257.909717) (xy 97.791037 -257.858787) (xy 97.814163 -257.810766) (xy 97.844187 -257.766729)
			(xy 97.880439 -257.727658) (xy 97.92211 -257.694427) (xy 97.968268 -257.667778) (xy 98.017882 -257.648306)
			(xy 98.069844 -257.636446) (xy 98.122994 -257.632463) (xy 98.176144 -257.636446) (xy 98.228106 -257.648306)
			(xy 98.27772 -257.667778) (xy 98.323878 -257.694427) (xy 98.365549 -257.727658) (xy 98.401801 -257.766729)
			(xy 98.431825 -257.810766) (xy 98.454951 -257.858787) (xy 98.470661 -257.909717) (xy 98.478604 -257.962421)
			(xy 98.479102 -257.98907) (xy 98.478604 -258.015719) (xy 98.470661 -258.068423) (xy 98.454951 -258.119353)
			(xy 98.431825 -258.167374) (xy 98.401801 -258.211411) (xy 98.365549 -258.250482) (xy 98.323878 -258.283713)
			(xy 98.27772 -258.310362) (xy 98.228106 -258.329834) (xy 98.176144 -258.341694) (xy 98.122994 -258.345678)
			(xy 98.069844 -258.341694) (xy 98.017882 -258.329834) (xy 97.968268 -258.310362) (xy 97.92211 -258.283713)
			(xy 97.880439 -258.250482) (xy 97.844187 -258.211411) (xy 97.814163 -258.167374) (xy 97.791037 -258.119353)
			(xy 97.775327 -258.068423) (xy 97.767384 -258.015719) (xy 97.539058 -258.015719) (xy 97.531115 -258.068423)
			(xy 97.515405 -258.119353) (xy 97.492279 -258.167374) (xy 97.462255 -258.211411) (xy 97.426003 -258.250482)
			(xy 97.384332 -258.283713) (xy 97.338174 -258.310362) (xy 97.28856 -258.329834) (xy 97.236598 -258.341694)
			(xy 97.183448 -258.345678) (xy 97.130298 -258.341694) (xy 97.078336 -258.329834) (xy 97.028722 -258.310362)
			(xy 96.982564 -258.283713) (xy 96.940893 -258.250482) (xy 96.904641 -258.211411) (xy 96.874617 -258.167374)
			(xy 96.851491 -258.119353) (xy 96.835781 -258.068423) (xy 96.827838 -258.015719) (xy 96.599004 -258.015719)
			(xy 96.591061 -258.068423) (xy 96.575351 -258.119353) (xy 96.552225 -258.167374) (xy 96.522201 -258.211411)
			(xy 96.485949 -258.250482) (xy 96.444278 -258.283713) (xy 96.39812 -258.310362) (xy 96.348506 -258.329834)
			(xy 96.296544 -258.341694) (xy 96.243394 -258.345678) (xy 96.190244 -258.341694) (xy 96.138282 -258.329834)
			(xy 96.088668 -258.310362) (xy 96.04251 -258.283713) (xy 96.000839 -258.250482) (xy 95.964587 -258.211411)
			(xy 95.934563 -258.167374) (xy 95.911437 -258.119353) (xy 95.895727 -258.068423) (xy 95.887784 -258.015719)
			(xy 95.659204 -258.015719) (xy 95.651261 -258.068423) (xy 95.635551 -258.119353) (xy 95.612425 -258.167374)
			(xy 95.582401 -258.211411) (xy 95.546149 -258.250482) (xy 95.504478 -258.283713) (xy 95.45832 -258.310362)
			(xy 95.408706 -258.329834) (xy 95.356744 -258.341694) (xy 95.303594 -258.345678) (xy 95.250444 -258.341694)
			(xy 95.198482 -258.329834) (xy 95.148868 -258.310362) (xy 95.10271 -258.283713) (xy 95.061039 -258.250482)
			(xy 95.024787 -258.211411) (xy 94.994763 -258.167374) (xy 94.971637 -258.119353) (xy 94.955927 -258.068423)
			(xy 94.947984 -258.015719) (xy 94.719404 -258.015719) (xy 94.711461 -258.068423) (xy 94.695751 -258.119353)
			(xy 94.672625 -258.167374) (xy 94.642601 -258.211411) (xy 94.606349 -258.250482) (xy 94.564678 -258.283713)
			(xy 94.51852 -258.310362) (xy 94.468906 -258.329834) (xy 94.416944 -258.341694) (xy 94.363794 -258.345678)
			(xy 94.310644 -258.341694) (xy 94.258682 -258.329834) (xy 94.209068 -258.310362) (xy 94.16291 -258.283713)
			(xy 94.121239 -258.250482) (xy 94.084987 -258.211411) (xy 94.054963 -258.167374) (xy 94.031837 -258.119353)
			(xy 94.016127 -258.068423) (xy 94.008184 -258.015719) (xy 93.779604 -258.015719) (xy 93.771661 -258.068423)
			(xy 93.755951 -258.119353) (xy 93.732825 -258.167374) (xy 93.702801 -258.211411) (xy 93.666549 -258.250482)
			(xy 93.624878 -258.283713) (xy 93.57872 -258.310362) (xy 93.529106 -258.329834) (xy 93.477144 -258.341694)
			(xy 93.423994 -258.345678) (xy 93.370844 -258.341694) (xy 93.318882 -258.329834) (xy 93.269268 -258.310362)
			(xy 93.22311 -258.283713) (xy 93.181439 -258.250482) (xy 93.145187 -258.211411) (xy 93.115163 -258.167374)
			(xy 93.092037 -258.119353) (xy 93.076327 -258.068423) (xy 93.068384 -258.015719) (xy 92.840058 -258.015719)
			(xy 92.832115 -258.068423) (xy 92.816405 -258.119353) (xy 92.793279 -258.167374) (xy 92.763255 -258.211411)
			(xy 92.727003 -258.250482) (xy 92.685332 -258.283713) (xy 92.639174 -258.310362) (xy 92.58956 -258.329834)
			(xy 92.537598 -258.341694) (xy 92.484448 -258.345678) (xy 92.431298 -258.341694) (xy 92.379336 -258.329834)
			(xy 92.329722 -258.310362) (xy 92.283564 -258.283713) (xy 92.241893 -258.250482) (xy 92.205641 -258.211411)
			(xy 92.175617 -258.167374) (xy 92.152491 -258.119353) (xy 92.136781 -258.068423) (xy 92.128838 -258.015719)
			(xy 91.900004 -258.015719) (xy 91.892061 -258.068423) (xy 91.876351 -258.119353) (xy 91.853225 -258.167374)
			(xy 91.823201 -258.211411) (xy 91.786949 -258.250482) (xy 91.745278 -258.283713) (xy 91.69912 -258.310362)
			(xy 91.649506 -258.329834) (xy 91.597544 -258.341694) (xy 91.544394 -258.345678) (xy 91.491244 -258.341694)
			(xy 91.439282 -258.329834) (xy 91.389668 -258.310362) (xy 91.34351 -258.283713) (xy 91.301839 -258.250482)
			(xy 91.265587 -258.211411) (xy 91.235563 -258.167374) (xy 91.212437 -258.119353) (xy 91.196727 -258.068423)
			(xy 91.188784 -258.015719) (xy 90.960458 -258.015719) (xy 90.952515 -258.068423) (xy 90.936805 -258.119353)
			(xy 90.913679 -258.167374) (xy 90.883655 -258.211411) (xy 90.847403 -258.250482) (xy 90.805732 -258.283713)
			(xy 90.759574 -258.310362) (xy 90.70996 -258.329834) (xy 90.657998 -258.341694) (xy 90.604848 -258.345678)
			(xy 90.551698 -258.341694) (xy 90.499736 -258.329834) (xy 90.450122 -258.310362) (xy 90.403964 -258.283713)
			(xy 90.362293 -258.250482) (xy 90.326041 -258.211411) (xy 90.296017 -258.167374) (xy 90.272891 -258.119353)
			(xy 90.257181 -258.068423) (xy 90.249238 -258.015719) (xy 90.020404 -258.015719) (xy 90.012461 -258.068423)
			(xy 89.996751 -258.119353) (xy 89.973625 -258.167374) (xy 89.943601 -258.211411) (xy 89.907349 -258.250482)
			(xy 89.865678 -258.283713) (xy 89.81952 -258.310362) (xy 89.769906 -258.329834) (xy 89.717944 -258.341694)
			(xy 89.664794 -258.345678) (xy 89.611644 -258.341694) (xy 89.559682 -258.329834) (xy 89.510068 -258.310362)
			(xy 89.46391 -258.283713) (xy 89.422239 -258.250482) (xy 89.385987 -258.211411) (xy 89.355963 -258.167374)
			(xy 89.332837 -258.119353) (xy 89.317127 -258.068423) (xy 89.309184 -258.015719) (xy 89.079659 -258.015719)
			(xy 89.077774 -258.041328) (xy 89.066317 -258.092447) (xy 89.047493 -258.141335) (xy 89.021711 -258.186939)
			(xy 88.989526 -258.228273) (xy 88.951633 -258.264446) (xy 88.93048 -258.2799) (xy 88.93048 -258.375404)
			(xy 88.930931 -258.389465) (xy 88.938601 -258.416522) (xy 88.953359 -258.440461) (xy 88.974086 -258.459468)
			(xy 88.99921 -258.472102) (xy 89.026828 -258.477406) (xy 89.054846 -258.474978) (xy 89.068148 -258.4704)
			(xy 89.098701 -258.459526) (xy 89.162472 -258.447764) (xy 89.194894 -258.447032) (xy 89.221542 -258.447505)
			(xy 89.274244 -258.455447) (xy 89.325173 -258.471156) (xy 89.373193 -258.49428) (xy 89.417229 -258.524303)
			(xy 89.456298 -258.560554) (xy 89.489529 -258.602223) (xy 89.516178 -258.648379) (xy 89.535649 -258.697992)
			(xy 89.547509 -258.749952) (xy 89.551492 -258.8031) (xy 89.549492 -258.829789) (xy 89.779084 -258.829789)
			(xy 89.779084 -258.776491) (xy 89.787027 -258.723787) (xy 89.802737 -258.672857) (xy 89.825863 -258.624836)
			(xy 89.855887 -258.580799) (xy 89.892139 -258.541728) (xy 89.93381 -258.508497) (xy 89.979968 -258.481848)
			(xy 90.029582 -258.462376) (xy 90.081544 -258.450516) (xy 90.134694 -258.446533) (xy 90.187844 -258.450516)
			(xy 90.239806 -258.462376) (xy 90.28942 -258.481848) (xy 90.335578 -258.508497) (xy 90.377249 -258.541728)
			(xy 90.413501 -258.580799) (xy 90.443525 -258.624836) (xy 90.466651 -258.672857) (xy 90.482361 -258.723787)
			(xy 90.490304 -258.776491) (xy 90.490802 -258.80314) (xy 90.490304 -258.829789) (xy 90.719138 -258.829789)
			(xy 90.719138 -258.776491) (xy 90.727081 -258.723787) (xy 90.742791 -258.672857) (xy 90.765917 -258.624836)
			(xy 90.795941 -258.580799) (xy 90.832193 -258.541728) (xy 90.873864 -258.508497) (xy 90.920022 -258.481848)
			(xy 90.969636 -258.462376) (xy 91.021598 -258.450516) (xy 91.074748 -258.446533) (xy 91.127898 -258.450516)
			(xy 91.17986 -258.462376) (xy 91.229474 -258.481848) (xy 91.275632 -258.508497) (xy 91.317303 -258.541728)
			(xy 91.353555 -258.580799) (xy 91.383579 -258.624836) (xy 91.406705 -258.672857) (xy 91.422415 -258.723787)
			(xy 91.430358 -258.776491) (xy 91.430856 -258.80314) (xy 91.430358 -258.829789) (xy 91.658938 -258.829789)
			(xy 91.658938 -258.776491) (xy 91.666881 -258.723787) (xy 91.682591 -258.672857) (xy 91.705717 -258.624836)
			(xy 91.735741 -258.580799) (xy 91.771993 -258.541728) (xy 91.813664 -258.508497) (xy 91.859822 -258.481848)
			(xy 91.909436 -258.462376) (xy 91.961398 -258.450516) (xy 92.014548 -258.446533) (xy 92.067698 -258.450516)
			(xy 92.11966 -258.462376) (xy 92.169274 -258.481848) (xy 92.215432 -258.508497) (xy 92.257103 -258.541728)
			(xy 92.293355 -258.580799) (xy 92.323379 -258.624836) (xy 92.346505 -258.672857) (xy 92.362215 -258.723787)
			(xy 92.370158 -258.776491) (xy 92.370656 -258.80314) (xy 92.370158 -258.829789) (xy 92.598738 -258.829789)
			(xy 92.598738 -258.776491) (xy 92.606681 -258.723787) (xy 92.622391 -258.672857) (xy 92.645517 -258.624836)
			(xy 92.675541 -258.580799) (xy 92.711793 -258.541728) (xy 92.753464 -258.508497) (xy 92.799622 -258.481848)
			(xy 92.849236 -258.462376) (xy 92.901198 -258.450516) (xy 92.954348 -258.446533) (xy 93.007498 -258.450516)
			(xy 93.05946 -258.462376) (xy 93.109074 -258.481848) (xy 93.155232 -258.508497) (xy 93.196903 -258.541728)
			(xy 93.233155 -258.580799) (xy 93.263179 -258.624836) (xy 93.286305 -258.672857) (xy 93.302015 -258.723787)
			(xy 93.309958 -258.776491) (xy 93.310456 -258.80314) (xy 93.309958 -258.829789) (xy 93.538538 -258.829789)
			(xy 93.538538 -258.776491) (xy 93.546481 -258.723787) (xy 93.562191 -258.672857) (xy 93.585317 -258.624836)
			(xy 93.615341 -258.580799) (xy 93.651593 -258.541728) (xy 93.693264 -258.508497) (xy 93.739422 -258.481848)
			(xy 93.789036 -258.462376) (xy 93.840998 -258.450516) (xy 93.894148 -258.446533) (xy 93.947298 -258.450516)
			(xy 93.99926 -258.462376) (xy 94.048874 -258.481848) (xy 94.095032 -258.508497) (xy 94.136703 -258.541728)
			(xy 94.172955 -258.580799) (xy 94.202979 -258.624836) (xy 94.226105 -258.672857) (xy 94.241815 -258.723787)
			(xy 94.249758 -258.776491) (xy 94.250256 -258.80314) (xy 94.249758 -258.829789) (xy 94.478084 -258.829789)
			(xy 94.478084 -258.776491) (xy 94.486027 -258.723787) (xy 94.501737 -258.672857) (xy 94.524863 -258.624836)
			(xy 94.554887 -258.580799) (xy 94.591139 -258.541728) (xy 94.63281 -258.508497) (xy 94.678968 -258.481848)
			(xy 94.728582 -258.462376) (xy 94.780544 -258.450516) (xy 94.833694 -258.446533) (xy 94.886844 -258.450516)
			(xy 94.938806 -258.462376) (xy 94.98842 -258.481848) (xy 95.034578 -258.508497) (xy 95.076249 -258.541728)
			(xy 95.112501 -258.580799) (xy 95.142525 -258.624836) (xy 95.165651 -258.672857) (xy 95.181361 -258.723787)
			(xy 95.189304 -258.776491) (xy 95.189802 -258.80314) (xy 95.189304 -258.829789) (xy 95.418138 -258.829789)
			(xy 95.418138 -258.776491) (xy 95.426081 -258.723787) (xy 95.441791 -258.672857) (xy 95.464917 -258.624836)
			(xy 95.494941 -258.580799) (xy 95.531193 -258.541728) (xy 95.572864 -258.508497) (xy 95.619022 -258.481848)
			(xy 95.668636 -258.462376) (xy 95.720598 -258.450516) (xy 95.773748 -258.446533) (xy 95.826898 -258.450516)
			(xy 95.87886 -258.462376) (xy 95.928474 -258.481848) (xy 95.974632 -258.508497) (xy 96.016303 -258.541728)
			(xy 96.052555 -258.580799) (xy 96.082579 -258.624836) (xy 96.105705 -258.672857) (xy 96.121415 -258.723787)
			(xy 96.129358 -258.776491) (xy 96.129856 -258.80314) (xy 96.129358 -258.829789) (xy 96.357938 -258.829789)
			(xy 96.357938 -258.776491) (xy 96.365881 -258.723787) (xy 96.381591 -258.672857) (xy 96.404717 -258.624836)
			(xy 96.434741 -258.580799) (xy 96.470993 -258.541728) (xy 96.512664 -258.508497) (xy 96.558822 -258.481848)
			(xy 96.608436 -258.462376) (xy 96.660398 -258.450516) (xy 96.713548 -258.446533) (xy 96.766698 -258.450516)
			(xy 96.81866 -258.462376) (xy 96.868274 -258.481848) (xy 96.914432 -258.508497) (xy 96.956103 -258.541728)
			(xy 96.992355 -258.580799) (xy 97.022379 -258.624836) (xy 97.045505 -258.672857) (xy 97.061215 -258.723787)
			(xy 97.069158 -258.776491) (xy 97.069656 -258.80314) (xy 97.069158 -258.829789) (xy 97.297738 -258.829789)
			(xy 97.297738 -258.776491) (xy 97.305681 -258.723787) (xy 97.321391 -258.672857) (xy 97.344517 -258.624836)
			(xy 97.374541 -258.580799) (xy 97.410793 -258.541728) (xy 97.452464 -258.508497) (xy 97.498622 -258.481848)
			(xy 97.548236 -258.462376) (xy 97.600198 -258.450516) (xy 97.653348 -258.446533) (xy 97.706498 -258.450516)
			(xy 97.75846 -258.462376) (xy 97.808074 -258.481848) (xy 97.854232 -258.508497) (xy 97.895903 -258.541728)
			(xy 97.932155 -258.580799) (xy 97.962179 -258.624836) (xy 97.985305 -258.672857) (xy 98.001015 -258.723787)
			(xy 98.008958 -258.776491) (xy 98.009456 -258.80314) (xy 98.008958 -258.829789) (xy 98.237538 -258.829789)
			(xy 98.237538 -258.776491) (xy 98.245481 -258.723787) (xy 98.261191 -258.672857) (xy 98.284317 -258.624836)
			(xy 98.314341 -258.580799) (xy 98.350593 -258.541728) (xy 98.392264 -258.508497) (xy 98.438422 -258.481848)
			(xy 98.488036 -258.462376) (xy 98.539998 -258.450516) (xy 98.593148 -258.446533) (xy 98.646298 -258.450516)
			(xy 98.69826 -258.462376) (xy 98.747874 -258.481848) (xy 98.794032 -258.508497) (xy 98.835703 -258.541728)
			(xy 98.871955 -258.580799) (xy 98.901979 -258.624836) (xy 98.925105 -258.672857) (xy 98.940815 -258.723787)
			(xy 98.948758 -258.776491) (xy 98.949256 -258.80314) (xy 98.948758 -258.829789) (xy 98.940815 -258.882493)
			(xy 98.925105 -258.933423) (xy 98.901979 -258.981444) (xy 98.871955 -259.025481) (xy 98.835703 -259.064552)
			(xy 98.794032 -259.097783) (xy 98.747874 -259.124432) (xy 98.69826 -259.143904) (xy 98.646298 -259.155764)
			(xy 98.593148 -259.159748) (xy 98.539998 -259.155764) (xy 98.488036 -259.143904) (xy 98.438422 -259.124432)
			(xy 98.392264 -259.097783) (xy 98.350593 -259.064552) (xy 98.314341 -259.025481) (xy 98.284317 -258.981444)
			(xy 98.261191 -258.933423) (xy 98.245481 -258.882493) (xy 98.237538 -258.829789) (xy 98.008958 -258.829789)
			(xy 98.001015 -258.882493) (xy 97.985305 -258.933423) (xy 97.962179 -258.981444) (xy 97.932155 -259.025481)
			(xy 97.895903 -259.064552) (xy 97.854232 -259.097783) (xy 97.808074 -259.124432) (xy 97.75846 -259.143904)
			(xy 97.706498 -259.155764) (xy 97.653348 -259.159748) (xy 97.600198 -259.155764) (xy 97.548236 -259.143904)
			(xy 97.498622 -259.124432) (xy 97.452464 -259.097783) (xy 97.410793 -259.064552) (xy 97.374541 -259.025481)
			(xy 97.344517 -258.981444) (xy 97.321391 -258.933423) (xy 97.305681 -258.882493) (xy 97.297738 -258.829789)
			(xy 97.069158 -258.829789) (xy 97.061215 -258.882493) (xy 97.045505 -258.933423) (xy 97.022379 -258.981444)
			(xy 96.992355 -259.025481) (xy 96.956103 -259.064552) (xy 96.914432 -259.097783) (xy 96.868274 -259.124432)
			(xy 96.81866 -259.143904) (xy 96.766698 -259.155764) (xy 96.713548 -259.159748) (xy 96.660398 -259.155764)
			(xy 96.608436 -259.143904) (xy 96.558822 -259.124432) (xy 96.512664 -259.097783) (xy 96.470993 -259.064552)
			(xy 96.434741 -259.025481) (xy 96.404717 -258.981444) (xy 96.381591 -258.933423) (xy 96.365881 -258.882493)
			(xy 96.357938 -258.829789) (xy 96.129358 -258.829789) (xy 96.121415 -258.882493) (xy 96.105705 -258.933423)
			(xy 96.082579 -258.981444) (xy 96.052555 -259.025481) (xy 96.016303 -259.064552) (xy 95.974632 -259.097783)
			(xy 95.928474 -259.124432) (xy 95.87886 -259.143904) (xy 95.826898 -259.155764) (xy 95.773748 -259.159748)
			(xy 95.720598 -259.155764) (xy 95.668636 -259.143904) (xy 95.619022 -259.124432) (xy 95.572864 -259.097783)
			(xy 95.531193 -259.064552) (xy 95.494941 -259.025481) (xy 95.464917 -258.981444) (xy 95.441791 -258.933423)
			(xy 95.426081 -258.882493) (xy 95.418138 -258.829789) (xy 95.189304 -258.829789) (xy 95.181361 -258.882493)
			(xy 95.165651 -258.933423) (xy 95.142525 -258.981444) (xy 95.112501 -259.025481) (xy 95.076249 -259.064552)
			(xy 95.034578 -259.097783) (xy 94.98842 -259.124432) (xy 94.938806 -259.143904) (xy 94.886844 -259.155764)
			(xy 94.833694 -259.159748) (xy 94.780544 -259.155764) (xy 94.728582 -259.143904) (xy 94.678968 -259.124432)
			(xy 94.63281 -259.097783) (xy 94.591139 -259.064552) (xy 94.554887 -259.025481) (xy 94.524863 -258.981444)
			(xy 94.501737 -258.933423) (xy 94.486027 -258.882493) (xy 94.478084 -258.829789) (xy 94.249758 -258.829789)
			(xy 94.241815 -258.882493) (xy 94.226105 -258.933423) (xy 94.202979 -258.981444) (xy 94.172955 -259.025481)
			(xy 94.136703 -259.064552) (xy 94.095032 -259.097783) (xy 94.048874 -259.124432) (xy 93.99926 -259.143904)
			(xy 93.947298 -259.155764) (xy 93.894148 -259.159748) (xy 93.840998 -259.155764) (xy 93.789036 -259.143904)
			(xy 93.739422 -259.124432) (xy 93.693264 -259.097783) (xy 93.651593 -259.064552) (xy 93.615341 -259.025481)
			(xy 93.585317 -258.981444) (xy 93.562191 -258.933423) (xy 93.546481 -258.882493) (xy 93.538538 -258.829789)
			(xy 93.309958 -258.829789) (xy 93.302015 -258.882493) (xy 93.286305 -258.933423) (xy 93.263179 -258.981444)
			(xy 93.233155 -259.025481) (xy 93.196903 -259.064552) (xy 93.155232 -259.097783) (xy 93.109074 -259.124432)
			(xy 93.05946 -259.143904) (xy 93.007498 -259.155764) (xy 92.954348 -259.159748) (xy 92.901198 -259.155764)
			(xy 92.849236 -259.143904) (xy 92.799622 -259.124432) (xy 92.753464 -259.097783) (xy 92.711793 -259.064552)
			(xy 92.675541 -259.025481) (xy 92.645517 -258.981444) (xy 92.622391 -258.933423) (xy 92.606681 -258.882493)
			(xy 92.598738 -258.829789) (xy 92.370158 -258.829789) (xy 92.362215 -258.882493) (xy 92.346505 -258.933423)
			(xy 92.323379 -258.981444) (xy 92.293355 -259.025481) (xy 92.257103 -259.064552) (xy 92.215432 -259.097783)
			(xy 92.169274 -259.124432) (xy 92.11966 -259.143904) (xy 92.067698 -259.155764) (xy 92.014548 -259.159748)
			(xy 91.961398 -259.155764) (xy 91.909436 -259.143904) (xy 91.859822 -259.124432) (xy 91.813664 -259.097783)
			(xy 91.771993 -259.064552) (xy 91.735741 -259.025481) (xy 91.705717 -258.981444) (xy 91.682591 -258.933423)
			(xy 91.666881 -258.882493) (xy 91.658938 -258.829789) (xy 91.430358 -258.829789) (xy 91.422415 -258.882493)
			(xy 91.406705 -258.933423) (xy 91.383579 -258.981444) (xy 91.353555 -259.025481) (xy 91.317303 -259.064552)
			(xy 91.275632 -259.097783) (xy 91.229474 -259.124432) (xy 91.17986 -259.143904) (xy 91.127898 -259.155764)
			(xy 91.074748 -259.159748) (xy 91.021598 -259.155764) (xy 90.969636 -259.143904) (xy 90.920022 -259.124432)
			(xy 90.873864 -259.097783) (xy 90.832193 -259.064552) (xy 90.795941 -259.025481) (xy 90.765917 -258.981444)
			(xy 90.742791 -258.933423) (xy 90.727081 -258.882493) (xy 90.719138 -258.829789) (xy 90.490304 -258.829789)
			(xy 90.482361 -258.882493) (xy 90.466651 -258.933423) (xy 90.443525 -258.981444) (xy 90.413501 -259.025481)
			(xy 90.377249 -259.064552) (xy 90.335578 -259.097783) (xy 90.28942 -259.124432) (xy 90.239806 -259.143904)
			(xy 90.187844 -259.155764) (xy 90.134694 -259.159748) (xy 90.081544 -259.155764) (xy 90.029582 -259.143904)
			(xy 89.979968 -259.124432) (xy 89.93381 -259.097783) (xy 89.892139 -259.064552) (xy 89.855887 -259.025481)
			(xy 89.825863 -258.981444) (xy 89.802737 -258.933423) (xy 89.787027 -258.882493) (xy 89.779084 -258.829789)
			(xy 89.549492 -258.829789) (xy 89.547509 -258.856248) (xy 89.535649 -258.908208) (xy 89.516178 -258.957821)
			(xy 89.489529 -259.003977) (xy 89.456298 -259.045646) (xy 89.417229 -259.081897) (xy 89.373193 -259.11192)
			(xy 89.325173 -259.135044) (xy 89.274244 -259.150753) (xy 89.221542 -259.158695) (xy 89.194894 -259.159248)
			(xy 89.16247 -259.158535) (xy 89.098697 -259.146772) (xy 89.068148 -259.13588) (xy 89.054842 -259.131313)
			(xy 89.026826 -259.128886) (xy 88.99921 -259.134189) (xy 88.974086 -259.146822) (xy 88.953359 -259.165826)
			(xy 88.938599 -259.189762) (xy 88.930925 -259.216816) (xy 88.93048 -259.230876) (xy 88.93048 -259.326126)
			(xy 88.951607 -259.341618) (xy 88.989506 -259.377788) (xy 89.021697 -259.419119) (xy 89.047485 -259.464721)
			(xy 89.066315 -259.513609) (xy 89.077779 -259.564728) (xy 89.081631 -259.616975) (xy 89.079672 -259.643605)
			(xy 89.309184 -259.643605) (xy 89.309184 -259.590307) (xy 89.317127 -259.537603) (xy 89.332837 -259.486673)
			(xy 89.355963 -259.438652) (xy 89.385987 -259.394615) (xy 89.422239 -259.355544) (xy 89.46391 -259.322313)
			(xy 89.510068 -259.295664) (xy 89.559682 -259.276192) (xy 89.611644 -259.264332) (xy 89.664794 -259.260349)
			(xy 89.717944 -259.264332) (xy 89.769906 -259.276192) (xy 89.81952 -259.295664) (xy 89.865678 -259.322313)
			(xy 89.907349 -259.355544) (xy 89.943601 -259.394615) (xy 89.973625 -259.438652) (xy 89.996751 -259.486673)
			(xy 90.012461 -259.537603) (xy 90.020404 -259.590307) (xy 90.020902 -259.616956) (xy 90.020404 -259.643605)
			(xy 90.248984 -259.643605) (xy 90.248984 -259.590307) (xy 90.256927 -259.537603) (xy 90.272637 -259.486673)
			(xy 90.295763 -259.438652) (xy 90.325787 -259.394615) (xy 90.362039 -259.355544) (xy 90.40371 -259.322313)
			(xy 90.449868 -259.295664) (xy 90.499482 -259.276192) (xy 90.551444 -259.264332) (xy 90.604594 -259.260349)
			(xy 90.657744 -259.264332) (xy 90.709706 -259.276192) (xy 90.75932 -259.295664) (xy 90.805478 -259.322313)
			(xy 90.847149 -259.355544) (xy 90.883401 -259.394615) (xy 90.913425 -259.438652) (xy 90.936551 -259.486673)
			(xy 90.952261 -259.537603) (xy 90.960204 -259.590307) (xy 90.960702 -259.616956) (xy 90.960204 -259.643605)
			(xy 91.189038 -259.643605) (xy 91.189038 -259.590307) (xy 91.196981 -259.537603) (xy 91.212691 -259.486673)
			(xy 91.235817 -259.438652) (xy 91.265841 -259.394615) (xy 91.302093 -259.355544) (xy 91.343764 -259.322313)
			(xy 91.389922 -259.295664) (xy 91.439536 -259.276192) (xy 91.491498 -259.264332) (xy 91.544648 -259.260349)
			(xy 91.597798 -259.264332) (xy 91.64976 -259.276192) (xy 91.699374 -259.295664) (xy 91.745532 -259.322313)
			(xy 91.787203 -259.355544) (xy 91.823455 -259.394615) (xy 91.853479 -259.438652) (xy 91.876605 -259.486673)
			(xy 91.892315 -259.537603) (xy 91.900258 -259.590307) (xy 91.900756 -259.616956) (xy 91.900258 -259.643605)
			(xy 92.128584 -259.643605) (xy 92.128584 -259.590307) (xy 92.136527 -259.537603) (xy 92.152237 -259.486673)
			(xy 92.175363 -259.438652) (xy 92.205387 -259.394615) (xy 92.241639 -259.355544) (xy 92.28331 -259.322313)
			(xy 92.329468 -259.295664) (xy 92.379082 -259.276192) (xy 92.431044 -259.264332) (xy 92.484194 -259.260349)
			(xy 92.537344 -259.264332) (xy 92.589306 -259.276192) (xy 92.63892 -259.295664) (xy 92.685078 -259.322313)
			(xy 92.726749 -259.355544) (xy 92.763001 -259.394615) (xy 92.793025 -259.438652) (xy 92.816151 -259.486673)
			(xy 92.831861 -259.537603) (xy 92.839804 -259.590307) (xy 92.840302 -259.616956) (xy 92.839804 -259.643605)
			(xy 93.068384 -259.643605) (xy 93.068384 -259.590307) (xy 93.076327 -259.537603) (xy 93.092037 -259.486673)
			(xy 93.115163 -259.438652) (xy 93.145187 -259.394615) (xy 93.181439 -259.355544) (xy 93.22311 -259.322313)
			(xy 93.269268 -259.295664) (xy 93.318882 -259.276192) (xy 93.370844 -259.264332) (xy 93.423994 -259.260349)
			(xy 93.477144 -259.264332) (xy 93.529106 -259.276192) (xy 93.57872 -259.295664) (xy 93.624878 -259.322313)
			(xy 93.666549 -259.355544) (xy 93.702801 -259.394615) (xy 93.732825 -259.438652) (xy 93.755951 -259.486673)
			(xy 93.771661 -259.537603) (xy 93.779604 -259.590307) (xy 93.780102 -259.616956) (xy 93.779604 -259.643605)
			(xy 94.008184 -259.643605) (xy 94.008184 -259.590307) (xy 94.016127 -259.537603) (xy 94.031837 -259.486673)
			(xy 94.054963 -259.438652) (xy 94.084987 -259.394615) (xy 94.121239 -259.355544) (xy 94.16291 -259.322313)
			(xy 94.209068 -259.295664) (xy 94.258682 -259.276192) (xy 94.310644 -259.264332) (xy 94.363794 -259.260349)
			(xy 94.416944 -259.264332) (xy 94.468906 -259.276192) (xy 94.51852 -259.295664) (xy 94.564678 -259.322313)
			(xy 94.606349 -259.355544) (xy 94.642601 -259.394615) (xy 94.672625 -259.438652) (xy 94.695751 -259.486673)
			(xy 94.711461 -259.537603) (xy 94.719404 -259.590307) (xy 94.719902 -259.616956) (xy 94.719404 -259.643605)
			(xy 94.947984 -259.643605) (xy 94.947984 -259.590307) (xy 94.955927 -259.537603) (xy 94.971637 -259.486673)
			(xy 94.994763 -259.438652) (xy 95.024787 -259.394615) (xy 95.061039 -259.355544) (xy 95.10271 -259.322313)
			(xy 95.148868 -259.295664) (xy 95.198482 -259.276192) (xy 95.250444 -259.264332) (xy 95.303594 -259.260349)
			(xy 95.356744 -259.264332) (xy 95.408706 -259.276192) (xy 95.45832 -259.295664) (xy 95.504478 -259.322313)
			(xy 95.546149 -259.355544) (xy 95.582401 -259.394615) (xy 95.612425 -259.438652) (xy 95.635551 -259.486673)
			(xy 95.651261 -259.537603) (xy 95.659204 -259.590307) (xy 95.659702 -259.616956) (xy 95.659204 -259.643605)
			(xy 95.887784 -259.643605) (xy 95.887784 -259.590307) (xy 95.895727 -259.537603) (xy 95.911437 -259.486673)
			(xy 95.934563 -259.438652) (xy 95.964587 -259.394615) (xy 96.000839 -259.355544) (xy 96.04251 -259.322313)
			(xy 96.088668 -259.295664) (xy 96.138282 -259.276192) (xy 96.190244 -259.264332) (xy 96.243394 -259.260349)
			(xy 96.296544 -259.264332) (xy 96.348506 -259.276192) (xy 96.39812 -259.295664) (xy 96.444278 -259.322313)
			(xy 96.485949 -259.355544) (xy 96.522201 -259.394615) (xy 96.552225 -259.438652) (xy 96.575351 -259.486673)
			(xy 96.591061 -259.537603) (xy 96.599004 -259.590307) (xy 96.599502 -259.616956) (xy 96.599004 -259.643605)
			(xy 96.827584 -259.643605) (xy 96.827584 -259.590307) (xy 96.835527 -259.537603) (xy 96.851237 -259.486673)
			(xy 96.874363 -259.438652) (xy 96.904387 -259.394615) (xy 96.940639 -259.355544) (xy 96.98231 -259.322313)
			(xy 97.028468 -259.295664) (xy 97.078082 -259.276192) (xy 97.130044 -259.264332) (xy 97.183194 -259.260349)
			(xy 97.236344 -259.264332) (xy 97.288306 -259.276192) (xy 97.33792 -259.295664) (xy 97.384078 -259.322313)
			(xy 97.425749 -259.355544) (xy 97.462001 -259.394615) (xy 97.492025 -259.438652) (xy 97.515151 -259.486673)
			(xy 97.530861 -259.537603) (xy 97.538804 -259.590307) (xy 97.539302 -259.616956) (xy 97.538804 -259.643605)
			(xy 97.767638 -259.643605) (xy 97.767638 -259.590307) (xy 97.775581 -259.537603) (xy 97.791291 -259.486673)
			(xy 97.814417 -259.438652) (xy 97.844441 -259.394615) (xy 97.880693 -259.355544) (xy 97.922364 -259.322313)
			(xy 97.968522 -259.295664) (xy 98.018136 -259.276192) (xy 98.070098 -259.264332) (xy 98.123248 -259.260349)
			(xy 98.176398 -259.264332) (xy 98.22836 -259.276192) (xy 98.277974 -259.295664) (xy 98.324132 -259.322313)
			(xy 98.365803 -259.355544) (xy 98.402055 -259.394615) (xy 98.432079 -259.438652) (xy 98.455205 -259.486673)
			(xy 98.470915 -259.537603) (xy 98.478858 -259.590307) (xy 98.479356 -259.616956) (xy 98.478858 -259.643605)
			(xy 98.470915 -259.696309) (xy 98.455205 -259.747239) (xy 98.432079 -259.79526) (xy 98.402055 -259.839297)
			(xy 98.365803 -259.878368) (xy 98.324132 -259.911599) (xy 98.277974 -259.938248) (xy 98.22836 -259.95772)
			(xy 98.176398 -259.96958) (xy 98.123248 -259.973564) (xy 98.070098 -259.96958) (xy 98.018136 -259.95772)
			(xy 97.968522 -259.938248) (xy 97.922364 -259.911599) (xy 97.880693 -259.878368) (xy 97.844441 -259.839297)
			(xy 97.814417 -259.79526) (xy 97.791291 -259.747239) (xy 97.775581 -259.696309) (xy 97.767638 -259.643605)
			(xy 97.538804 -259.643605) (xy 97.530861 -259.696309) (xy 97.515151 -259.747239) (xy 97.492025 -259.79526)
			(xy 97.462001 -259.839297) (xy 97.425749 -259.878368) (xy 97.384078 -259.911599) (xy 97.33792 -259.938248)
			(xy 97.288306 -259.95772) (xy 97.236344 -259.96958) (xy 97.183194 -259.973564) (xy 97.130044 -259.96958)
			(xy 97.078082 -259.95772) (xy 97.028468 -259.938248) (xy 96.98231 -259.911599) (xy 96.940639 -259.878368)
			(xy 96.904387 -259.839297) (xy 96.874363 -259.79526) (xy 96.851237 -259.747239) (xy 96.835527 -259.696309)
			(xy 96.827584 -259.643605) (xy 96.599004 -259.643605) (xy 96.591061 -259.696309) (xy 96.575351 -259.747239)
			(xy 96.552225 -259.79526) (xy 96.522201 -259.839297) (xy 96.485949 -259.878368) (xy 96.444278 -259.911599)
			(xy 96.39812 -259.938248) (xy 96.348506 -259.95772) (xy 96.296544 -259.96958) (xy 96.243394 -259.973564)
			(xy 96.190244 -259.96958) (xy 96.138282 -259.95772) (xy 96.088668 -259.938248) (xy 96.04251 -259.911599)
			(xy 96.000839 -259.878368) (xy 95.964587 -259.839297) (xy 95.934563 -259.79526) (xy 95.911437 -259.747239)
			(xy 95.895727 -259.696309) (xy 95.887784 -259.643605) (xy 95.659204 -259.643605) (xy 95.651261 -259.696309)
			(xy 95.635551 -259.747239) (xy 95.612425 -259.79526) (xy 95.582401 -259.839297) (xy 95.546149 -259.878368)
			(xy 95.504478 -259.911599) (xy 95.45832 -259.938248) (xy 95.408706 -259.95772) (xy 95.356744 -259.96958)
			(xy 95.303594 -259.973564) (xy 95.250444 -259.96958) (xy 95.198482 -259.95772) (xy 95.148868 -259.938248)
			(xy 95.10271 -259.911599) (xy 95.061039 -259.878368) (xy 95.024787 -259.839297) (xy 94.994763 -259.79526)
			(xy 94.971637 -259.747239) (xy 94.955927 -259.696309) (xy 94.947984 -259.643605) (xy 94.719404 -259.643605)
			(xy 94.711461 -259.696309) (xy 94.695751 -259.747239) (xy 94.672625 -259.79526) (xy 94.642601 -259.839297)
			(xy 94.606349 -259.878368) (xy 94.564678 -259.911599) (xy 94.51852 -259.938248) (xy 94.468906 -259.95772)
			(xy 94.416944 -259.96958) (xy 94.363794 -259.973564) (xy 94.310644 -259.96958) (xy 94.258682 -259.95772)
			(xy 94.209068 -259.938248) (xy 94.16291 -259.911599) (xy 94.121239 -259.878368) (xy 94.084987 -259.839297)
			(xy 94.054963 -259.79526) (xy 94.031837 -259.747239) (xy 94.016127 -259.696309) (xy 94.008184 -259.643605)
			(xy 93.779604 -259.643605) (xy 93.771661 -259.696309) (xy 93.755951 -259.747239) (xy 93.732825 -259.79526)
			(xy 93.702801 -259.839297) (xy 93.666549 -259.878368) (xy 93.624878 -259.911599) (xy 93.57872 -259.938248)
			(xy 93.529106 -259.95772) (xy 93.477144 -259.96958) (xy 93.423994 -259.973564) (xy 93.370844 -259.96958)
			(xy 93.318882 -259.95772) (xy 93.269268 -259.938248) (xy 93.22311 -259.911599) (xy 93.181439 -259.878368)
			(xy 93.145187 -259.839297) (xy 93.115163 -259.79526) (xy 93.092037 -259.747239) (xy 93.076327 -259.696309)
			(xy 93.068384 -259.643605) (xy 92.839804 -259.643605) (xy 92.831861 -259.696309) (xy 92.816151 -259.747239)
			(xy 92.793025 -259.79526) (xy 92.763001 -259.839297) (xy 92.726749 -259.878368) (xy 92.685078 -259.911599)
			(xy 92.63892 -259.938248) (xy 92.589306 -259.95772) (xy 92.537344 -259.96958) (xy 92.484194 -259.973564)
			(xy 92.431044 -259.96958) (xy 92.379082 -259.95772) (xy 92.329468 -259.938248) (xy 92.28331 -259.911599)
			(xy 92.241639 -259.878368) (xy 92.205387 -259.839297) (xy 92.175363 -259.79526) (xy 92.152237 -259.747239)
			(xy 92.136527 -259.696309) (xy 92.128584 -259.643605) (xy 91.900258 -259.643605) (xy 91.892315 -259.696309)
			(xy 91.876605 -259.747239) (xy 91.853479 -259.79526) (xy 91.823455 -259.839297) (xy 91.787203 -259.878368)
			(xy 91.745532 -259.911599) (xy 91.699374 -259.938248) (xy 91.64976 -259.95772) (xy 91.597798 -259.96958)
			(xy 91.544648 -259.973564) (xy 91.491498 -259.96958) (xy 91.439536 -259.95772) (xy 91.389922 -259.938248)
			(xy 91.343764 -259.911599) (xy 91.302093 -259.878368) (xy 91.265841 -259.839297) (xy 91.235817 -259.79526)
			(xy 91.212691 -259.747239) (xy 91.196981 -259.696309) (xy 91.189038 -259.643605) (xy 90.960204 -259.643605)
			(xy 90.952261 -259.696309) (xy 90.936551 -259.747239) (xy 90.913425 -259.79526) (xy 90.883401 -259.839297)
			(xy 90.847149 -259.878368) (xy 90.805478 -259.911599) (xy 90.75932 -259.938248) (xy 90.709706 -259.95772)
			(xy 90.657744 -259.96958) (xy 90.604594 -259.973564) (xy 90.551444 -259.96958) (xy 90.499482 -259.95772)
			(xy 90.449868 -259.938248) (xy 90.40371 -259.911599) (xy 90.362039 -259.878368) (xy 90.325787 -259.839297)
			(xy 90.295763 -259.79526) (xy 90.272637 -259.747239) (xy 90.256927 -259.696309) (xy 90.248984 -259.643605)
			(xy 90.020404 -259.643605) (xy 90.012461 -259.696309) (xy 89.996751 -259.747239) (xy 89.973625 -259.79526)
			(xy 89.943601 -259.839297) (xy 89.907349 -259.878368) (xy 89.865678 -259.911599) (xy 89.81952 -259.938248)
			(xy 89.769906 -259.95772) (xy 89.717944 -259.96958) (xy 89.664794 -259.973564) (xy 89.611644 -259.96958)
			(xy 89.559682 -259.95772) (xy 89.510068 -259.938248) (xy 89.46391 -259.911599) (xy 89.422239 -259.878368)
			(xy 89.385987 -259.839297) (xy 89.355963 -259.79526) (xy 89.332837 -259.747239) (xy 89.317127 -259.696309)
			(xy 89.309184 -259.643605) (xy 89.079672 -259.643605) (xy 89.077787 -259.669222) (xy 89.06633 -259.720342)
			(xy 89.047507 -259.769233) (xy 89.021725 -259.814838) (xy 88.98954 -259.856174) (xy 88.951646 -259.892349)
			(xy 88.93048 -259.907786) (xy 88.93048 -260.003036) (xy 88.930935 -260.017094) (xy 88.93861 -260.044142)
			(xy 88.953369 -260.068074) (xy 88.974094 -260.087074) (xy 88.999214 -260.099704) (xy 89.026826 -260.105006)
			(xy 89.054837 -260.10258) (xy 89.068148 -260.098032) (xy 89.098694 -260.08713) (xy 89.162469 -260.075366)
			(xy 89.194894 -260.074664) (xy 89.195148 -260.074664) (xy 89.221797 -260.075165) (xy 89.274499 -260.083115)
			(xy 89.325428 -260.098831) (xy 89.373446 -260.121961) (xy 89.41748 -260.151988) (xy 89.456548 -260.188243)
			(xy 89.489776 -260.229915) (xy 89.516423 -260.276074) (xy 89.535894 -260.325689) (xy 89.547753 -260.377651)
			(xy 89.551736 -260.4308) (xy 89.549741 -260.457421) (xy 89.779338 -260.457421) (xy 89.779338 -260.404123)
			(xy 89.787281 -260.351419) (xy 89.802991 -260.300489) (xy 89.826117 -260.252468) (xy 89.856141 -260.208431)
			(xy 89.892393 -260.16936) (xy 89.934064 -260.136129) (xy 89.980222 -260.10948) (xy 90.029836 -260.090008)
			(xy 90.081798 -260.078148) (xy 90.134948 -260.074165) (xy 90.188098 -260.078148) (xy 90.24006 -260.090008)
			(xy 90.289674 -260.10948) (xy 90.335832 -260.136129) (xy 90.377503 -260.16936) (xy 90.413755 -260.208431)
			(xy 90.443779 -260.252468) (xy 90.466905 -260.300489) (xy 90.482615 -260.351419) (xy 90.490558 -260.404123)
			(xy 90.491056 -260.430772) (xy 90.490558 -260.457421) (xy 90.719138 -260.457421) (xy 90.719138 -260.404123)
			(xy 90.727081 -260.351419) (xy 90.742791 -260.300489) (xy 90.765917 -260.252468) (xy 90.795941 -260.208431)
			(xy 90.832193 -260.16936) (xy 90.873864 -260.136129) (xy 90.920022 -260.10948) (xy 90.969636 -260.090008)
			(xy 91.021598 -260.078148) (xy 91.074748 -260.074165) (xy 91.127898 -260.078148) (xy 91.17986 -260.090008)
			(xy 91.229474 -260.10948) (xy 91.275632 -260.136129) (xy 91.317303 -260.16936) (xy 91.353555 -260.208431)
			(xy 91.383579 -260.252468) (xy 91.406705 -260.300489) (xy 91.422415 -260.351419) (xy 91.430358 -260.404123)
			(xy 91.430856 -260.430772) (xy 91.430358 -260.457421) (xy 91.658684 -260.457421) (xy 91.658684 -260.404123)
			(xy 91.666627 -260.351419) (xy 91.682337 -260.300489) (xy 91.705463 -260.252468) (xy 91.735487 -260.208431)
			(xy 91.771739 -260.16936) (xy 91.81341 -260.136129) (xy 91.859568 -260.10948) (xy 91.909182 -260.090008)
			(xy 91.961144 -260.078148) (xy 92.014294 -260.074165) (xy 92.067444 -260.078148) (xy 92.119406 -260.090008)
			(xy 92.16902 -260.10948) (xy 92.215178 -260.136129) (xy 92.256849 -260.16936) (xy 92.293101 -260.208431)
			(xy 92.323125 -260.252468) (xy 92.346251 -260.300489) (xy 92.361961 -260.351419) (xy 92.369904 -260.404123)
			(xy 92.370402 -260.430772) (xy 92.369904 -260.457421) (xy 92.598738 -260.457421) (xy 92.598738 -260.404123)
			(xy 92.606681 -260.351419) (xy 92.622391 -260.300489) (xy 92.645517 -260.252468) (xy 92.675541 -260.208431)
			(xy 92.711793 -260.16936) (xy 92.753464 -260.136129) (xy 92.799622 -260.10948) (xy 92.849236 -260.090008)
			(xy 92.901198 -260.078148) (xy 92.954348 -260.074165) (xy 93.007498 -260.078148) (xy 93.05946 -260.090008)
			(xy 93.109074 -260.10948) (xy 93.155232 -260.136129) (xy 93.196903 -260.16936) (xy 93.233155 -260.208431)
			(xy 93.263179 -260.252468) (xy 93.286305 -260.300489) (xy 93.302015 -260.351419) (xy 93.309958 -260.404123)
			(xy 93.310456 -260.430772) (xy 93.309958 -260.457421) (xy 93.538538 -260.457421) (xy 93.538538 -260.404123)
			(xy 93.546481 -260.351419) (xy 93.562191 -260.300489) (xy 93.585317 -260.252468) (xy 93.615341 -260.208431)
			(xy 93.651593 -260.16936) (xy 93.693264 -260.136129) (xy 93.739422 -260.10948) (xy 93.789036 -260.090008)
			(xy 93.840998 -260.078148) (xy 93.894148 -260.074165) (xy 93.947298 -260.078148) (xy 93.99926 -260.090008)
			(xy 94.048874 -260.10948) (xy 94.095032 -260.136129) (xy 94.136703 -260.16936) (xy 94.172955 -260.208431)
			(xy 94.202979 -260.252468) (xy 94.226105 -260.300489) (xy 94.241815 -260.351419) (xy 94.249758 -260.404123)
			(xy 94.250256 -260.430772) (xy 94.249758 -260.457421) (xy 94.47783 -260.457421) (xy 94.47783 -260.404123)
			(xy 94.485773 -260.351419) (xy 94.501483 -260.300489) (xy 94.524609 -260.252468) (xy 94.554633 -260.208431)
			(xy 94.590885 -260.16936) (xy 94.632556 -260.136129) (xy 94.678714 -260.10948) (xy 94.728328 -260.090008)
			(xy 94.78029 -260.078148) (xy 94.83344 -260.074165) (xy 94.88659 -260.078148) (xy 94.938552 -260.090008)
			(xy 94.988166 -260.10948) (xy 95.034324 -260.136129) (xy 95.075995 -260.16936) (xy 95.112247 -260.208431)
			(xy 95.142271 -260.252468) (xy 95.165397 -260.300489) (xy 95.181107 -260.351419) (xy 95.18905 -260.404123)
			(xy 95.189548 -260.430772) (xy 95.18905 -260.457421) (xy 95.418138 -260.457421) (xy 95.418138 -260.404123)
			(xy 95.426081 -260.351419) (xy 95.441791 -260.300489) (xy 95.464917 -260.252468) (xy 95.494941 -260.208431)
			(xy 95.531193 -260.16936) (xy 95.572864 -260.136129) (xy 95.619022 -260.10948) (xy 95.668636 -260.090008)
			(xy 95.720598 -260.078148) (xy 95.773748 -260.074165) (xy 95.826898 -260.078148) (xy 95.87886 -260.090008)
			(xy 95.928474 -260.10948) (xy 95.974632 -260.136129) (xy 96.016303 -260.16936) (xy 96.052555 -260.208431)
			(xy 96.082579 -260.252468) (xy 96.105705 -260.300489) (xy 96.121415 -260.351419) (xy 96.129358 -260.404123)
			(xy 96.129856 -260.430772) (xy 96.129358 -260.457421) (xy 96.35743 -260.457421) (xy 96.35743 -260.404123)
			(xy 96.365373 -260.351419) (xy 96.381083 -260.300489) (xy 96.404209 -260.252468) (xy 96.434233 -260.208431)
			(xy 96.470485 -260.16936) (xy 96.512156 -260.136129) (xy 96.558314 -260.10948) (xy 96.607928 -260.090008)
			(xy 96.65989 -260.078148) (xy 96.71304 -260.074165) (xy 96.76619 -260.078148) (xy 96.818152 -260.090008)
			(xy 96.867766 -260.10948) (xy 96.913924 -260.136129) (xy 96.955595 -260.16936) (xy 96.991847 -260.208431)
			(xy 97.021871 -260.252468) (xy 97.044997 -260.300489) (xy 97.060707 -260.351419) (xy 97.06865 -260.404123)
			(xy 97.069148 -260.430772) (xy 97.06865 -260.457421) (xy 97.297738 -260.457421) (xy 97.297738 -260.404123)
			(xy 97.305681 -260.351419) (xy 97.321391 -260.300489) (xy 97.344517 -260.252468) (xy 97.374541 -260.208431)
			(xy 97.410793 -260.16936) (xy 97.452464 -260.136129) (xy 97.498622 -260.10948) (xy 97.548236 -260.090008)
			(xy 97.600198 -260.078148) (xy 97.653348 -260.074165) (xy 97.706498 -260.078148) (xy 97.75846 -260.090008)
			(xy 97.808074 -260.10948) (xy 97.854232 -260.136129) (xy 97.895903 -260.16936) (xy 97.932155 -260.208431)
			(xy 97.962179 -260.252468) (xy 97.985305 -260.300489) (xy 98.001015 -260.351419) (xy 98.008958 -260.404123)
			(xy 98.009456 -260.430772) (xy 98.008958 -260.457421) (xy 98.237284 -260.457421) (xy 98.237284 -260.404123)
			(xy 98.245227 -260.351419) (xy 98.260937 -260.300489) (xy 98.284063 -260.252468) (xy 98.314087 -260.208431)
			(xy 98.350339 -260.16936) (xy 98.39201 -260.136129) (xy 98.438168 -260.10948) (xy 98.487782 -260.090008)
			(xy 98.539744 -260.078148) (xy 98.592894 -260.074165) (xy 98.646044 -260.078148) (xy 98.698006 -260.090008)
			(xy 98.74762 -260.10948) (xy 98.793778 -260.136129) (xy 98.835449 -260.16936) (xy 98.871701 -260.208431)
			(xy 98.901725 -260.252468) (xy 98.924851 -260.300489) (xy 98.940561 -260.351419) (xy 98.948504 -260.404123)
			(xy 98.949002 -260.430772) (xy 98.948504 -260.457421) (xy 98.940561 -260.510125) (xy 98.924851 -260.561055)
			(xy 98.901725 -260.609076) (xy 98.871701 -260.653113) (xy 98.835449 -260.692184) (xy 98.793778 -260.725415)
			(xy 98.74762 -260.752064) (xy 98.698006 -260.771536) (xy 98.646044 -260.783396) (xy 98.592894 -260.78738)
			(xy 98.539744 -260.783396) (xy 98.487782 -260.771536) (xy 98.438168 -260.752064) (xy 98.39201 -260.725415)
			(xy 98.350339 -260.692184) (xy 98.314087 -260.653113) (xy 98.284063 -260.609076) (xy 98.260937 -260.561055)
			(xy 98.245227 -260.510125) (xy 98.237284 -260.457421) (xy 98.008958 -260.457421) (xy 98.001015 -260.510125)
			(xy 97.985305 -260.561055) (xy 97.962179 -260.609076) (xy 97.932155 -260.653113) (xy 97.895903 -260.692184)
			(xy 97.854232 -260.725415) (xy 97.808074 -260.752064) (xy 97.75846 -260.771536) (xy 97.706498 -260.783396)
			(xy 97.653348 -260.78738) (xy 97.600198 -260.783396) (xy 97.548236 -260.771536) (xy 97.498622 -260.752064)
			(xy 97.452464 -260.725415) (xy 97.410793 -260.692184) (xy 97.374541 -260.653113) (xy 97.344517 -260.609076)
			(xy 97.321391 -260.561055) (xy 97.305681 -260.510125) (xy 97.297738 -260.457421) (xy 97.06865 -260.457421)
			(xy 97.060707 -260.510125) (xy 97.044997 -260.561055) (xy 97.021871 -260.609076) (xy 96.991847 -260.653113)
			(xy 96.955595 -260.692184) (xy 96.913924 -260.725415) (xy 96.867766 -260.752064) (xy 96.818152 -260.771536)
			(xy 96.76619 -260.783396) (xy 96.71304 -260.78738) (xy 96.65989 -260.783396) (xy 96.607928 -260.771536)
			(xy 96.558314 -260.752064) (xy 96.512156 -260.725415) (xy 96.470485 -260.692184) (xy 96.434233 -260.653113)
			(xy 96.404209 -260.609076) (xy 96.381083 -260.561055) (xy 96.365373 -260.510125) (xy 96.35743 -260.457421)
			(xy 96.129358 -260.457421) (xy 96.121415 -260.510125) (xy 96.105705 -260.561055) (xy 96.082579 -260.609076)
			(xy 96.052555 -260.653113) (xy 96.016303 -260.692184) (xy 95.974632 -260.725415) (xy 95.928474 -260.752064)
			(xy 95.87886 -260.771536) (xy 95.826898 -260.783396) (xy 95.773748 -260.78738) (xy 95.720598 -260.783396)
			(xy 95.668636 -260.771536) (xy 95.619022 -260.752064) (xy 95.572864 -260.725415) (xy 95.531193 -260.692184)
			(xy 95.494941 -260.653113) (xy 95.464917 -260.609076) (xy 95.441791 -260.561055) (xy 95.426081 -260.510125)
			(xy 95.418138 -260.457421) (xy 95.18905 -260.457421) (xy 95.181107 -260.510125) (xy 95.165397 -260.561055)
			(xy 95.142271 -260.609076) (xy 95.112247 -260.653113) (xy 95.075995 -260.692184) (xy 95.034324 -260.725415)
			(xy 94.988166 -260.752064) (xy 94.938552 -260.771536) (xy 94.88659 -260.783396) (xy 94.83344 -260.78738)
			(xy 94.78029 -260.783396) (xy 94.728328 -260.771536) (xy 94.678714 -260.752064) (xy 94.632556 -260.725415)
			(xy 94.590885 -260.692184) (xy 94.554633 -260.653113) (xy 94.524609 -260.609076) (xy 94.501483 -260.561055)
			(xy 94.485773 -260.510125) (xy 94.47783 -260.457421) (xy 94.249758 -260.457421) (xy 94.241815 -260.510125)
			(xy 94.226105 -260.561055) (xy 94.202979 -260.609076) (xy 94.172955 -260.653113) (xy 94.136703 -260.692184)
			(xy 94.095032 -260.725415) (xy 94.048874 -260.752064) (xy 93.99926 -260.771536) (xy 93.947298 -260.783396)
			(xy 93.894148 -260.78738) (xy 93.840998 -260.783396) (xy 93.789036 -260.771536) (xy 93.739422 -260.752064)
			(xy 93.693264 -260.725415) (xy 93.651593 -260.692184) (xy 93.615341 -260.653113) (xy 93.585317 -260.609076)
			(xy 93.562191 -260.561055) (xy 93.546481 -260.510125) (xy 93.538538 -260.457421) (xy 93.309958 -260.457421)
			(xy 93.302015 -260.510125) (xy 93.286305 -260.561055) (xy 93.263179 -260.609076) (xy 93.233155 -260.653113)
			(xy 93.196903 -260.692184) (xy 93.155232 -260.725415) (xy 93.109074 -260.752064) (xy 93.05946 -260.771536)
			(xy 93.007498 -260.783396) (xy 92.954348 -260.78738) (xy 92.901198 -260.783396) (xy 92.849236 -260.771536)
			(xy 92.799622 -260.752064) (xy 92.753464 -260.725415) (xy 92.711793 -260.692184) (xy 92.675541 -260.653113)
			(xy 92.645517 -260.609076) (xy 92.622391 -260.561055) (xy 92.606681 -260.510125) (xy 92.598738 -260.457421)
			(xy 92.369904 -260.457421) (xy 92.361961 -260.510125) (xy 92.346251 -260.561055) (xy 92.323125 -260.609076)
			(xy 92.293101 -260.653113) (xy 92.256849 -260.692184) (xy 92.215178 -260.725415) (xy 92.16902 -260.752064)
			(xy 92.119406 -260.771536) (xy 92.067444 -260.783396) (xy 92.014294 -260.78738) (xy 91.961144 -260.783396)
			(xy 91.909182 -260.771536) (xy 91.859568 -260.752064) (xy 91.81341 -260.725415) (xy 91.771739 -260.692184)
			(xy 91.735487 -260.653113) (xy 91.705463 -260.609076) (xy 91.682337 -260.561055) (xy 91.666627 -260.510125)
			(xy 91.658684 -260.457421) (xy 91.430358 -260.457421) (xy 91.422415 -260.510125) (xy 91.406705 -260.561055)
			(xy 91.383579 -260.609076) (xy 91.353555 -260.653113) (xy 91.317303 -260.692184) (xy 91.275632 -260.725415)
			(xy 91.229474 -260.752064) (xy 91.17986 -260.771536) (xy 91.127898 -260.783396) (xy 91.074748 -260.78738)
			(xy 91.021598 -260.783396) (xy 90.969636 -260.771536) (xy 90.920022 -260.752064) (xy 90.873864 -260.725415)
			(xy 90.832193 -260.692184) (xy 90.795941 -260.653113) (xy 90.765917 -260.609076) (xy 90.742791 -260.561055)
			(xy 90.727081 -260.510125) (xy 90.719138 -260.457421) (xy 90.490558 -260.457421) (xy 90.482615 -260.510125)
			(xy 90.466905 -260.561055) (xy 90.443779 -260.609076) (xy 90.413755 -260.653113) (xy 90.377503 -260.692184)
			(xy 90.335832 -260.725415) (xy 90.289674 -260.752064) (xy 90.24006 -260.771536) (xy 90.188098 -260.783396)
			(xy 90.134948 -260.78738) (xy 90.081798 -260.783396) (xy 90.029836 -260.771536) (xy 89.980222 -260.752064)
			(xy 89.934064 -260.725415) (xy 89.892393 -260.692184) (xy 89.856141 -260.653113) (xy 89.826117 -260.609076)
			(xy 89.802991 -260.561055) (xy 89.787281 -260.510125) (xy 89.779338 -260.457421) (xy 89.549741 -260.457421)
			(xy 89.547753 -260.483949) (xy 89.535894 -260.535911) (xy 89.516423 -260.585526) (xy 89.489776 -260.631685)
			(xy 89.456548 -260.673357) (xy 89.41748 -260.709612) (xy 89.373446 -260.739639) (xy 89.325428 -260.762769)
			(xy 89.274499 -260.778485) (xy 89.221797 -260.786435) (xy 89.195148 -260.78688) (xy 89.194894 -260.78688)
			(xy 89.162473 -260.786139) (xy 89.098704 -260.774377) (xy 89.068148 -260.763512) (xy 89.054844 -260.758944)
			(xy 89.02683 -260.756515) (xy 88.999216 -260.761819) (xy 88.974095 -260.774452) (xy 88.953372 -260.793458)
			(xy 88.938617 -260.817395) (xy 88.930951 -260.844449) (xy 88.93048 -260.858508) (xy 88.93048 -260.954012)
			(xy 88.9516 -260.969505) (xy 88.989487 -261.005672) (xy 89.021666 -261.047) (xy 89.047443 -261.092596)
			(xy 89.066262 -261.141477) (xy 89.077717 -261.192587) (xy 89.08156 -261.244824) (xy 89.079595 -261.271491)
			(xy 89.309184 -261.271491) (xy 89.309184 -261.218193) (xy 89.317127 -261.165489) (xy 89.332837 -261.114559)
			(xy 89.355963 -261.066538) (xy 89.385987 -261.022501) (xy 89.422239 -260.98343) (xy 89.46391 -260.950199)
			(xy 89.510068 -260.92355) (xy 89.559682 -260.904078) (xy 89.611644 -260.892218) (xy 89.664794 -260.888235)
			(xy 89.717944 -260.892218) (xy 89.769906 -260.904078) (xy 89.81952 -260.92355) (xy 89.865678 -260.950199)
			(xy 89.907349 -260.98343) (xy 89.943601 -261.022501) (xy 89.973625 -261.066538) (xy 89.996751 -261.114559)
			(xy 90.012461 -261.165489) (xy 90.020404 -261.218193) (xy 90.020902 -261.244842) (xy 90.020404 -261.271491)
			(xy 90.248984 -261.271491) (xy 90.248984 -261.218193) (xy 90.256927 -261.165489) (xy 90.272637 -261.114559)
			(xy 90.295763 -261.066538) (xy 90.325787 -261.022501) (xy 90.362039 -260.98343) (xy 90.40371 -260.950199)
			(xy 90.449868 -260.92355) (xy 90.499482 -260.904078) (xy 90.551444 -260.892218) (xy 90.604594 -260.888235)
			(xy 90.657744 -260.892218) (xy 90.709706 -260.904078) (xy 90.75932 -260.92355) (xy 90.805478 -260.950199)
			(xy 90.847149 -260.98343) (xy 90.883401 -261.022501) (xy 90.913425 -261.066538) (xy 90.936551 -261.114559)
			(xy 90.952261 -261.165489) (xy 90.960204 -261.218193) (xy 90.960702 -261.244842) (xy 90.960204 -261.271491)
			(xy 91.188784 -261.271491) (xy 91.188784 -261.218193) (xy 91.196727 -261.165489) (xy 91.212437 -261.114559)
			(xy 91.235563 -261.066538) (xy 91.265587 -261.022501) (xy 91.301839 -260.98343) (xy 91.34351 -260.950199)
			(xy 91.389668 -260.92355) (xy 91.439282 -260.904078) (xy 91.491244 -260.892218) (xy 91.544394 -260.888235)
			(xy 91.597544 -260.892218) (xy 91.649506 -260.904078) (xy 91.69912 -260.92355) (xy 91.745278 -260.950199)
			(xy 91.786949 -260.98343) (xy 91.823201 -261.022501) (xy 91.853225 -261.066538) (xy 91.876351 -261.114559)
			(xy 91.892061 -261.165489) (xy 91.900004 -261.218193) (xy 91.900502 -261.244842) (xy 91.900004 -261.271491)
			(xy 92.128584 -261.271491) (xy 92.128584 -261.218193) (xy 92.136527 -261.165489) (xy 92.152237 -261.114559)
			(xy 92.175363 -261.066538) (xy 92.205387 -261.022501) (xy 92.241639 -260.98343) (xy 92.28331 -260.950199)
			(xy 92.329468 -260.92355) (xy 92.379082 -260.904078) (xy 92.431044 -260.892218) (xy 92.484194 -260.888235)
			(xy 92.537344 -260.892218) (xy 92.589306 -260.904078) (xy 92.63892 -260.92355) (xy 92.685078 -260.950199)
			(xy 92.726749 -260.98343) (xy 92.763001 -261.022501) (xy 92.793025 -261.066538) (xy 92.816151 -261.114559)
			(xy 92.831861 -261.165489) (xy 92.839804 -261.218193) (xy 92.840302 -261.244842) (xy 92.839804 -261.271491)
			(xy 93.068384 -261.271491) (xy 93.068384 -261.218193) (xy 93.076327 -261.165489) (xy 93.092037 -261.114559)
			(xy 93.115163 -261.066538) (xy 93.145187 -261.022501) (xy 93.181439 -260.98343) (xy 93.22311 -260.950199)
			(xy 93.269268 -260.92355) (xy 93.318882 -260.904078) (xy 93.370844 -260.892218) (xy 93.423994 -260.888235)
			(xy 93.477144 -260.892218) (xy 93.529106 -260.904078) (xy 93.57872 -260.92355) (xy 93.624878 -260.950199)
			(xy 93.666549 -260.98343) (xy 93.702801 -261.022501) (xy 93.732825 -261.066538) (xy 93.755951 -261.114559)
			(xy 93.771661 -261.165489) (xy 93.779604 -261.218193) (xy 93.780102 -261.244842) (xy 93.779604 -261.271491)
			(xy 94.008184 -261.271491) (xy 94.008184 -261.218193) (xy 94.016127 -261.165489) (xy 94.031837 -261.114559)
			(xy 94.054963 -261.066538) (xy 94.084987 -261.022501) (xy 94.121239 -260.98343) (xy 94.16291 -260.950199)
			(xy 94.209068 -260.92355) (xy 94.258682 -260.904078) (xy 94.310644 -260.892218) (xy 94.363794 -260.888235)
			(xy 94.416944 -260.892218) (xy 94.468906 -260.904078) (xy 94.51852 -260.92355) (xy 94.564678 -260.950199)
			(xy 94.606349 -260.98343) (xy 94.642601 -261.022501) (xy 94.672625 -261.066538) (xy 94.695751 -261.114559)
			(xy 94.711461 -261.165489) (xy 94.719404 -261.218193) (xy 94.719902 -261.244842) (xy 94.719404 -261.271491)
			(xy 94.947984 -261.271491) (xy 94.947984 -261.218193) (xy 94.955927 -261.165489) (xy 94.971637 -261.114559)
			(xy 94.994763 -261.066538) (xy 95.024787 -261.022501) (xy 95.061039 -260.98343) (xy 95.10271 -260.950199)
			(xy 95.148868 -260.92355) (xy 95.198482 -260.904078) (xy 95.250444 -260.892218) (xy 95.303594 -260.888235)
			(xy 95.356744 -260.892218) (xy 95.408706 -260.904078) (xy 95.45832 -260.92355) (xy 95.504478 -260.950199)
			(xy 95.546149 -260.98343) (xy 95.582401 -261.022501) (xy 95.612425 -261.066538) (xy 95.635551 -261.114559)
			(xy 95.651261 -261.165489) (xy 95.659204 -261.218193) (xy 95.659702 -261.244842) (xy 95.659204 -261.271491)
			(xy 95.887784 -261.271491) (xy 95.887784 -261.218193) (xy 95.895727 -261.165489) (xy 95.911437 -261.114559)
			(xy 95.934563 -261.066538) (xy 95.964587 -261.022501) (xy 96.000839 -260.98343) (xy 96.04251 -260.950199)
			(xy 96.088668 -260.92355) (xy 96.138282 -260.904078) (xy 96.190244 -260.892218) (xy 96.243394 -260.888235)
			(xy 96.296544 -260.892218) (xy 96.348506 -260.904078) (xy 96.39812 -260.92355) (xy 96.444278 -260.950199)
			(xy 96.485949 -260.98343) (xy 96.522201 -261.022501) (xy 96.552225 -261.066538) (xy 96.575351 -261.114559)
			(xy 96.591061 -261.165489) (xy 96.599004 -261.218193) (xy 96.599502 -261.244842) (xy 96.599004 -261.271491)
			(xy 96.827584 -261.271491) (xy 96.827584 -261.218193) (xy 96.835527 -261.165489) (xy 96.851237 -261.114559)
			(xy 96.874363 -261.066538) (xy 96.904387 -261.022501) (xy 96.940639 -260.98343) (xy 96.98231 -260.950199)
			(xy 97.028468 -260.92355) (xy 97.078082 -260.904078) (xy 97.130044 -260.892218) (xy 97.183194 -260.888235)
			(xy 97.236344 -260.892218) (xy 97.288306 -260.904078) (xy 97.33792 -260.92355) (xy 97.384078 -260.950199)
			(xy 97.425749 -260.98343) (xy 97.462001 -261.022501) (xy 97.492025 -261.066538) (xy 97.515151 -261.114559)
			(xy 97.530861 -261.165489) (xy 97.538804 -261.218193) (xy 97.539302 -261.244842) (xy 97.538804 -261.271491)
			(xy 97.767384 -261.271491) (xy 97.767384 -261.218193) (xy 97.775327 -261.165489) (xy 97.791037 -261.114559)
			(xy 97.814163 -261.066538) (xy 97.844187 -261.022501) (xy 97.880439 -260.98343) (xy 97.92211 -260.950199)
			(xy 97.968268 -260.92355) (xy 98.017882 -260.904078) (xy 98.069844 -260.892218) (xy 98.122994 -260.888235)
			(xy 98.176144 -260.892218) (xy 98.228106 -260.904078) (xy 98.27772 -260.92355) (xy 98.323878 -260.950199)
			(xy 98.365549 -260.98343) (xy 98.401801 -261.022501) (xy 98.431825 -261.066538) (xy 98.454951 -261.114559)
			(xy 98.470661 -261.165489) (xy 98.478604 -261.218193) (xy 98.479102 -261.244842) (xy 98.478604 -261.271491)
			(xy 98.707184 -261.271491) (xy 98.707184 -261.218193) (xy 98.715127 -261.165489) (xy 98.730837 -261.114559)
			(xy 98.753963 -261.066538) (xy 98.783987 -261.022501) (xy 98.820239 -260.98343) (xy 98.86191 -260.950199)
			(xy 98.908068 -260.92355) (xy 98.957682 -260.904078) (xy 99.009644 -260.892218) (xy 99.062794 -260.888235)
			(xy 99.115944 -260.892218) (xy 99.167906 -260.904078) (xy 99.21752 -260.92355) (xy 99.263678 -260.950199)
			(xy 99.305349 -260.98343) (xy 99.341601 -261.022501) (xy 99.371625 -261.066538) (xy 99.394751 -261.114559)
			(xy 99.410461 -261.165489) (xy 99.418404 -261.218193) (xy 99.418902 -261.244842) (xy 99.418404 -261.271491)
			(xy 99.410461 -261.324195) (xy 99.394751 -261.375125) (xy 99.371625 -261.423146) (xy 99.341601 -261.467183)
			(xy 99.305349 -261.506254) (xy 99.263678 -261.539485) (xy 99.21752 -261.566134) (xy 99.167906 -261.585606)
			(xy 99.115944 -261.597466) (xy 99.062794 -261.60145) (xy 99.009644 -261.597466) (xy 98.957682 -261.585606)
			(xy 98.908068 -261.566134) (xy 98.86191 -261.539485) (xy 98.820239 -261.506254) (xy 98.783987 -261.467183)
			(xy 98.753963 -261.423146) (xy 98.730837 -261.375125) (xy 98.715127 -261.324195) (xy 98.707184 -261.271491)
			(xy 98.478604 -261.271491) (xy 98.470661 -261.324195) (xy 98.454951 -261.375125) (xy 98.431825 -261.423146)
			(xy 98.401801 -261.467183) (xy 98.365549 -261.506254) (xy 98.323878 -261.539485) (xy 98.27772 -261.566134)
			(xy 98.228106 -261.585606) (xy 98.176144 -261.597466) (xy 98.122994 -261.60145) (xy 98.069844 -261.597466)
			(xy 98.017882 -261.585606) (xy 97.968268 -261.566134) (xy 97.92211 -261.539485) (xy 97.880439 -261.506254)
			(xy 97.844187 -261.467183) (xy 97.814163 -261.423146) (xy 97.791037 -261.375125) (xy 97.775327 -261.324195)
			(xy 97.767384 -261.271491) (xy 97.538804 -261.271491) (xy 97.530861 -261.324195) (xy 97.515151 -261.375125)
			(xy 97.492025 -261.423146) (xy 97.462001 -261.467183) (xy 97.425749 -261.506254) (xy 97.384078 -261.539485)
			(xy 97.33792 -261.566134) (xy 97.288306 -261.585606) (xy 97.236344 -261.597466) (xy 97.183194 -261.60145)
			(xy 97.130044 -261.597466) (xy 97.078082 -261.585606) (xy 97.028468 -261.566134) (xy 96.98231 -261.539485)
			(xy 96.940639 -261.506254) (xy 96.904387 -261.467183) (xy 96.874363 -261.423146) (xy 96.851237 -261.375125)
			(xy 96.835527 -261.324195) (xy 96.827584 -261.271491) (xy 96.599004 -261.271491) (xy 96.591061 -261.324195)
			(xy 96.575351 -261.375125) (xy 96.552225 -261.423146) (xy 96.522201 -261.467183) (xy 96.485949 -261.506254)
			(xy 96.444278 -261.539485) (xy 96.39812 -261.566134) (xy 96.348506 -261.585606) (xy 96.296544 -261.597466)
			(xy 96.243394 -261.60145) (xy 96.190244 -261.597466) (xy 96.138282 -261.585606) (xy 96.088668 -261.566134)
			(xy 96.04251 -261.539485) (xy 96.000839 -261.506254) (xy 95.964587 -261.467183) (xy 95.934563 -261.423146)
			(xy 95.911437 -261.375125) (xy 95.895727 -261.324195) (xy 95.887784 -261.271491) (xy 95.659204 -261.271491)
			(xy 95.651261 -261.324195) (xy 95.635551 -261.375125) (xy 95.612425 -261.423146) (xy 95.582401 -261.467183)
			(xy 95.546149 -261.506254) (xy 95.504478 -261.539485) (xy 95.45832 -261.566134) (xy 95.408706 -261.585606)
			(xy 95.356744 -261.597466) (xy 95.303594 -261.60145) (xy 95.250444 -261.597466) (xy 95.198482 -261.585606)
			(xy 95.148868 -261.566134) (xy 95.10271 -261.539485) (xy 95.061039 -261.506254) (xy 95.024787 -261.467183)
			(xy 94.994763 -261.423146) (xy 94.971637 -261.375125) (xy 94.955927 -261.324195) (xy 94.947984 -261.271491)
			(xy 94.719404 -261.271491) (xy 94.711461 -261.324195) (xy 94.695751 -261.375125) (xy 94.672625 -261.423146)
			(xy 94.642601 -261.467183) (xy 94.606349 -261.506254) (xy 94.564678 -261.539485) (xy 94.51852 -261.566134)
			(xy 94.468906 -261.585606) (xy 94.416944 -261.597466) (xy 94.363794 -261.60145) (xy 94.310644 -261.597466)
			(xy 94.258682 -261.585606) (xy 94.209068 -261.566134) (xy 94.16291 -261.539485) (xy 94.121239 -261.506254)
			(xy 94.084987 -261.467183) (xy 94.054963 -261.423146) (xy 94.031837 -261.375125) (xy 94.016127 -261.324195)
			(xy 94.008184 -261.271491) (xy 93.779604 -261.271491) (xy 93.771661 -261.324195) (xy 93.755951 -261.375125)
			(xy 93.732825 -261.423146) (xy 93.702801 -261.467183) (xy 93.666549 -261.506254) (xy 93.624878 -261.539485)
			(xy 93.57872 -261.566134) (xy 93.529106 -261.585606) (xy 93.477144 -261.597466) (xy 93.423994 -261.60145)
			(xy 93.370844 -261.597466) (xy 93.318882 -261.585606) (xy 93.269268 -261.566134) (xy 93.22311 -261.539485)
			(xy 93.181439 -261.506254) (xy 93.145187 -261.467183) (xy 93.115163 -261.423146) (xy 93.092037 -261.375125)
			(xy 93.076327 -261.324195) (xy 93.068384 -261.271491) (xy 92.839804 -261.271491) (xy 92.831861 -261.324195)
			(xy 92.816151 -261.375125) (xy 92.793025 -261.423146) (xy 92.763001 -261.467183) (xy 92.726749 -261.506254)
			(xy 92.685078 -261.539485) (xy 92.63892 -261.566134) (xy 92.589306 -261.585606) (xy 92.537344 -261.597466)
			(xy 92.484194 -261.60145) (xy 92.431044 -261.597466) (xy 92.379082 -261.585606) (xy 92.329468 -261.566134)
			(xy 92.28331 -261.539485) (xy 92.241639 -261.506254) (xy 92.205387 -261.467183) (xy 92.175363 -261.423146)
			(xy 92.152237 -261.375125) (xy 92.136527 -261.324195) (xy 92.128584 -261.271491) (xy 91.900004 -261.271491)
			(xy 91.892061 -261.324195) (xy 91.876351 -261.375125) (xy 91.853225 -261.423146) (xy 91.823201 -261.467183)
			(xy 91.786949 -261.506254) (xy 91.745278 -261.539485) (xy 91.69912 -261.566134) (xy 91.649506 -261.585606)
			(xy 91.597544 -261.597466) (xy 91.544394 -261.60145) (xy 91.491244 -261.597466) (xy 91.439282 -261.585606)
			(xy 91.389668 -261.566134) (xy 91.34351 -261.539485) (xy 91.301839 -261.506254) (xy 91.265587 -261.467183)
			(xy 91.235563 -261.423146) (xy 91.212437 -261.375125) (xy 91.196727 -261.324195) (xy 91.188784 -261.271491)
			(xy 90.960204 -261.271491) (xy 90.952261 -261.324195) (xy 90.936551 -261.375125) (xy 90.913425 -261.423146)
			(xy 90.883401 -261.467183) (xy 90.847149 -261.506254) (xy 90.805478 -261.539485) (xy 90.75932 -261.566134)
			(xy 90.709706 -261.585606) (xy 90.657744 -261.597466) (xy 90.604594 -261.60145) (xy 90.551444 -261.597466)
			(xy 90.499482 -261.585606) (xy 90.449868 -261.566134) (xy 90.40371 -261.539485) (xy 90.362039 -261.506254)
			(xy 90.325787 -261.467183) (xy 90.295763 -261.423146) (xy 90.272637 -261.375125) (xy 90.256927 -261.324195)
			(xy 90.248984 -261.271491) (xy 90.020404 -261.271491) (xy 90.012461 -261.324195) (xy 89.996751 -261.375125)
			(xy 89.973625 -261.423146) (xy 89.943601 -261.467183) (xy 89.907349 -261.506254) (xy 89.865678 -261.539485)
			(xy 89.81952 -261.566134) (xy 89.769906 -261.585606) (xy 89.717944 -261.597466) (xy 89.664794 -261.60145)
			(xy 89.611644 -261.597466) (xy 89.559682 -261.585606) (xy 89.510068 -261.566134) (xy 89.46391 -261.539485)
			(xy 89.422239 -261.506254) (xy 89.385987 -261.467183) (xy 89.355963 -261.423146) (xy 89.332837 -261.375125)
			(xy 89.317127 -261.324195) (xy 89.309184 -261.271491) (xy 89.079595 -261.271491) (xy 89.07771 -261.297061)
			(xy 89.066248 -261.348169) (xy 89.047422 -261.397048) (xy 89.021639 -261.44264) (xy 88.989454 -261.483964)
			(xy 88.951563 -261.520126) (xy 88.93048 -261.535672) (xy 88.93048 -261.630922) (xy 88.930933 -261.644981)
			(xy 88.938606 -261.672033) (xy 88.953365 -261.695968) (xy 88.97409 -261.714971) (xy 88.999212 -261.727603)
			(xy 89.026827 -261.732906) (xy 89.054841 -261.730479) (xy 89.068148 -261.725918) (xy 89.098694 -261.715016)
			(xy 89.162469 -261.703253) (xy 89.194894 -261.70255) (xy 89.195148 -261.70255) (xy 89.221798 -261.703051)
			(xy 89.274502 -261.711002) (xy 89.325433 -261.726718) (xy 89.373453 -261.749848) (xy 89.417489 -261.779877)
			(xy 89.456558 -261.816134) (xy 89.489788 -261.857807) (xy 89.516436 -261.903968) (xy 89.535907 -261.953584)
			(xy 89.547767 -262.005549) (xy 89.55175 -262.0587) (xy 89.549756 -262.085307) (xy 89.779084 -262.085307)
			(xy 89.779084 -262.032009) (xy 89.787027 -261.979305) (xy 89.802737 -261.928375) (xy 89.825863 -261.880354)
			(xy 89.855887 -261.836317) (xy 89.892139 -261.797246) (xy 89.93381 -261.764015) (xy 89.979968 -261.737366)
			(xy 90.029582 -261.717894) (xy 90.081544 -261.706034) (xy 90.134694 -261.702051) (xy 90.187844 -261.706034)
			(xy 90.239806 -261.717894) (xy 90.28942 -261.737366) (xy 90.335578 -261.764015) (xy 90.377249 -261.797246)
			(xy 90.413501 -261.836317) (xy 90.443525 -261.880354) (xy 90.466651 -261.928375) (xy 90.482361 -261.979305)
			(xy 90.490304 -262.032009) (xy 90.490802 -262.058658) (xy 90.490304 -262.085307) (xy 90.718884 -262.085307)
			(xy 90.718884 -262.032009) (xy 90.726827 -261.979305) (xy 90.742537 -261.928375) (xy 90.765663 -261.880354)
			(xy 90.795687 -261.836317) (xy 90.831939 -261.797246) (xy 90.87361 -261.764015) (xy 90.919768 -261.737366)
			(xy 90.969382 -261.717894) (xy 91.021344 -261.706034) (xy 91.074494 -261.702051) (xy 91.127644 -261.706034)
			(xy 91.179606 -261.717894) (xy 91.22922 -261.737366) (xy 91.275378 -261.764015) (xy 91.317049 -261.797246)
			(xy 91.353301 -261.836317) (xy 91.383325 -261.880354) (xy 91.406451 -261.928375) (xy 91.422161 -261.979305)
			(xy 91.430104 -262.032009) (xy 91.430602 -262.058658) (xy 91.430104 -262.085307) (xy 91.658938 -262.085307)
			(xy 91.658938 -262.032009) (xy 91.666881 -261.979305) (xy 91.682591 -261.928375) (xy 91.705717 -261.880354)
			(xy 91.735741 -261.836317) (xy 91.771993 -261.797246) (xy 91.813664 -261.764015) (xy 91.859822 -261.737366)
			(xy 91.909436 -261.717894) (xy 91.961398 -261.706034) (xy 92.014548 -261.702051) (xy 92.067698 -261.706034)
			(xy 92.11966 -261.717894) (xy 92.169274 -261.737366) (xy 92.215432 -261.764015) (xy 92.257103 -261.797246)
			(xy 92.293355 -261.836317) (xy 92.323379 -261.880354) (xy 92.346505 -261.928375) (xy 92.362215 -261.979305)
			(xy 92.370158 -262.032009) (xy 92.370656 -262.058658) (xy 92.370158 -262.085307) (xy 92.598738 -262.085307)
			(xy 92.598738 -262.032009) (xy 92.606681 -261.979305) (xy 92.622391 -261.928375) (xy 92.645517 -261.880354)
			(xy 92.675541 -261.836317) (xy 92.711793 -261.797246) (xy 92.753464 -261.764015) (xy 92.799622 -261.737366)
			(xy 92.849236 -261.717894) (xy 92.901198 -261.706034) (xy 92.954348 -261.702051) (xy 93.007498 -261.706034)
			(xy 93.05946 -261.717894) (xy 93.109074 -261.737366) (xy 93.155232 -261.764015) (xy 93.196903 -261.797246)
			(xy 93.233155 -261.836317) (xy 93.263179 -261.880354) (xy 93.286305 -261.928375) (xy 93.302015 -261.979305)
			(xy 93.309958 -262.032009) (xy 93.310456 -262.058658) (xy 93.309958 -262.085307) (xy 93.538538 -262.085307)
			(xy 93.538538 -262.032009) (xy 93.546481 -261.979305) (xy 93.562191 -261.928375) (xy 93.585317 -261.880354)
			(xy 93.615341 -261.836317) (xy 93.651593 -261.797246) (xy 93.693264 -261.764015) (xy 93.739422 -261.737366)
			(xy 93.789036 -261.717894) (xy 93.840998 -261.706034) (xy 93.894148 -261.702051) (xy 93.947298 -261.706034)
			(xy 93.99926 -261.717894) (xy 94.048874 -261.737366) (xy 94.095032 -261.764015) (xy 94.136703 -261.797246)
			(xy 94.172955 -261.836317) (xy 94.202979 -261.880354) (xy 94.226105 -261.928375) (xy 94.241815 -261.979305)
			(xy 94.249758 -262.032009) (xy 94.250256 -262.058658) (xy 94.249758 -262.085307) (xy 94.478338 -262.085307)
			(xy 94.478338 -262.032009) (xy 94.486281 -261.979305) (xy 94.501991 -261.928375) (xy 94.525117 -261.880354)
			(xy 94.555141 -261.836317) (xy 94.591393 -261.797246) (xy 94.633064 -261.764015) (xy 94.679222 -261.737366)
			(xy 94.728836 -261.717894) (xy 94.780798 -261.706034) (xy 94.833948 -261.702051) (xy 94.887098 -261.706034)
			(xy 94.93906 -261.717894) (xy 94.988674 -261.737366) (xy 95.034832 -261.764015) (xy 95.076503 -261.797246)
			(xy 95.112755 -261.836317) (xy 95.142779 -261.880354) (xy 95.165905 -261.928375) (xy 95.181615 -261.979305)
			(xy 95.189558 -262.032009) (xy 95.190056 -262.058658) (xy 95.189558 -262.085307) (xy 95.418138 -262.085307)
			(xy 95.418138 -262.032009) (xy 95.426081 -261.979305) (xy 95.441791 -261.928375) (xy 95.464917 -261.880354)
			(xy 95.494941 -261.836317) (xy 95.531193 -261.797246) (xy 95.572864 -261.764015) (xy 95.619022 -261.737366)
			(xy 95.668636 -261.717894) (xy 95.720598 -261.706034) (xy 95.773748 -261.702051) (xy 95.826898 -261.706034)
			(xy 95.87886 -261.717894) (xy 95.928474 -261.737366) (xy 95.974632 -261.764015) (xy 96.016303 -261.797246)
			(xy 96.052555 -261.836317) (xy 96.082579 -261.880354) (xy 96.105705 -261.928375) (xy 96.121415 -261.979305)
			(xy 96.129358 -262.032009) (xy 96.129856 -262.058658) (xy 96.129358 -262.085307) (xy 96.357938 -262.085307)
			(xy 96.357938 -262.032009) (xy 96.365881 -261.979305) (xy 96.381591 -261.928375) (xy 96.404717 -261.880354)
			(xy 96.434741 -261.836317) (xy 96.470993 -261.797246) (xy 96.512664 -261.764015) (xy 96.558822 -261.737366)
			(xy 96.608436 -261.717894) (xy 96.660398 -261.706034) (xy 96.713548 -261.702051) (xy 96.766698 -261.706034)
			(xy 96.81866 -261.717894) (xy 96.868274 -261.737366) (xy 96.914432 -261.764015) (xy 96.956103 -261.797246)
			(xy 96.992355 -261.836317) (xy 97.022379 -261.880354) (xy 97.045505 -261.928375) (xy 97.061215 -261.979305)
			(xy 97.069158 -262.032009) (xy 97.069656 -262.058658) (xy 97.069158 -262.085307) (xy 97.297484 -262.085307)
			(xy 97.297484 -262.032009) (xy 97.305427 -261.979305) (xy 97.321137 -261.928375) (xy 97.344263 -261.880354)
			(xy 97.374287 -261.836317) (xy 97.410539 -261.797246) (xy 97.45221 -261.764015) (xy 97.498368 -261.737366)
			(xy 97.547982 -261.717894) (xy 97.599944 -261.706034) (xy 97.653094 -261.702051) (xy 97.706244 -261.706034)
			(xy 97.758206 -261.717894) (xy 97.80782 -261.737366) (xy 97.853978 -261.764015) (xy 97.895649 -261.797246)
			(xy 97.931901 -261.836317) (xy 97.961925 -261.880354) (xy 97.985051 -261.928375) (xy 98.000761 -261.979305)
			(xy 98.008704 -262.032009) (xy 98.009202 -262.058658) (xy 98.008704 -262.085307) (xy 98.237538 -262.085307)
			(xy 98.237538 -262.032009) (xy 98.245481 -261.979305) (xy 98.261191 -261.928375) (xy 98.284317 -261.880354)
			(xy 98.314341 -261.836317) (xy 98.350593 -261.797246) (xy 98.392264 -261.764015) (xy 98.438422 -261.737366)
			(xy 98.488036 -261.717894) (xy 98.539998 -261.706034) (xy 98.593148 -261.702051) (xy 98.646298 -261.706034)
			(xy 98.69826 -261.717894) (xy 98.747874 -261.737366) (xy 98.794032 -261.764015) (xy 98.835703 -261.797246)
			(xy 98.871955 -261.836317) (xy 98.901979 -261.880354) (xy 98.925105 -261.928375) (xy 98.940815 -261.979305)
			(xy 98.948758 -262.032009) (xy 98.949256 -262.058658) (xy 98.948758 -262.085307) (xy 99.177338 -262.085307)
			(xy 99.177338 -262.032009) (xy 99.185281 -261.979305) (xy 99.200991 -261.928375) (xy 99.224117 -261.880354)
			(xy 99.254141 -261.836317) (xy 99.290393 -261.797246) (xy 99.332064 -261.764015) (xy 99.378222 -261.737366)
			(xy 99.427836 -261.717894) (xy 99.479798 -261.706034) (xy 99.532948 -261.702051) (xy 99.586098 -261.706034)
			(xy 99.63806 -261.717894) (xy 99.687674 -261.737366) (xy 99.733832 -261.764015) (xy 99.775503 -261.797246)
			(xy 99.811755 -261.836317) (xy 99.841779 -261.880354) (xy 99.864905 -261.928375) (xy 99.880615 -261.979305)
			(xy 99.888558 -262.032009) (xy 99.889056 -262.058658) (xy 99.888558 -262.085307) (xy 99.880615 -262.138011)
			(xy 99.864905 -262.188941) (xy 99.841779 -262.236962) (xy 99.811755 -262.280999) (xy 99.775503 -262.32007)
			(xy 99.733832 -262.353301) (xy 99.687674 -262.37995) (xy 99.63806 -262.399422) (xy 99.586098 -262.411282)
			(xy 99.532948 -262.415266) (xy 99.479798 -262.411282) (xy 99.427836 -262.399422) (xy 99.378222 -262.37995)
			(xy 99.332064 -262.353301) (xy 99.290393 -262.32007) (xy 99.254141 -262.280999) (xy 99.224117 -262.236962)
			(xy 99.200991 -262.188941) (xy 99.185281 -262.138011) (xy 99.177338 -262.085307) (xy 98.948758 -262.085307)
			(xy 98.940815 -262.138011) (xy 98.925105 -262.188941) (xy 98.901979 -262.236962) (xy 98.871955 -262.280999)
			(xy 98.835703 -262.32007) (xy 98.794032 -262.353301) (xy 98.747874 -262.37995) (xy 98.69826 -262.399422)
			(xy 98.646298 -262.411282) (xy 98.593148 -262.415266) (xy 98.539998 -262.411282) (xy 98.488036 -262.399422)
			(xy 98.438422 -262.37995) (xy 98.392264 -262.353301) (xy 98.350593 -262.32007) (xy 98.314341 -262.280999)
			(xy 98.284317 -262.236962) (xy 98.261191 -262.188941) (xy 98.245481 -262.138011) (xy 98.237538 -262.085307)
			(xy 98.008704 -262.085307) (xy 98.000761 -262.138011) (xy 97.985051 -262.188941) (xy 97.961925 -262.236962)
			(xy 97.931901 -262.280999) (xy 97.895649 -262.32007) (xy 97.853978 -262.353301) (xy 97.80782 -262.37995)
			(xy 97.758206 -262.399422) (xy 97.706244 -262.411282) (xy 97.653094 -262.415266) (xy 97.599944 -262.411282)
			(xy 97.547982 -262.399422) (xy 97.498368 -262.37995) (xy 97.45221 -262.353301) (xy 97.410539 -262.32007)
			(xy 97.374287 -262.280999) (xy 97.344263 -262.236962) (xy 97.321137 -262.188941) (xy 97.305427 -262.138011)
			(xy 97.297484 -262.085307) (xy 97.069158 -262.085307) (xy 97.061215 -262.138011) (xy 97.045505 -262.188941)
			(xy 97.022379 -262.236962) (xy 96.992355 -262.280999) (xy 96.956103 -262.32007) (xy 96.914432 -262.353301)
			(xy 96.868274 -262.37995) (xy 96.81866 -262.399422) (xy 96.766698 -262.411282) (xy 96.713548 -262.415266)
			(xy 96.660398 -262.411282) (xy 96.608436 -262.399422) (xy 96.558822 -262.37995) (xy 96.512664 -262.353301)
			(xy 96.470993 -262.32007) (xy 96.434741 -262.280999) (xy 96.404717 -262.236962) (xy 96.381591 -262.188941)
			(xy 96.365881 -262.138011) (xy 96.357938 -262.085307) (xy 96.129358 -262.085307) (xy 96.121415 -262.138011)
			(xy 96.105705 -262.188941) (xy 96.082579 -262.236962) (xy 96.052555 -262.280999) (xy 96.016303 -262.32007)
			(xy 95.974632 -262.353301) (xy 95.928474 -262.37995) (xy 95.87886 -262.399422) (xy 95.826898 -262.411282)
			(xy 95.773748 -262.415266) (xy 95.720598 -262.411282) (xy 95.668636 -262.399422) (xy 95.619022 -262.37995)
			(xy 95.572864 -262.353301) (xy 95.531193 -262.32007) (xy 95.494941 -262.280999) (xy 95.464917 -262.236962)
			(xy 95.441791 -262.188941) (xy 95.426081 -262.138011) (xy 95.418138 -262.085307) (xy 95.189558 -262.085307)
			(xy 95.181615 -262.138011) (xy 95.165905 -262.188941) (xy 95.142779 -262.236962) (xy 95.112755 -262.280999)
			(xy 95.076503 -262.32007) (xy 95.034832 -262.353301) (xy 94.988674 -262.37995) (xy 94.93906 -262.399422)
			(xy 94.887098 -262.411282) (xy 94.833948 -262.415266) (xy 94.780798 -262.411282) (xy 94.728836 -262.399422)
			(xy 94.679222 -262.37995) (xy 94.633064 -262.353301) (xy 94.591393 -262.32007) (xy 94.555141 -262.280999)
			(xy 94.525117 -262.236962) (xy 94.501991 -262.188941) (xy 94.486281 -262.138011) (xy 94.478338 -262.085307)
			(xy 94.249758 -262.085307) (xy 94.241815 -262.138011) (xy 94.226105 -262.188941) (xy 94.202979 -262.236962)
			(xy 94.172955 -262.280999) (xy 94.136703 -262.32007) (xy 94.095032 -262.353301) (xy 94.048874 -262.37995)
			(xy 93.99926 -262.399422) (xy 93.947298 -262.411282) (xy 93.894148 -262.415266) (xy 93.840998 -262.411282)
			(xy 93.789036 -262.399422) (xy 93.739422 -262.37995) (xy 93.693264 -262.353301) (xy 93.651593 -262.32007)
			(xy 93.615341 -262.280999) (xy 93.585317 -262.236962) (xy 93.562191 -262.188941) (xy 93.546481 -262.138011)
			(xy 93.538538 -262.085307) (xy 93.309958 -262.085307) (xy 93.302015 -262.138011) (xy 93.286305 -262.188941)
			(xy 93.263179 -262.236962) (xy 93.233155 -262.280999) (xy 93.196903 -262.32007) (xy 93.155232 -262.353301)
			(xy 93.109074 -262.37995) (xy 93.05946 -262.399422) (xy 93.007498 -262.411282) (xy 92.954348 -262.415266)
			(xy 92.901198 -262.411282) (xy 92.849236 -262.399422) (xy 92.799622 -262.37995) (xy 92.753464 -262.353301)
			(xy 92.711793 -262.32007) (xy 92.675541 -262.280999) (xy 92.645517 -262.236962) (xy 92.622391 -262.188941)
			(xy 92.606681 -262.138011) (xy 92.598738 -262.085307) (xy 92.370158 -262.085307) (xy 92.362215 -262.138011)
			(xy 92.346505 -262.188941) (xy 92.323379 -262.236962) (xy 92.293355 -262.280999) (xy 92.257103 -262.32007)
			(xy 92.215432 -262.353301) (xy 92.169274 -262.37995) (xy 92.11966 -262.399422) (xy 92.067698 -262.411282)
			(xy 92.014548 -262.415266) (xy 91.961398 -262.411282) (xy 91.909436 -262.399422) (xy 91.859822 -262.37995)
			(xy 91.813664 -262.353301) (xy 91.771993 -262.32007) (xy 91.735741 -262.280999) (xy 91.705717 -262.236962)
			(xy 91.682591 -262.188941) (xy 91.666881 -262.138011) (xy 91.658938 -262.085307) (xy 91.430104 -262.085307)
			(xy 91.422161 -262.138011) (xy 91.406451 -262.188941) (xy 91.383325 -262.236962) (xy 91.353301 -262.280999)
			(xy 91.317049 -262.32007) (xy 91.275378 -262.353301) (xy 91.22922 -262.37995) (xy 91.179606 -262.399422)
			(xy 91.127644 -262.411282) (xy 91.074494 -262.415266) (xy 91.021344 -262.411282) (xy 90.969382 -262.399422)
			(xy 90.919768 -262.37995) (xy 90.87361 -262.353301) (xy 90.831939 -262.32007) (xy 90.795687 -262.280999)
			(xy 90.765663 -262.236962) (xy 90.742537 -262.188941) (xy 90.726827 -262.138011) (xy 90.718884 -262.085307)
			(xy 90.490304 -262.085307) (xy 90.482361 -262.138011) (xy 90.466651 -262.188941) (xy 90.443525 -262.236962)
			(xy 90.413501 -262.280999) (xy 90.377249 -262.32007) (xy 90.335578 -262.353301) (xy 90.28942 -262.37995)
			(xy 90.239806 -262.399422) (xy 90.187844 -262.411282) (xy 90.134694 -262.415266) (xy 90.081544 -262.411282)
			(xy 90.029582 -262.399422) (xy 89.979968 -262.37995) (xy 89.93381 -262.353301) (xy 89.892139 -262.32007)
			(xy 89.855887 -262.280999) (xy 89.825863 -262.236962) (xy 89.802737 -262.188941) (xy 89.787027 -262.138011)
			(xy 89.779084 -262.085307) (xy 89.549756 -262.085307) (xy 89.547767 -262.111851) (xy 89.535907 -262.163816)
			(xy 89.516436 -262.213432) (xy 89.489788 -262.259593) (xy 89.456558 -262.301266) (xy 89.417489 -262.337523)
			(xy 89.373453 -262.367552) (xy 89.325433 -262.390682) (xy 89.274502 -262.406398) (xy 89.221798 -262.414349)
			(xy 89.195148 -262.414766) (xy 89.194894 -262.414766) (xy 89.162473 -262.414024) (xy 89.098704 -262.402263)
			(xy 89.068148 -262.391398) (xy 89.054843 -262.386831) (xy 89.026828 -262.384402) (xy 88.999213 -262.389706)
			(xy 88.974091 -262.402339) (xy 88.953366 -262.421344) (xy 88.938609 -262.445281) (xy 88.930939 -262.472334)
			(xy 88.93048 -262.486394) (xy 88.93048 -262.581644) (xy 88.951606 -262.597136) (xy 88.989502 -262.633305)
			(xy 89.02169 -262.674636) (xy 89.047477 -262.720237) (xy 89.066304 -262.769123) (xy 89.077766 -262.82024)
			(xy 89.081616 -262.872485) (xy 89.079656 -262.899123) (xy 89.309184 -262.899123) (xy 89.309184 -262.845825)
			(xy 89.317127 -262.793121) (xy 89.332837 -262.742191) (xy 89.355963 -262.69417) (xy 89.385987 -262.650133)
			(xy 89.422239 -262.611062) (xy 89.46391 -262.577831) (xy 89.510068 -262.551182) (xy 89.559682 -262.53171)
			(xy 89.611644 -262.51985) (xy 89.664794 -262.515867) (xy 89.717944 -262.51985) (xy 89.769906 -262.53171)
			(xy 89.81952 -262.551182) (xy 89.865678 -262.577831) (xy 89.907349 -262.611062) (xy 89.943601 -262.650133)
			(xy 89.973625 -262.69417) (xy 89.996751 -262.742191) (xy 90.012461 -262.793121) (xy 90.020404 -262.845825)
			(xy 90.020902 -262.872474) (xy 90.020404 -262.899123) (xy 90.249238 -262.899123) (xy 90.249238 -262.845825)
			(xy 90.257181 -262.793121) (xy 90.272891 -262.742191) (xy 90.296017 -262.69417) (xy 90.326041 -262.650133)
			(xy 90.362293 -262.611062) (xy 90.403964 -262.577831) (xy 90.450122 -262.551182) (xy 90.499736 -262.53171)
			(xy 90.551698 -262.51985) (xy 90.604848 -262.515867) (xy 90.657998 -262.51985) (xy 90.70996 -262.53171)
			(xy 90.759574 -262.551182) (xy 90.805732 -262.577831) (xy 90.847403 -262.611062) (xy 90.883655 -262.650133)
			(xy 90.913679 -262.69417) (xy 90.936805 -262.742191) (xy 90.952515 -262.793121) (xy 90.960458 -262.845825)
			(xy 90.960956 -262.872474) (xy 90.960458 -262.899123) (xy 91.188784 -262.899123) (xy 91.188784 -262.845825)
			(xy 91.196727 -262.793121) (xy 91.212437 -262.742191) (xy 91.235563 -262.69417) (xy 91.265587 -262.650133)
			(xy 91.301839 -262.611062) (xy 91.34351 -262.577831) (xy 91.389668 -262.551182) (xy 91.439282 -262.53171)
			(xy 91.491244 -262.51985) (xy 91.544394 -262.515867) (xy 91.597544 -262.51985) (xy 91.649506 -262.53171)
			(xy 91.69912 -262.551182) (xy 91.745278 -262.577831) (xy 91.786949 -262.611062) (xy 91.823201 -262.650133)
			(xy 91.853225 -262.69417) (xy 91.876351 -262.742191) (xy 91.892061 -262.793121) (xy 91.900004 -262.845825)
			(xy 91.900502 -262.872474) (xy 91.900004 -262.899123) (xy 92.128584 -262.899123) (xy 92.128584 -262.845825)
			(xy 92.136527 -262.793121) (xy 92.152237 -262.742191) (xy 92.175363 -262.69417) (xy 92.205387 -262.650133)
			(xy 92.241639 -262.611062) (xy 92.28331 -262.577831) (xy 92.329468 -262.551182) (xy 92.379082 -262.53171)
			(xy 92.431044 -262.51985) (xy 92.484194 -262.515867) (xy 92.537344 -262.51985) (xy 92.589306 -262.53171)
			(xy 92.63892 -262.551182) (xy 92.685078 -262.577831) (xy 92.726749 -262.611062) (xy 92.763001 -262.650133)
			(xy 92.793025 -262.69417) (xy 92.816151 -262.742191) (xy 92.831861 -262.793121) (xy 92.839804 -262.845825)
			(xy 92.840302 -262.872474) (xy 92.839804 -262.899123) (xy 93.068384 -262.899123) (xy 93.068384 -262.845825)
			(xy 93.076327 -262.793121) (xy 93.092037 -262.742191) (xy 93.115163 -262.69417) (xy 93.145187 -262.650133)
			(xy 93.181439 -262.611062) (xy 93.22311 -262.577831) (xy 93.269268 -262.551182) (xy 93.318882 -262.53171)
			(xy 93.370844 -262.51985) (xy 93.423994 -262.515867) (xy 93.477144 -262.51985) (xy 93.529106 -262.53171)
			(xy 93.57872 -262.551182) (xy 93.624878 -262.577831) (xy 93.666549 -262.611062) (xy 93.702801 -262.650133)
			(xy 93.732825 -262.69417) (xy 93.755951 -262.742191) (xy 93.771661 -262.793121) (xy 93.779604 -262.845825)
			(xy 93.780102 -262.872474) (xy 93.779604 -262.899123) (xy 94.008184 -262.899123) (xy 94.008184 -262.845825)
			(xy 94.016127 -262.793121) (xy 94.031837 -262.742191) (xy 94.054963 -262.69417) (xy 94.084987 -262.650133)
			(xy 94.121239 -262.611062) (xy 94.16291 -262.577831) (xy 94.209068 -262.551182) (xy 94.258682 -262.53171)
			(xy 94.310644 -262.51985) (xy 94.363794 -262.515867) (xy 94.416944 -262.51985) (xy 94.468906 -262.53171)
			(xy 94.51852 -262.551182) (xy 94.564678 -262.577831) (xy 94.606349 -262.611062) (xy 94.642601 -262.650133)
			(xy 94.672625 -262.69417) (xy 94.695751 -262.742191) (xy 94.711461 -262.793121) (xy 94.719404 -262.845825)
			(xy 94.719902 -262.872474) (xy 94.719404 -262.899123) (xy 94.947984 -262.899123) (xy 94.947984 -262.845825)
			(xy 94.955927 -262.793121) (xy 94.971637 -262.742191) (xy 94.994763 -262.69417) (xy 95.024787 -262.650133)
			(xy 95.061039 -262.611062) (xy 95.10271 -262.577831) (xy 95.148868 -262.551182) (xy 95.198482 -262.53171)
			(xy 95.250444 -262.51985) (xy 95.303594 -262.515867) (xy 95.356744 -262.51985) (xy 95.408706 -262.53171)
			(xy 95.45832 -262.551182) (xy 95.504478 -262.577831) (xy 95.546149 -262.611062) (xy 95.582401 -262.650133)
			(xy 95.612425 -262.69417) (xy 95.635551 -262.742191) (xy 95.651261 -262.793121) (xy 95.659204 -262.845825)
			(xy 95.659702 -262.872474) (xy 95.659204 -262.899123) (xy 95.887784 -262.899123) (xy 95.887784 -262.845825)
			(xy 95.895727 -262.793121) (xy 95.911437 -262.742191) (xy 95.934563 -262.69417) (xy 95.964587 -262.650133)
			(xy 96.000839 -262.611062) (xy 96.04251 -262.577831) (xy 96.088668 -262.551182) (xy 96.138282 -262.53171)
			(xy 96.190244 -262.51985) (xy 96.243394 -262.515867) (xy 96.296544 -262.51985) (xy 96.348506 -262.53171)
			(xy 96.39812 -262.551182) (xy 96.444278 -262.577831) (xy 96.485949 -262.611062) (xy 96.522201 -262.650133)
			(xy 96.552225 -262.69417) (xy 96.575351 -262.742191) (xy 96.591061 -262.793121) (xy 96.599004 -262.845825)
			(xy 96.599502 -262.872474) (xy 96.599004 -262.899123) (xy 96.827838 -262.899123) (xy 96.827838 -262.845825)
			(xy 96.835781 -262.793121) (xy 96.851491 -262.742191) (xy 96.874617 -262.69417) (xy 96.904641 -262.650133)
			(xy 96.940893 -262.611062) (xy 96.982564 -262.577831) (xy 97.028722 -262.551182) (xy 97.078336 -262.53171)
			(xy 97.130298 -262.51985) (xy 97.183448 -262.515867) (xy 97.236598 -262.51985) (xy 97.28856 -262.53171)
			(xy 97.338174 -262.551182) (xy 97.384332 -262.577831) (xy 97.426003 -262.611062) (xy 97.462255 -262.650133)
			(xy 97.492279 -262.69417) (xy 97.515405 -262.742191) (xy 97.531115 -262.793121) (xy 97.539058 -262.845825)
			(xy 97.539556 -262.872474) (xy 97.539058 -262.899123) (xy 97.767384 -262.899123) (xy 97.767384 -262.845825)
			(xy 97.775327 -262.793121) (xy 97.791037 -262.742191) (xy 97.814163 -262.69417) (xy 97.844187 -262.650133)
			(xy 97.880439 -262.611062) (xy 97.92211 -262.577831) (xy 97.968268 -262.551182) (xy 98.017882 -262.53171)
			(xy 98.069844 -262.51985) (xy 98.122994 -262.515867) (xy 98.176144 -262.51985) (xy 98.228106 -262.53171)
			(xy 98.27772 -262.551182) (xy 98.323878 -262.577831) (xy 98.365549 -262.611062) (xy 98.401801 -262.650133)
			(xy 98.431825 -262.69417) (xy 98.454951 -262.742191) (xy 98.470661 -262.793121) (xy 98.478604 -262.845825)
			(xy 98.479102 -262.872474) (xy 98.478604 -262.899123) (xy 98.707184 -262.899123) (xy 98.707184 -262.845825)
			(xy 98.715127 -262.793121) (xy 98.730837 -262.742191) (xy 98.753963 -262.69417) (xy 98.783987 -262.650133)
			(xy 98.820239 -262.611062) (xy 98.86191 -262.577831) (xy 98.908068 -262.551182) (xy 98.957682 -262.53171)
			(xy 99.009644 -262.51985) (xy 99.062794 -262.515867) (xy 99.115944 -262.51985) (xy 99.167906 -262.53171)
			(xy 99.21752 -262.551182) (xy 99.263678 -262.577831) (xy 99.305349 -262.611062) (xy 99.341601 -262.650133)
			(xy 99.371625 -262.69417) (xy 99.394751 -262.742191) (xy 99.410461 -262.793121) (xy 99.418404 -262.845825)
			(xy 99.418902 -262.872474) (xy 99.418404 -262.899123) (xy 99.646984 -262.899123) (xy 99.646984 -262.845825)
			(xy 99.654927 -262.793121) (xy 99.670637 -262.742191) (xy 99.693763 -262.69417) (xy 99.723787 -262.650133)
			(xy 99.760039 -262.611062) (xy 99.80171 -262.577831) (xy 99.847868 -262.551182) (xy 99.897482 -262.53171)
			(xy 99.949444 -262.51985) (xy 100.002594 -262.515867) (xy 100.055744 -262.51985) (xy 100.107706 -262.53171)
			(xy 100.15732 -262.551182) (xy 100.203478 -262.577831) (xy 100.245149 -262.611062) (xy 100.281401 -262.650133)
			(xy 100.311425 -262.69417) (xy 100.334551 -262.742191) (xy 100.350261 -262.793121) (xy 100.358204 -262.845825)
			(xy 100.358702 -262.872474) (xy 100.358204 -262.899123) (xy 100.586784 -262.899123) (xy 100.586784 -262.845825)
			(xy 100.594727 -262.793121) (xy 100.610437 -262.742191) (xy 100.633563 -262.69417) (xy 100.663587 -262.650133)
			(xy 100.699839 -262.611062) (xy 100.74151 -262.577831) (xy 100.787668 -262.551182) (xy 100.837282 -262.53171)
			(xy 100.889244 -262.51985) (xy 100.942394 -262.515867) (xy 100.995544 -262.51985) (xy 101.047506 -262.53171)
			(xy 101.09712 -262.551182) (xy 101.143278 -262.577831) (xy 101.184949 -262.611062) (xy 101.221201 -262.650133)
			(xy 101.251225 -262.69417) (xy 101.274351 -262.742191) (xy 101.290061 -262.793121) (xy 101.298004 -262.845825)
			(xy 101.298502 -262.872474) (xy 101.298004 -262.899123) (xy 101.290061 -262.951827) (xy 101.274351 -263.002757)
			(xy 101.251225 -263.050778) (xy 101.221201 -263.094815) (xy 101.184949 -263.133886) (xy 101.143278 -263.167117)
			(xy 101.09712 -263.193766) (xy 101.047506 -263.213238) (xy 100.995544 -263.225098) (xy 100.942394 -263.229082)
			(xy 100.889244 -263.225098) (xy 100.837282 -263.213238) (xy 100.787668 -263.193766) (xy 100.74151 -263.167117)
			(xy 100.699839 -263.133886) (xy 100.663587 -263.094815) (xy 100.633563 -263.050778) (xy 100.610437 -263.002757)
			(xy 100.594727 -262.951827) (xy 100.586784 -262.899123) (xy 100.358204 -262.899123) (xy 100.350261 -262.951827)
			(xy 100.334551 -263.002757) (xy 100.311425 -263.050778) (xy 100.281401 -263.094815) (xy 100.245149 -263.133886)
			(xy 100.203478 -263.167117) (xy 100.15732 -263.193766) (xy 100.107706 -263.213238) (xy 100.055744 -263.225098)
			(xy 100.002594 -263.229082) (xy 99.949444 -263.225098) (xy 99.897482 -263.213238) (xy 99.847868 -263.193766)
			(xy 99.80171 -263.167117) (xy 99.760039 -263.133886) (xy 99.723787 -263.094815) (xy 99.693763 -263.050778)
			(xy 99.670637 -263.002757) (xy 99.654927 -262.951827) (xy 99.646984 -262.899123) (xy 99.418404 -262.899123)
			(xy 99.410461 -262.951827) (xy 99.394751 -263.002757) (xy 99.371625 -263.050778) (xy 99.341601 -263.094815)
			(xy 99.305349 -263.133886) (xy 99.263678 -263.167117) (xy 99.21752 -263.193766) (xy 99.167906 -263.213238)
			(xy 99.115944 -263.225098) (xy 99.062794 -263.229082) (xy 99.009644 -263.225098) (xy 98.957682 -263.213238)
			(xy 98.908068 -263.193766) (xy 98.86191 -263.167117) (xy 98.820239 -263.133886) (xy 98.783987 -263.094815)
			(xy 98.753963 -263.050778) (xy 98.730837 -263.002757) (xy 98.715127 -262.951827) (xy 98.707184 -262.899123)
			(xy 98.478604 -262.899123) (xy 98.470661 -262.951827) (xy 98.454951 -263.002757) (xy 98.431825 -263.050778)
			(xy 98.401801 -263.094815) (xy 98.365549 -263.133886) (xy 98.323878 -263.167117) (xy 98.27772 -263.193766)
			(xy 98.228106 -263.213238) (xy 98.176144 -263.225098) (xy 98.122994 -263.229082) (xy 98.069844 -263.225098)
			(xy 98.017882 -263.213238) (xy 97.968268 -263.193766) (xy 97.92211 -263.167117) (xy 97.880439 -263.133886)
			(xy 97.844187 -263.094815) (xy 97.814163 -263.050778) (xy 97.791037 -263.002757) (xy 97.775327 -262.951827)
			(xy 97.767384 -262.899123) (xy 97.539058 -262.899123) (xy 97.531115 -262.951827) (xy 97.515405 -263.002757)
			(xy 97.492279 -263.050778) (xy 97.462255 -263.094815) (xy 97.426003 -263.133886) (xy 97.384332 -263.167117)
			(xy 97.338174 -263.193766) (xy 97.28856 -263.213238) (xy 97.236598 -263.225098) (xy 97.183448 -263.229082)
			(xy 97.130298 -263.225098) (xy 97.078336 -263.213238) (xy 97.028722 -263.193766) (xy 96.982564 -263.167117)
			(xy 96.940893 -263.133886) (xy 96.904641 -263.094815) (xy 96.874617 -263.050778) (xy 96.851491 -263.002757)
			(xy 96.835781 -262.951827) (xy 96.827838 -262.899123) (xy 96.599004 -262.899123) (xy 96.591061 -262.951827)
			(xy 96.575351 -263.002757) (xy 96.552225 -263.050778) (xy 96.522201 -263.094815) (xy 96.485949 -263.133886)
			(xy 96.444278 -263.167117) (xy 96.39812 -263.193766) (xy 96.348506 -263.213238) (xy 96.296544 -263.225098)
			(xy 96.243394 -263.229082) (xy 96.190244 -263.225098) (xy 96.138282 -263.213238) (xy 96.088668 -263.193766)
			(xy 96.04251 -263.167117) (xy 96.000839 -263.133886) (xy 95.964587 -263.094815) (xy 95.934563 -263.050778)
			(xy 95.911437 -263.002757) (xy 95.895727 -262.951827) (xy 95.887784 -262.899123) (xy 95.659204 -262.899123)
			(xy 95.651261 -262.951827) (xy 95.635551 -263.002757) (xy 95.612425 -263.050778) (xy 95.582401 -263.094815)
			(xy 95.546149 -263.133886) (xy 95.504478 -263.167117) (xy 95.45832 -263.193766) (xy 95.408706 -263.213238)
			(xy 95.356744 -263.225098) (xy 95.303594 -263.229082) (xy 95.250444 -263.225098) (xy 95.198482 -263.213238)
			(xy 95.148868 -263.193766) (xy 95.10271 -263.167117) (xy 95.061039 -263.133886) (xy 95.024787 -263.094815)
			(xy 94.994763 -263.050778) (xy 94.971637 -263.002757) (xy 94.955927 -262.951827) (xy 94.947984 -262.899123)
			(xy 94.719404 -262.899123) (xy 94.711461 -262.951827) (xy 94.695751 -263.002757) (xy 94.672625 -263.050778)
			(xy 94.642601 -263.094815) (xy 94.606349 -263.133886) (xy 94.564678 -263.167117) (xy 94.51852 -263.193766)
			(xy 94.468906 -263.213238) (xy 94.416944 -263.225098) (xy 94.363794 -263.229082) (xy 94.310644 -263.225098)
			(xy 94.258682 -263.213238) (xy 94.209068 -263.193766) (xy 94.16291 -263.167117) (xy 94.121239 -263.133886)
			(xy 94.084987 -263.094815) (xy 94.054963 -263.050778) (xy 94.031837 -263.002757) (xy 94.016127 -262.951827)
			(xy 94.008184 -262.899123) (xy 93.779604 -262.899123) (xy 93.771661 -262.951827) (xy 93.755951 -263.002757)
			(xy 93.732825 -263.050778) (xy 93.702801 -263.094815) (xy 93.666549 -263.133886) (xy 93.624878 -263.167117)
			(xy 93.57872 -263.193766) (xy 93.529106 -263.213238) (xy 93.477144 -263.225098) (xy 93.423994 -263.229082)
			(xy 93.370844 -263.225098) (xy 93.318882 -263.213238) (xy 93.269268 -263.193766) (xy 93.22311 -263.167117)
			(xy 93.181439 -263.133886) (xy 93.145187 -263.094815) (xy 93.115163 -263.050778) (xy 93.092037 -263.002757)
			(xy 93.076327 -262.951827) (xy 93.068384 -262.899123) (xy 92.839804 -262.899123) (xy 92.831861 -262.951827)
			(xy 92.816151 -263.002757) (xy 92.793025 -263.050778) (xy 92.763001 -263.094815) (xy 92.726749 -263.133886)
			(xy 92.685078 -263.167117) (xy 92.63892 -263.193766) (xy 92.589306 -263.213238) (xy 92.537344 -263.225098)
			(xy 92.484194 -263.229082) (xy 92.431044 -263.225098) (xy 92.379082 -263.213238) (xy 92.329468 -263.193766)
			(xy 92.28331 -263.167117) (xy 92.241639 -263.133886) (xy 92.205387 -263.094815) (xy 92.175363 -263.050778)
			(xy 92.152237 -263.002757) (xy 92.136527 -262.951827) (xy 92.128584 -262.899123) (xy 91.900004 -262.899123)
			(xy 91.892061 -262.951827) (xy 91.876351 -263.002757) (xy 91.853225 -263.050778) (xy 91.823201 -263.094815)
			(xy 91.786949 -263.133886) (xy 91.745278 -263.167117) (xy 91.69912 -263.193766) (xy 91.649506 -263.213238)
			(xy 91.597544 -263.225098) (xy 91.544394 -263.229082) (xy 91.491244 -263.225098) (xy 91.439282 -263.213238)
			(xy 91.389668 -263.193766) (xy 91.34351 -263.167117) (xy 91.301839 -263.133886) (xy 91.265587 -263.094815)
			(xy 91.235563 -263.050778) (xy 91.212437 -263.002757) (xy 91.196727 -262.951827) (xy 91.188784 -262.899123)
			(xy 90.960458 -262.899123) (xy 90.952515 -262.951827) (xy 90.936805 -263.002757) (xy 90.913679 -263.050778)
			(xy 90.883655 -263.094815) (xy 90.847403 -263.133886) (xy 90.805732 -263.167117) (xy 90.759574 -263.193766)
			(xy 90.70996 -263.213238) (xy 90.657998 -263.225098) (xy 90.604848 -263.229082) (xy 90.551698 -263.225098)
			(xy 90.499736 -263.213238) (xy 90.450122 -263.193766) (xy 90.403964 -263.167117) (xy 90.362293 -263.133886)
			(xy 90.326041 -263.094815) (xy 90.296017 -263.050778) (xy 90.272891 -263.002757) (xy 90.257181 -262.951827)
			(xy 90.249238 -262.899123) (xy 90.020404 -262.899123) (xy 90.012461 -262.951827) (xy 89.996751 -263.002757)
			(xy 89.973625 -263.050778) (xy 89.943601 -263.094815) (xy 89.907349 -263.133886) (xy 89.865678 -263.167117)
			(xy 89.81952 -263.193766) (xy 89.769906 -263.213238) (xy 89.717944 -263.225098) (xy 89.664794 -263.229082)
			(xy 89.611644 -263.225098) (xy 89.559682 -263.213238) (xy 89.510068 -263.193766) (xy 89.46391 -263.167117)
			(xy 89.422239 -263.133886) (xy 89.385987 -263.094815) (xy 89.355963 -263.050778) (xy 89.332837 -263.002757)
			(xy 89.317127 -262.951827) (xy 89.309184 -262.899123) (xy 89.079656 -262.899123) (xy 89.077771 -262.92473)
			(xy 89.066313 -262.975848) (xy 89.047489 -263.024736) (xy 89.021707 -263.070339) (xy 88.989522 -263.111672)
			(xy 88.951629 -263.147845) (xy 88.93048 -263.163304) (xy 88.93048 -263.258808) (xy 88.930931 -263.272869)
			(xy 88.938602 -263.299924) (xy 88.95336 -263.323862) (xy 88.974087 -263.342869) (xy 88.999211 -263.355503)
			(xy 89.026828 -263.360806) (xy 89.054844 -263.358378) (xy 89.068148 -263.353804) (xy 89.098701 -263.34293)
			(xy 89.162472 -263.331168) (xy 89.194894 -263.330436) (xy 89.221542 -263.330909) (xy 89.274243 -263.338851)
			(xy 89.325172 -263.35456) (xy 89.373191 -263.377684) (xy 89.417226 -263.407706) (xy 89.456296 -263.443956)
			(xy 89.489526 -263.485625) (xy 89.516174 -263.531781) (xy 89.535645 -263.581393) (xy 89.547505 -263.633353)
			(xy 89.551488 -263.6865) (xy 89.549488 -263.713193) (xy 89.779084 -263.713193) (xy 89.779084 -263.659895)
			(xy 89.787027 -263.607191) (xy 89.802737 -263.556261) (xy 89.825863 -263.50824) (xy 89.855887 -263.464203)
			(xy 89.892139 -263.425132) (xy 89.93381 -263.391901) (xy 89.979968 -263.365252) (xy 90.029582 -263.34578)
			(xy 90.081544 -263.33392) (xy 90.134694 -263.329937) (xy 90.187844 -263.33392) (xy 90.239806 -263.34578)
			(xy 90.28942 -263.365252) (xy 90.335578 -263.391901) (xy 90.377249 -263.425132) (xy 90.413501 -263.464203)
			(xy 90.443525 -263.50824) (xy 90.466651 -263.556261) (xy 90.482361 -263.607191) (xy 90.490304 -263.659895)
			(xy 90.490802 -263.686544) (xy 90.490304 -263.713193) (xy 90.719138 -263.713193) (xy 90.719138 -263.659895)
			(xy 90.727081 -263.607191) (xy 90.742791 -263.556261) (xy 90.765917 -263.50824) (xy 90.795941 -263.464203)
			(xy 90.832193 -263.425132) (xy 90.873864 -263.391901) (xy 90.920022 -263.365252) (xy 90.969636 -263.34578)
			(xy 91.021598 -263.33392) (xy 91.074748 -263.329937) (xy 91.127898 -263.33392) (xy 91.17986 -263.34578)
			(xy 91.229474 -263.365252) (xy 91.275632 -263.391901) (xy 91.317303 -263.425132) (xy 91.353555 -263.464203)
			(xy 91.383579 -263.50824) (xy 91.406705 -263.556261) (xy 91.422415 -263.607191) (xy 91.430358 -263.659895)
			(xy 91.430856 -263.686544) (xy 91.430358 -263.713193) (xy 91.658938 -263.713193) (xy 91.658938 -263.659895)
			(xy 91.666881 -263.607191) (xy 91.682591 -263.556261) (xy 91.705717 -263.50824) (xy 91.735741 -263.464203)
			(xy 91.771993 -263.425132) (xy 91.813664 -263.391901) (xy 91.859822 -263.365252) (xy 91.909436 -263.34578)
			(xy 91.961398 -263.33392) (xy 92.014548 -263.329937) (xy 92.067698 -263.33392) (xy 92.11966 -263.34578)
			(xy 92.169274 -263.365252) (xy 92.215432 -263.391901) (xy 92.257103 -263.425132) (xy 92.293355 -263.464203)
			(xy 92.323379 -263.50824) (xy 92.346505 -263.556261) (xy 92.362215 -263.607191) (xy 92.370158 -263.659895)
			(xy 92.370656 -263.686544) (xy 92.370158 -263.713193) (xy 92.598738 -263.713193) (xy 92.598738 -263.659895)
			(xy 92.606681 -263.607191) (xy 92.622391 -263.556261) (xy 92.645517 -263.50824) (xy 92.675541 -263.464203)
			(xy 92.711793 -263.425132) (xy 92.753464 -263.391901) (xy 92.799622 -263.365252) (xy 92.849236 -263.34578)
			(xy 92.901198 -263.33392) (xy 92.954348 -263.329937) (xy 93.007498 -263.33392) (xy 93.05946 -263.34578)
			(xy 93.109074 -263.365252) (xy 93.155232 -263.391901) (xy 93.196903 -263.425132) (xy 93.233155 -263.464203)
			(xy 93.263179 -263.50824) (xy 93.286305 -263.556261) (xy 93.302015 -263.607191) (xy 93.309958 -263.659895)
			(xy 93.310456 -263.686544) (xy 93.309958 -263.713193) (xy 93.538538 -263.713193) (xy 93.538538 -263.659895)
			(xy 93.546481 -263.607191) (xy 93.562191 -263.556261) (xy 93.585317 -263.50824) (xy 93.615341 -263.464203)
			(xy 93.651593 -263.425132) (xy 93.693264 -263.391901) (xy 93.739422 -263.365252) (xy 93.789036 -263.34578)
			(xy 93.840998 -263.33392) (xy 93.894148 -263.329937) (xy 93.947298 -263.33392) (xy 93.99926 -263.34578)
			(xy 94.048874 -263.365252) (xy 94.095032 -263.391901) (xy 94.136703 -263.425132) (xy 94.172955 -263.464203)
			(xy 94.202979 -263.50824) (xy 94.226105 -263.556261) (xy 94.241815 -263.607191) (xy 94.249758 -263.659895)
			(xy 94.250256 -263.686544) (xy 94.249758 -263.713193) (xy 94.478084 -263.713193) (xy 94.478084 -263.659895)
			(xy 94.486027 -263.607191) (xy 94.501737 -263.556261) (xy 94.524863 -263.50824) (xy 94.554887 -263.464203)
			(xy 94.591139 -263.425132) (xy 94.63281 -263.391901) (xy 94.678968 -263.365252) (xy 94.728582 -263.34578)
			(xy 94.780544 -263.33392) (xy 94.833694 -263.329937) (xy 94.886844 -263.33392) (xy 94.938806 -263.34578)
			(xy 94.98842 -263.365252) (xy 95.034578 -263.391901) (xy 95.076249 -263.425132) (xy 95.112501 -263.464203)
			(xy 95.142525 -263.50824) (xy 95.165651 -263.556261) (xy 95.181361 -263.607191) (xy 95.189304 -263.659895)
			(xy 95.189802 -263.686544) (xy 95.189304 -263.713193) (xy 95.418138 -263.713193) (xy 95.418138 -263.659895)
			(xy 95.426081 -263.607191) (xy 95.441791 -263.556261) (xy 95.464917 -263.50824) (xy 95.494941 -263.464203)
			(xy 95.531193 -263.425132) (xy 95.572864 -263.391901) (xy 95.619022 -263.365252) (xy 95.668636 -263.34578)
			(xy 95.720598 -263.33392) (xy 95.773748 -263.329937) (xy 95.826898 -263.33392) (xy 95.87886 -263.34578)
			(xy 95.928474 -263.365252) (xy 95.974632 -263.391901) (xy 96.016303 -263.425132) (xy 96.052555 -263.464203)
			(xy 96.082579 -263.50824) (xy 96.105705 -263.556261) (xy 96.121415 -263.607191) (xy 96.129358 -263.659895)
			(xy 96.129856 -263.686544) (xy 96.129358 -263.713193) (xy 96.357938 -263.713193) (xy 96.357938 -263.659895)
			(xy 96.365881 -263.607191) (xy 96.381591 -263.556261) (xy 96.404717 -263.50824) (xy 96.434741 -263.464203)
			(xy 96.470993 -263.425132) (xy 96.512664 -263.391901) (xy 96.558822 -263.365252) (xy 96.608436 -263.34578)
			(xy 96.660398 -263.33392) (xy 96.713548 -263.329937) (xy 96.766698 -263.33392) (xy 96.81866 -263.34578)
			(xy 96.868274 -263.365252) (xy 96.914432 -263.391901) (xy 96.956103 -263.425132) (xy 96.992355 -263.464203)
			(xy 97.022379 -263.50824) (xy 97.045505 -263.556261) (xy 97.061215 -263.607191) (xy 97.069158 -263.659895)
			(xy 97.069656 -263.686544) (xy 97.069158 -263.713193) (xy 97.297738 -263.713193) (xy 97.297738 -263.659895)
			(xy 97.305681 -263.607191) (xy 97.321391 -263.556261) (xy 97.344517 -263.50824) (xy 97.374541 -263.464203)
			(xy 97.410793 -263.425132) (xy 97.452464 -263.391901) (xy 97.498622 -263.365252) (xy 97.548236 -263.34578)
			(xy 97.600198 -263.33392) (xy 97.653348 -263.329937) (xy 97.706498 -263.33392) (xy 97.75846 -263.34578)
			(xy 97.808074 -263.365252) (xy 97.854232 -263.391901) (xy 97.895903 -263.425132) (xy 97.932155 -263.464203)
			(xy 97.962179 -263.50824) (xy 97.985305 -263.556261) (xy 98.001015 -263.607191) (xy 98.008958 -263.659895)
			(xy 98.009456 -263.686544) (xy 98.008958 -263.713193) (xy 98.237538 -263.713193) (xy 98.237538 -263.659895)
			(xy 98.245481 -263.607191) (xy 98.261191 -263.556261) (xy 98.284317 -263.50824) (xy 98.314341 -263.464203)
			(xy 98.350593 -263.425132) (xy 98.392264 -263.391901) (xy 98.438422 -263.365252) (xy 98.488036 -263.34578)
			(xy 98.539998 -263.33392) (xy 98.593148 -263.329937) (xy 98.646298 -263.33392) (xy 98.69826 -263.34578)
			(xy 98.747874 -263.365252) (xy 98.794032 -263.391901) (xy 98.835703 -263.425132) (xy 98.871955 -263.464203)
			(xy 98.901979 -263.50824) (xy 98.925105 -263.556261) (xy 98.940815 -263.607191) (xy 98.948758 -263.659895)
			(xy 98.949256 -263.686544) (xy 98.948758 -263.713193) (xy 99.177338 -263.713193) (xy 99.177338 -263.659895)
			(xy 99.185281 -263.607191) (xy 99.200991 -263.556261) (xy 99.224117 -263.50824) (xy 99.254141 -263.464203)
			(xy 99.290393 -263.425132) (xy 99.332064 -263.391901) (xy 99.378222 -263.365252) (xy 99.427836 -263.34578)
			(xy 99.479798 -263.33392) (xy 99.532948 -263.329937) (xy 99.586098 -263.33392) (xy 99.63806 -263.34578)
			(xy 99.687674 -263.365252) (xy 99.733832 -263.391901) (xy 99.775503 -263.425132) (xy 99.811755 -263.464203)
			(xy 99.841779 -263.50824) (xy 99.864905 -263.556261) (xy 99.880615 -263.607191) (xy 99.888558 -263.659895)
			(xy 99.889056 -263.686544) (xy 99.888558 -263.713193) (xy 100.117138 -263.713193) (xy 100.117138 -263.659895)
			(xy 100.125081 -263.607191) (xy 100.140791 -263.556261) (xy 100.163917 -263.50824) (xy 100.193941 -263.464203)
			(xy 100.230193 -263.425132) (xy 100.271864 -263.391901) (xy 100.318022 -263.365252) (xy 100.367636 -263.34578)
			(xy 100.419598 -263.33392) (xy 100.472748 -263.329937) (xy 100.525898 -263.33392) (xy 100.57786 -263.34578)
			(xy 100.627474 -263.365252) (xy 100.673632 -263.391901) (xy 100.715303 -263.425132) (xy 100.751555 -263.464203)
			(xy 100.781579 -263.50824) (xy 100.804705 -263.556261) (xy 100.820415 -263.607191) (xy 100.828358 -263.659895)
			(xy 100.828856 -263.686544) (xy 100.828358 -263.713193) (xy 101.056684 -263.713193) (xy 101.056684 -263.659895)
			(xy 101.064627 -263.607191) (xy 101.080337 -263.556261) (xy 101.103463 -263.50824) (xy 101.133487 -263.464203)
			(xy 101.169739 -263.425132) (xy 101.21141 -263.391901) (xy 101.257568 -263.365252) (xy 101.307182 -263.34578)
			(xy 101.359144 -263.33392) (xy 101.412294 -263.329937) (xy 101.465444 -263.33392) (xy 101.517406 -263.34578)
			(xy 101.56702 -263.365252) (xy 101.613178 -263.391901) (xy 101.654849 -263.425132) (xy 101.691101 -263.464203)
			(xy 101.721125 -263.50824) (xy 101.744251 -263.556261) (xy 101.759961 -263.607191) (xy 101.767904 -263.659895)
			(xy 101.768402 -263.686544) (xy 101.767904 -263.713193) (xy 101.996738 -263.713193) (xy 101.996738 -263.659895)
			(xy 102.004681 -263.607191) (xy 102.020391 -263.556261) (xy 102.043517 -263.50824) (xy 102.073541 -263.464203)
			(xy 102.109793 -263.425132) (xy 102.151464 -263.391901) (xy 102.197622 -263.365252) (xy 102.247236 -263.34578)
			(xy 102.299198 -263.33392) (xy 102.352348 -263.329937) (xy 102.405498 -263.33392) (xy 102.45746 -263.34578)
			(xy 102.507074 -263.365252) (xy 102.553232 -263.391901) (xy 102.594903 -263.425132) (xy 102.631155 -263.464203)
			(xy 102.661179 -263.50824) (xy 102.684305 -263.556261) (xy 102.700015 -263.607191) (xy 102.707958 -263.659895)
			(xy 102.708456 -263.686544) (xy 102.707958 -263.713193) (xy 102.700015 -263.765897) (xy 102.684305 -263.816827)
			(xy 102.661179 -263.864848) (xy 102.631155 -263.908885) (xy 102.594903 -263.947956) (xy 102.553232 -263.981187)
			(xy 102.507074 -264.007836) (xy 102.45746 -264.027308) (xy 102.405498 -264.039168) (xy 102.352348 -264.043152)
			(xy 102.299198 -264.039168) (xy 102.247236 -264.027308) (xy 102.197622 -264.007836) (xy 102.151464 -263.981187)
			(xy 102.109793 -263.947956) (xy 102.073541 -263.908885) (xy 102.043517 -263.864848) (xy 102.020391 -263.816827)
			(xy 102.004681 -263.765897) (xy 101.996738 -263.713193) (xy 101.767904 -263.713193) (xy 101.759961 -263.765897)
			(xy 101.744251 -263.816827) (xy 101.721125 -263.864848) (xy 101.691101 -263.908885) (xy 101.654849 -263.947956)
			(xy 101.613178 -263.981187) (xy 101.56702 -264.007836) (xy 101.517406 -264.027308) (xy 101.465444 -264.039168)
			(xy 101.412294 -264.043152) (xy 101.359144 -264.039168) (xy 101.307182 -264.027308) (xy 101.257568 -264.007836)
			(xy 101.21141 -263.981187) (xy 101.169739 -263.947956) (xy 101.133487 -263.908885) (xy 101.103463 -263.864848)
			(xy 101.080337 -263.816827) (xy 101.064627 -263.765897) (xy 101.056684 -263.713193) (xy 100.828358 -263.713193)
			(xy 100.820415 -263.765897) (xy 100.804705 -263.816827) (xy 100.781579 -263.864848) (xy 100.751555 -263.908885)
			(xy 100.715303 -263.947956) (xy 100.673632 -263.981187) (xy 100.627474 -264.007836) (xy 100.57786 -264.027308)
			(xy 100.525898 -264.039168) (xy 100.472748 -264.043152) (xy 100.419598 -264.039168) (xy 100.367636 -264.027308)
			(xy 100.318022 -264.007836) (xy 100.271864 -263.981187) (xy 100.230193 -263.947956) (xy 100.193941 -263.908885)
			(xy 100.163917 -263.864848) (xy 100.140791 -263.816827) (xy 100.125081 -263.765897) (xy 100.117138 -263.713193)
			(xy 99.888558 -263.713193) (xy 99.880615 -263.765897) (xy 99.864905 -263.816827) (xy 99.841779 -263.864848)
			(xy 99.811755 -263.908885) (xy 99.775503 -263.947956) (xy 99.733832 -263.981187) (xy 99.687674 -264.007836)
			(xy 99.63806 -264.027308) (xy 99.586098 -264.039168) (xy 99.532948 -264.043152) (xy 99.479798 -264.039168)
			(xy 99.427836 -264.027308) (xy 99.378222 -264.007836) (xy 99.332064 -263.981187) (xy 99.290393 -263.947956)
			(xy 99.254141 -263.908885) (xy 99.224117 -263.864848) (xy 99.200991 -263.816827) (xy 99.185281 -263.765897)
			(xy 99.177338 -263.713193) (xy 98.948758 -263.713193) (xy 98.940815 -263.765897) (xy 98.925105 -263.816827)
			(xy 98.901979 -263.864848) (xy 98.871955 -263.908885) (xy 98.835703 -263.947956) (xy 98.794032 -263.981187)
			(xy 98.747874 -264.007836) (xy 98.69826 -264.027308) (xy 98.646298 -264.039168) (xy 98.593148 -264.043152)
			(xy 98.539998 -264.039168) (xy 98.488036 -264.027308) (xy 98.438422 -264.007836) (xy 98.392264 -263.981187)
			(xy 98.350593 -263.947956) (xy 98.314341 -263.908885) (xy 98.284317 -263.864848) (xy 98.261191 -263.816827)
			(xy 98.245481 -263.765897) (xy 98.237538 -263.713193) (xy 98.008958 -263.713193) (xy 98.001015 -263.765897)
			(xy 97.985305 -263.816827) (xy 97.962179 -263.864848) (xy 97.932155 -263.908885) (xy 97.895903 -263.947956)
			(xy 97.854232 -263.981187) (xy 97.808074 -264.007836) (xy 97.75846 -264.027308) (xy 97.706498 -264.039168)
			(xy 97.653348 -264.043152) (xy 97.600198 -264.039168) (xy 97.548236 -264.027308) (xy 97.498622 -264.007836)
			(xy 97.452464 -263.981187) (xy 97.410793 -263.947956) (xy 97.374541 -263.908885) (xy 97.344517 -263.864848)
			(xy 97.321391 -263.816827) (xy 97.305681 -263.765897) (xy 97.297738 -263.713193) (xy 97.069158 -263.713193)
			(xy 97.061215 -263.765897) (xy 97.045505 -263.816827) (xy 97.022379 -263.864848) (xy 96.992355 -263.908885)
			(xy 96.956103 -263.947956) (xy 96.914432 -263.981187) (xy 96.868274 -264.007836) (xy 96.81866 -264.027308)
			(xy 96.766698 -264.039168) (xy 96.713548 -264.043152) (xy 96.660398 -264.039168) (xy 96.608436 -264.027308)
			(xy 96.558822 -264.007836) (xy 96.512664 -263.981187) (xy 96.470993 -263.947956) (xy 96.434741 -263.908885)
			(xy 96.404717 -263.864848) (xy 96.381591 -263.816827) (xy 96.365881 -263.765897) (xy 96.357938 -263.713193)
			(xy 96.129358 -263.713193) (xy 96.121415 -263.765897) (xy 96.105705 -263.816827) (xy 96.082579 -263.864848)
			(xy 96.052555 -263.908885) (xy 96.016303 -263.947956) (xy 95.974632 -263.981187) (xy 95.928474 -264.007836)
			(xy 95.87886 -264.027308) (xy 95.826898 -264.039168) (xy 95.773748 -264.043152) (xy 95.720598 -264.039168)
			(xy 95.668636 -264.027308) (xy 95.619022 -264.007836) (xy 95.572864 -263.981187) (xy 95.531193 -263.947956)
			(xy 95.494941 -263.908885) (xy 95.464917 -263.864848) (xy 95.441791 -263.816827) (xy 95.426081 -263.765897)
			(xy 95.418138 -263.713193) (xy 95.189304 -263.713193) (xy 95.181361 -263.765897) (xy 95.165651 -263.816827)
			(xy 95.142525 -263.864848) (xy 95.112501 -263.908885) (xy 95.076249 -263.947956) (xy 95.034578 -263.981187)
			(xy 94.98842 -264.007836) (xy 94.938806 -264.027308) (xy 94.886844 -264.039168) (xy 94.833694 -264.043152)
			(xy 94.780544 -264.039168) (xy 94.728582 -264.027308) (xy 94.678968 -264.007836) (xy 94.63281 -263.981187)
			(xy 94.591139 -263.947956) (xy 94.554887 -263.908885) (xy 94.524863 -263.864848) (xy 94.501737 -263.816827)
			(xy 94.486027 -263.765897) (xy 94.478084 -263.713193) (xy 94.249758 -263.713193) (xy 94.241815 -263.765897)
			(xy 94.226105 -263.816827) (xy 94.202979 -263.864848) (xy 94.172955 -263.908885) (xy 94.136703 -263.947956)
			(xy 94.095032 -263.981187) (xy 94.048874 -264.007836) (xy 93.99926 -264.027308) (xy 93.947298 -264.039168)
			(xy 93.894148 -264.043152) (xy 93.840998 -264.039168) (xy 93.789036 -264.027308) (xy 93.739422 -264.007836)
			(xy 93.693264 -263.981187) (xy 93.651593 -263.947956) (xy 93.615341 -263.908885) (xy 93.585317 -263.864848)
			(xy 93.562191 -263.816827) (xy 93.546481 -263.765897) (xy 93.538538 -263.713193) (xy 93.309958 -263.713193)
			(xy 93.302015 -263.765897) (xy 93.286305 -263.816827) (xy 93.263179 -263.864848) (xy 93.233155 -263.908885)
			(xy 93.196903 -263.947956) (xy 93.155232 -263.981187) (xy 93.109074 -264.007836) (xy 93.05946 -264.027308)
			(xy 93.007498 -264.039168) (xy 92.954348 -264.043152) (xy 92.901198 -264.039168) (xy 92.849236 -264.027308)
			(xy 92.799622 -264.007836) (xy 92.753464 -263.981187) (xy 92.711793 -263.947956) (xy 92.675541 -263.908885)
			(xy 92.645517 -263.864848) (xy 92.622391 -263.816827) (xy 92.606681 -263.765897) (xy 92.598738 -263.713193)
			(xy 92.370158 -263.713193) (xy 92.362215 -263.765897) (xy 92.346505 -263.816827) (xy 92.323379 -263.864848)
			(xy 92.293355 -263.908885) (xy 92.257103 -263.947956) (xy 92.215432 -263.981187) (xy 92.169274 -264.007836)
			(xy 92.11966 -264.027308) (xy 92.067698 -264.039168) (xy 92.014548 -264.043152) (xy 91.961398 -264.039168)
			(xy 91.909436 -264.027308) (xy 91.859822 -264.007836) (xy 91.813664 -263.981187) (xy 91.771993 -263.947956)
			(xy 91.735741 -263.908885) (xy 91.705717 -263.864848) (xy 91.682591 -263.816827) (xy 91.666881 -263.765897)
			(xy 91.658938 -263.713193) (xy 91.430358 -263.713193) (xy 91.422415 -263.765897) (xy 91.406705 -263.816827)
			(xy 91.383579 -263.864848) (xy 91.353555 -263.908885) (xy 91.317303 -263.947956) (xy 91.275632 -263.981187)
			(xy 91.229474 -264.007836) (xy 91.17986 -264.027308) (xy 91.127898 -264.039168) (xy 91.074748 -264.043152)
			(xy 91.021598 -264.039168) (xy 90.969636 -264.027308) (xy 90.920022 -264.007836) (xy 90.873864 -263.981187)
			(xy 90.832193 -263.947956) (xy 90.795941 -263.908885) (xy 90.765917 -263.864848) (xy 90.742791 -263.816827)
			(xy 90.727081 -263.765897) (xy 90.719138 -263.713193) (xy 90.490304 -263.713193) (xy 90.482361 -263.765897)
			(xy 90.466651 -263.816827) (xy 90.443525 -263.864848) (xy 90.413501 -263.908885) (xy 90.377249 -263.947956)
			(xy 90.335578 -263.981187) (xy 90.28942 -264.007836) (xy 90.239806 -264.027308) (xy 90.187844 -264.039168)
			(xy 90.134694 -264.043152) (xy 90.081544 -264.039168) (xy 90.029582 -264.027308) (xy 89.979968 -264.007836)
			(xy 89.93381 -263.981187) (xy 89.892139 -263.947956) (xy 89.855887 -263.908885) (xy 89.825863 -263.864848)
			(xy 89.802737 -263.816827) (xy 89.787027 -263.765897) (xy 89.779084 -263.713193) (xy 89.549488 -263.713193)
			(xy 89.547505 -263.739647) (xy 89.535645 -263.791607) (xy 89.516174 -263.841219) (xy 89.489526 -263.887375)
			(xy 89.456296 -263.929044) (xy 89.417226 -263.965294) (xy 89.373191 -263.995316) (xy 89.325172 -264.01844)
			(xy 89.274243 -264.034149) (xy 89.221542 -264.042091) (xy 89.194894 -264.042652) (xy 89.16247 -264.041939)
			(xy 89.098697 -264.030176) (xy 89.068148 -264.019284) (xy 89.054842 -264.014717) (xy 89.026827 -264.012289)
			(xy 88.999211 -264.017593) (xy 88.974087 -264.030226) (xy 88.953361 -264.04923) (xy 88.938601 -264.073166)
			(xy 88.930928 -264.10022) (xy 88.93048 -264.11428) (xy 88.93048 -264.20953) (xy 88.951607 -264.225022)
			(xy 88.989505 -264.261192) (xy 89.021695 -264.302523) (xy 89.047484 -264.348125) (xy 89.066313 -264.397012)
			(xy 89.077777 -264.448131) (xy 89.081628 -264.500377) (xy 89.079668 -264.527009) (xy 89.309184 -264.527009)
			(xy 89.309184 -264.473711) (xy 89.317127 -264.421007) (xy 89.332837 -264.370077) (xy 89.355963 -264.322056)
			(xy 89.385987 -264.278019) (xy 89.422239 -264.238948) (xy 89.46391 -264.205717) (xy 89.510068 -264.179068)
			(xy 89.559682 -264.159596) (xy 89.611644 -264.147736) (xy 89.664794 -264.143753) (xy 89.717944 -264.147736)
			(xy 89.769906 -264.159596) (xy 89.81952 -264.179068) (xy 89.865678 -264.205717) (xy 89.907349 -264.238948)
			(xy 89.943601 -264.278019) (xy 89.973625 -264.322056) (xy 89.996751 -264.370077) (xy 90.012461 -264.421007)
			(xy 90.020404 -264.473711) (xy 90.020902 -264.50036) (xy 90.020404 -264.527009) (xy 90.248984 -264.527009)
			(xy 90.248984 -264.473711) (xy 90.256927 -264.421007) (xy 90.272637 -264.370077) (xy 90.295763 -264.322056)
			(xy 90.325787 -264.278019) (xy 90.362039 -264.238948) (xy 90.40371 -264.205717) (xy 90.449868 -264.179068)
			(xy 90.499482 -264.159596) (xy 90.551444 -264.147736) (xy 90.604594 -264.143753) (xy 90.657744 -264.147736)
			(xy 90.709706 -264.159596) (xy 90.75932 -264.179068) (xy 90.805478 -264.205717) (xy 90.847149 -264.238948)
			(xy 90.883401 -264.278019) (xy 90.913425 -264.322056) (xy 90.936551 -264.370077) (xy 90.952261 -264.421007)
			(xy 90.960204 -264.473711) (xy 90.960702 -264.50036) (xy 90.960204 -264.527009) (xy 91.189038 -264.527009)
			(xy 91.189038 -264.473711) (xy 91.196981 -264.421007) (xy 91.212691 -264.370077) (xy 91.235817 -264.322056)
			(xy 91.265841 -264.278019) (xy 91.302093 -264.238948) (xy 91.343764 -264.205717) (xy 91.389922 -264.179068)
			(xy 91.439536 -264.159596) (xy 91.491498 -264.147736) (xy 91.544648 -264.143753) (xy 91.597798 -264.147736)
			(xy 91.64976 -264.159596) (xy 91.699374 -264.179068) (xy 91.745532 -264.205717) (xy 91.787203 -264.238948)
			(xy 91.823455 -264.278019) (xy 91.853479 -264.322056) (xy 91.876605 -264.370077) (xy 91.892315 -264.421007)
			(xy 91.900258 -264.473711) (xy 91.900756 -264.50036) (xy 91.900258 -264.527009) (xy 92.128584 -264.527009)
			(xy 92.128584 -264.473711) (xy 92.136527 -264.421007) (xy 92.152237 -264.370077) (xy 92.175363 -264.322056)
			(xy 92.205387 -264.278019) (xy 92.241639 -264.238948) (xy 92.28331 -264.205717) (xy 92.329468 -264.179068)
			(xy 92.379082 -264.159596) (xy 92.431044 -264.147736) (xy 92.484194 -264.143753) (xy 92.537344 -264.147736)
			(xy 92.589306 -264.159596) (xy 92.63892 -264.179068) (xy 92.685078 -264.205717) (xy 92.726749 -264.238948)
			(xy 92.763001 -264.278019) (xy 92.793025 -264.322056) (xy 92.816151 -264.370077) (xy 92.831861 -264.421007)
			(xy 92.839804 -264.473711) (xy 92.840302 -264.50036) (xy 92.839804 -264.527009) (xy 93.068384 -264.527009)
			(xy 93.068384 -264.473711) (xy 93.076327 -264.421007) (xy 93.092037 -264.370077) (xy 93.115163 -264.322056)
			(xy 93.145187 -264.278019) (xy 93.181439 -264.238948) (xy 93.22311 -264.205717) (xy 93.269268 -264.179068)
			(xy 93.318882 -264.159596) (xy 93.370844 -264.147736) (xy 93.423994 -264.143753) (xy 93.477144 -264.147736)
			(xy 93.529106 -264.159596) (xy 93.57872 -264.179068) (xy 93.624878 -264.205717) (xy 93.666549 -264.238948)
			(xy 93.702801 -264.278019) (xy 93.732825 -264.322056) (xy 93.755951 -264.370077) (xy 93.771661 -264.421007)
			(xy 93.779604 -264.473711) (xy 93.780102 -264.50036) (xy 93.779604 -264.527009) (xy 94.008184 -264.527009)
			(xy 94.008184 -264.473711) (xy 94.016127 -264.421007) (xy 94.031837 -264.370077) (xy 94.054963 -264.322056)
			(xy 94.084987 -264.278019) (xy 94.121239 -264.238948) (xy 94.16291 -264.205717) (xy 94.209068 -264.179068)
			(xy 94.258682 -264.159596) (xy 94.310644 -264.147736) (xy 94.363794 -264.143753) (xy 94.416944 -264.147736)
			(xy 94.468906 -264.159596) (xy 94.51852 -264.179068) (xy 94.564678 -264.205717) (xy 94.606349 -264.238948)
			(xy 94.642601 -264.278019) (xy 94.672625 -264.322056) (xy 94.695751 -264.370077) (xy 94.711461 -264.421007)
			(xy 94.719404 -264.473711) (xy 94.719902 -264.50036) (xy 94.719404 -264.527009) (xy 94.947984 -264.527009)
			(xy 94.947984 -264.473711) (xy 94.955927 -264.421007) (xy 94.971637 -264.370077) (xy 94.994763 -264.322056)
			(xy 95.024787 -264.278019) (xy 95.061039 -264.238948) (xy 95.10271 -264.205717) (xy 95.148868 -264.179068)
			(xy 95.198482 -264.159596) (xy 95.250444 -264.147736) (xy 95.303594 -264.143753) (xy 95.356744 -264.147736)
			(xy 95.408706 -264.159596) (xy 95.45832 -264.179068) (xy 95.504478 -264.205717) (xy 95.546149 -264.238948)
			(xy 95.582401 -264.278019) (xy 95.612425 -264.322056) (xy 95.635551 -264.370077) (xy 95.651261 -264.421007)
			(xy 95.659204 -264.473711) (xy 95.659702 -264.50036) (xy 95.659204 -264.527009) (xy 95.887784 -264.527009)
			(xy 95.887784 -264.473711) (xy 95.895727 -264.421007) (xy 95.911437 -264.370077) (xy 95.934563 -264.322056)
			(xy 95.964587 -264.278019) (xy 96.000839 -264.238948) (xy 96.04251 -264.205717) (xy 96.088668 -264.179068)
			(xy 96.138282 -264.159596) (xy 96.190244 -264.147736) (xy 96.243394 -264.143753) (xy 96.296544 -264.147736)
			(xy 96.348506 -264.159596) (xy 96.39812 -264.179068) (xy 96.444278 -264.205717) (xy 96.485949 -264.238948)
			(xy 96.522201 -264.278019) (xy 96.552225 -264.322056) (xy 96.575351 -264.370077) (xy 96.591061 -264.421007)
			(xy 96.599004 -264.473711) (xy 96.599502 -264.50036) (xy 96.599004 -264.527009) (xy 96.827584 -264.527009)
			(xy 96.827584 -264.473711) (xy 96.835527 -264.421007) (xy 96.851237 -264.370077) (xy 96.874363 -264.322056)
			(xy 96.904387 -264.278019) (xy 96.940639 -264.238948) (xy 96.98231 -264.205717) (xy 97.028468 -264.179068)
			(xy 97.078082 -264.159596) (xy 97.130044 -264.147736) (xy 97.183194 -264.143753) (xy 97.236344 -264.147736)
			(xy 97.288306 -264.159596) (xy 97.33792 -264.179068) (xy 97.384078 -264.205717) (xy 97.425749 -264.238948)
			(xy 97.462001 -264.278019) (xy 97.492025 -264.322056) (xy 97.515151 -264.370077) (xy 97.530861 -264.421007)
			(xy 97.538804 -264.473711) (xy 97.539302 -264.50036) (xy 97.538804 -264.527009) (xy 97.767638 -264.527009)
			(xy 97.767638 -264.473711) (xy 97.775581 -264.421007) (xy 97.791291 -264.370077) (xy 97.814417 -264.322056)
			(xy 97.844441 -264.278019) (xy 97.880693 -264.238948) (xy 97.922364 -264.205717) (xy 97.968522 -264.179068)
			(xy 98.018136 -264.159596) (xy 98.070098 -264.147736) (xy 98.123248 -264.143753) (xy 98.176398 -264.147736)
			(xy 98.22836 -264.159596) (xy 98.277974 -264.179068) (xy 98.324132 -264.205717) (xy 98.365803 -264.238948)
			(xy 98.402055 -264.278019) (xy 98.432079 -264.322056) (xy 98.455205 -264.370077) (xy 98.470915 -264.421007)
			(xy 98.478858 -264.473711) (xy 98.479356 -264.50036) (xy 98.478858 -264.527009) (xy 98.707184 -264.527009)
			(xy 98.707184 -264.473711) (xy 98.715127 -264.421007) (xy 98.730837 -264.370077) (xy 98.753963 -264.322056)
			(xy 98.783987 -264.278019) (xy 98.820239 -264.238948) (xy 98.86191 -264.205717) (xy 98.908068 -264.179068)
			(xy 98.957682 -264.159596) (xy 99.009644 -264.147736) (xy 99.062794 -264.143753) (xy 99.115944 -264.147736)
			(xy 99.167906 -264.159596) (xy 99.21752 -264.179068) (xy 99.263678 -264.205717) (xy 99.305349 -264.238948)
			(xy 99.341601 -264.278019) (xy 99.371625 -264.322056) (xy 99.394751 -264.370077) (xy 99.410461 -264.421007)
			(xy 99.418404 -264.473711) (xy 99.418902 -264.50036) (xy 99.418404 -264.527009) (xy 99.646984 -264.527009)
			(xy 99.646984 -264.473711) (xy 99.654927 -264.421007) (xy 99.670637 -264.370077) (xy 99.693763 -264.322056)
			(xy 99.723787 -264.278019) (xy 99.760039 -264.238948) (xy 99.80171 -264.205717) (xy 99.847868 -264.179068)
			(xy 99.897482 -264.159596) (xy 99.949444 -264.147736) (xy 100.002594 -264.143753) (xy 100.055744 -264.147736)
			(xy 100.107706 -264.159596) (xy 100.15732 -264.179068) (xy 100.203478 -264.205717) (xy 100.245149 -264.238948)
			(xy 100.281401 -264.278019) (xy 100.311425 -264.322056) (xy 100.334551 -264.370077) (xy 100.350261 -264.421007)
			(xy 100.358204 -264.473711) (xy 100.358702 -264.50036) (xy 100.358204 -264.527009) (xy 100.586784 -264.527009)
			(xy 100.586784 -264.473711) (xy 100.594727 -264.421007) (xy 100.610437 -264.370077) (xy 100.633563 -264.322056)
			(xy 100.663587 -264.278019) (xy 100.699839 -264.238948) (xy 100.74151 -264.205717) (xy 100.787668 -264.179068)
			(xy 100.837282 -264.159596) (xy 100.889244 -264.147736) (xy 100.942394 -264.143753) (xy 100.995544 -264.147736)
			(xy 101.047506 -264.159596) (xy 101.09712 -264.179068) (xy 101.143278 -264.205717) (xy 101.184949 -264.238948)
			(xy 101.221201 -264.278019) (xy 101.251225 -264.322056) (xy 101.274351 -264.370077) (xy 101.290061 -264.421007)
			(xy 101.298004 -264.473711) (xy 101.298502 -264.50036) (xy 101.298004 -264.527009) (xy 103.406184 -264.527009)
			(xy 103.406184 -264.473711) (xy 103.414127 -264.421007) (xy 103.429837 -264.370077) (xy 103.452963 -264.322056)
			(xy 103.482987 -264.278019) (xy 103.519239 -264.238948) (xy 103.56091 -264.205717) (xy 103.607068 -264.179068)
			(xy 103.656682 -264.159596) (xy 103.708644 -264.147736) (xy 103.761794 -264.143753) (xy 103.814944 -264.147736)
			(xy 103.866906 -264.159596) (xy 103.91652 -264.179068) (xy 103.962678 -264.205717) (xy 104.004349 -264.238948)
			(xy 104.040601 -264.278019) (xy 104.070625 -264.322056) (xy 104.093751 -264.370077) (xy 104.109461 -264.421007)
			(xy 104.117404 -264.473711) (xy 104.117902 -264.50036) (xy 104.117404 -264.527009) (xy 104.345984 -264.527009)
			(xy 104.345984 -264.473711) (xy 104.353927 -264.421007) (xy 104.369637 -264.370077) (xy 104.392763 -264.322056)
			(xy 104.422787 -264.278019) (xy 104.459039 -264.238948) (xy 104.50071 -264.205717) (xy 104.546868 -264.179068)
			(xy 104.596482 -264.159596) (xy 104.648444 -264.147736) (xy 104.701594 -264.143753) (xy 104.754744 -264.147736)
			(xy 104.806706 -264.159596) (xy 104.85632 -264.179068) (xy 104.902478 -264.205717) (xy 104.944149 -264.238948)
			(xy 104.980401 -264.278019) (xy 105.010425 -264.322056) (xy 105.033551 -264.370077) (xy 105.049261 -264.421007)
			(xy 105.057204 -264.473711) (xy 105.057702 -264.50036) (xy 105.057204 -264.527009) (xy 105.049261 -264.579713)
			(xy 105.033551 -264.630643) (xy 105.010425 -264.678664) (xy 104.980401 -264.722701) (xy 104.944149 -264.761772)
			(xy 104.902478 -264.795003) (xy 104.85632 -264.821652) (xy 104.806706 -264.841124) (xy 104.754744 -264.852984)
			(xy 104.701594 -264.856968) (xy 104.648444 -264.852984) (xy 104.596482 -264.841124) (xy 104.546868 -264.821652)
			(xy 104.50071 -264.795003) (xy 104.459039 -264.761772) (xy 104.422787 -264.722701) (xy 104.392763 -264.678664)
			(xy 104.369637 -264.630643) (xy 104.353927 -264.579713) (xy 104.345984 -264.527009) (xy 104.117404 -264.527009)
			(xy 104.109461 -264.579713) (xy 104.093751 -264.630643) (xy 104.070625 -264.678664) (xy 104.040601 -264.722701)
			(xy 104.004349 -264.761772) (xy 103.962678 -264.795003) (xy 103.91652 -264.821652) (xy 103.866906 -264.841124)
			(xy 103.814944 -264.852984) (xy 103.761794 -264.856968) (xy 103.708644 -264.852984) (xy 103.656682 -264.841124)
			(xy 103.607068 -264.821652) (xy 103.56091 -264.795003) (xy 103.519239 -264.761772) (xy 103.482987 -264.722701)
			(xy 103.452963 -264.678664) (xy 103.429837 -264.630643) (xy 103.414127 -264.579713) (xy 103.406184 -264.527009)
			(xy 101.298004 -264.527009) (xy 101.290061 -264.579713) (xy 101.274351 -264.630643) (xy 101.251225 -264.678664)
			(xy 101.221201 -264.722701) (xy 101.184949 -264.761772) (xy 101.143278 -264.795003) (xy 101.09712 -264.821652)
			(xy 101.047506 -264.841124) (xy 100.995544 -264.852984) (xy 100.942394 -264.856968) (xy 100.889244 -264.852984)
			(xy 100.837282 -264.841124) (xy 100.787668 -264.821652) (xy 100.74151 -264.795003) (xy 100.699839 -264.761772)
			(xy 100.663587 -264.722701) (xy 100.633563 -264.678664) (xy 100.610437 -264.630643) (xy 100.594727 -264.579713)
			(xy 100.586784 -264.527009) (xy 100.358204 -264.527009) (xy 100.350261 -264.579713) (xy 100.334551 -264.630643)
			(xy 100.311425 -264.678664) (xy 100.281401 -264.722701) (xy 100.245149 -264.761772) (xy 100.203478 -264.795003)
			(xy 100.15732 -264.821652) (xy 100.107706 -264.841124) (xy 100.055744 -264.852984) (xy 100.002594 -264.856968)
			(xy 99.949444 -264.852984) (xy 99.897482 -264.841124) (xy 99.847868 -264.821652) (xy 99.80171 -264.795003)
			(xy 99.760039 -264.761772) (xy 99.723787 -264.722701) (xy 99.693763 -264.678664) (xy 99.670637 -264.630643)
			(xy 99.654927 -264.579713) (xy 99.646984 -264.527009) (xy 99.418404 -264.527009) (xy 99.410461 -264.579713)
			(xy 99.394751 -264.630643) (xy 99.371625 -264.678664) (xy 99.341601 -264.722701) (xy 99.305349 -264.761772)
			(xy 99.263678 -264.795003) (xy 99.21752 -264.821652) (xy 99.167906 -264.841124) (xy 99.115944 -264.852984)
			(xy 99.062794 -264.856968) (xy 99.009644 -264.852984) (xy 98.957682 -264.841124) (xy 98.908068 -264.821652)
			(xy 98.86191 -264.795003) (xy 98.820239 -264.761772) (xy 98.783987 -264.722701) (xy 98.753963 -264.678664)
			(xy 98.730837 -264.630643) (xy 98.715127 -264.579713) (xy 98.707184 -264.527009) (xy 98.478858 -264.527009)
			(xy 98.470915 -264.579713) (xy 98.455205 -264.630643) (xy 98.432079 -264.678664) (xy 98.402055 -264.722701)
			(xy 98.365803 -264.761772) (xy 98.324132 -264.795003) (xy 98.277974 -264.821652) (xy 98.22836 -264.841124)
			(xy 98.176398 -264.852984) (xy 98.123248 -264.856968) (xy 98.070098 -264.852984) (xy 98.018136 -264.841124)
			(xy 97.968522 -264.821652) (xy 97.922364 -264.795003) (xy 97.880693 -264.761772) (xy 97.844441 -264.722701)
			(xy 97.814417 -264.678664) (xy 97.791291 -264.630643) (xy 97.775581 -264.579713) (xy 97.767638 -264.527009)
			(xy 97.538804 -264.527009) (xy 97.530861 -264.579713) (xy 97.515151 -264.630643) (xy 97.492025 -264.678664)
			(xy 97.462001 -264.722701) (xy 97.425749 -264.761772) (xy 97.384078 -264.795003) (xy 97.33792 -264.821652)
			(xy 97.288306 -264.841124) (xy 97.236344 -264.852984) (xy 97.183194 -264.856968) (xy 97.130044 -264.852984)
			(xy 97.078082 -264.841124) (xy 97.028468 -264.821652) (xy 96.98231 -264.795003) (xy 96.940639 -264.761772)
			(xy 96.904387 -264.722701) (xy 96.874363 -264.678664) (xy 96.851237 -264.630643) (xy 96.835527 -264.579713)
			(xy 96.827584 -264.527009) (xy 96.599004 -264.527009) (xy 96.591061 -264.579713) (xy 96.575351 -264.630643)
			(xy 96.552225 -264.678664) (xy 96.522201 -264.722701) (xy 96.485949 -264.761772) (xy 96.444278 -264.795003)
			(xy 96.39812 -264.821652) (xy 96.348506 -264.841124) (xy 96.296544 -264.852984) (xy 96.243394 -264.856968)
			(xy 96.190244 -264.852984) (xy 96.138282 -264.841124) (xy 96.088668 -264.821652) (xy 96.04251 -264.795003)
			(xy 96.000839 -264.761772) (xy 95.964587 -264.722701) (xy 95.934563 -264.678664) (xy 95.911437 -264.630643)
			(xy 95.895727 -264.579713) (xy 95.887784 -264.527009) (xy 95.659204 -264.527009) (xy 95.651261 -264.579713)
			(xy 95.635551 -264.630643) (xy 95.612425 -264.678664) (xy 95.582401 -264.722701) (xy 95.546149 -264.761772)
			(xy 95.504478 -264.795003) (xy 95.45832 -264.821652) (xy 95.408706 -264.841124) (xy 95.356744 -264.852984)
			(xy 95.303594 -264.856968) (xy 95.250444 -264.852984) (xy 95.198482 -264.841124) (xy 95.148868 -264.821652)
			(xy 95.10271 -264.795003) (xy 95.061039 -264.761772) (xy 95.024787 -264.722701) (xy 94.994763 -264.678664)
			(xy 94.971637 -264.630643) (xy 94.955927 -264.579713) (xy 94.947984 -264.527009) (xy 94.719404 -264.527009)
			(xy 94.711461 -264.579713) (xy 94.695751 -264.630643) (xy 94.672625 -264.678664) (xy 94.642601 -264.722701)
			(xy 94.606349 -264.761772) (xy 94.564678 -264.795003) (xy 94.51852 -264.821652) (xy 94.468906 -264.841124)
			(xy 94.416944 -264.852984) (xy 94.363794 -264.856968) (xy 94.310644 -264.852984) (xy 94.258682 -264.841124)
			(xy 94.209068 -264.821652) (xy 94.16291 -264.795003) (xy 94.121239 -264.761772) (xy 94.084987 -264.722701)
			(xy 94.054963 -264.678664) (xy 94.031837 -264.630643) (xy 94.016127 -264.579713) (xy 94.008184 -264.527009)
			(xy 93.779604 -264.527009) (xy 93.771661 -264.579713) (xy 93.755951 -264.630643) (xy 93.732825 -264.678664)
			(xy 93.702801 -264.722701) (xy 93.666549 -264.761772) (xy 93.624878 -264.795003) (xy 93.57872 -264.821652)
			(xy 93.529106 -264.841124) (xy 93.477144 -264.852984) (xy 93.423994 -264.856968) (xy 93.370844 -264.852984)
			(xy 93.318882 -264.841124) (xy 93.269268 -264.821652) (xy 93.22311 -264.795003) (xy 93.181439 -264.761772)
			(xy 93.145187 -264.722701) (xy 93.115163 -264.678664) (xy 93.092037 -264.630643) (xy 93.076327 -264.579713)
			(xy 93.068384 -264.527009) (xy 92.839804 -264.527009) (xy 92.831861 -264.579713) (xy 92.816151 -264.630643)
			(xy 92.793025 -264.678664) (xy 92.763001 -264.722701) (xy 92.726749 -264.761772) (xy 92.685078 -264.795003)
			(xy 92.63892 -264.821652) (xy 92.589306 -264.841124) (xy 92.537344 -264.852984) (xy 92.484194 -264.856968)
			(xy 92.431044 -264.852984) (xy 92.379082 -264.841124) (xy 92.329468 -264.821652) (xy 92.28331 -264.795003)
			(xy 92.241639 -264.761772) (xy 92.205387 -264.722701) (xy 92.175363 -264.678664) (xy 92.152237 -264.630643)
			(xy 92.136527 -264.579713) (xy 92.128584 -264.527009) (xy 91.900258 -264.527009) (xy 91.892315 -264.579713)
			(xy 91.876605 -264.630643) (xy 91.853479 -264.678664) (xy 91.823455 -264.722701) (xy 91.787203 -264.761772)
			(xy 91.745532 -264.795003) (xy 91.699374 -264.821652) (xy 91.64976 -264.841124) (xy 91.597798 -264.852984)
			(xy 91.544648 -264.856968) (xy 91.491498 -264.852984) (xy 91.439536 -264.841124) (xy 91.389922 -264.821652)
			(xy 91.343764 -264.795003) (xy 91.302093 -264.761772) (xy 91.265841 -264.722701) (xy 91.235817 -264.678664)
			(xy 91.212691 -264.630643) (xy 91.196981 -264.579713) (xy 91.189038 -264.527009) (xy 90.960204 -264.527009)
			(xy 90.952261 -264.579713) (xy 90.936551 -264.630643) (xy 90.913425 -264.678664) (xy 90.883401 -264.722701)
			(xy 90.847149 -264.761772) (xy 90.805478 -264.795003) (xy 90.75932 -264.821652) (xy 90.709706 -264.841124)
			(xy 90.657744 -264.852984) (xy 90.604594 -264.856968) (xy 90.551444 -264.852984) (xy 90.499482 -264.841124)
			(xy 90.449868 -264.821652) (xy 90.40371 -264.795003) (xy 90.362039 -264.761772) (xy 90.325787 -264.722701)
			(xy 90.295763 -264.678664) (xy 90.272637 -264.630643) (xy 90.256927 -264.579713) (xy 90.248984 -264.527009)
			(xy 90.020404 -264.527009) (xy 90.012461 -264.579713) (xy 89.996751 -264.630643) (xy 89.973625 -264.678664)
			(xy 89.943601 -264.722701) (xy 89.907349 -264.761772) (xy 89.865678 -264.795003) (xy 89.81952 -264.821652)
			(xy 89.769906 -264.841124) (xy 89.717944 -264.852984) (xy 89.664794 -264.856968) (xy 89.611644 -264.852984)
			(xy 89.559682 -264.841124) (xy 89.510068 -264.821652) (xy 89.46391 -264.795003) (xy 89.422239 -264.761772)
			(xy 89.385987 -264.722701) (xy 89.355963 -264.678664) (xy 89.332837 -264.630643) (xy 89.317127 -264.579713)
			(xy 89.309184 -264.527009) (xy 89.079668 -264.527009) (xy 89.077783 -264.552624) (xy 89.066326 -264.603744)
			(xy 89.047503 -264.652634) (xy 89.021721 -264.698238) (xy 88.989536 -264.739574) (xy 88.951642 -264.775748)
			(xy 88.93048 -264.79119) (xy 88.93048 -264.88644) (xy 88.930935 -264.900498) (xy 88.938611 -264.927545)
			(xy 88.953371 -264.951475) (xy 88.974095 -264.970475) (xy 88.999215 -264.983104) (xy 89.026826 -264.988406)
			(xy 89.054836 -264.98598) (xy 89.068148 -264.981436) (xy 89.098701 -264.970561) (xy 89.162472 -264.958798)
			(xy 89.194894 -264.958068) (xy 89.222878 -264.958616) (xy 89.278157 -264.967371) (xy 89.331387 -264.984664)
			(xy 89.381256 -265.010072) (xy 89.426536 -265.042967) (xy 89.466113 -265.082541) (xy 89.499013 -265.127819)
			(xy 89.524424 -265.177685) (xy 89.541722 -265.230913) (xy 89.550481 -265.286192) (xy 89.551002 -265.314176)
			(xy 89.550561 -265.339758) (xy 89.550407 -265.340825) (xy 89.779084 -265.340825) (xy 89.779084 -265.287527)
			(xy 89.787027 -265.234823) (xy 89.802737 -265.183893) (xy 89.825863 -265.135872) (xy 89.855887 -265.091835)
			(xy 89.892139 -265.052764) (xy 89.93381 -265.019533) (xy 89.979968 -264.992884) (xy 90.029582 -264.973412)
			(xy 90.081544 -264.961552) (xy 90.134694 -264.957569) (xy 90.187844 -264.961552) (xy 90.239806 -264.973412)
			(xy 90.28942 -264.992884) (xy 90.335578 -265.019533) (xy 90.377249 -265.052764) (xy 90.413501 -265.091835)
			(xy 90.443525 -265.135872) (xy 90.466651 -265.183893) (xy 90.482361 -265.234823) (xy 90.490304 -265.287527)
			(xy 90.490802 -265.314176) (xy 90.490304 -265.340825) (xy 90.719138 -265.340825) (xy 90.719138 -265.287527)
			(xy 90.727081 -265.234823) (xy 90.742791 -265.183893) (xy 90.765917 -265.135872) (xy 90.795941 -265.091835)
			(xy 90.832193 -265.052764) (xy 90.873864 -265.019533) (xy 90.920022 -264.992884) (xy 90.969636 -264.973412)
			(xy 91.021598 -264.961552) (xy 91.074748 -264.957569) (xy 91.127898 -264.961552) (xy 91.17986 -264.973412)
			(xy 91.229474 -264.992884) (xy 91.275632 -265.019533) (xy 91.317303 -265.052764) (xy 91.353555 -265.091835)
			(xy 91.383579 -265.135872) (xy 91.406705 -265.183893) (xy 91.422415 -265.234823) (xy 91.430358 -265.287527)
			(xy 91.430856 -265.314176) (xy 91.430358 -265.340825) (xy 91.658684 -265.340825) (xy 91.658684 -265.287527)
			(xy 91.666627 -265.234823) (xy 91.682337 -265.183893) (xy 91.705463 -265.135872) (xy 91.735487 -265.091835)
			(xy 91.771739 -265.052764) (xy 91.81341 -265.019533) (xy 91.859568 -264.992884) (xy 91.909182 -264.973412)
			(xy 91.961144 -264.961552) (xy 92.014294 -264.957569) (xy 92.067444 -264.961552) (xy 92.119406 -264.973412)
			(xy 92.16902 -264.992884) (xy 92.215178 -265.019533) (xy 92.256849 -265.052764) (xy 92.293101 -265.091835)
			(xy 92.323125 -265.135872) (xy 92.346251 -265.183893) (xy 92.361961 -265.234823) (xy 92.369904 -265.287527)
			(xy 92.370402 -265.314176) (xy 92.369904 -265.340825) (xy 92.598738 -265.340825) (xy 92.598738 -265.287527)
			(xy 92.606681 -265.234823) (xy 92.622391 -265.183893) (xy 92.645517 -265.135872) (xy 92.675541 -265.091835)
			(xy 92.711793 -265.052764) (xy 92.753464 -265.019533) (xy 92.799622 -264.992884) (xy 92.849236 -264.973412)
			(xy 92.901198 -264.961552) (xy 92.954348 -264.957569) (xy 93.007498 -264.961552) (xy 93.05946 -264.973412)
			(xy 93.109074 -264.992884) (xy 93.155232 -265.019533) (xy 93.196903 -265.052764) (xy 93.233155 -265.091835)
			(xy 93.263179 -265.135872) (xy 93.286305 -265.183893) (xy 93.302015 -265.234823) (xy 93.309958 -265.287527)
			(xy 93.310456 -265.314176) (xy 93.309958 -265.340825) (xy 93.538538 -265.340825) (xy 93.538538 -265.287527)
			(xy 93.546481 -265.234823) (xy 93.562191 -265.183893) (xy 93.585317 -265.135872) (xy 93.615341 -265.091835)
			(xy 93.651593 -265.052764) (xy 93.693264 -265.019533) (xy 93.739422 -264.992884) (xy 93.789036 -264.973412)
			(xy 93.840998 -264.961552) (xy 93.894148 -264.957569) (xy 93.947298 -264.961552) (xy 93.99926 -264.973412)
			(xy 94.048874 -264.992884) (xy 94.095032 -265.019533) (xy 94.136703 -265.052764) (xy 94.172955 -265.091835)
			(xy 94.202979 -265.135872) (xy 94.226105 -265.183893) (xy 94.241815 -265.234823) (xy 94.249758 -265.287527)
			(xy 94.250256 -265.314176) (xy 94.249758 -265.340825) (xy 94.478338 -265.340825) (xy 94.478338 -265.287527)
			(xy 94.486281 -265.234823) (xy 94.501991 -265.183893) (xy 94.525117 -265.135872) (xy 94.555141 -265.091835)
			(xy 94.591393 -265.052764) (xy 94.633064 -265.019533) (xy 94.679222 -264.992884) (xy 94.728836 -264.973412)
			(xy 94.780798 -264.961552) (xy 94.833948 -264.957569) (xy 94.887098 -264.961552) (xy 94.93906 -264.973412)
			(xy 94.988674 -264.992884) (xy 95.034832 -265.019533) (xy 95.076503 -265.052764) (xy 95.112755 -265.091835)
			(xy 95.142779 -265.135872) (xy 95.165905 -265.183893) (xy 95.181615 -265.234823) (xy 95.189558 -265.287527)
			(xy 95.190056 -265.314176) (xy 95.189558 -265.340825) (xy 95.418138 -265.340825) (xy 95.418138 -265.287527)
			(xy 95.426081 -265.234823) (xy 95.441791 -265.183893) (xy 95.464917 -265.135872) (xy 95.494941 -265.091835)
			(xy 95.531193 -265.052764) (xy 95.572864 -265.019533) (xy 95.619022 -264.992884) (xy 95.668636 -264.973412)
			(xy 95.720598 -264.961552) (xy 95.773748 -264.957569) (xy 95.826898 -264.961552) (xy 95.87886 -264.973412)
			(xy 95.928474 -264.992884) (xy 95.974632 -265.019533) (xy 96.016303 -265.052764) (xy 96.052555 -265.091835)
			(xy 96.082579 -265.135872) (xy 96.105705 -265.183893) (xy 96.121415 -265.234823) (xy 96.129358 -265.287527)
			(xy 96.129856 -265.314176) (xy 96.129358 -265.340825) (xy 96.357938 -265.340825) (xy 96.357938 -265.287527)
			(xy 96.365881 -265.234823) (xy 96.381591 -265.183893) (xy 96.404717 -265.135872) (xy 96.434741 -265.091835)
			(xy 96.470993 -265.052764) (xy 96.512664 -265.019533) (xy 96.558822 -264.992884) (xy 96.608436 -264.973412)
			(xy 96.660398 -264.961552) (xy 96.713548 -264.957569) (xy 96.766698 -264.961552) (xy 96.81866 -264.973412)
			(xy 96.868274 -264.992884) (xy 96.914432 -265.019533) (xy 96.956103 -265.052764) (xy 96.992355 -265.091835)
			(xy 97.022379 -265.135872) (xy 97.045505 -265.183893) (xy 97.061215 -265.234823) (xy 97.069158 -265.287527)
			(xy 97.069656 -265.314176) (xy 97.069158 -265.340825) (xy 97.297738 -265.340825) (xy 97.297738 -265.287527)
			(xy 97.305681 -265.234823) (xy 97.321391 -265.183893) (xy 97.344517 -265.135872) (xy 97.374541 -265.091835)
			(xy 97.410793 -265.052764) (xy 97.452464 -265.019533) (xy 97.498622 -264.992884) (xy 97.548236 -264.973412)
			(xy 97.600198 -264.961552) (xy 97.653348 -264.957569) (xy 97.706498 -264.961552) (xy 97.75846 -264.973412)
			(xy 97.808074 -264.992884) (xy 97.854232 -265.019533) (xy 97.895903 -265.052764) (xy 97.932155 -265.091835)
			(xy 97.962179 -265.135872) (xy 97.985305 -265.183893) (xy 98.001015 -265.234823) (xy 98.008958 -265.287527)
			(xy 98.009456 -265.314176) (xy 98.008958 -265.340825) (xy 98.237284 -265.340825) (xy 98.237284 -265.287527)
			(xy 98.245227 -265.234823) (xy 98.260937 -265.183893) (xy 98.284063 -265.135872) (xy 98.314087 -265.091835)
			(xy 98.350339 -265.052764) (xy 98.39201 -265.019533) (xy 98.438168 -264.992884) (xy 98.487782 -264.973412)
			(xy 98.539744 -264.961552) (xy 98.592894 -264.957569) (xy 98.646044 -264.961552) (xy 98.698006 -264.973412)
			(xy 98.74762 -264.992884) (xy 98.793778 -265.019533) (xy 98.835449 -265.052764) (xy 98.871701 -265.091835)
			(xy 98.901725 -265.135872) (xy 98.924851 -265.183893) (xy 98.940561 -265.234823) (xy 98.948504 -265.287527)
			(xy 98.949002 -265.314176) (xy 98.948504 -265.340825) (xy 99.177338 -265.340825) (xy 99.177338 -265.287527)
			(xy 99.185281 -265.234823) (xy 99.200991 -265.183893) (xy 99.224117 -265.135872) (xy 99.254141 -265.091835)
			(xy 99.290393 -265.052764) (xy 99.332064 -265.019533) (xy 99.378222 -264.992884) (xy 99.427836 -264.973412)
			(xy 99.479798 -264.961552) (xy 99.532948 -264.957569) (xy 99.586098 -264.961552) (xy 99.63806 -264.973412)
			(xy 99.687674 -264.992884) (xy 99.733832 -265.019533) (xy 99.775503 -265.052764) (xy 99.811755 -265.091835)
			(xy 99.841779 -265.135872) (xy 99.864905 -265.183893) (xy 99.880615 -265.234823) (xy 99.888558 -265.287527)
			(xy 99.889056 -265.314176) (xy 99.888558 -265.340825) (xy 100.117138 -265.340825) (xy 100.117138 -265.287527)
			(xy 100.125081 -265.234823) (xy 100.140791 -265.183893) (xy 100.163917 -265.135872) (xy 100.193941 -265.091835)
			(xy 100.230193 -265.052764) (xy 100.271864 -265.019533) (xy 100.318022 -264.992884) (xy 100.367636 -264.973412)
			(xy 100.419598 -264.961552) (xy 100.472748 -264.957569) (xy 100.525898 -264.961552) (xy 100.57786 -264.973412)
			(xy 100.627474 -264.992884) (xy 100.673632 -265.019533) (xy 100.715303 -265.052764) (xy 100.751555 -265.091835)
			(xy 100.781579 -265.135872) (xy 100.804705 -265.183893) (xy 100.820415 -265.234823) (xy 100.828358 -265.287527)
			(xy 100.828856 -265.314176) (xy 100.828358 -265.340825) (xy 102.936538 -265.340825) (xy 102.936538 -265.287527)
			(xy 102.944481 -265.234823) (xy 102.960191 -265.183893) (xy 102.983317 -265.135872) (xy 103.013341 -265.091835)
			(xy 103.049593 -265.052764) (xy 103.091264 -265.019533) (xy 103.137422 -264.992884) (xy 103.187036 -264.973412)
			(xy 103.238998 -264.961552) (xy 103.292148 -264.957569) (xy 103.345298 -264.961552) (xy 103.39726 -264.973412)
			(xy 103.446874 -264.992884) (xy 103.493032 -265.019533) (xy 103.534703 -265.052764) (xy 103.570955 -265.091835)
			(xy 103.600979 -265.135872) (xy 103.624105 -265.183893) (xy 103.639815 -265.234823) (xy 103.647758 -265.287527)
			(xy 103.648256 -265.314176) (xy 103.647758 -265.340825) (xy 103.876338 -265.340825) (xy 103.876338 -265.287527)
			(xy 103.884281 -265.234823) (xy 103.899991 -265.183893) (xy 103.923117 -265.135872) (xy 103.953141 -265.091835)
			(xy 103.989393 -265.052764) (xy 104.031064 -265.019533) (xy 104.077222 -264.992884) (xy 104.126836 -264.973412)
			(xy 104.178798 -264.961552) (xy 104.231948 -264.957569) (xy 104.285098 -264.961552) (xy 104.33706 -264.973412)
			(xy 104.386674 -264.992884) (xy 104.432832 -265.019533) (xy 104.474503 -265.052764) (xy 104.510755 -265.091835)
			(xy 104.540779 -265.135872) (xy 104.563905 -265.183893) (xy 104.579615 -265.234823) (xy 104.587558 -265.287527)
			(xy 104.588056 -265.314176) (xy 104.587558 -265.340825) (xy 104.579615 -265.393529) (xy 104.563905 -265.444459)
			(xy 104.540779 -265.49248) (xy 104.510755 -265.536517) (xy 104.474503 -265.575588) (xy 104.432832 -265.608819)
			(xy 104.386674 -265.635468) (xy 104.33706 -265.65494) (xy 104.285098 -265.6668) (xy 104.231948 -265.670784)
			(xy 104.178798 -265.6668) (xy 104.126836 -265.65494) (xy 104.077222 -265.635468) (xy 104.031064 -265.608819)
			(xy 103.989393 -265.575588) (xy 103.953141 -265.536517) (xy 103.923117 -265.49248) (xy 103.899991 -265.444459)
			(xy 103.884281 -265.393529) (xy 103.876338 -265.340825) (xy 103.647758 -265.340825) (xy 103.639815 -265.393529)
			(xy 103.624105 -265.444459) (xy 103.600979 -265.49248) (xy 103.570955 -265.536517) (xy 103.534703 -265.575588)
			(xy 103.493032 -265.608819) (xy 103.446874 -265.635468) (xy 103.39726 -265.65494) (xy 103.345298 -265.6668)
			(xy 103.292148 -265.670784) (xy 103.238998 -265.6668) (xy 103.187036 -265.65494) (xy 103.137422 -265.635468)
			(xy 103.091264 -265.608819) (xy 103.049593 -265.575588) (xy 103.013341 -265.536517) (xy 102.983317 -265.49248)
			(xy 102.960191 -265.444459) (xy 102.944481 -265.393529) (xy 102.936538 -265.340825) (xy 100.828358 -265.340825)
			(xy 100.820415 -265.393529) (xy 100.804705 -265.444459) (xy 100.781579 -265.49248) (xy 100.751555 -265.536517)
			(xy 100.715303 -265.575588) (xy 100.673632 -265.608819) (xy 100.627474 -265.635468) (xy 100.57786 -265.65494)
			(xy 100.525898 -265.6668) (xy 100.472748 -265.670784) (xy 100.419598 -265.6668) (xy 100.367636 -265.65494)
			(xy 100.318022 -265.635468) (xy 100.271864 -265.608819) (xy 100.230193 -265.575588) (xy 100.193941 -265.536517)
			(xy 100.163917 -265.49248) (xy 100.140791 -265.444459) (xy 100.125081 -265.393529) (xy 100.117138 -265.340825)
			(xy 99.888558 -265.340825) (xy 99.880615 -265.393529) (xy 99.864905 -265.444459) (xy 99.841779 -265.49248)
			(xy 99.811755 -265.536517) (xy 99.775503 -265.575588) (xy 99.733832 -265.608819) (xy 99.687674 -265.635468)
			(xy 99.63806 -265.65494) (xy 99.586098 -265.6668) (xy 99.532948 -265.670784) (xy 99.479798 -265.6668)
			(xy 99.427836 -265.65494) (xy 99.378222 -265.635468) (xy 99.332064 -265.608819) (xy 99.290393 -265.575588)
			(xy 99.254141 -265.536517) (xy 99.224117 -265.49248) (xy 99.200991 -265.444459) (xy 99.185281 -265.393529)
			(xy 99.177338 -265.340825) (xy 98.948504 -265.340825) (xy 98.940561 -265.393529) (xy 98.924851 -265.444459)
			(xy 98.901725 -265.49248) (xy 98.871701 -265.536517) (xy 98.835449 -265.575588) (xy 98.793778 -265.608819)
			(xy 98.74762 -265.635468) (xy 98.698006 -265.65494) (xy 98.646044 -265.6668) (xy 98.592894 -265.670784)
			(xy 98.539744 -265.6668) (xy 98.487782 -265.65494) (xy 98.438168 -265.635468) (xy 98.39201 -265.608819)
			(xy 98.350339 -265.575588) (xy 98.314087 -265.536517) (xy 98.284063 -265.49248) (xy 98.260937 -265.444459)
			(xy 98.245227 -265.393529) (xy 98.237284 -265.340825) (xy 98.008958 -265.340825) (xy 98.001015 -265.393529)
			(xy 97.985305 -265.444459) (xy 97.962179 -265.49248) (xy 97.932155 -265.536517) (xy 97.895903 -265.575588)
			(xy 97.854232 -265.608819) (xy 97.808074 -265.635468) (xy 97.75846 -265.65494) (xy 97.706498 -265.6668)
			(xy 97.653348 -265.670784) (xy 97.600198 -265.6668) (xy 97.548236 -265.65494) (xy 97.498622 -265.635468)
			(xy 97.452464 -265.608819) (xy 97.410793 -265.575588) (xy 97.374541 -265.536517) (xy 97.344517 -265.49248)
			(xy 97.321391 -265.444459) (xy 97.305681 -265.393529) (xy 97.297738 -265.340825) (xy 97.069158 -265.340825)
			(xy 97.061215 -265.393529) (xy 97.045505 -265.444459) (xy 97.022379 -265.49248) (xy 96.992355 -265.536517)
			(xy 96.956103 -265.575588) (xy 96.914432 -265.608819) (xy 96.868274 -265.635468) (xy 96.81866 -265.65494)
			(xy 96.766698 -265.6668) (xy 96.713548 -265.670784) (xy 96.660398 -265.6668) (xy 96.608436 -265.65494)
			(xy 96.558822 -265.635468) (xy 96.512664 -265.608819) (xy 96.470993 -265.575588) (xy 96.434741 -265.536517)
			(xy 96.404717 -265.49248) (xy 96.381591 -265.444459) (xy 96.365881 -265.393529) (xy 96.357938 -265.340825)
			(xy 96.129358 -265.340825) (xy 96.121415 -265.393529) (xy 96.105705 -265.444459) (xy 96.082579 -265.49248)
			(xy 96.052555 -265.536517) (xy 96.016303 -265.575588) (xy 95.974632 -265.608819) (xy 95.928474 -265.635468)
			(xy 95.87886 -265.65494) (xy 95.826898 -265.6668) (xy 95.773748 -265.670784) (xy 95.720598 -265.6668)
			(xy 95.668636 -265.65494) (xy 95.619022 -265.635468) (xy 95.572864 -265.608819) (xy 95.531193 -265.575588)
			(xy 95.494941 -265.536517) (xy 95.464917 -265.49248) (xy 95.441791 -265.444459) (xy 95.426081 -265.393529)
			(xy 95.418138 -265.340825) (xy 95.189558 -265.340825) (xy 95.181615 -265.393529) (xy 95.165905 -265.444459)
			(xy 95.142779 -265.49248) (xy 95.112755 -265.536517) (xy 95.076503 -265.575588) (xy 95.034832 -265.608819)
			(xy 94.988674 -265.635468) (xy 94.93906 -265.65494) (xy 94.887098 -265.6668) (xy 94.833948 -265.670784)
			(xy 94.780798 -265.6668) (xy 94.728836 -265.65494) (xy 94.679222 -265.635468) (xy 94.633064 -265.608819)
			(xy 94.591393 -265.575588) (xy 94.555141 -265.536517) (xy 94.525117 -265.49248) (xy 94.501991 -265.444459)
			(xy 94.486281 -265.393529) (xy 94.478338 -265.340825) (xy 94.249758 -265.340825) (xy 94.241815 -265.393529)
			(xy 94.226105 -265.444459) (xy 94.202979 -265.49248) (xy 94.172955 -265.536517) (xy 94.136703 -265.575588)
			(xy 94.095032 -265.608819) (xy 94.048874 -265.635468) (xy 93.99926 -265.65494) (xy 93.947298 -265.6668)
			(xy 93.894148 -265.670784) (xy 93.840998 -265.6668) (xy 93.789036 -265.65494) (xy 93.739422 -265.635468)
			(xy 93.693264 -265.608819) (xy 93.651593 -265.575588) (xy 93.615341 -265.536517) (xy 93.585317 -265.49248)
			(xy 93.562191 -265.444459) (xy 93.546481 -265.393529) (xy 93.538538 -265.340825) (xy 93.309958 -265.340825)
			(xy 93.302015 -265.393529) (xy 93.286305 -265.444459) (xy 93.263179 -265.49248) (xy 93.233155 -265.536517)
			(xy 93.196903 -265.575588) (xy 93.155232 -265.608819) (xy 93.109074 -265.635468) (xy 93.05946 -265.65494)
			(xy 93.007498 -265.6668) (xy 92.954348 -265.670784) (xy 92.901198 -265.6668) (xy 92.849236 -265.65494)
			(xy 92.799622 -265.635468) (xy 92.753464 -265.608819) (xy 92.711793 -265.575588) (xy 92.675541 -265.536517)
			(xy 92.645517 -265.49248) (xy 92.622391 -265.444459) (xy 92.606681 -265.393529) (xy 92.598738 -265.340825)
			(xy 92.369904 -265.340825) (xy 92.361961 -265.393529) (xy 92.346251 -265.444459) (xy 92.323125 -265.49248)
			(xy 92.293101 -265.536517) (xy 92.256849 -265.575588) (xy 92.215178 -265.608819) (xy 92.16902 -265.635468)
			(xy 92.119406 -265.65494) (xy 92.067444 -265.6668) (xy 92.014294 -265.670784) (xy 91.961144 -265.6668)
			(xy 91.909182 -265.65494) (xy 91.859568 -265.635468) (xy 91.81341 -265.608819) (xy 91.771739 -265.575588)
			(xy 91.735487 -265.536517) (xy 91.705463 -265.49248) (xy 91.682337 -265.444459) (xy 91.666627 -265.393529)
			(xy 91.658684 -265.340825) (xy 91.430358 -265.340825) (xy 91.422415 -265.393529) (xy 91.406705 -265.444459)
			(xy 91.383579 -265.49248) (xy 91.353555 -265.536517) (xy 91.317303 -265.575588) (xy 91.275632 -265.608819)
			(xy 91.229474 -265.635468) (xy 91.17986 -265.65494) (xy 91.127898 -265.6668) (xy 91.074748 -265.670784)
			(xy 91.021598 -265.6668) (xy 90.969636 -265.65494) (xy 90.920022 -265.635468) (xy 90.873864 -265.608819)
			(xy 90.832193 -265.575588) (xy 90.795941 -265.536517) (xy 90.765917 -265.49248) (xy 90.742791 -265.444459)
			(xy 90.727081 -265.393529) (xy 90.719138 -265.340825) (xy 90.490304 -265.340825) (xy 90.482361 -265.393529)
			(xy 90.466651 -265.444459) (xy 90.443525 -265.49248) (xy 90.413501 -265.536517) (xy 90.377249 -265.575588)
			(xy 90.335578 -265.608819) (xy 90.28942 -265.635468) (xy 90.239806 -265.65494) (xy 90.187844 -265.6668)
			(xy 90.134694 -265.670784) (xy 90.081544 -265.6668) (xy 90.029582 -265.65494) (xy 89.979968 -265.635468)
			(xy 89.93381 -265.608819) (xy 89.892139 -265.575588) (xy 89.855887 -265.536517) (xy 89.825863 -265.49248)
			(xy 89.802737 -265.444459) (xy 89.787027 -265.393529) (xy 89.779084 -265.340825) (xy 89.550407 -265.340825)
			(xy 89.543242 -265.390397) (xy 89.528751 -265.439466) (xy 89.507387 -265.485957) (xy 89.479588 -265.528911)
			(xy 89.445929 -265.567444) (xy 89.426796 -265.584432) (xy 89.416503 -265.593874) (xy 89.40107 -265.617142)
			(xy 89.392505 -265.643717) (xy 89.391449 -265.671618) (xy 89.397979 -265.698764) (xy 89.411609 -265.723133)
			(xy 89.421208 -265.733276) (xy 89.48928 -265.801348) (xy 89.523316 -265.801348)
		)
		(stroke
			(width 0)
			(type solid)
		)
		(fill yes)
		(layer "In13.Cu")
		(net "PVCCFA_EHV_CPU1")
	)
	(gr_poly
		(pts
			(xy 338.213446 -265.99769) (xy 338.223652 -265.973102) (xy 338.250303 -265.927018) (xy 338.28352 -265.885417)
			(xy 338.322562 -265.849227) (xy 338.366559 -265.819257) (xy 338.41453 -265.796173) (xy 338.465403 -265.780492)
			(xy 338.518044 -265.772563) (xy 338.57128 -265.772563) (xy 338.623921 -265.780492) (xy 338.674794 -265.796173)
			(xy 338.722765 -265.819257) (xy 338.766762 -265.849227) (xy 338.805804 -265.885417) (xy 338.839021 -265.927018)
			(xy 338.865672 -265.973102) (xy 338.875878 -265.99769) (xy 338.888578 -266.029948) (xy 339.140546 -266.029948)
			(xy 339.153246 -265.99769) (xy 339.163452 -265.973102) (xy 339.190103 -265.927018) (xy 339.22332 -265.885417)
			(xy 339.262362 -265.849227) (xy 339.306359 -265.819257) (xy 339.35433 -265.796173) (xy 339.405203 -265.780492)
			(xy 339.457844 -265.772563) (xy 339.51108 -265.772563) (xy 339.563721 -265.780492) (xy 339.614594 -265.796173)
			(xy 339.662565 -265.819257) (xy 339.706562 -265.849227) (xy 339.745604 -265.885417) (xy 339.778821 -265.927018)
			(xy 339.805472 -265.973102) (xy 339.815678 -265.99769) (xy 339.828378 -266.029948) (xy 340.080346 -266.029948)
			(xy 340.093046 -265.99769) (xy 340.103252 -265.973102) (xy 340.129903 -265.927018) (xy 340.16312 -265.885417)
			(xy 340.202162 -265.849227) (xy 340.246159 -265.819257) (xy 340.29413 -265.796173) (xy 340.345003 -265.780492)
			(xy 340.397644 -265.772563) (xy 340.45088 -265.772563) (xy 340.503521 -265.780492) (xy 340.554394 -265.796173)
			(xy 340.602365 -265.819257) (xy 340.646362 -265.849227) (xy 340.685404 -265.885417) (xy 340.718621 -265.927018)
			(xy 340.745272 -265.973102) (xy 340.755478 -265.99769) (xy 340.768178 -266.029948) (xy 341.020146 -266.029948)
			(xy 341.032846 -265.99769) (xy 341.043052 -265.973102) (xy 341.069703 -265.927018) (xy 341.10292 -265.885417)
			(xy 341.141962 -265.849227) (xy 341.185959 -265.819257) (xy 341.23393 -265.796173) (xy 341.284803 -265.780492)
			(xy 341.337444 -265.772563) (xy 341.39068 -265.772563) (xy 341.443321 -265.780492) (xy 341.494194 -265.796173)
			(xy 341.542165 -265.819257) (xy 341.586162 -265.849227) (xy 341.625204 -265.885417) (xy 341.658421 -265.927018)
			(xy 341.685072 -265.973102) (xy 341.695278 -265.99769) (xy 341.707978 -266.029948) (xy 341.959946 -266.029948)
			(xy 341.972646 -265.99769) (xy 341.982852 -265.973102) (xy 342.009503 -265.927018) (xy 342.04272 -265.885417)
			(xy 342.081762 -265.849227) (xy 342.125759 -265.819257) (xy 342.17373 -265.796173) (xy 342.224603 -265.780492)
			(xy 342.277244 -265.772563) (xy 342.33048 -265.772563) (xy 342.383121 -265.780492) (xy 342.433994 -265.796173)
			(xy 342.481965 -265.819257) (xy 342.525962 -265.849227) (xy 342.565004 -265.885417) (xy 342.598221 -265.927018)
			(xy 342.624872 -265.973102) (xy 342.635078 -265.99769) (xy 342.647778 -266.029948) (xy 342.899746 -266.029948)
			(xy 342.912446 -265.99769) (xy 342.922652 -265.973102) (xy 342.949303 -265.927018) (xy 342.98252 -265.885417)
			(xy 343.021562 -265.849227) (xy 343.065559 -265.819257) (xy 343.11353 -265.796173) (xy 343.164403 -265.780492)
			(xy 343.217044 -265.772563) (xy 343.27028 -265.772563) (xy 343.322921 -265.780492) (xy 343.373794 -265.796173)
			(xy 343.421765 -265.819257) (xy 343.465762 -265.849227) (xy 343.504804 -265.885417) (xy 343.538021 -265.927018)
			(xy 343.564672 -265.973102) (xy 343.574878 -265.99769) (xy 343.587578 -266.029948) (xy 343.839546 -266.029948)
			(xy 343.852246 -265.99769) (xy 343.862452 -265.973102) (xy 343.889103 -265.927018) (xy 343.92232 -265.885417)
			(xy 343.961362 -265.849227) (xy 344.005359 -265.819257) (xy 344.05333 -265.796173) (xy 344.104203 -265.780492)
			(xy 344.156844 -265.772563) (xy 344.21008 -265.772563) (xy 344.262721 -265.780492) (xy 344.313594 -265.796173)
			(xy 344.361565 -265.819257) (xy 344.405562 -265.849227) (xy 344.444604 -265.885417) (xy 344.477821 -265.927018)
			(xy 344.504472 -265.973102) (xy 344.514678 -265.99769) (xy 344.527378 -266.029948) (xy 344.779346 -266.029948)
			(xy 344.792046 -265.99769) (xy 344.802252 -265.973102) (xy 344.828903 -265.927018) (xy 344.86212 -265.885417)
			(xy 344.901162 -265.849227) (xy 344.945159 -265.819257) (xy 344.99313 -265.796173) (xy 345.044003 -265.780492)
			(xy 345.096644 -265.772563) (xy 345.14988 -265.772563) (xy 345.202521 -265.780492) (xy 345.253394 -265.796173)
			(xy 345.301365 -265.819257) (xy 345.345362 -265.849227) (xy 345.384404 -265.885417) (xy 345.417621 -265.927018)
			(xy 345.444272 -265.973102) (xy 345.454478 -265.99769) (xy 345.467178 -266.029948) (xy 345.719146 -266.029948)
			(xy 345.731846 -265.99769) (xy 345.742052 -265.973102) (xy 345.768703 -265.927018) (xy 345.80192 -265.885417)
			(xy 345.840962 -265.849227) (xy 345.884959 -265.819257) (xy 345.93293 -265.796173) (xy 345.983803 -265.780492)
			(xy 346.036444 -265.772563) (xy 346.08968 -265.772563) (xy 346.142321 -265.780492) (xy 346.193194 -265.796173)
			(xy 346.241165 -265.819257) (xy 346.285162 -265.849227) (xy 346.324204 -265.885417) (xy 346.357421 -265.927018)
			(xy 346.384072 -265.973102) (xy 346.394278 -265.99769) (xy 346.406978 -266.029948) (xy 346.658946 -266.029948)
			(xy 346.671646 -265.99769) (xy 346.681852 -265.973102) (xy 346.708503 -265.927018) (xy 346.74172 -265.885417)
			(xy 346.780762 -265.849227) (xy 346.824759 -265.819257) (xy 346.87273 -265.796173) (xy 346.923603 -265.780492)
			(xy 346.976244 -265.772563) (xy 347.02948 -265.772563) (xy 347.082121 -265.780492) (xy 347.132994 -265.796173)
			(xy 347.180965 -265.819257) (xy 347.224962 -265.849227) (xy 347.264004 -265.885417) (xy 347.297221 -265.927018)
			(xy 347.323872 -265.973102) (xy 347.334078 -265.99769) (xy 347.346778 -266.029948) (xy 347.598746 -266.029948)
			(xy 347.611446 -265.99769) (xy 347.621652 -265.973102) (xy 347.648303 -265.927018) (xy 347.68152 -265.885417)
			(xy 347.720562 -265.849227) (xy 347.764559 -265.819257) (xy 347.81253 -265.796173) (xy 347.863403 -265.780492)
			(xy 347.916044 -265.772563) (xy 347.96928 -265.772563) (xy 348.021921 -265.780492) (xy 348.072794 -265.796173)
			(xy 348.120765 -265.819257) (xy 348.164762 -265.849227) (xy 348.203804 -265.885417) (xy 348.237021 -265.927018)
			(xy 348.263672 -265.973102) (xy 348.273878 -265.99769) (xy 348.286578 -266.029948) (xy 348.538546 -266.029948)
			(xy 348.551246 -265.99769) (xy 348.561452 -265.973102) (xy 348.588103 -265.927018) (xy 348.62132 -265.885417)
			(xy 348.660362 -265.849227) (xy 348.704359 -265.819257) (xy 348.75233 -265.796173) (xy 348.803203 -265.780492)
			(xy 348.855844 -265.772563) (xy 348.90908 -265.772563) (xy 348.961721 -265.780492) (xy 349.012594 -265.796173)
			(xy 349.060565 -265.819257) (xy 349.104562 -265.849227) (xy 349.143604 -265.885417) (xy 349.176821 -265.927018)
			(xy 349.203472 -265.973102) (xy 349.213678 -265.99769) (xy 349.226378 -266.029948) (xy 349.478346 -266.029948)
			(xy 349.491046 -265.99769) (xy 349.501252 -265.973102) (xy 349.527903 -265.927018) (xy 349.56112 -265.885417)
			(xy 349.600162 -265.849227) (xy 349.644159 -265.819257) (xy 349.69213 -265.796173) (xy 349.743003 -265.780492)
			(xy 349.795644 -265.772563) (xy 349.84888 -265.772563) (xy 349.901521 -265.780492) (xy 349.952394 -265.796173)
			(xy 350.000365 -265.819257) (xy 350.044362 -265.849227) (xy 350.083404 -265.885417) (xy 350.116621 -265.927018)
			(xy 350.143272 -265.973102) (xy 350.153478 -265.99769) (xy 350.166178 -266.029948) (xy 350.418146 -266.029948)
			(xy 350.430846 -265.99769) (xy 350.441052 -265.973102) (xy 350.467703 -265.927018) (xy 350.50092 -265.885417)
			(xy 350.539962 -265.849227) (xy 350.583959 -265.819257) (xy 350.63193 -265.796173) (xy 350.682803 -265.780492)
			(xy 350.735444 -265.772563) (xy 350.78868 -265.772563) (xy 350.841321 -265.780492) (xy 350.892194 -265.796173)
			(xy 350.940165 -265.819257) (xy 350.984162 -265.849227) (xy 351.023204 -265.885417) (xy 351.056421 -265.927018)
			(xy 351.083072 -265.973102) (xy 351.093278 -265.99769) (xy 351.105978 -266.029948) (xy 351.357946 -266.029948)
			(xy 351.370646 -265.99769) (xy 351.38085 -265.973103) (xy 351.407498 -265.927022) (xy 351.440715 -265.885426)
			(xy 351.479759 -265.849245) (xy 351.523758 -265.819285) (xy 351.571731 -265.796215) (xy 351.622606 -265.780552)
			(xy 351.675246 -265.772644) (xy 351.701862 -265.772138) (xy 351.729773 -265.772685) (xy 351.784909 -265.781401)
			(xy 351.838012 -265.798609) (xy 351.863152 -265.810746) (xy 351.895918 -265.82751) (xy 351.97034 -265.753088)
			(xy 351.980315 -265.742455) (xy 351.994278 -265.716872) (xy 352.000452 -265.688388) (xy 351.998336 -265.65932)
			(xy 351.988101 -265.632031) (xy 351.97058 -265.608741) (xy 351.959164 -265.599672) (xy 351.937334 -265.582747)
			(xy 351.898681 -265.54329) (xy 351.866584 -265.498338) (xy 351.841813 -265.448969) (xy 351.824963 -265.396367)
			(xy 351.816438 -265.341794) (xy 351.815908 -265.314176) (xy 351.816459 -265.286195) (xy 351.825217 -265.230921)
			(xy 351.842514 -265.177698) (xy 351.867923 -265.127837) (xy 351.90082 -265.082564) (xy 351.940394 -265.042994)
			(xy 351.985671 -265.010102) (xy 352.035535 -264.984698) (xy 352.08876 -264.967408) (xy 352.144035 -264.958656)
			(xy 352.172016 -264.958068) (xy 352.199633 -264.95859) (xy 352.254206 -264.96712) (xy 352.306807 -264.983973)
			(xy 352.356175 -265.008746) (xy 352.401126 -265.040844) (xy 352.440583 -265.079497) (xy 352.457512 -265.101324)
			(xy 352.466591 -265.112722) (xy 352.489879 -265.13022) (xy 352.517157 -265.140438) (xy 352.54621 -265.142545)
			(xy 352.574677 -265.13637) (xy 352.600245 -265.122415) (xy 352.610928 -265.1125) (xy 352.693986 -265.029442)
			(xy 352.703999 -265.018674) (xy 352.717929 -264.992793) (xy 352.723916 -264.964017) (xy 352.721467 -264.934727)
			(xy 352.710784 -264.907346) (xy 352.69275 -264.884136) (xy 352.668856 -264.86702) (xy 352.641079 -264.85741)
			(xy 352.626422 -264.856214) (xy 352.599244 -264.854537) (xy 352.545832 -264.84396) (xy 352.494654 -264.825374)
			(xy 352.446902 -264.799212) (xy 352.40369 -264.766084) (xy 352.366026 -264.726764) (xy 352.334788 -264.682166)
			(xy 352.310705 -264.633333) (xy 352.294338 -264.581402) (xy 352.286069 -264.527585) (xy 352.285554 -264.50036)
			(xy 352.286106 -264.472378) (xy 352.294866 -264.417103) (xy 352.312163 -264.363879) (xy 352.337573 -264.314016)
			(xy 352.370469 -264.26874) (xy 352.410042 -264.229168) (xy 352.455317 -264.196272) (xy 352.505181 -264.170862)
			(xy 352.558405 -264.153565) (xy 352.61368 -264.144806) (xy 352.641662 -264.144252) (xy 352.67149 -264.14486)
			(xy 352.730314 -264.154799) (xy 352.786662 -264.17439) (xy 352.813112 -264.188194) (xy 352.826588 -264.194953)
			(xy 352.856089 -264.201086) (xy 352.886096 -264.198344) (xy 352.913998 -264.186967) (xy 352.937367 -264.167945)
			(xy 352.954169 -264.142933) (xy 352.962943 -264.114106) (xy 352.96348 -264.09904) (xy 352.96348 -261.689088)
			(xy 352.844354 -261.569962) (xy 352.80854 -261.600188) (xy 352.789145 -261.616128) (xy 352.746717 -261.642967)
			(xy 352.700938 -261.663573) (xy 352.652716 -261.677538) (xy 352.60301 -261.684584) (xy 352.577908 -261.685024)
			(xy 352.551798 -261.684566) (xy 352.500139 -261.67694) (xy 352.450148 -261.661849) (xy 352.402898 -261.639617)
			(xy 352.359402 -261.610722) (xy 352.320594 -261.575783) (xy 352.287305 -261.53555) (xy 352.26025 -261.490886)
			(xy 352.24001 -261.44275) (xy 352.227018 -261.392172) (xy 352.223832 -261.366254) (xy 352.219006 -261.320788)
			(xy 350.17202 -261.320788) (xy 350.16059 -261.35584) (xy 350.151953 -261.380658) (xy 350.128412 -261.427638)
			(xy 350.098222 -261.470647) (xy 350.062039 -261.508753) (xy 350.020648 -261.541127) (xy 349.974949 -261.567067)
			(xy 349.925934 -261.586008) (xy 349.874667 -261.59754) (xy 349.822262 -261.601412) (xy 349.769857 -261.59754)
			(xy 349.71859 -261.586008) (xy 349.669575 -261.567067) (xy 349.623876 -261.541127) (xy 349.582485 -261.508753)
			(xy 349.546302 -261.470647) (xy 349.516112 -261.427638) (xy 349.492571 -261.380658) (xy 349.483934 -261.35584)
			(xy 349.472504 -261.320788) (xy 349.23222 -261.320788) (xy 349.22079 -261.35584) (xy 349.212153 -261.380658)
			(xy 349.188612 -261.427638) (xy 349.158422 -261.470647) (xy 349.122239 -261.508753) (xy 349.080848 -261.541127)
			(xy 349.035149 -261.567067) (xy 348.986134 -261.586008) (xy 348.934867 -261.59754) (xy 348.882462 -261.601412)
			(xy 348.830057 -261.59754) (xy 348.77879 -261.586008) (xy 348.729775 -261.567067) (xy 348.684076 -261.541127)
			(xy 348.642685 -261.508753) (xy 348.606502 -261.470647) (xy 348.576312 -261.427638) (xy 348.552771 -261.380658)
			(xy 348.544134 -261.35584) (xy 348.532704 -261.320788) (xy 348.29242 -261.320788) (xy 348.28099 -261.35584)
			(xy 348.271769 -261.382196) (xy 348.246295 -261.431881) (xy 348.21338 -261.476982) (xy 348.17383 -261.516393)
			(xy 348.128614 -261.54915) (xy 348.07884 -261.574449) (xy 348.025728 -261.591671) (xy 347.970579 -261.600394)
			(xy 347.942662 -261.60095) (xy 347.91468 -261.600398) (xy 347.859405 -261.591639) (xy 347.80618 -261.574341)
			(xy 347.756316 -261.548932) (xy 347.71104 -261.516036) (xy 347.671467 -261.476463) (xy 347.63857 -261.431187)
			(xy 347.61316 -261.381324) (xy 347.595862 -261.328099) (xy 347.587102 -261.272824) (xy 347.586554 -261.244842)
			(xy 347.587009 -261.218917) (xy 347.594496 -261.167612) (xy 347.609334 -261.117931) (xy 347.619828 -261.09422)
			(xy 347.635068 -261.062216) (xy 347.32976 -260.756908) (xy 347.321632 -260.753098) (xy 347.299009 -260.741991)
			(xy 347.256868 -260.714348) (xy 347.219046 -260.68104) (xy 347.186299 -260.642732) (xy 347.15928 -260.600188)
			(xy 347.13853 -260.554261) (xy 347.124464 -260.505866) (xy 347.117361 -260.455971) (xy 347.116908 -260.430772)
			(xy 347.117415 -260.403616) (xy 347.125657 -260.349932) (xy 347.141959 -260.298124) (xy 347.165945 -260.249394)
			(xy 347.197056 -260.204875) (xy 347.21546 -260.1849) (xy 347.21546 -260.060948) (xy 347.214931 -260.045535)
			(xy 347.205754 -260.016108) (xy 347.188219 -259.990756) (xy 347.163922 -259.971787) (xy 347.135074 -259.960925)
			(xy 347.1043 -259.959159) (xy 347.089222 -259.962396) (xy 347.067981 -259.967385) (xy 347.024678 -259.972735)
			(xy 347.002862 -259.973064) (xy 346.976218 -259.972563) (xy 346.923525 -259.964616) (xy 346.872606 -259.948905)
			(xy 346.824597 -259.92578) (xy 346.78057 -259.895759) (xy 346.741508 -259.859511) (xy 346.708286 -259.817847)
			(xy 346.681643 -259.771697) (xy 346.662176 -259.722092) (xy 346.650319 -259.670139) (xy 346.646337 -259.617)
			(xy 346.650319 -259.563861) (xy 346.662176 -259.511908) (xy 346.681643 -259.462303) (xy 346.708286 -259.416153)
			(xy 346.741509 -259.374489) (xy 346.78057 -259.338241) (xy 346.824597 -259.30822) (xy 346.872606 -259.285095)
			(xy 346.923525 -259.269384) (xy 346.976218 -259.261437) (xy 347.002862 -259.260848) (xy 347.024677 -259.261195)
			(xy 347.067978 -259.266543) (xy 347.089222 -259.271516) (xy 347.104306 -259.274739) (xy 347.135087 -259.272972)
			(xy 347.163943 -259.262113) (xy 347.188252 -259.24315) (xy 347.205807 -259.217804) (xy 347.215012 -259.188379)
			(xy 347.21546 -259.172964) (xy 347.21546 -259.049012) (xy 347.197076 -259.029019) (xy 347.16597 -258.984498)
			(xy 347.141984 -258.93577) (xy 347.125676 -258.883965) (xy 347.117424 -258.830285) (xy 347.11742 -258.775973)
			(xy 347.125663 -258.722291) (xy 347.141962 -258.670483) (xy 347.16594 -258.621752) (xy 347.19704 -258.577226)
			(xy 347.21546 -258.557268) (xy 347.21546 -258.433062) (xy 347.21492 -258.417659) (xy 347.205728 -258.388255)
			(xy 347.18819 -258.362926) (xy 347.163901 -258.343975) (xy 347.135069 -258.333123) (xy 347.104312 -258.331358)
			(xy 347.089222 -258.33451) (xy 347.068043 -258.339485) (xy 347.024868 -258.344834) (xy 347.003116 -258.345178)
			(xy 346.976466 -258.344706) (xy 346.923762 -258.336764) (xy 346.87283 -258.321056) (xy 346.824808 -258.297932)
			(xy 346.780769 -258.267908) (xy 346.741697 -258.231657) (xy 346.708465 -258.189986) (xy 346.681815 -258.143828)
			(xy 346.662342 -258.094213) (xy 346.650481 -258.04225) (xy 346.646498 -257.9891) (xy 346.650481 -257.93595)
			(xy 346.662342 -257.883987) (xy 346.681815 -257.834372) (xy 346.708465 -257.788214) (xy 346.741697 -257.746543)
			(xy 346.780769 -257.710292) (xy 346.824808 -257.680268) (xy 346.87283 -257.657144) (xy 346.923762 -257.641436)
			(xy 346.976466 -257.633494) (xy 347.003116 -257.632962) (xy 347.024867 -257.633321) (xy 347.068041 -257.638671)
			(xy 347.089222 -257.64363) (xy 347.104302 -257.646855) (xy 347.135075 -257.645089) (xy 347.163922 -257.634229)
			(xy 347.18822 -257.615262) (xy 347.205758 -257.589914) (xy 347.214941 -257.56049) (xy 347.21546 -257.545078)
			(xy 347.21546 -257.42138) (xy 347.197029 -257.401383) (xy 347.165838 -257.356839) (xy 347.141788 -257.308067)
			(xy 347.125438 -257.256204) (xy 347.117169 -257.202457) (xy 347.117174 -257.148077) (xy 347.125453 -257.094332)
			(xy 347.141812 -257.042471) (xy 347.165872 -256.993704) (xy 347.197072 -256.949165) (xy 347.21546 -256.929128)
			(xy 347.21546 -256.80543) (xy 347.214929 -256.790019) (xy 347.205748 -256.760597) (xy 347.188213 -256.73525)
			(xy 347.163918 -256.716284) (xy 347.135073 -256.705424) (xy 347.104302 -256.703659) (xy 347.089222 -256.706878)
			(xy 347.067981 -256.711867) (xy 347.024678 -256.717218) (xy 347.002862 -256.717546) (xy 346.976212 -256.717046)
			(xy 346.923507 -256.709096) (xy 346.872576 -256.693381) (xy 346.824555 -256.670251) (xy 346.780518 -256.640223)
			(xy 346.741448 -256.603967) (xy 346.708217 -256.562294) (xy 346.681569 -256.516133) (xy 346.662097 -256.466516)
			(xy 346.650237 -256.414552) (xy 346.646254 -256.3614) (xy 346.650237 -256.308248) (xy 346.662097 -256.256284)
			(xy 346.681569 -256.206667) (xy 346.708217 -256.160506) (xy 346.741448 -256.118833) (xy 346.780518 -256.082577)
			(xy 346.824555 -256.052549) (xy 346.872576 -256.029419) (xy 346.923507 -256.013704) (xy 346.976212 -256.005754)
			(xy 347.002862 -256.00533) (xy 347.024677 -256.005677) (xy 347.067979 -256.011025) (xy 347.089222 -256.015998)
			(xy 347.104305 -256.019222) (xy 347.135085 -256.017455) (xy 347.163939 -256.006596) (xy 347.188246 -255.987632)
			(xy 347.205797 -255.962285) (xy 347.214998 -255.932861) (xy 347.21546 -255.917446) (xy 347.21546 -255.793494)
			(xy 347.197078 -255.773501) (xy 347.165974 -255.728981) (xy 347.141991 -255.680254) (xy 347.125685 -255.62845)
			(xy 347.117436 -255.574771) (xy 347.117433 -255.520461) (xy 347.125678 -255.466781) (xy 347.141979 -255.414976)
			(xy 347.165957 -255.366247) (xy 347.197058 -255.321724) (xy 347.21546 -255.30175) (xy 347.21546 -255.177544)
			(xy 347.214931 -255.162132) (xy 347.205752 -255.132706) (xy 347.188218 -255.107355) (xy 347.163921 -255.088386)
			(xy 347.135074 -255.077525) (xy 347.1043 -255.075759) (xy 347.089222 -255.078992) (xy 347.067981 -255.083981)
			(xy 347.024678 -255.089332) (xy 347.002862 -255.08966) (xy 346.976218 -255.089159) (xy 346.923526 -255.081212)
			(xy 346.872607 -255.065501) (xy 346.824599 -255.042376) (xy 346.780572 -255.012355) (xy 346.741511 -254.976108)
			(xy 346.708289 -254.934445) (xy 346.681647 -254.888295) (xy 346.66218 -254.838691) (xy 346.650323 -254.786739)
			(xy 346.646341 -254.7336) (xy 346.650323 -254.680461) (xy 346.66218 -254.628509) (xy 346.681647 -254.578905)
			(xy 346.708289 -254.532755) (xy 346.741511 -254.491092) (xy 346.780572 -254.454844) (xy 346.824599 -254.424824)
			(xy 346.872607 -254.401699) (xy 346.923526 -254.385988) (xy 346.976218 -254.378041) (xy 347.002862 -254.377444)
			(xy 347.024677 -254.377791) (xy 347.067979 -254.383139) (xy 347.089222 -254.388112) (xy 347.104306 -254.391336)
			(xy 347.135086 -254.389568) (xy 347.163942 -254.37871) (xy 347.188251 -254.359746) (xy 347.205805 -254.3344)
			(xy 347.215009 -254.304975) (xy 347.21546 -254.28956) (xy 347.21546 -254.165608) (xy 347.197077 -254.145615)
			(xy 347.16597 -254.101094) (xy 347.141985 -254.052367) (xy 347.125678 -254.000562) (xy 347.117427 -253.946881)
			(xy 347.117423 -253.892571) (xy 347.125666 -253.838889) (xy 347.141966 -253.787082) (xy 347.165944 -253.738351)
			(xy 347.197044 -253.693826) (xy 347.21546 -253.673864) (xy 347.21546 -250.020836) (xy 347.214918 -250.005749)
			(xy 347.206112 -249.976889) (xy 347.189258 -249.951862) (xy 347.165827 -249.932852) (xy 347.137863 -249.921517)
			(xy 347.107808 -249.918848) (xy 347.078285 -249.925077) (xy 347.064838 -249.931936) (xy 347.038336 -249.94585)
			(xy 346.981824 -249.965567) (xy 346.922807 -249.975531) (xy 346.89288 -249.976132) (xy 346.86623 -249.975633)
			(xy 346.813525 -249.967686) (xy 346.762594 -249.951973) (xy 346.714573 -249.928845) (xy 346.670535 -249.898819)
			(xy 346.631464 -249.862564) (xy 346.598233 -249.820891) (xy 346.571584 -249.774731) (xy 346.552112 -249.725115)
			(xy 346.540251 -249.673151) (xy 346.536268 -249.62) (xy 346.540251 -249.566849) (xy 346.552112 -249.514885)
			(xy 346.571584 -249.465269) (xy 346.598233 -249.419109) (xy 346.631464 -249.377436) (xy 346.670535 -249.341181)
			(xy 346.714573 -249.311155) (xy 346.762594 -249.288027) (xy 346.813525 -249.272314) (xy 346.86623 -249.264367)
			(xy 346.89288 -249.263916) (xy 346.922804 -249.264531) (xy 346.981814 -249.274522) (xy 347.038332 -249.294211)
			(xy 347.064838 -249.308112) (xy 347.07831 -249.314915) (xy 347.107828 -249.321131) (xy 347.137875 -249.31846)
			(xy 347.165833 -249.307135) (xy 347.189268 -249.288142) (xy 347.206139 -249.263136) (xy 347.214976 -249.234294)
			(xy 347.21546 -249.219212) (xy 347.21546 -249.130312) (xy 347.190949 -249.118592) (xy 347.145496 -249.088834)
			(xy 347.10509 -249.052518) (xy 347.070669 -249.010486) (xy 347.043032 -248.963714) (xy 347.02282 -248.913286)
			(xy 347.010501 -248.860373) (xy 347.006363 -248.806203) (xy 347.0105 -248.752033) (xy 347.022818 -248.69912)
			(xy 347.043029 -248.648692) (xy 347.070665 -248.601919) (xy 347.105086 -248.559887) (xy 347.145491 -248.52357)
			(xy 347.190943 -248.493811) (xy 347.21546 -248.482104) (xy 347.21546 -248.393204) (xy 347.214955 -248.378096)
			(xy 347.206203 -248.349179) (xy 347.189374 -248.324088) (xy 347.16594 -248.305018) (xy 347.137952 -248.293639)
			(xy 347.10786 -248.290945) (xy 347.078297 -248.297173) (xy 347.064838 -248.30405) (xy 347.038364 -248.317922)
			(xy 346.981935 -248.337603) (xy 346.923015 -248.347612) (xy 346.893134 -248.348246) (xy 346.866478 -248.347775)
			(xy 346.813762 -248.339834) (xy 346.762818 -248.324124) (xy 346.714785 -248.300997) (xy 346.670735 -248.270968)
			(xy 346.631653 -248.234709) (xy 346.598413 -248.19303) (xy 346.571756 -248.146862) (xy 346.552278 -248.097237)
			(xy 346.540414 -248.045262) (xy 346.53643 -247.9921) (xy 346.540414 -247.938938) (xy 346.552278 -247.886963)
			(xy 346.571756 -247.837338) (xy 346.598413 -247.79117) (xy 346.631653 -247.749491) (xy 346.670735 -247.713232)
			(xy 346.714785 -247.683203) (xy 346.762818 -247.660076) (xy 346.813762 -247.644366) (xy 346.866478 -247.636425)
			(xy 346.893134 -247.63603) (xy 346.923018 -247.63664) (xy 346.981943 -247.646632) (xy 347.038365 -247.666347)
			(xy 347.064838 -247.680226) (xy 347.078328 -247.687035) (xy 347.107884 -247.693247) (xy 347.137966 -247.690551)
			(xy 347.165946 -247.679182) (xy 347.189384 -247.660134) (xy 347.206232 -247.635068) (xy 347.215021 -247.606174)
			(xy 347.21546 -247.591072) (xy 347.21546 -247.502426) (xy 347.190948 -247.490706) (xy 347.145493 -247.460948)
			(xy 347.105085 -247.424631) (xy 347.070662 -247.382598) (xy 347.043023 -247.335824) (xy 347.022809 -247.285395)
			(xy 347.01049 -247.232481) (xy 347.00635 -247.178309) (xy 347.010487 -247.124137) (xy 347.022804 -247.071222)
			(xy 347.043015 -247.020792) (xy 347.070652 -246.974017) (xy 347.105072 -246.931982) (xy 347.145478 -246.895663)
			(xy 347.190932 -246.865903) (xy 347.21546 -246.854218) (xy 347.21546 -246.765318) (xy 347.214916 -246.750233)
			(xy 347.206107 -246.721378) (xy 347.189252 -246.696356) (xy 347.165823 -246.677349) (xy 347.137862 -246.666017)
			(xy 347.107811 -246.663348) (xy 347.078291 -246.669575) (xy 347.064838 -246.676418) (xy 347.038336 -246.690333)
			(xy 346.981825 -246.710051) (xy 346.922807 -246.720015) (xy 346.89288 -246.720614) (xy 346.866231 -246.720115)
			(xy 346.813529 -246.712169) (xy 346.7626 -246.696457) (xy 346.714582 -246.67333) (xy 346.670546 -246.643305)
			(xy 346.631477 -246.607052) (xy 346.598248 -246.565381) (xy 346.5716 -246.519224) (xy 346.552129 -246.46961)
			(xy 346.540269 -246.417649) (xy 346.536286 -246.3645) (xy 346.540269 -246.311351) (xy 346.552129 -246.25939)
			(xy 346.5716 -246.209776) (xy 346.598248 -246.163619) (xy 346.631477 -246.121948) (xy 346.670546 -246.085695)
			(xy 346.714582 -246.05567) (xy 346.7626 -246.032543) (xy 346.813529 -246.016831) (xy 346.866231 -246.008885)
			(xy 346.89288 -246.008398) (xy 346.922804 -246.009013) (xy 346.981814 -246.019004) (xy 347.038332 -246.038692)
			(xy 347.064838 -246.052594) (xy 347.078309 -246.059398) (xy 347.107826 -246.065615) (xy 347.137872 -246.062945)
			(xy 347.165829 -246.051619) (xy 347.189263 -246.032625) (xy 347.20613 -246.007618) (xy 347.214963 -245.978776)
			(xy 347.21546 -245.963694) (xy 347.21546 -245.874794) (xy 347.190951 -245.863074) (xy 347.1455 -245.833317)
			(xy 347.105097 -245.797002) (xy 347.070678 -245.754971) (xy 347.043043 -245.7082) (xy 347.022833 -245.657774)
			(xy 347.010516 -245.604863) (xy 347.006379 -245.550696) (xy 347.010518 -245.496529) (xy 347.022835 -245.443618)
			(xy 347.043047 -245.393193) (xy 347.070683 -245.346422) (xy 347.105103 -245.304392) (xy 347.145507 -245.268078)
			(xy 347.190958 -245.238322) (xy 347.21546 -245.226586) (xy 347.21546 -245.137432) (xy 347.214918 -245.122346)
			(xy 347.206111 -245.093487) (xy 347.189257 -245.068461) (xy 347.165826 -245.049451) (xy 347.137863 -245.038117)
			(xy 347.107809 -245.035448) (xy 347.078286 -245.041677) (xy 347.064838 -245.048532) (xy 347.038336 -245.062446)
			(xy 346.981824 -245.082163) (xy 346.922807 -245.092127) (xy 346.89288 -245.092728) (xy 346.86623 -245.092229)
			(xy 346.813526 -245.084282) (xy 346.762595 -245.06857) (xy 346.714575 -245.045442) (xy 346.670537 -245.015415)
			(xy 346.631467 -244.979161) (xy 346.598236 -244.937489) (xy 346.571587 -244.89133) (xy 346.552115 -244.841714)
			(xy 346.540255 -244.789751) (xy 346.536272 -244.7366) (xy 346.540255 -244.683449) (xy 346.552115 -244.631486)
			(xy 346.571587 -244.58187) (xy 346.598236 -244.535711) (xy 346.631467 -244.494039) (xy 346.670537 -244.457785)
			(xy 346.714575 -244.427758) (xy 346.762595 -244.40463) (xy 346.813526 -244.388918) (xy 346.86623 -244.380971)
			(xy 346.89288 -244.380512) (xy 346.922804 -244.381127) (xy 346.981814 -244.391118) (xy 347.038332 -244.410807)
			(xy 347.064838 -244.424708) (xy 347.07831 -244.431512) (xy 347.107827 -244.437728) (xy 347.137874 -244.435057)
			(xy 347.165832 -244.423732) (xy 347.189267 -244.404738) (xy 347.206137 -244.379732) (xy 347.214973 -244.35089)
			(xy 347.21546 -244.335808) (xy 347.21546 -244.246908) (xy 347.19095 -244.235188) (xy 347.145497 -244.20543)
			(xy 347.105092 -244.169115) (xy 347.070671 -244.127083) (xy 347.043034 -244.080311) (xy 347.022823 -244.029883)
			(xy 347.010505 -243.976971) (xy 347.006366 -243.922802) (xy 347.010504 -243.868632) (xy 347.022822 -243.81572)
			(xy 347.043033 -243.765292) (xy 347.070669 -243.71852) (xy 347.105089 -243.676488) (xy 347.145494 -243.640172)
			(xy 347.190947 -243.610414) (xy 347.21546 -243.5987) (xy 347.21546 -243.5098) (xy 347.214914 -243.494717)
			(xy 347.206102 -243.465867) (xy 347.189247 -243.44085) (xy 347.165819 -243.421847) (xy 347.137861 -243.410517)
			(xy 347.107814 -243.407848) (xy 347.078297 -243.414073) (xy 347.064838 -243.4209) (xy 347.038335 -243.434812)
			(xy 346.981823 -243.454525) (xy 346.922807 -243.464487) (xy 346.89288 -243.465096) (xy 346.866233 -243.464597)
			(xy 346.813533 -243.456651) (xy 346.762607 -243.44094) (xy 346.714591 -243.417814) (xy 346.670557 -243.38779)
			(xy 346.631491 -243.35154) (xy 346.598263 -243.309871) (xy 346.571616 -243.263716) (xy 346.552146 -243.214105)
			(xy 346.540287 -243.162146) (xy 346.536304 -243.109) (xy 346.540287 -243.055854) (xy 346.552146 -243.003895)
			(xy 346.571616 -242.954284) (xy 346.598263 -242.908129) (xy 346.631491 -242.86646) (xy 346.670557 -242.83021)
			(xy 346.714591 -242.800186) (xy 346.762607 -242.77706) (xy 346.813533 -242.761349) (xy 346.866233 -242.753403)
			(xy 346.89288 -242.75288) (xy 346.922805 -242.753495) (xy 346.981814 -242.763485) (xy 347.038333 -242.783172)
			(xy 347.064838 -242.797076) (xy 347.078308 -242.803881) (xy 347.107824 -242.810099) (xy 347.137869 -242.807429)
			(xy 347.165825 -242.796103) (xy 347.189257 -242.777108) (xy 347.206121 -242.7521) (xy 347.21495 -242.723257)
			(xy 347.21546 -242.708176) (xy 347.21546 -242.619022) (xy 347.190949 -242.607302) (xy 347.145494 -242.577544)
			(xy 347.105087 -242.541228) (xy 347.070664 -242.499195) (xy 347.043026 -242.452421) (xy 347.022812 -242.401993)
			(xy 347.010493 -242.349079) (xy 347.006354 -242.294907) (xy 347.010491 -242.240736) (xy 347.022808 -242.187822)
			(xy 347.043019 -242.137392) (xy 347.070656 -242.090617) (xy 347.105076 -242.048583) (xy 347.145482 -242.012265)
			(xy 347.190935 -241.982505) (xy 347.21546 -241.970814) (xy 347.21546 -241.881914) (xy 347.214916 -241.86683)
			(xy 347.206106 -241.837976) (xy 347.189251 -241.812955) (xy 347.165822 -241.793949) (xy 347.137862 -241.782617)
			(xy 347.107812 -241.779948) (xy 347.078293 -241.786175) (xy 347.064838 -241.793014) (xy 347.038336 -241.806929)
			(xy 346.981825 -241.826647) (xy 346.922807 -241.836612) (xy 346.89288 -241.83721) (xy 346.866232 -241.836711)
			(xy 346.81353 -241.828765) (xy 346.762602 -241.813053) (xy 346.714584 -241.789926) (xy 346.670549 -241.759901)
			(xy 346.63148 -241.723649) (xy 346.598251 -241.681979) (xy 346.571603 -241.635822) (xy 346.552133 -241.586209)
			(xy 346.540273 -241.534248) (xy 346.53629 -241.4811) (xy 346.540273 -241.427952) (xy 346.552133 -241.375991)
			(xy 346.571603 -241.326378) (xy 346.598251 -241.280221) (xy 346.63148 -241.238551) (xy 346.670549 -241.202299)
			(xy 346.714584 -241.172274) (xy 346.762602 -241.149147) (xy 346.81353 -241.133435) (xy 346.866232 -241.125489)
			(xy 346.89288 -241.124994) (xy 346.922805 -241.125609) (xy 346.981814 -241.135599) (xy 347.038332 -241.155287)
			(xy 347.064838 -241.16919) (xy 347.078309 -241.175994) (xy 347.107825 -241.182212) (xy 347.137871 -241.179541)
			(xy 347.165828 -241.168216) (xy 347.189261 -241.149222) (xy 347.206128 -241.124214) (xy 347.21496 -241.095372)
			(xy 347.21546 -241.08029) (xy 347.21546 -240.99139) (xy 347.190951 -240.97967) (xy 347.145501 -240.949913)
			(xy 347.105098 -240.913598) (xy 347.07068 -240.871567) (xy 347.043046 -240.824797) (xy 347.022836 -240.774371)
			(xy 347.01052 -240.721461) (xy 347.006383 -240.667294) (xy 347.010521 -240.613127) (xy 347.022839 -240.560218)
			(xy 347.043051 -240.509793) (xy 347.070687 -240.463023) (xy 347.105106 -240.420994) (xy 347.14551 -240.38468)
			(xy 347.190961 -240.354924) (xy 347.21546 -240.343182) (xy 347.21546 -240.254028) (xy 347.214917 -240.238942)
			(xy 347.20611 -240.210085) (xy 347.189256 -240.185059) (xy 347.165825 -240.166051) (xy 347.137863 -240.154717)
			(xy 347.107809 -240.152048) (xy 347.078288 -240.158276) (xy 347.064838 -240.165128) (xy 347.038336 -240.179042)
			(xy 346.981824 -240.19876) (xy 346.922807 -240.208724) (xy 346.89288 -240.209324) (xy 346.86623 -240.208825)
			(xy 346.813527 -240.200878) (xy 346.762597 -240.185166) (xy 346.714577 -240.162038) (xy 346.67054 -240.132012)
			(xy 346.63147 -240.095759) (xy 346.59824 -240.054087) (xy 346.571591 -240.007928) (xy 346.552119 -239.958313)
			(xy 346.540259 -239.90635) (xy 346.536276 -239.8532) (xy 346.540259 -239.80005) (xy 346.552119 -239.748087)
			(xy 346.571591 -239.698472) (xy 346.59824 -239.652313) (xy 346.63147 -239.610641) (xy 346.67054 -239.574388)
			(xy 346.714577 -239.544362) (xy 346.762597 -239.521234) (xy 346.813527 -239.505522) (xy 346.86623 -239.497575)
			(xy 346.89288 -239.497108) (xy 346.922804 -239.497723) (xy 346.981814 -239.507714) (xy 347.038332 -239.527402)
			(xy 347.064838 -239.541304) (xy 347.07831 -239.548108) (xy 347.107827 -239.554324) (xy 347.137873 -239.551653)
			(xy 347.165831 -239.540328) (xy 347.189266 -239.521335) (xy 347.206135 -239.496328) (xy 347.21497 -239.467486)
			(xy 347.21546 -239.452404) (xy 347.21546 -239.363504) (xy 347.19095 -239.351784) (xy 347.145498 -239.322027)
			(xy 347.105093 -239.285711) (xy 347.070673 -239.243679) (xy 347.043037 -239.196907) (xy 347.022825 -239.146481)
			(xy 347.010508 -239.093569) (xy 347.00637 -239.0394) (xy 347.010508 -238.985231) (xy 347.022825 -238.932319)
			(xy 347.043037 -238.881893) (xy 347.070673 -238.835121) (xy 347.105093 -238.793089) (xy 347.145498 -238.756773)
			(xy 347.19095 -238.727016) (xy 347.21546 -238.715296) (xy 347.21546 -238.626396) (xy 347.214926 -238.611302)
			(xy 347.20613 -238.582427) (xy 347.189277 -238.557383) (xy 347.16584 -238.53836) (xy 347.137866 -238.527018)
			(xy 347.107798 -238.524349) (xy 347.078263 -238.530585) (xy 347.064838 -238.537496) (xy 347.038335 -238.551408)
			(xy 346.981823 -238.571121) (xy 346.922807 -238.581084) (xy 346.89288 -238.581692) (xy 346.866233 -238.581192)
			(xy 346.813534 -238.573247) (xy 346.762608 -238.557536) (xy 346.714593 -238.53441) (xy 346.67056 -238.504387)
			(xy 346.631494 -238.468136) (xy 346.598266 -238.426469) (xy 346.57162 -238.380314) (xy 346.55215 -238.330703)
			(xy 346.540292 -238.278745) (xy 346.536309 -238.2256) (xy 346.540292 -238.172455) (xy 346.55215 -238.120497)
			(xy 346.57162 -238.070886) (xy 346.598266 -238.024731) (xy 346.631494 -237.983064) (xy 346.67056 -237.946813)
			(xy 346.714593 -237.91679) (xy 346.762608 -237.893664) (xy 346.813534 -237.877953) (xy 346.866233 -237.870008)
			(xy 346.89288 -237.869476) (xy 346.922805 -237.870091) (xy 346.981814 -237.880081) (xy 347.038333 -237.899768)
			(xy 347.064838 -237.913672) (xy 347.078308 -237.920477) (xy 347.107823 -237.926696) (xy 347.137868 -237.924026)
			(xy 347.165824 -237.9127) (xy 347.189255 -237.893705) (xy 347.206119 -237.868696) (xy 347.214947 -237.839853)
			(xy 347.21546 -237.824772) (xy 347.21546 -237.735618) (xy 347.192463 -237.724673) (xy 347.149587 -237.697183)
			(xy 347.111065 -237.663866) (xy 347.077682 -237.625401) (xy 347.050119 -237.582573) (xy 347.028939 -237.536254)
			(xy 347.014574 -237.487391) (xy 347.007316 -237.43698) (xy 347.006926 -237.411514) (xy 347.007441 -237.384304)
			(xy 347.015722 -237.330518) (xy 347.032093 -237.278619) (xy 347.056173 -237.229816) (xy 347.0874 -237.185247)
			(xy 347.125047 -237.14595) (xy 347.168236 -237.112842) (xy 347.215962 -237.086692) (xy 347.267112 -237.068112)
			(xy 347.293692 -237.062264) (xy 347.308932 -237.059216) (xy 347.551502 -236.816646) (xy 347.533922 -236.793018)
			(xy 347.50594 -236.7412) (xy 347.486855 -236.685488) (xy 347.477185 -236.627397) (xy 347.476572 -236.597952)
			(xy 347.477125 -236.569971) (xy 347.485885 -236.514698) (xy 347.503184 -236.461476) (xy 347.528594 -236.411615)
			(xy 347.561491 -236.366343) (xy 347.601064 -236.326773) (xy 347.646339 -236.29388) (xy 347.696202 -236.268473)
			(xy 347.749426 -236.251179) (xy 347.804699 -236.242422) (xy 347.83268 -236.241844) (xy 347.862131 -236.242394)
			(xy 347.920236 -236.252045) (xy 347.975958 -236.271138) (xy 348.027772 -236.29915) (xy 348.051374 -236.316774)
			(xy 348.12732 -236.240828) (xy 348.137653 -236.229736) (xy 348.151878 -236.202985) (xy 348.157618 -236.173235)
			(xy 348.154366 -236.143111) (xy 348.14241 -236.115272) (xy 348.122803 -236.092173) (xy 348.110302 -236.083602)
			(xy 348.089148 -236.069455) (xy 348.050702 -236.036114) (xy 348.017389 -235.997643) (xy 347.989888 -235.954825)
			(xy 347.968758 -235.908529) (xy 347.954429 -235.859699) (xy 347.947192 -235.809327) (xy 347.946726 -235.783882)
			(xy 347.947248 -235.755899) (xy 347.956006 -235.700621) (xy 347.973304 -235.647394) (xy 347.998716 -235.597529)
			(xy 348.031615 -235.552253) (xy 348.071193 -235.512681) (xy 348.116474 -235.479788) (xy 348.166343 -235.454384)
			(xy 348.219572 -235.437094) (xy 348.27485 -235.428344) (xy 348.302834 -235.427774) (xy 348.328279 -235.42823)
			(xy 348.37865 -235.435472) (xy 348.427478 -235.449806) (xy 348.473772 -235.470939) (xy 348.51659 -235.498441)
			(xy 348.55506 -235.531754) (xy 348.588401 -235.5702) (xy 348.602554 -235.59135) (xy 348.611213 -235.603768)
			(xy 348.634327 -235.623295) (xy 348.662139 -235.63521) (xy 348.69222 -235.638474) (xy 348.721942 -235.632801)
			(xy 348.748705 -235.618686) (xy 348.75978 -235.608368) (xy 348.869254 -235.498894) (xy 348.8786 -235.488946)
			(xy 348.892115 -235.465243) (xy 348.898867 -235.438807) (xy 348.898372 -235.411526) (xy 348.890667 -235.385351)
			(xy 348.876301 -235.362154) (xy 348.856303 -235.343592) (xy 348.832101 -235.330993) (xy 348.805425 -235.325256)
			(xy 348.791784 -235.325666) (xy 348.77248 -235.326174) (xy 348.745403 -235.325667) (xy 348.691875 -235.317464)
			(xy 348.640206 -235.30125) (xy 348.591587 -235.277399) (xy 348.547141 -235.246461) (xy 348.507892 -235.20915)
			(xy 348.474746 -235.166326) (xy 348.448466 -235.118977) (xy 348.429659 -235.068194) (xy 348.418759 -235.015149)
			(xy 348.416016 -234.961065) (xy 348.421495 -234.907189) (xy 348.435069 -234.854764) (xy 348.456424 -234.804999)
			(xy 348.485069 -234.759042) (xy 348.520342 -234.717952) (xy 348.561431 -234.682677) (xy 348.607387 -234.654031)
			(xy 348.657151 -234.632673) (xy 348.709575 -234.619098) (xy 348.763451 -234.613617) (xy 348.817535 -234.616357)
			(xy 348.87058 -234.627255) (xy 348.921364 -234.64606) (xy 348.968714 -234.672338) (xy 349.01154 -234.705483)
			(xy 349.048852 -234.74473) (xy 349.079792 -234.789175) (xy 349.103645 -234.837793) (xy 349.119861 -234.889461)
			(xy 349.128066 -234.942989) (xy 349.128588 -234.970066) (xy 349.12808 -234.98937) (xy 349.127773 -235.003004)
			(xy 349.133543 -235.029646) (xy 349.146153 -235.053814) (xy 349.164706 -235.073787) (xy 349.187881 -235.088141)
			(xy 349.214027 -235.095854) (xy 349.241282 -235.096378) (xy 349.267705 -235.089675) (xy 349.291415 -235.076222)
			(xy 349.301308 -235.06684) (xy 349.357696 -235.010452) (xy 349.35668 -234.987846) (xy 349.356172 -234.970066)
			(xy 349.356723 -234.942084) (xy 349.365483 -234.88681) (xy 349.38278 -234.833586) (xy 349.408189 -234.783723)
			(xy 349.441086 -234.738448) (xy 349.480659 -234.698877) (xy 349.525935 -234.665982) (xy 349.575799 -234.640575)
			(xy 349.629023 -234.623279) (xy 349.684298 -234.614522) (xy 349.71228 -234.613958) (xy 349.73006 -234.614466)
			(xy 349.752666 -234.615482) (xy 349.943674 -234.424474) (xy 349.912686 -234.388914) (xy 349.896476 -234.369407)
			(xy 349.869162 -234.326673) (xy 349.84818 -234.280498) (xy 349.833955 -234.231816) (xy 349.826773 -234.181609)
			(xy 349.826326 -234.15625) (xy 349.826879 -234.12827) (xy 349.83564 -234.073001) (xy 349.85294 -234.019783)
			(xy 349.878351 -233.969926) (xy 349.911248 -233.924658) (xy 349.950822 -233.885094) (xy 349.996098 -233.852207)
			(xy 350.045961 -233.826807) (xy 350.099183 -233.809521) (xy 350.154454 -233.800772) (xy 350.182434 -233.800142)
			(xy 350.207797 -233.800565) (xy 350.258016 -233.807719) (xy 350.306709 -233.821933) (xy 350.352889 -233.842919)
			(xy 350.395621 -233.870252) (xy 350.415098 -233.886502) (xy 350.450658 -233.91749) (xy 350.53651 -233.831638)
			(xy 350.546139 -233.821375) (xy 350.559852 -233.796812) (xy 350.566341 -233.769439) (xy 350.565113 -233.741334)
			(xy 350.556262 -233.714631) (xy 350.540459 -233.691357) (xy 350.518904 -233.67328) (xy 350.506284 -233.667046)
			(xy 350.483124 -233.656168) (xy 350.439919 -233.628755) (xy 350.401081 -233.595441) (xy 350.367411 -233.556912)
			(xy 350.339601 -233.513961) (xy 350.318223 -233.467473) (xy 350.303719 -233.418404) (xy 350.296385 -233.367764)
			(xy 350.295972 -233.34218) (xy 350.296522 -233.314197) (xy 350.30528 -233.258921) (xy 350.322576 -233.205696)
			(xy 350.347985 -233.155831) (xy 350.380881 -233.110554) (xy 350.420454 -233.070981) (xy 350.465731 -233.038085)
			(xy 350.515596 -233.012676) (xy 350.568821 -232.99538) (xy 350.624097 -232.986622) (xy 350.65208 -232.986072)
			(xy 350.677664 -232.986514) (xy 350.728304 -232.993836) (xy 350.777375 -233.008332) (xy 350.823866 -233.029703)
			(xy 350.866818 -233.05751) (xy 350.905347 -233.091179) (xy 350.938659 -233.130017) (xy 350.966068 -233.173224)
			(xy 350.976946 -233.196384) (xy 350.983124 -233.209033) (xy 351.001222 -233.230583) (xy 351.02451 -233.246381)
			(xy 351.051223 -233.255229) (xy 351.079337 -233.256458) (xy 351.10672 -233.249973) (xy 351.131297 -233.236268)
			(xy 351.141538 -233.22661) (xy 351.33788 -233.030268) (xy 351.419668 -233.030268) (xy 351.43059 -233.02468)
			(xy 351.455721 -233.012523) (xy 351.508827 -232.995315) (xy 351.563968 -232.986604) (xy 351.619792 -232.986604)
			(xy 351.674933 -232.995315) (xy 351.728039 -233.012523) (xy 351.75317 -233.02468) (xy 351.764092 -233.030268)
			(xy 352.359722 -233.030268) (xy 352.370644 -233.02468) (xy 352.395775 -233.012523) (xy 352.448881 -232.995315)
			(xy 352.504022 -232.986604) (xy 352.559846 -232.986604) (xy 352.614987 -232.995315) (xy 352.668093 -233.012523)
			(xy 352.693224 -233.02468) (xy 352.704146 -233.030268) (xy 353.299522 -233.030268) (xy 353.310444 -233.02468)
			(xy 353.335575 -233.012523) (xy 353.388681 -232.995315) (xy 353.443822 -232.986604) (xy 353.499646 -232.986604)
			(xy 353.554787 -232.995315) (xy 353.607893 -233.012523) (xy 353.633024 -233.02468) (xy 353.643946 -233.030268)
			(xy 354.239068 -233.030268) (xy 354.24999 -233.02468) (xy 354.275121 -233.012523) (xy 354.328227 -232.995315)
			(xy 354.383368 -232.986604) (xy 354.439192 -232.986604) (xy 354.494333 -232.995315) (xy 354.547439 -233.012523)
			(xy 354.57257 -233.02468) (xy 354.583492 -233.030268) (xy 355.178868 -233.030268) (xy 355.18979 -233.02468)
			(xy 355.214921 -233.012523) (xy 355.268027 -232.995315) (xy 355.323168 -232.986604) (xy 355.378992 -232.986604)
			(xy 355.434133 -232.995315) (xy 355.487239 -233.012523) (xy 355.51237 -233.02468) (xy 355.523292 -233.030268)
			(xy 356.118668 -233.030268) (xy 356.12959 -233.02468) (xy 356.154721 -233.012523) (xy 356.207827 -232.995315)
			(xy 356.262968 -232.986604) (xy 356.318792 -232.986604) (xy 356.373933 -232.995315) (xy 356.427039 -233.012523)
			(xy 356.45217 -233.02468) (xy 356.463092 -233.030268) (xy 356.710996 -233.030268) (xy 356.806754 -232.93451)
			(xy 356.757478 -232.88498) (xy 356.738174 -232.88371) (xy 356.711425 -232.881497) (xy 356.65899 -232.870044)
			(xy 356.608867 -232.850853) (xy 356.562191 -232.824359) (xy 356.520019 -232.79116) (xy 356.483306 -232.75201)
			(xy 356.452884 -232.707794) (xy 356.42944 -232.659513) (xy 356.413506 -232.608262) (xy 356.405443 -232.5552)
			(xy 356.404926 -232.528364) (xy 356.405478 -232.500384) (xy 356.414237 -232.445113) (xy 356.431536 -232.391893)
			(xy 356.456946 -232.342034) (xy 356.489843 -232.296764) (xy 356.529417 -232.257198) (xy 356.574694 -232.224309)
			(xy 356.624558 -232.198909) (xy 356.677781 -232.181621) (xy 356.733054 -232.172872) (xy 356.761034 -232.172256)
			(xy 356.786399 -232.172706) (xy 356.836617 -232.179908) (xy 356.885304 -232.194161) (xy 356.931477 -232.215176)
			(xy 356.974202 -232.24253) (xy 357.012615 -232.275668) (xy 357.045938 -232.31392) (xy 357.073497 -232.356512)
			(xy 357.094735 -232.402583) (xy 357.10241 -232.426764) (xy 357.107218 -232.441002) (xy 357.123804 -232.466046)
			(xy 357.146954 -232.485186) (xy 357.174667 -232.49677) (xy 357.204552 -232.499798) (xy 357.234026 -232.494007)
			(xy 357.260544 -232.479899) (xy 357.271574 -232.46969) (xy 357.394256 -232.347008) (xy 357.397558 -232.341674)
			(xy 357.412557 -232.318327) (xy 357.448629 -232.276161) (xy 357.490805 -232.2401) (xy 357.514144 -232.225088)
			(xy 357.519478 -232.221786) (xy 357.856282 -231.884982) (xy 357.84282 -231.853486) (xy 357.833906 -231.831419)
			(xy 357.82135 -231.785513) (xy 357.815019 -231.738344) (xy 357.814626 -231.714548) (xy 357.815143 -231.686561)
			(xy 357.823893 -231.631276) (xy 357.841185 -231.57804) (xy 357.866593 -231.528166) (xy 357.899492 -231.482881)
			(xy 357.93907 -231.443301) (xy 357.984354 -231.410401) (xy 358.034227 -231.38499) (xy 358.087462 -231.367696)
			(xy 358.142747 -231.358944) (xy 358.170734 -231.35844) (xy 358.19453 -231.358837) (xy 358.241697 -231.365173)
			(xy 358.287603 -231.377726) (xy 358.309672 -231.386634) (xy 358.341168 -231.400096) (xy 358.418384 -231.32288)
			(xy 358.428015 -231.312621) (xy 358.44173 -231.288064) (xy 358.448214 -231.260694) (xy 358.446972 -231.232593)
			(xy 358.438101 -231.205901) (xy 358.422274 -231.182648) (xy 358.41178 -231.173274) (xy 358.392234 -231.156261)
			(xy 358.357788 -231.11755) (xy 358.329314 -231.074257) (xy 358.307412 -231.027295) (xy 358.292545 -230.977656)
			(xy 358.285026 -230.926387) (xy 358.284526 -230.900478) (xy 358.285048 -230.872495) (xy 358.293807 -230.817218)
			(xy 358.311105 -230.763992) (xy 358.336517 -230.714127) (xy 358.369417 -230.668852) (xy 358.408994 -230.62928)
			(xy 358.454275 -230.596388) (xy 358.504143 -230.570984) (xy 358.557372 -230.553694) (xy 358.612651 -230.544944)
			(xy 358.640634 -230.54437) (xy 358.666546 -230.544832) (xy 358.717824 -230.552339) (xy 358.767471 -230.567202)
			(xy 358.814438 -230.589108) (xy 358.857731 -230.617594) (xy 358.896436 -230.652058) (xy 358.91343 -230.671624)
			(xy 358.922821 -230.68209) (xy 358.946089 -230.69786) (xy 358.972772 -230.706701) (xy 359.000853 -230.707946)
			(xy 359.028213 -230.701501) (xy 359.052786 -230.687852) (xy 359.063036 -230.678228) (xy 359.149396 -230.591868)
			(xy 359.149396 -230.493316) (xy 359.148948 -230.483495) (xy 359.141572 -230.465292) (xy 359.127895 -230.451195)
			(xy 359.109922 -230.443272) (xy 359.10012 -230.442516) (xy 359.073999 -230.441293) (xy 359.022517 -230.432138)
			(xy 358.972927 -230.41555) (xy 358.926298 -230.391885) (xy 358.883633 -230.361654) (xy 358.845849 -230.325506)
			(xy 358.813761 -230.28422) (xy 358.788057 -230.238683) (xy 358.769292 -230.189876) (xy 358.757869 -230.138848)
			(xy 358.754034 -230.086699) (xy 358.757869 -230.034549) (xy 358.769292 -229.983522) (xy 358.788058 -229.934715)
			(xy 358.813762 -229.889179) (xy 358.845851 -229.847892) (xy 358.883635 -229.811745) (xy 358.9263 -229.781514)
			(xy 358.97293 -229.75785) (xy 359.022519 -229.741262) (xy 359.074002 -229.732107) (xy 359.10012 -229.730808)
			(xy 359.109927 -229.730063) (xy 359.127907 -229.72214) (xy 359.141593 -229.708041) (xy 359.148978 -229.689832)
			(xy 359.149396 -229.680008) (xy 359.149396 -228.865684) (xy 359.148942 -228.855867) (xy 359.14156 -228.837674)
			(xy 359.127884 -228.823588) (xy 359.109918 -228.815671) (xy 359.10012 -228.814884) (xy 359.073994 -228.813661)
			(xy 359.022502 -228.804504) (xy 358.972903 -228.787913) (xy 358.926265 -228.764244) (xy 358.883591 -228.734008)
			(xy 358.8458 -228.697853) (xy 358.813705 -228.656559) (xy 358.787996 -228.611014) (xy 358.769227 -228.562197)
			(xy 358.757802 -228.51116) (xy 358.753966 -228.459001) (xy 358.757802 -228.406842) (xy 358.769227 -228.355804)
			(xy 358.787996 -228.306988) (xy 358.813704 -228.261443) (xy 358.845799 -228.220148) (xy 358.88359 -228.183994)
			(xy 358.926263 -228.153756) (xy 358.972901 -228.130088) (xy 359.0225 -228.113496) (xy 359.073993 -228.10434)
			(xy 359.10012 -228.103176) (xy 359.109924 -228.102431) (xy 359.127899 -228.094506) (xy 359.141577 -228.080406)
			(xy 359.148952 -228.062198) (xy 359.149396 -228.052376) (xy 359.149396 -227.237798) (xy 359.148945 -227.22798)
			(xy 359.141565 -227.209782) (xy 359.127889 -227.195691) (xy 359.10992 -227.187771) (xy 359.10012 -227.186998)
			(xy 359.073984 -227.185788) (xy 359.022467 -227.176654) (xy 358.972841 -227.16008) (xy 358.926175 -227.136421)
			(xy 358.883475 -227.106187) (xy 358.845658 -227.07003) (xy 358.813541 -227.028727) (xy 358.787813 -226.983169)
			(xy 358.769031 -226.934336) (xy 358.757596 -226.883281) (xy 358.753757 -226.831101) (xy 358.757596 -226.778922)
			(xy 358.76903 -226.727866) (xy 358.787812 -226.679033) (xy 358.813539 -226.633475) (xy 358.845657 -226.592172)
			(xy 358.883473 -226.556015) (xy 358.926173 -226.525781) (xy 358.972839 -226.502121) (xy 359.022464 -226.485546)
			(xy 359.073981 -226.476412) (xy 359.10012 -226.47529) (xy 359.109925 -226.474545) (xy 359.127902 -226.46662)
			(xy 359.141583 -226.452521) (xy 359.148963 -226.434313) (xy 359.149396 -226.42449) (xy 359.149396 -225.609912)
			(xy 359.148947 -225.600092) (xy 359.14157 -225.581889) (xy 359.127893 -225.567794) (xy 359.109922 -225.559872)
			(xy 359.10012 -225.559112) (xy 359.07399 -225.557902) (xy 359.022485 -225.548771) (xy 358.972872 -225.532199)
			(xy 358.926218 -225.508546) (xy 358.883527 -225.478319) (xy 358.84572 -225.44217) (xy 358.813611 -225.400878)
			(xy 358.78789 -225.35533) (xy 358.769112 -225.306509) (xy 358.757681 -225.255466) (xy 358.753843 -225.203299)
			(xy 358.757682 -225.151132) (xy 358.769113 -225.100089) (xy 358.787891 -225.051268) (xy 358.813612 -225.00572)
			(xy 358.845722 -224.964428) (xy 358.883529 -224.928279) (xy 358.92622 -224.898053) (xy 358.972874 -224.8744)
			(xy 359.022488 -224.857829) (xy 359.073992 -224.848697) (xy 359.10012 -224.847404) (xy 359.109926 -224.846659)
			(xy 359.127906 -224.838735) (xy 359.141591 -224.824636) (xy 359.148975 -224.806428) (xy 359.149396 -224.796604)
			(xy 359.149396 -224.092262) (xy 359.14901 -224.082719) (xy 359.142054 -224.064946) (xy 359.129083 -224.050947)
			(xy 359.111892 -224.042658) (xy 359.09286 -224.041229) (xy 359.074623 -224.046855) (xy 359.059706 -224.05876)
			(xy 359.054654 -224.066862) (xy 358.960166 -224.230438) (xy 358.969818 -224.253552) (xy 358.978333 -224.275184)
			(xy 358.990316 -224.320102) (xy 358.996357 -224.366197) (xy 358.996742 -224.389442) (xy 358.996244 -224.416091)
			(xy 358.988301 -224.468795) (xy 358.972591 -224.519725) (xy 358.949465 -224.567746) (xy 358.919441 -224.611783)
			(xy 358.883189 -224.650854) (xy 358.841518 -224.684085) (xy 358.79536 -224.710734) (xy 358.745746 -224.730206)
			(xy 358.693784 -224.742066) (xy 358.640634 -224.74605) (xy 358.587484 -224.742066) (xy 358.535522 -224.730206)
			(xy 358.485908 -224.710734) (xy 358.43975 -224.684085) (xy 358.398079 -224.650854) (xy 358.361827 -224.611783)
			(xy 358.331803 -224.567746) (xy 358.308677 -224.519725) (xy 358.292967 -224.468795) (xy 358.285024 -224.416091)
			(xy 358.284526 -224.389442) (xy 358.284975 -224.363816) (xy 358.292328 -224.313094) (xy 358.306872 -224.263949)
			(xy 358.328309 -224.217395) (xy 358.356195 -224.174393) (xy 358.389955 -224.135831) (xy 358.428893 -224.102505)
			(xy 358.472204 -224.075102) (xy 358.518995 -224.054188) (xy 358.5683 -224.040194) (xy 358.593644 -224.036382)
			(xy 358.618282 -224.03308) (xy 358.790494 -223.734376) (xy 358.781096 -223.711516) (xy 358.772577 -223.689885)
			(xy 358.760584 -223.644967) (xy 358.754535 -223.598871) (xy 358.754172 -223.575626) (xy 358.754672 -223.548149)
			(xy 358.763099 -223.493845) (xy 358.779773 -223.441482) (xy 358.804296 -223.392304) (xy 358.836087 -223.347479)
			(xy 358.874389 -223.308073) (xy 358.918293 -223.275022) (xy 358.966755 -223.249112) (xy 359.018624 -223.230958)
			(xy 359.072667 -223.220992) (xy 359.10012 -223.219772) (xy 359.109924 -223.219027) (xy 359.127898 -223.211101)
			(xy 359.141575 -223.197001) (xy 359.148948 -223.178794) (xy 359.149396 -223.168972) (xy 359.149396 -222.354394)
			(xy 359.148944 -222.344576) (xy 359.141564 -222.32638) (xy 359.127887 -222.31229) (xy 359.109919 -222.304371)
			(xy 359.10012 -222.303594) (xy 359.073994 -222.30237) (xy 359.0225 -222.293214) (xy 358.972899 -222.276622)
			(xy 358.92626 -222.252953) (xy 358.883585 -222.222715) (xy 358.845793 -222.18656) (xy 358.813697 -222.145265)
			(xy 358.787987 -222.099718) (xy 358.769218 -222.0509) (xy 358.757792 -221.999862) (xy 358.753956 -221.947701)
			(xy 358.757792 -221.89554) (xy 358.769217 -221.844502) (xy 358.787986 -221.795684) (xy 358.813696 -221.750137)
			(xy 358.845791 -221.708842) (xy 358.883583 -221.672686) (xy 358.926258 -221.642448) (xy 358.972897 -221.618778)
			(xy 359.022498 -221.602187) (xy 359.073991 -221.59303) (xy 359.10012 -221.591886) (xy 359.109925 -221.591141)
			(xy 359.127901 -221.583216) (xy 359.141582 -221.569116) (xy 359.14896 -221.550909) (xy 359.149396 -221.541086)
			(xy 359.149396 -220.78188) (xy 359.088436 -220.676216) (xy 359.063544 -220.672914) (xy 359.038182 -220.669111)
			(xy 358.988831 -220.655168) (xy 358.94199 -220.634289) (xy 358.898629 -220.606906) (xy 358.859645 -220.573587)
			(xy 358.825843 -220.535019) (xy 358.797925 -220.492002) (xy 358.776466 -220.445424) (xy 358.76191 -220.396249)
			(xy 358.75456 -220.345496) (xy 358.754172 -220.319854) (xy 358.754678 -220.292381) (xy 358.763114 -220.238085)
			(xy 358.779793 -220.185731) (xy 358.804321 -220.136563) (xy 358.836113 -220.091748) (xy 358.874414 -220.05235)
			(xy 358.918316 -220.019308) (xy 358.966773 -219.993404) (xy 359.018636 -219.975255) (xy 359.072672 -219.965292)
			(xy 359.10012 -219.964) (xy 359.109926 -219.963255) (xy 359.127905 -219.955331) (xy 359.141589 -219.941232)
			(xy 359.148972 -219.923024) (xy 359.149396 -219.9132) (xy 359.149396 -219.098876) (xy 359.148941 -219.08906)
			(xy 359.141558 -219.07087) (xy 359.127882 -219.056786) (xy 359.109916 -219.04887) (xy 359.10012 -219.048076)
			(xy 359.07401 -219.046832) (xy 359.022552 -219.037641) (xy 358.972991 -219.021025) (xy 358.926393 -218.997342)
			(xy 358.883758 -218.967099) (xy 358.846004 -218.930947) (xy 358.813941 -218.889664) (xy 358.788259 -218.844136)
			(xy 358.76951 -218.795342) (xy 358.758097 -218.744332) (xy 358.754265 -218.692201) (xy 358.758096 -218.640069)
			(xy 358.769509 -218.589059) (xy 358.788258 -218.540265) (xy 358.81394 -218.494737) (xy 358.846003 -218.453454)
			(xy 358.883757 -218.417302) (xy 358.926392 -218.387059) (xy 358.97299 -218.363375) (xy 359.022551 -218.346759)
			(xy 359.074008 -218.337568) (xy 359.10012 -218.336368) (xy 359.109924 -218.335623) (xy 359.127897 -218.327697)
			(xy 359.141573 -218.313597) (xy 359.148945 -218.29539) (xy 359.149396 -218.285568) (xy 359.149396 -217.581226)
			(xy 359.149004 -217.571688) (xy 359.142043 -217.553928) (xy 359.129073 -217.53994) (xy 359.111889 -217.531658)
			(xy 359.092867 -217.530228) (xy 359.074638 -217.535847) (xy 359.059723 -217.547739) (xy 359.054654 -217.555826)
			(xy 358.960166 -217.719402) (xy 358.969818 -217.742516) (xy 358.978335 -217.764148) (xy 358.990323 -217.809066)
			(xy 358.996368 -217.855161) (xy 358.996742 -217.878406) (xy 358.996244 -217.905055) (xy 358.988301 -217.957759)
			(xy 358.972591 -218.008689) (xy 358.949465 -218.05671) (xy 358.919441 -218.100747) (xy 358.883189 -218.139818)
			(xy 358.841518 -218.173049) (xy 358.79536 -218.199698) (xy 358.745746 -218.21917) (xy 358.693784 -218.23103)
			(xy 358.640634 -218.235014) (xy 358.587484 -218.23103) (xy 358.535522 -218.21917) (xy 358.485908 -218.199698)
			(xy 358.43975 -218.173049) (xy 358.398079 -218.139818) (xy 358.361827 -218.100747) (xy 358.331803 -218.05671)
			(xy 358.308677 -218.008689) (xy 358.292967 -217.957759) (xy 358.285024 -217.905055) (xy 358.284526 -217.878406)
			(xy 358.284978 -217.852782) (xy 358.292334 -217.802063) (xy 358.306882 -217.752922) (xy 358.328321 -217.706373)
			(xy 358.356208 -217.663376) (xy 358.389969 -217.624818) (xy 358.428905 -217.591496) (xy 358.472215 -217.564096)
			(xy 358.519004 -217.543184) (xy 358.568306 -217.529193) (xy 358.593644 -217.525346) (xy 358.618282 -217.522044)
			(xy 358.790748 -217.223086) (xy 358.78135 -217.199972) (xy 358.772837 -217.178383) (xy 358.760848 -217.133551)
			(xy 358.754794 -217.08754) (xy 358.754426 -217.064336) (xy 358.754932 -217.036875) (xy 358.763362 -216.982604)
			(xy 358.780028 -216.930271) (xy 358.804533 -216.881119) (xy 358.836297 -216.836314) (xy 358.874566 -216.79692)
			(xy 358.918432 -216.76387) (xy 358.966853 -216.737951) (xy 359.018681 -216.719775) (xy 359.072685 -216.709776)
			(xy 359.10012 -216.708482) (xy 359.109925 -216.707737) (xy 359.1279 -216.699812) (xy 359.14158 -216.685712)
			(xy 359.148957 -216.667505) (xy 359.149396 -216.657682) (xy 359.149396 -215.843358) (xy 359.148938 -215.833545)
			(xy 359.141551 -215.81536) (xy 359.127876 -215.801282) (xy 359.109914 -215.79337) (xy 359.10012 -215.792558)
			(xy 359.072679 -215.791257) (xy 359.018661 -215.78126) (xy 358.966819 -215.763088) (xy 358.918382 -215.737173)
			(xy 358.874497 -215.704129) (xy 358.836205 -215.664738) (xy 358.804415 -215.619936) (xy 358.779881 -215.570785)
			(xy 358.763183 -215.51845) (xy 358.754718 -215.464171) (xy 358.754172 -215.436704) (xy 358.754563 -215.413502)
			(xy 358.760619 -215.367493) (xy 358.77259 -215.322658) (xy 358.781096 -215.301068) (xy 358.790494 -215.277954)
			(xy 358.618028 -214.978996) (xy 358.593136 -214.975694) (xy 358.567793 -214.971871) (xy 358.518484 -214.957895)
			(xy 358.471688 -214.936992) (xy 358.428374 -214.909594) (xy 358.389436 -214.876269) (xy 358.355679 -214.837704)
			(xy 358.327801 -214.794697) (xy 358.306379 -214.748137) (xy 358.291855 -214.698986) (xy 358.284529 -214.64826)
			(xy 358.284018 -214.622634) (xy 358.284516 -214.595985) (xy 358.292459 -214.543281) (xy 358.308169 -214.492351)
			(xy 358.331295 -214.44433) (xy 358.361319 -214.400293) (xy 358.397571 -214.361222) (xy 358.439242 -214.327991)
			(xy 358.4854 -214.301342) (xy 358.535014 -214.28187) (xy 358.586976 -214.27001) (xy 358.640126 -214.266027)
			(xy 358.693276 -214.27001) (xy 358.745238 -214.28187) (xy 358.794852 -214.301342) (xy 358.84101 -214.327991)
			(xy 358.882681 -214.361222) (xy 358.918933 -214.400293) (xy 358.948957 -214.44433) (xy 358.972083 -214.492351)
			(xy 358.987793 -214.543281) (xy 358.995736 -214.595985) (xy 358.996234 -214.622634) (xy 358.99584 -214.645836)
			(xy 358.98978 -214.691843) (xy 358.977805 -214.736676) (xy 358.96931 -214.75827) (xy 358.959912 -214.781384)
			(xy 359.054654 -214.945214) (xy 359.059766 -214.953263) (xy 359.074669 -214.965134) (xy 359.092879 -214.970743)
			(xy 359.111879 -214.969313) (xy 359.129044 -214.961044) (xy 359.142004 -214.947076) (xy 359.148967 -214.929341)
			(xy 359.149396 -214.919814) (xy 359.149396 -191.238632) (xy 367.94948 -182.438548) (xy 367.94948 -179.436268)
			(xy 370.7892 -176.596548) (xy 375.0564 -176.596548) (xy 376.3391 -175.313848) (xy 376.3391 -173.083728)
			(xy 386.92328 -162.499548) (xy 394.403072 -162.499548) (xy 394.596874 -162.305746) (xy 394.606965 -162.294944)
			(xy 394.621003 -162.268944) (xy 394.627016 -162.240014) (xy 394.624502 -162.210573) (xy 394.613669 -162.183082)
			(xy 394.595425 -162.159839) (xy 394.571294 -162.142787) (xy 394.543293 -162.133351) (xy 394.528548 -162.132264)
			(xy 394.501906 -162.130928) (xy 394.449359 -162.121737) (xy 394.398605 -162.105317) (xy 394.350632 -162.081988)
			(xy 394.306377 -162.052205) (xy 394.266701 -162.016547) (xy 394.232378 -161.975712) (xy 394.204077 -161.930494)
			(xy 394.18235 -161.881775) (xy 394.16762 -161.830504) (xy 394.160175 -161.777682) (xy 394.15974 -161.75101)
			(xy 394.160203 -161.723758) (xy 394.167959 -161.669808) (xy 394.183314 -161.617512) (xy 394.205957 -161.567934)
			(xy 394.235425 -161.522083) (xy 394.27112 -161.480893) (xy 394.312313 -161.445203) (xy 394.358167 -161.415739)
			(xy 394.407748 -161.393101) (xy 394.460046 -161.377751) (xy 394.513996 -161.37) (xy 394.541248 -161.369502)
			(xy 394.567922 -161.369944) (xy 394.620751 -161.377371) (xy 394.672029 -161.392088) (xy 394.720756 -161.413807)
			(xy 394.76598 -161.442104) (xy 394.806821 -161.476428) (xy 394.842479 -161.516108) (xy 394.87226 -161.56037)
			(xy 394.895582 -161.60835) (xy 394.91199 -161.659112) (xy 394.921164 -161.711666) (xy 394.922502 -161.73831)
			(xy 394.923513 -161.753068) (xy 394.932948 -161.781091) (xy 394.950009 -161.805242) (xy 394.973268 -161.8235)
			(xy 395.000779 -161.834337) (xy 395.030241 -161.836848) (xy 395.05919 -161.830822) (xy 395.085203 -161.816763)
			(xy 395.095984 -161.806636) (xy 399.686272 -157.216348) (xy 399.70456 -157.216348) (xy 399.718199 -157.215915)
			(xy 399.744504 -157.208698) (xy 399.767957 -157.19477) (xy 399.786881 -157.175125) (xy 399.799924 -157.151168)
			(xy 399.806153 -157.124611) (xy 399.805123 -157.097354) (xy 399.796908 -157.071343) (xy 399.789904 -157.05963)
			(xy 399.76654 -157.022579) (xy 399.726197 -156.944821) (xy 399.693471 -156.863564) (xy 399.668662 -156.779551)
			(xy 399.651997 -156.693551) (xy 399.643628 -156.606352) (xy 399.643092 -156.562552) (xy 399.64358 -156.520276)
			(xy 399.651382 -156.436084) (xy 399.666918 -156.352971) (xy 399.690057 -156.271647) (xy 399.720601 -156.192804)
			(xy 399.758289 -156.117116) (xy 399.8028 -156.045228) (xy 399.853754 -155.977754) (xy 399.910717 -155.915269)
			(xy 399.973202 -155.858306) (xy 400.040676 -155.807352) (xy 400.112564 -155.762841) (xy 400.188252 -155.725153)
			(xy 400.267095 -155.694609) (xy 400.348419 -155.67147) (xy 400.431532 -155.655934) (xy 400.515724 -155.648132)
			(xy 400.600276 -155.648132) (xy 400.684468 -155.655934) (xy 400.767581 -155.67147) (xy 400.848905 -155.694609)
			(xy 400.927748 -155.725153) (xy 401.003436 -155.762841) (xy 401.075324 -155.807352) (xy 401.142798 -155.858306)
			(xy 401.205283 -155.915269) (xy 401.262246 -155.977754) (xy 401.3132 -156.045228) (xy 401.357711 -156.117116)
			(xy 401.395399 -156.192804) (xy 401.425943 -156.271647) (xy 401.449082 -156.352971) (xy 401.464618 -156.436084)
			(xy 401.47242 -156.520276) (xy 401.472908 -156.562552) (xy 401.472397 -156.606353) (xy 401.464028 -156.693555)
			(xy 401.447362 -156.779557) (xy 401.422553 -156.863573) (xy 401.389826 -156.944832) (xy 401.349482 -157.022591)
			(xy 401.326096 -157.05963) (xy 401.31907 -157.07132) (xy 401.310878 -157.097323) (xy 401.309865 -157.124568)
			(xy 401.316105 -157.151108) (xy 401.329151 -157.175047) (xy 401.348072 -157.194676) (xy 401.371515 -157.208593)
			(xy 401.397808 -157.215804) (xy 401.41144 -157.216348) (xy 403.53488 -157.216348) (xy 403.56028 -157.241748)
			(xy 408.86888 -157.241748) (xy 409.42768 -156.682948) (xy 409.42768 -149.266148) (xy 408.74188 -148.580348)
			(xy 408.478482 -148.580348) (xy 408.458366 -148.599368) (xy 408.413345 -148.631581) (xy 408.363883 -148.656445)
			(xy 408.311172 -148.67336) (xy 408.256479 -148.681921) (xy 408.201121 -148.681921) (xy 408.146428 -148.67336)
			(xy 408.093717 -148.656445) (xy 408.044255 -148.631581) (xy 407.999234 -148.599368) (xy 407.979118 -148.580348)
			(xy 401.62988 -148.580348) (xy 400.879818 -149.33041) (xy 400.870063 -149.340812) (xy 400.856233 -149.365736)
			(xy 400.849836 -149.393513) (xy 400.851372 -149.421975) (xy 400.86072 -149.448903) (xy 400.877152 -149.472194)
			(xy 400.899385 -149.490031) (xy 400.91233 -149.496018) (xy 400.950219 -149.51243) (xy 401.023159 -149.551143)
			(xy 401.092313 -149.596271) (xy 401.157119 -149.647448) (xy 401.217049 -149.704257) (xy 401.271616 -149.766235)
			(xy 401.320375 -149.832879) (xy 401.36293 -149.903646) (xy 401.398934 -149.97796) (xy 401.428094 -150.055217)
			(xy 401.450173 -150.134787) (xy 401.464991 -150.216023) (xy 401.472429 -150.298264) (xy 401.472908 -150.339552)
			(xy 401.472437 -150.38183) (xy 401.464639 -150.466027) (xy 401.449106 -150.549144) (xy 401.425969 -150.630474)
			(xy 401.395427 -150.709322) (xy 401.35774 -150.785015) (xy 401.313229 -150.856908) (xy 401.262274 -150.924387)
			(xy 401.205311 -150.986877) (xy 401.142824 -151.043844) (xy 401.075348 -151.094802) (xy 401.003457 -151.139316)
			(xy 400.927766 -151.177008) (xy 400.848919 -151.207554) (xy 400.767591 -151.230695) (xy 400.684474 -151.246233)
			(xy 400.600278 -151.254035) (xy 400.558 -151.25446) (xy 400.516711 -151.254003) (xy 400.43447 -151.246562)
			(xy 400.353234 -151.231739) (xy 400.273664 -151.209657) (xy 400.196408 -151.180494) (xy 400.122094 -151.144488)
			(xy 400.051327 -151.101932) (xy 399.984683 -151.053172) (xy 399.922703 -150.998604) (xy 399.865894 -150.938674)
			(xy 399.814716 -150.873868) (xy 399.769586 -150.804714) (xy 399.730872 -150.731774) (xy 399.714466 -150.693882)
			(xy 399.708537 -150.6809) (xy 399.690704 -150.658635) (xy 399.667401 -150.64218) (xy 399.640453 -150.632822)
			(xy 399.611967 -150.631294) (xy 399.584173 -150.637715) (xy 399.559243 -150.651582) (xy 399.548858 -150.66137)
			(xy 398.98828 -151.221948) (xy 398.98828 -151.229568) (xy 397.835952 -152.381896) (xy 399.668996 -152.381896)
			(xy 399.668996 -152.2972) (xy 399.677047 -152.212886) (xy 399.693076 -152.12972) (xy 399.716937 -152.048453)
			(xy 399.748416 -151.969823) (xy 399.787227 -151.894542) (xy 399.833017 -151.82329) (xy 399.885373 -151.756714)
			(xy 399.943821 -151.695416) (xy 400.007831 -151.639951) (xy 400.076823 -151.590822) (xy 400.150173 -151.548473)
			(xy 400.227216 -151.513289) (xy 400.307255 -151.485587) (xy 400.389564 -151.465619) (xy 400.473399 -151.453566)
			(xy 400.558 -151.449536) (xy 400.642601 -151.453566) (xy 400.726436 -151.465619) (xy 400.808745 -151.485587)
			(xy 400.888784 -151.513289) (xy 400.965827 -151.548473) (xy 401.039177 -151.590822) (xy 401.108169 -151.639951)
			(xy 401.172179 -151.695416) (xy 401.230627 -151.756714) (xy 401.282983 -151.82329) (xy 401.328773 -151.894542)
			(xy 401.367584 -151.969823) (xy 401.399063 -152.048453) (xy 401.422924 -152.12972) (xy 401.438953 -152.212886)
			(xy 401.447004 -152.2972) (xy 401.447508 -152.339548) (xy 401.447004 -152.381896) (xy 401.438953 -152.46621)
			(xy 401.422924 -152.549376) (xy 401.399063 -152.630643) (xy 401.367584 -152.709273) (xy 401.328773 -152.784554)
			(xy 401.282983 -152.855806) (xy 401.230627 -152.922382) (xy 401.172179 -152.98368) (xy 401.108169 -153.039145)
			(xy 401.039177 -153.088274) (xy 400.965827 -153.130623) (xy 400.888784 -153.165807) (xy 400.808745 -153.193509)
			(xy 400.726436 -153.213477) (xy 400.642601 -153.22553) (xy 400.558 -153.229561) (xy 400.473399 -153.22553)
			(xy 400.389564 -153.213477) (xy 400.307255 -153.193509) (xy 400.227216 -153.165807) (xy 400.150173 -153.130623)
			(xy 400.076823 -153.088274) (xy 400.007831 -153.039145) (xy 399.943821 -152.98368) (xy 399.885373 -152.922382)
			(xy 399.833017 -152.855806) (xy 399.787227 -152.784554) (xy 399.748416 -152.709273) (xy 399.716937 -152.630643)
			(xy 399.693076 -152.549376) (xy 399.677047 -152.46621) (xy 399.668996 -152.381896) (xy 397.835952 -152.381896)
			(xy 397.5608 -152.657048) (xy 346.94622 -152.657048) (xy 345.45778 -154.145488) (xy 345.45778 -156.613098)
			(xy 391.029188 -156.613098) (xy 391.033259 -156.557476) (xy 391.045385 -156.503039) (xy 391.065308 -156.450948)
			(xy 391.092604 -156.402313) (xy 391.12669 -156.35817) (xy 391.166839 -156.319461) (xy 391.212197 -156.28701)
			(xy 391.261797 -156.261509) (xy 391.314581 -156.243502) (xy 391.369424 -156.233372) (xy 391.425158 -156.231335)
			(xy 391.480595 -156.237435) (xy 391.534552 -156.251541) (xy 391.585881 -156.273353) (xy 391.633487 -156.302407)
			(xy 391.676355 -156.338082) (xy 391.713572 -156.379619) (xy 391.744345 -156.426132) (xy 391.768017 -156.476629)
			(xy 391.784085 -156.530036) (xy 391.792205 -156.585212) (xy 391.792714 -156.613098) (xy 391.792205 -156.640984)
			(xy 391.784085 -156.69616) (xy 391.768017 -156.749567) (xy 391.744345 -156.800064) (xy 391.713572 -156.846577)
			(xy 391.676355 -156.888114) (xy 391.633487 -156.923789) (xy 391.585881 -156.952843) (xy 391.534552 -156.974655)
			(xy 391.480595 -156.988761) (xy 391.425158 -156.994861) (xy 391.369424 -156.992824) (xy 391.314581 -156.982694)
			(xy 391.261797 -156.964687) (xy 391.212197 -156.939186) (xy 391.166839 -156.906735) (xy 391.12669 -156.868026)
			(xy 391.092604 -156.823883) (xy 391.065308 -156.775248) (xy 391.045385 -156.723157) (xy 391.033259 -156.66872)
			(xy 391.029188 -156.613098) (xy 345.45778 -156.613098) (xy 345.45778 -157.840426) (xy 359.54157 -157.840426)
			(xy 359.545641 -157.784804) (xy 359.557767 -157.730367) (xy 359.57769 -157.678276) (xy 359.604986 -157.629641)
			(xy 359.639072 -157.585498) (xy 359.679221 -157.546789) (xy 359.724579 -157.514338) (xy 359.774179 -157.488837)
			(xy 359.826963 -157.47083) (xy 359.881806 -157.4607) (xy 359.93754 -157.458663) (xy 359.992977 -157.464763)
			(xy 360.046934 -157.478869) (xy 360.098263 -157.500681) (xy 360.145869 -157.529735) (xy 360.188737 -157.56541)
			(xy 360.225954 -157.606947) (xy 360.256727 -157.65346) (xy 360.280399 -157.703957) (xy 360.296467 -157.757364)
			(xy 360.304587 -157.81254) (xy 360.305096 -157.840426) (xy 360.304587 -157.868312) (xy 360.296467 -157.923488)
			(xy 360.280399 -157.976895) (xy 360.256727 -158.027392) (xy 360.225954 -158.073905) (xy 360.188737 -158.115442)
			(xy 360.145869 -158.151117) (xy 360.098263 -158.180171) (xy 360.046934 -158.201983) (xy 359.992977 -158.216089)
			(xy 359.93754 -158.222189) (xy 359.881806 -158.220152) (xy 359.826963 -158.210022) (xy 359.774179 -158.192015)
			(xy 359.724579 -158.166514) (xy 359.679221 -158.134063) (xy 359.639072 -158.095354) (xy 359.604986 -158.051211)
			(xy 359.57769 -158.002576) (xy 359.557767 -157.950485) (xy 359.545641 -157.896048) (xy 359.54157 -157.840426)
			(xy 345.45778 -157.840426) (xy 345.45778 -160.435036) (xy 372.05666 -160.435036) (xy 372.057146 -160.407785)
			(xy 372.064902 -160.353837) (xy 372.080257 -160.301542) (xy 372.102899 -160.251965) (xy 372.132365 -160.206115)
			(xy 372.168056 -160.164924) (xy 372.209247 -160.129233) (xy 372.255097 -160.099767) (xy 372.304674 -160.077125)
			(xy 372.356969 -160.06177) (xy 372.410917 -160.054014) (xy 372.465419 -160.054014) (xy 372.519367 -160.06177)
			(xy 372.571662 -160.077125) (xy 372.621239 -160.099767) (xy 372.667089 -160.129233) (xy 372.70828 -160.164924)
			(xy 372.743971 -160.206115) (xy 372.773437 -160.251965) (xy 372.796079 -160.301542) (xy 372.811434 -160.353837)
			(xy 372.81919 -160.407785) (xy 372.819676 -160.435036) (xy 372.819422 -160.450022) (xy 372.81954 -160.460568)
			(xy 372.827199 -160.48019) (xy 372.84209 -160.495088) (xy 372.861709 -160.502756) (xy 372.872254 -160.502854)
			(xy 372.88724 -160.5026) (xy 373.75084 -160.5026) (xy 373.765826 -160.502854) (xy 373.776374 -160.502764)
			(xy 373.796002 -160.495099) (xy 373.810901 -160.480199) (xy 373.818565 -160.46057) (xy 373.818658 -160.450022)
			(xy 373.818404 -160.435036) (xy 373.81889 -160.407785) (xy 373.826646 -160.353837) (xy 373.842001 -160.301542)
			(xy 373.864643 -160.251965) (xy 373.894109 -160.206115) (xy 373.9298 -160.164924) (xy 373.970991 -160.129233)
			(xy 374.016841 -160.099767) (xy 374.066418 -160.077125) (xy 374.118713 -160.06177) (xy 374.172661 -160.054014)
			(xy 374.227163 -160.054014) (xy 374.281111 -160.06177) (xy 374.333406 -160.077125) (xy 374.382983 -160.099767)
			(xy 374.428833 -160.129233) (xy 374.470024 -160.164924) (xy 374.505715 -160.206115) (xy 374.535181 -160.251965)
			(xy 374.557823 -160.301542) (xy 374.573178 -160.353837) (xy 374.580934 -160.407785) (xy 374.580935 -160.407858)
			(xy 394.51915 -160.407858) (xy 394.519699 -160.377817) (xy 394.529089 -160.318473) (xy 394.54766 -160.261333)
			(xy 394.574956 -160.207809) (xy 394.6103 -160.159223) (xy 394.631164 -160.137602) (xy 394.640188 -160.12802)
			(xy 394.653461 -160.105302) (xy 394.660473 -160.079942) (xy 394.660756 -160.053632) (xy 394.654292 -160.028128)
			(xy 394.641511 -160.005129) (xy 394.632688 -159.995362) (xy 394.612734 -159.973903) (xy 394.578986 -159.926)
			(xy 394.552955 -159.873504) (xy 394.535251 -159.817645) (xy 394.526291 -159.759738) (xy 394.525754 -159.73044)
			(xy 394.52624 -159.703189) (xy 394.533996 -159.649241) (xy 394.549351 -159.596946) (xy 394.571993 -159.547369)
			(xy 394.601459 -159.501519) (xy 394.63715 -159.460328) (xy 394.678341 -159.424637) (xy 394.724191 -159.395171)
			(xy 394.773768 -159.372529) (xy 394.826063 -159.357174) (xy 394.880011 -159.349418) (xy 394.934513 -159.349418)
			(xy 394.988461 -159.357174) (xy 395.040756 -159.372529) (xy 395.090333 -159.395171) (xy 395.136183 -159.424637)
			(xy 395.177374 -159.460328) (xy 395.213065 -159.501519) (xy 395.242531 -159.547369) (xy 395.265173 -159.596946)
			(xy 395.280528 -159.649241) (xy 395.288284 -159.703189) (xy 395.28877 -159.73044) (xy 395.288214 -159.760481)
			(xy 395.278825 -159.819824) (xy 395.260255 -159.876963) (xy 395.232961 -159.930488) (xy 395.197619 -159.979074)
			(xy 395.176756 -160.000696) (xy 395.167739 -160.010282) (xy 395.154476 -160.033001) (xy 395.147469 -160.058358)
			(xy 395.147186 -160.084664) (xy 395.153645 -160.110166) (xy 395.166415 -160.133166) (xy 395.175232 -160.142936)
			(xy 395.195189 -160.164393) (xy 395.228935 -160.212296) (xy 395.254966 -160.264794) (xy 395.272669 -160.320652)
			(xy 395.281629 -160.37856) (xy 395.282166 -160.407858) (xy 395.28168 -160.435109) (xy 395.273924 -160.489057)
			(xy 395.258569 -160.541352) (xy 395.235927 -160.590929) (xy 395.206461 -160.636779) (xy 395.17077 -160.67797)
			(xy 395.129579 -160.713661) (xy 395.083729 -160.743127) (xy 395.034152 -160.765769) (xy 394.981857 -160.781124)
			(xy 394.927909 -160.78888) (xy 394.873407 -160.78888) (xy 394.819459 -160.781124) (xy 394.767164 -160.765769)
			(xy 394.717587 -160.743127) (xy 394.671737 -160.713661) (xy 394.630546 -160.67797) (xy 394.594855 -160.636779)
			(xy 394.565389 -160.590929) (xy 394.542747 -160.541352) (xy 394.527392 -160.489057) (xy 394.519636 -160.435109)
			(xy 394.51915 -160.407858) (xy 374.580935 -160.407858) (xy 374.58142 -160.435036) (xy 374.580901 -160.463698)
			(xy 374.572292 -160.520372) (xy 374.555304 -160.575121) (xy 374.530318 -160.626713) (xy 374.497897 -160.673988)
			(xy 374.45877 -160.715883) (xy 374.413817 -160.751454) (xy 374.36405 -160.779902) (xy 374.310587 -160.800586)
			(xy 374.254633 -160.813041) (xy 374.226074 -160.815528) (xy 374.211531 -160.81704) (xy 374.184124 -160.82718)
			(xy 374.160711 -160.844668) (xy 374.14321 -160.86807) (xy 374.133053 -160.895471) (xy 374.131586 -160.910016)
			(xy 374.129071 -160.938597) (xy 374.116648 -160.994607) (xy 374.095978 -161.048126) (xy 374.07897 -161.07791)
			(xy 390.87374 -161.07791) (xy 390.877811 -161.022288) (xy 390.889937 -160.967851) (xy 390.90986 -160.91576)
			(xy 390.937156 -160.867125) (xy 390.971242 -160.822982) (xy 391.011391 -160.784273) (xy 391.056749 -160.751822)
			(xy 391.106349 -160.726321) (xy 391.159133 -160.708314) (xy 391.213976 -160.698184) (xy 391.26971 -160.696147)
			(xy 391.325147 -160.702247) (xy 391.379104 -160.716353) (xy 391.430433 -160.738165) (xy 391.478039 -160.767219)
			(xy 391.520907 -160.802894) (xy 391.558124 -160.844431) (xy 391.588897 -160.890944) (xy 391.612569 -160.941441)
			(xy 391.628637 -160.994848) (xy 391.636757 -161.050024) (xy 391.637266 -161.07791) (xy 391.636757 -161.105796)
			(xy 391.628637 -161.160972) (xy 391.612569 -161.214379) (xy 391.588897 -161.264876) (xy 391.558124 -161.311389)
			(xy 391.520907 -161.352926) (xy 391.478039 -161.388601) (xy 391.430433 -161.417655) (xy 391.379104 -161.439467)
			(xy 391.325147 -161.453573) (xy 391.26971 -161.459673) (xy 391.213976 -161.457636) (xy 391.159133 -161.447506)
			(xy 391.106349 -161.429499) (xy 391.056749 -161.403998) (xy 391.011391 -161.371547) (xy 390.971242 -161.332838)
			(xy 390.937156 -161.288695) (xy 390.90986 -161.24006) (xy 390.889937 -161.187969) (xy 390.877811 -161.133532)
			(xy 390.87374 -161.07791) (xy 374.07897 -161.07791) (xy 374.067528 -161.097946) (xy 374.031938 -161.142945)
			(xy 373.990012 -161.182108) (xy 373.942695 -161.214551) (xy 373.891054 -161.239544) (xy 373.836252 -161.256522)
			(xy 373.779526 -161.265104) (xy 373.75084 -161.265616) (xy 372.88724 -161.265616) (xy 372.858555 -161.265172)
			(xy 372.801836 -161.256552) (xy 372.747044 -161.239545) (xy 372.695412 -161.214534) (xy 372.648103 -161.182081)
			(xy 372.60618 -161.142916) (xy 372.570586 -161.097922) (xy 372.542124 -161.04811) (xy 372.521432 -160.994601)
			(xy 372.508977 -160.938598) (xy 372.506494 -160.910016) (xy 372.505009 -160.895471) (xy 372.494856 -160.868066)
			(xy 372.477361 -160.844655) (xy 372.453955 -160.827155) (xy 372.426552 -160.816996) (xy 372.412006 -160.815528)
			(xy 372.383446 -160.812998) (xy 372.327476 -160.800584) (xy 372.273995 -160.779929) (xy 372.22421 -160.751499)
			(xy 372.179243 -160.715935) (xy 372.140108 -160.674039) (xy 372.107688 -160.626755) (xy 372.082713 -160.57515)
			(xy 372.065747 -160.520387) (xy 372.057172 -160.463702) (xy 372.05666 -160.435036) (xy 345.45778 -160.435036)
			(xy 345.45778 -164.043868) (xy 370.968522 -164.043868) (xy 370.972593 -163.988246) (xy 370.984719 -163.933809)
			(xy 371.004642 -163.881718) (xy 371.031938 -163.833083) (xy 371.066024 -163.78894) (xy 371.106173 -163.750231)
			(xy 371.151531 -163.71778) (xy 371.201131 -163.692279) (xy 371.253915 -163.674272) (xy 371.308758 -163.664142)
			(xy 371.364492 -163.662105) (xy 371.419929 -163.668205) (xy 371.473886 -163.682311) (xy 371.525215 -163.704123)
			(xy 371.572821 -163.733177) (xy 371.615689 -163.768852) (xy 371.652906 -163.810389) (xy 371.683679 -163.856902)
			(xy 371.707351 -163.907399) (xy 371.723419 -163.960806) (xy 371.731539 -164.015982) (xy 371.732048 -164.043868)
			(xy 371.731539 -164.071754) (xy 371.723419 -164.12693) (xy 371.707351 -164.180337) (xy 371.683679 -164.230834)
			(xy 371.652906 -164.277347) (xy 371.615689 -164.318884) (xy 371.572821 -164.354559) (xy 371.545017 -164.371528)
			(xy 371.771416 -164.371528) (xy 371.775487 -164.315906) (xy 371.787613 -164.261469) (xy 371.807536 -164.209378)
			(xy 371.834832 -164.160743) (xy 371.868918 -164.1166) (xy 371.909067 -164.077891) (xy 371.954425 -164.04544)
			(xy 372.004025 -164.019939) (xy 372.056809 -164.001932) (xy 372.111652 -163.991802) (xy 372.167386 -163.989765)
			(xy 372.222823 -163.995865) (xy 372.27678 -164.009971) (xy 372.328109 -164.031783) (xy 372.375715 -164.060837)
			(xy 372.418583 -164.096512) (xy 372.4558 -164.138049) (xy 372.486573 -164.184562) (xy 372.510245 -164.235059)
			(xy 372.526313 -164.288466) (xy 372.534433 -164.343642) (xy 372.534803 -164.363908) (xy 372.749062 -164.363908)
			(xy 372.753133 -164.308286) (xy 372.765259 -164.253849) (xy 372.785182 -164.201758) (xy 372.812478 -164.153123)
			(xy 372.846564 -164.10898) (xy 372.886713 -164.070271) (xy 372.932071 -164.03782) (xy 372.981671 -164.012319)
			(xy 373.034455 -163.994312) (xy 373.089298 -163.984182) (xy 373.145032 -163.982145) (xy 373.200469 -163.988245)
			(xy 373.254426 -164.002351) (xy 373.305755 -164.024163) (xy 373.353361 -164.053217) (xy 373.396229 -164.088892)
			(xy 373.433446 -164.130429) (xy 373.464219 -164.176942) (xy 373.487891 -164.227439) (xy 373.503959 -164.280846)
			(xy 373.512079 -164.336022) (xy 373.512588 -164.363908) (xy 373.512079 -164.391794) (xy 373.503959 -164.44697)
			(xy 373.487891 -164.500377) (xy 373.464219 -164.550874) (xy 373.433446 -164.597387) (xy 373.396229 -164.638924)
			(xy 373.353361 -164.674599) (xy 373.305755 -164.703653) (xy 373.254426 -164.725465) (xy 373.200469 -164.739571)
			(xy 373.145032 -164.745671) (xy 373.089298 -164.743634) (xy 373.034455 -164.733504) (xy 372.981671 -164.715497)
			(xy 372.932071 -164.689996) (xy 372.886713 -164.657545) (xy 372.846564 -164.618836) (xy 372.812478 -164.574693)
			(xy 372.785182 -164.526058) (xy 372.765259 -164.473967) (xy 372.753133 -164.41953) (xy 372.749062 -164.363908)
			(xy 372.534803 -164.363908) (xy 372.534942 -164.371528) (xy 372.534433 -164.399414) (xy 372.526313 -164.45459)
			(xy 372.510245 -164.507997) (xy 372.486573 -164.558494) (xy 372.4558 -164.605007) (xy 372.418583 -164.646544)
			(xy 372.375715 -164.682219) (xy 372.328109 -164.711273) (xy 372.27678 -164.733085) (xy 372.222823 -164.747191)
			(xy 372.167386 -164.753291) (xy 372.111652 -164.751254) (xy 372.056809 -164.741124) (xy 372.004025 -164.723117)
			(xy 371.954425 -164.697616) (xy 371.909067 -164.665165) (xy 371.868918 -164.626456) (xy 371.834832 -164.582313)
			(xy 371.807536 -164.533678) (xy 371.787613 -164.481587) (xy 371.775487 -164.42715) (xy 371.771416 -164.371528)
			(xy 371.545017 -164.371528) (xy 371.525215 -164.383613) (xy 371.473886 -164.405425) (xy 371.419929 -164.419531)
			(xy 371.364492 -164.425631) (xy 371.308758 -164.423594) (xy 371.253915 -164.413464) (xy 371.201131 -164.395457)
			(xy 371.151531 -164.369956) (xy 371.106173 -164.337505) (xy 371.066024 -164.298796) (xy 371.031938 -164.254653)
			(xy 371.004642 -164.206018) (xy 370.984719 -164.153927) (xy 370.972593 -164.09949) (xy 370.968522 -164.043868)
			(xy 345.45778 -164.043868) (xy 345.45778 -168.029949) (xy 348.20379 -168.029949) (xy 348.20379 -167.975451)
			(xy 348.211546 -167.921507) (xy 348.226899 -167.869216) (xy 348.249538 -167.819642) (xy 348.279 -167.773795)
			(xy 348.314688 -167.732606) (xy 348.355874 -167.696916) (xy 348.401719 -167.66745) (xy 348.451292 -167.644808)
			(xy 348.503582 -167.629451) (xy 348.557525 -167.621692) (xy 348.584774 -167.621204) (xy 348.603824 -167.621712)
			(xy 348.614239 -167.621718) (xy 348.63372 -167.614416) (xy 348.648715 -167.599994) (xy 348.656771 -167.580811)
			(xy 348.657164 -167.570404) (xy 348.657164 -167.565832) (xy 348.657658 -167.532531) (xy 348.666337 -167.466499)
			(xy 348.683566 -167.402165) (xy 348.709048 -167.340632) (xy 348.742347 -167.282953) (xy 348.782893 -167.230117)
			(xy 348.829992 -167.183027) (xy 348.882836 -167.142492) (xy 348.911418 -167.125396) (xy 349.83547 -166.591742)
			(xy 349.864533 -166.575642) (xy 349.925937 -166.550271) (xy 349.990123 -166.533114) (xy 350.055996 -166.524463)
			(xy 350.089216 -166.523924) (xy 350.089724 -166.523924) (xy 350.121194 -166.524421) (xy 350.183655 -166.532179)
			(xy 350.244683 -166.547574) (xy 350.30335 -166.570371) (xy 350.331278 -166.584884) (xy 350.343283 -166.590881)
			(xy 350.369399 -166.597018) (xy 350.396212 -166.596142) (xy 350.421872 -166.588314) (xy 350.444607 -166.574072)
			(xy 350.462849 -166.554402) (xy 350.469454 -166.54272) (xy 350.481927 -166.519971) (xy 350.512036 -166.477722)
			(xy 350.547593 -166.439944) (xy 350.587941 -166.407332) (xy 350.632337 -166.38049) (xy 350.679961 -166.359911)
			(xy 350.729934 -166.345976) (xy 350.781334 -166.338942) (xy 350.807274 -166.338504) (xy 350.834529 -166.338941)
			(xy 350.888484 -166.346695) (xy 350.940787 -166.36205) (xy 350.990372 -166.384691) (xy 351.03623 -166.41416)
			(xy 351.077427 -166.449854) (xy 351.113125 -166.491049) (xy 351.142596 -166.536905) (xy 351.165241 -166.586488)
			(xy 351.180599 -166.63879) (xy 351.188357 -166.692745) (xy 351.188357 -166.747255) (xy 351.180599 -166.80121)
			(xy 351.165241 -166.853512) (xy 351.142596 -166.903095) (xy 351.113125 -166.948951) (xy 351.077427 -166.990146)
			(xy 351.03623 -167.02584) (xy 350.990372 -167.055309) (xy 350.940787 -167.07795) (xy 350.888484 -167.093305)
			(xy 350.834529 -167.101059) (xy 350.807274 -167.10152) (xy 350.781883 -167.10108) (xy 350.731552 -167.09433)
			(xy 350.706944 -167.088058) (xy 350.6939 -167.084917) (xy 350.667077 -167.084867) (xy 350.641167 -167.091805)
			(xy 350.617958 -167.105252) (xy 350.599053 -167.124279) (xy 350.585756 -167.147574) (xy 350.581976 -167.160448)
			(xy 350.572961 -167.192834) (xy 350.547594 -167.255091) (xy 350.514252 -167.313466) (xy 350.494003 -167.34005)
			(xy 369.160803 -167.34005) (xy 369.160803 -167.28555) (xy 369.168559 -167.231606) (xy 369.183914 -167.179314)
			(xy 369.206554 -167.12974) (xy 369.236019 -167.083892) (xy 369.271709 -167.042704) (xy 369.312897 -167.007015)
			(xy 369.358745 -166.977551) (xy 369.40832 -166.954912) (xy 369.460612 -166.939558) (xy 369.514556 -166.931803)
			(xy 369.541806 -166.93134) (xy 369.560856 -166.931848) (xy 369.571269 -166.931846) (xy 369.590744 -166.924539)
			(xy 369.605736 -166.91012) (xy 369.613797 -166.890944) (xy 369.614196 -166.88054) (xy 369.614196 -166.875968)
			(xy 369.614752 -166.84267) (xy 369.623426 -166.776641) (xy 369.640648 -166.71231) (xy 369.666122 -166.650779)
			(xy 369.699412 -166.593101) (xy 369.739949 -166.540263) (xy 369.787038 -166.493171) (xy 369.839873 -166.452631)
			(xy 369.86845 -166.435532) (xy 370.792502 -165.901878) (xy 370.82156 -165.885769) (xy 370.882966 -165.8604)
			(xy 370.947153 -165.843245) (xy 371.013028 -165.834597) (xy 371.046248 -165.83406) (xy 371.046756 -165.83406)
			(xy 371.078227 -165.834539) (xy 371.140688 -165.842302) (xy 371.201717 -165.857702) (xy 371.260383 -165.880504)
			(xy 371.28831 -165.89502) (xy 371.300288 -165.901081) (xy 371.326416 -165.907218) (xy 371.35324 -165.906336)
			(xy 371.378909 -165.898495) (xy 371.401647 -165.884237) (xy 371.419886 -165.864547) (xy 371.426486 -165.852856)
			(xy 371.438908 -165.830078) (xy 371.469027 -165.787832) (xy 371.504592 -165.750056) (xy 371.544949 -165.717448)
			(xy 371.589351 -165.69061) (xy 371.636981 -165.670036) (xy 371.686959 -165.656105) (xy 371.738364 -165.649075)
			(xy 371.764306 -165.64864) (xy 371.79156 -165.64903) (xy 371.845514 -165.656788) (xy 371.897815 -165.672146)
			(xy 371.947398 -165.69479) (xy 371.993253 -165.724261) (xy 372.034448 -165.759957) (xy 372.070143 -165.801152)
			(xy 372.099612 -165.847008) (xy 372.122256 -165.896591) (xy 372.137613 -165.948892) (xy 372.14537 -166.002846)
			(xy 372.14537 -166.057354) (xy 372.137613 -166.111308) (xy 372.122256 -166.163609) (xy 372.099612 -166.213192)
			(xy 372.070143 -166.259048) (xy 372.034448 -166.300243) (xy 371.993253 -166.335939) (xy 371.947398 -166.36541)
			(xy 371.897815 -166.388054) (xy 371.845514 -166.403412) (xy 371.79156 -166.41117) (xy 371.764306 -166.411656)
			(xy 371.738915 -166.411228) (xy 371.688583 -166.404469) (xy 371.663976 -166.398194) (xy 371.650916 -166.395134)
			(xy 371.624107 -166.395078) (xy 371.598208 -166.402004) (xy 371.575005 -166.415435) (xy 371.556099 -166.434443)
			(xy 371.542794 -166.457719) (xy 371.539008 -166.470584) (xy 371.530041 -166.502985) (xy 371.504666 -166.565242)
			(xy 371.471316 -166.623617) (xy 371.451785 -166.649251) (xy 372.910346 -166.649251) (xy 372.910346 -166.594749)
			(xy 372.918102 -166.5408) (xy 372.933456 -166.488505) (xy 372.956095 -166.438927) (xy 372.98556 -166.393075)
			(xy 373.021249 -166.351882) (xy 373.062438 -166.316188) (xy 373.108286 -166.286718) (xy 373.157862 -166.264072)
			(xy 373.210155 -166.248711) (xy 373.264103 -166.240949) (xy 373.291354 -166.24046) (xy 373.319727 -166.240978)
			(xy 373.375847 -166.249391) (xy 373.430102 -166.266023) (xy 373.481295 -166.290507) (xy 373.528297 -166.322303)
			(xy 373.570071 -166.36071) (xy 373.605696 -166.404881) (xy 373.634386 -166.453841) (xy 373.64543 -166.479982)
			(xy 373.649555 -166.489205) (xy 373.663696 -166.503614) (xy 373.682312 -166.511426) (xy 373.7025 -166.511423)
			(xy 373.711978 -166.507922) (xy 373.743057 -166.495621) (xy 373.807615 -166.478305) (xy 373.873884 -166.469579)
			(xy 373.907304 -166.46906) (xy 373.907812 -166.46906) (xy 373.941031 -166.469606) (xy 374.006903 -166.478264)
			(xy 374.071088 -166.495419) (xy 374.132496 -166.520778) (xy 374.161558 -166.536878) (xy 375.08561 -167.070532)
			(xy 375.114227 -167.087663) (xy 375.167141 -167.128264) (xy 375.214298 -167.17543) (xy 375.25489 -167.228352)
			(xy 375.288221 -167.286122) (xy 375.313719 -167.347752) (xy 375.330949 -167.412184) (xy 375.3358 -167.445182)
			(xy 375.337563 -167.455112) (xy 375.347644 -167.472558) (xy 375.363672 -167.484767) (xy 375.383168 -167.489853)
			(xy 375.393204 -167.48887) (xy 375.406657 -167.487077) (xy 375.433734 -167.485171) (xy 375.447306 -167.48506)
			(xy 375.474555 -167.485611) (xy 375.528497 -167.493367) (xy 375.580787 -167.508721) (xy 375.630359 -167.531361)
			(xy 375.676205 -167.560825) (xy 375.717391 -167.596513) (xy 375.753079 -167.6377) (xy 375.782542 -167.683546)
			(xy 375.805181 -167.733119) (xy 375.820534 -167.785409) (xy 375.82829 -167.839351) (xy 375.82829 -167.893849)
			(xy 375.820534 -167.947791) (xy 375.805181 -168.000081) (xy 375.782542 -168.049654) (xy 375.753079 -168.0955)
			(xy 375.717391 -168.136687) (xy 375.676205 -168.172375) (xy 375.630359 -168.201839) (xy 375.580787 -168.224479)
			(xy 375.528497 -168.239833) (xy 375.474555 -168.247589) (xy 375.447306 -168.248076) (xy 375.418933 -168.247569)
			(xy 375.362813 -168.239152) (xy 375.30856 -168.222516) (xy 375.257368 -168.19803) (xy 375.210366 -168.166232)
			(xy 375.168592 -168.127824) (xy 375.132966 -168.083654) (xy 375.104275 -168.034695) (xy 375.09323 -168.008554)
			(xy 375.089063 -167.999357) (xy 375.07493 -167.984961) (xy 375.056331 -167.977146) (xy 375.036158 -167.977128)
			(xy 375.026682 -167.980614) (xy 374.995609 -167.992929) (xy 374.931047 -168.010239) (xy 374.864777 -168.01896)
			(xy 374.831356 -168.019476) (xy 374.830848 -168.019476) (xy 374.797629 -168.018942) (xy 374.731757 -168.01028)
			(xy 374.667571 -167.993122) (xy 374.606164 -167.967759) (xy 374.577102 -167.951658) (xy 373.65305 -167.418004)
			(xy 373.624423 -167.400889) (xy 373.571507 -167.360287) (xy 373.524348 -167.31312) (xy 373.483757 -167.260196)
			(xy 373.450428 -167.202422) (xy 373.424932 -167.140789) (xy 373.407708 -167.076353) (xy 373.40286 -167.043354)
			(xy 373.401115 -167.033418) (xy 373.391034 -167.015964) (xy 373.374999 -167.003753) (xy 373.355494 -166.998676)
			(xy 373.345456 -166.999666) (xy 373.332002 -167.001453) (xy 373.304926 -167.003363) (xy 373.291354 -167.003476)
			(xy 373.264103 -167.003051) (xy 373.210155 -166.995289) (xy 373.157862 -166.979928) (xy 373.108286 -166.957282)
			(xy 373.062438 -166.927812) (xy 373.021249 -166.892118) (xy 372.98556 -166.850925) (xy 372.956095 -166.805073)
			(xy 372.933456 -166.755495) (xy 372.918102 -166.7032) (xy 372.910346 -166.649251) (xy 371.451785 -166.649251)
			(xy 371.430571 -166.677093) (xy 371.383141 -166.72474) (xy 371.329851 -166.765728) (xy 371.30101 -166.783004)
			(xy 370.376958 -167.316658) (xy 370.34791 -167.332786) (xy 370.2865 -167.35815) (xy 370.22231 -167.375299)
			(xy 370.156433 -167.383942) (xy 370.123212 -167.384476) (xy 370.122704 -167.384476) (xy 370.096416 -167.384188)
			(xy 370.044113 -167.378842) (xy 370.01831 -167.373808) (xy 370.003874 -167.371259) (xy 369.974668 -167.373646)
			(xy 369.947345 -167.384236) (xy 369.924158 -167.402155) (xy 369.907019 -167.425924) (xy 369.901724 -167.439594)
			(xy 369.89262 -167.464089) (xy 369.868678 -167.510537) (xy 369.838624 -167.553286) (xy 369.803021 -167.591536)
			(xy 369.762532 -167.624572) (xy 369.717917 -167.651777) (xy 369.670007 -167.672643) (xy 369.6197 -167.686779)
			(xy 369.567934 -167.693921) (xy 369.541806 -167.694356) (xy 369.514556 -167.693797) (xy 369.460612 -167.686042)
			(xy 369.40832 -167.670688) (xy 369.358745 -167.648049) (xy 369.312897 -167.618585) (xy 369.271709 -167.582896)
			(xy 369.236019 -167.541708) (xy 369.206554 -167.49586) (xy 369.183914 -167.446286) (xy 369.168559 -167.393994)
			(xy 369.160803 -167.34005) (xy 350.494003 -167.34005) (xy 350.473517 -167.366944) (xy 350.426096 -167.414595)
			(xy 350.372815 -167.455589) (xy 350.343978 -167.472868) (xy 349.577278 -167.915649) (xy 351.89949 -167.915649)
			(xy 351.89949 -167.861151) (xy 351.907246 -167.807207) (xy 351.922599 -167.754916) (xy 351.945238 -167.705342)
			(xy 351.9747 -167.659495) (xy 352.010388 -167.618306) (xy 352.051574 -167.582616) (xy 352.097419 -167.55315)
			(xy 352.146992 -167.530508) (xy 352.199282 -167.515151) (xy 352.253225 -167.507392) (xy 352.280474 -167.506904)
			(xy 352.306738 -167.507336) (xy 352.358773 -167.514527) (xy 352.409327 -167.528792) (xy 352.457446 -167.549859)
			(xy 352.502219 -167.577331) (xy 352.542798 -167.610687) (xy 352.578415 -167.649296) (xy 352.608397 -167.692428)
			(xy 352.632176 -167.739266) (xy 352.641154 -167.763952) (xy 352.646004 -167.776558) (xy 352.661235 -167.798851)
			(xy 352.681776 -167.816374) (xy 352.706191 -167.827901) (xy 352.732774 -167.832626) (xy 352.759666 -167.83022)
			(xy 352.772472 -167.825928) (xy 352.800997 -167.81576) (xy 352.859856 -167.801506) (xy 352.919992 -167.794345)
			(xy 352.950272 -167.793924) (xy 352.95078 -167.793924) (xy 352.983998 -167.794489) (xy 353.049869 -167.803142)
			(xy 353.114055 -167.820291) (xy 353.175463 -167.845645) (xy 353.204526 -167.861742) (xy 354.128578 -168.395396)
			(xy 354.157109 -168.412489) (xy 354.2099 -168.452943) (xy 354.256964 -168.499937) (xy 354.297495 -168.552669)
			(xy 354.330802 -168.610237) (xy 354.356314 -168.671658) (xy 354.373597 -168.735883) (xy 354.378514 -168.768776)
			(xy 354.380629 -168.781921) (xy 354.390786 -168.806521) (xy 354.406973 -168.827649) (xy 354.428083 -168.843858)
			(xy 354.452672 -168.854043) (xy 354.479061 -168.857506) (xy 354.492306 -168.856152) (xy 354.504447 -168.854714)
			(xy 354.528849 -168.853189) (xy 354.541074 -168.853104) (xy 354.568329 -168.853541) (xy 354.622284 -168.861295)
			(xy 354.674587 -168.87665) (xy 354.724172 -168.899291) (xy 354.77003 -168.92876) (xy 354.811227 -168.964454)
			(xy 354.846925 -169.005649) (xy 354.876396 -169.051505) (xy 354.899041 -169.101088) (xy 354.914399 -169.15339)
			(xy 354.922157 -169.207345) (xy 354.922157 -169.261855) (xy 354.914399 -169.31581) (xy 354.899041 -169.368112)
			(xy 354.876396 -169.417695) (xy 354.846925 -169.463551) (xy 354.811227 -169.504746) (xy 354.77003 -169.54044)
			(xy 354.724172 -169.569909) (xy 354.674587 -169.59255) (xy 354.622284 -169.607905) (xy 354.568329 -169.615659)
			(xy 354.541074 -169.61612) (xy 354.51229 -169.615665) (xy 354.455374 -169.607019) (xy 354.400406 -169.589913)
			(xy 354.348635 -169.564736) (xy 354.301239 -169.53206) (xy 354.259296 -169.492629) (xy 354.223758 -169.447338)
			(xy 354.195435 -169.397219) (xy 354.184712 -169.370502) (xy 354.179625 -169.358216) (xy 354.164051 -169.33667)
			(xy 354.143432 -169.319889) (xy 354.119172 -169.309016) (xy 354.092925 -169.304791) (xy 354.066478 -169.307502)
			(xy 354.053902 -169.311828) (xy 354.025112 -169.322182) (xy 353.96567 -169.336684) (xy 353.904917 -169.343935)
			(xy 353.874324 -169.34434) (xy 353.873816 -169.34434) (xy 353.840597 -169.343782) (xy 353.774726 -169.335127)
			(xy 353.710541 -169.317976) (xy 353.649132 -169.292621) (xy 353.62007 -169.276522) (xy 352.696018 -168.742868)
			(xy 352.670322 -168.727554) (xy 352.622373 -168.691784) (xy 352.578954 -168.650634) (xy 352.540663 -168.604673)
			(xy 352.508031 -168.554536) (xy 352.481508 -168.500916) (xy 352.461461 -168.444554) (xy 352.448167 -168.386229)
			(xy 352.444558 -168.356534) (xy 352.4427 -168.343127) (xy 352.432844 -168.317929) (xy 352.416717 -168.296203)
			(xy 352.39545 -168.279474) (xy 352.370537 -168.268918) (xy 352.343726 -168.265274) (xy 352.330258 -168.266618)
			(xy 352.31787 -168.268163) (xy 352.292958 -168.269813) (xy 352.280474 -168.26992) (xy 352.253225 -168.269408)
			(xy 352.199282 -168.261649) (xy 352.146992 -168.246292) (xy 352.097419 -168.22365) (xy 352.051574 -168.194184)
			(xy 352.010388 -168.158494) (xy 351.9747 -168.117305) (xy 351.945238 -168.071458) (xy 351.922599 -168.021884)
			(xy 351.907246 -167.969593) (xy 351.89949 -167.915649) (xy 349.577278 -167.915649) (xy 349.419926 -168.006522)
			(xy 349.390862 -168.02262) (xy 349.329459 -168.047992) (xy 349.265273 -168.06515) (xy 349.1994 -168.073802)
			(xy 349.16618 -168.07434) (xy 349.165672 -168.07434) (xy 349.139384 -168.074057) (xy 349.087081 -168.068708)
			(xy 349.061278 -168.063672) (xy 349.046844 -168.061114) (xy 349.017639 -168.063509) (xy 348.990317 -168.074103)
			(xy 348.967131 -168.092022) (xy 348.94999 -168.115789) (xy 348.944692 -168.129458) (xy 348.935595 -168.153956)
			(xy 348.911654 -168.200406) (xy 348.881601 -168.243157) (xy 348.845997 -168.281408) (xy 348.805508 -168.314445)
			(xy 348.760891 -168.34165) (xy 348.712979 -168.362515) (xy 348.66267 -168.376648) (xy 348.610903 -168.383787)
			(xy 348.584774 -168.38422) (xy 348.557525 -168.383708) (xy 348.503582 -168.375949) (xy 348.451292 -168.360592)
			(xy 348.401719 -168.33795) (xy 348.355874 -168.308484) (xy 348.314688 -168.272794) (xy 348.279 -168.231605)
			(xy 348.249538 -168.185758) (xy 348.226899 -168.136184) (xy 348.211546 -168.083893) (xy 348.20379 -168.029949)
			(xy 345.45778 -168.029949) (xy 345.45778 -170.963649) (xy 348.08949 -170.963649) (xy 348.08949 -170.909151)
			(xy 348.097246 -170.855207) (xy 348.112599 -170.802916) (xy 348.135238 -170.753342) (xy 348.1647 -170.707495)
			(xy 348.200388 -170.666306) (xy 348.241574 -170.630616) (xy 348.287419 -170.60115) (xy 348.336992 -170.578508)
			(xy 348.389282 -170.563151) (xy 348.443225 -170.555392) (xy 348.470474 -170.554904) (xy 348.491086 -170.555192)
			(xy 348.532069 -170.559646) (xy 348.552262 -170.563794) (xy 348.567692 -170.56654) (xy 348.598879 -170.56363)
			(xy 348.627721 -170.551414) (xy 348.65151 -170.531038) (xy 348.668014 -170.504416) (xy 348.672404 -170.489372)
			(xy 348.681248 -170.456612) (xy 348.706453 -170.393609) (xy 348.739821 -170.334523) (xy 348.780757 -170.280405)
			(xy 348.828534 -170.232218) (xy 348.8823 -170.190821) (xy 348.911418 -170.173396) (xy 349.83547 -169.639742)
			(xy 349.864533 -169.623642) (xy 349.925937 -169.598271) (xy 349.990123 -169.581114) (xy 350.055996 -169.572463)
			(xy 350.089216 -169.571924) (xy 350.089724 -169.571924) (xy 350.121194 -169.572421) (xy 350.183655 -169.580179)
			(xy 350.244683 -169.595574) (xy 350.30335 -169.618371) (xy 350.331278 -169.632884) (xy 350.343283 -169.638881)
			(xy 350.369399 -169.645018) (xy 350.396212 -169.644142) (xy 350.421872 -169.636314) (xy 350.444607 -169.622072)
			(xy 350.462849 -169.602402) (xy 350.469454 -169.59072) (xy 350.481927 -169.567971) (xy 350.512036 -169.525722)
			(xy 350.547593 -169.487944) (xy 350.587941 -169.455332) (xy 350.632337 -169.42849) (xy 350.679961 -169.407911)
			(xy 350.729934 -169.393976) (xy 350.781334 -169.386942) (xy 350.807274 -169.386504) (xy 350.834529 -169.386941)
			(xy 350.888484 -169.394695) (xy 350.940787 -169.41005) (xy 350.990372 -169.432691) (xy 351.03623 -169.46216)
			(xy 351.077427 -169.497854) (xy 351.113125 -169.539049) (xy 351.142596 -169.584905) (xy 351.165241 -169.634488)
			(xy 351.180599 -169.68679) (xy 351.188357 -169.740745) (xy 351.188357 -169.795255) (xy 351.180599 -169.84921)
			(xy 351.165241 -169.901512) (xy 351.142596 -169.951095) (xy 351.113125 -169.996951) (xy 351.077427 -170.038146)
			(xy 351.03623 -170.07384) (xy 350.990372 -170.103309) (xy 350.940787 -170.12595) (xy 350.888484 -170.141305)
			(xy 350.834529 -170.149059) (xy 350.807274 -170.14952) (xy 350.781883 -170.14908) (xy 350.731552 -170.14233)
			(xy 350.706944 -170.136058) (xy 350.6939 -170.132917) (xy 350.667077 -170.132867) (xy 350.641167 -170.139805)
			(xy 350.617958 -170.153252) (xy 350.599053 -170.172279) (xy 350.585756 -170.195574) (xy 350.581976 -170.208448)
			(xy 350.572961 -170.240834) (xy 350.559549 -170.27375) (xy 369.046503 -170.27375) (xy 369.046503 -170.21925)
			(xy 369.054259 -170.165306) (xy 369.069614 -170.113014) (xy 369.092254 -170.06344) (xy 369.121719 -170.017592)
			(xy 369.157409 -169.976404) (xy 369.198597 -169.940715) (xy 369.244445 -169.911251) (xy 369.29402 -169.888612)
			(xy 369.346312 -169.873258) (xy 369.400256 -169.865503) (xy 369.427506 -169.86504) (xy 369.448118 -169.865324)
			(xy 369.489102 -169.869781) (xy 369.509294 -169.87393) (xy 369.524722 -169.876682) (xy 369.555908 -169.873764)
			(xy 369.584747 -169.861545) (xy 369.608536 -169.84117) (xy 369.625043 -169.814551) (xy 369.629436 -169.799508)
			(xy 369.638285 -169.766749) (xy 369.663488 -169.703746) (xy 369.696854 -169.644659) (xy 369.737789 -169.59054)
			(xy 369.785566 -169.542353) (xy 369.839332 -169.500956) (xy 369.86845 -169.483532) (xy 370.792502 -168.949878)
			(xy 370.82156 -168.933769) (xy 370.882966 -168.9084) (xy 370.947153 -168.891245) (xy 371.013028 -168.882597)
			(xy 371.046248 -168.88206) (xy 371.046756 -168.88206) (xy 371.078227 -168.882539) (xy 371.140688 -168.890302)
			(xy 371.201717 -168.905702) (xy 371.260383 -168.928504) (xy 371.28831 -168.94302) (xy 371.300288 -168.949081)
			(xy 371.326416 -168.955218) (xy 371.35324 -168.954336) (xy 371.378909 -168.946495) (xy 371.401647 -168.932237)
			(xy 371.419886 -168.912547) (xy 371.426486 -168.900856) (xy 371.438908 -168.878078) (xy 371.469027 -168.835832)
			(xy 371.504592 -168.798056) (xy 371.544949 -168.765448) (xy 371.589351 -168.73861) (xy 371.636981 -168.718036)
			(xy 371.686959 -168.704105) (xy 371.738364 -168.697075) (xy 371.764306 -168.69664) (xy 371.79156 -168.69703)
			(xy 371.845514 -168.704788) (xy 371.897815 -168.720146) (xy 371.947398 -168.74279) (xy 371.993253 -168.772261)
			(xy 372.034448 -168.807957) (xy 372.070143 -168.849152) (xy 372.099612 -168.895008) (xy 372.122256 -168.944591)
			(xy 372.137613 -168.996892) (xy 372.14537 -169.050846) (xy 372.14537 -169.105354) (xy 372.137613 -169.159308)
			(xy 372.122256 -169.211609) (xy 372.099612 -169.261192) (xy 372.070143 -169.307048) (xy 372.034448 -169.348243)
			(xy 371.993253 -169.383939) (xy 371.947398 -169.41341) (xy 371.897815 -169.436054) (xy 371.845514 -169.451412)
			(xy 371.79156 -169.45917) (xy 371.764306 -169.459656) (xy 371.738915 -169.459228) (xy 371.688583 -169.452469)
			(xy 371.663976 -169.446194) (xy 371.650916 -169.443134) (xy 371.624107 -169.443078) (xy 371.598208 -169.450004)
			(xy 371.575005 -169.463435) (xy 371.556099 -169.482443) (xy 371.542794 -169.505719) (xy 371.539008 -169.518584)
			(xy 371.530041 -169.550985) (xy 371.504666 -169.613242) (xy 371.471316 -169.671617) (xy 371.430571 -169.725093)
			(xy 371.383141 -169.77274) (xy 371.329851 -169.813728) (xy 371.30101 -169.831004) (xy 370.53437 -170.27375)
			(xy 372.856503 -170.27375) (xy 372.856503 -170.21925) (xy 372.864259 -170.165306) (xy 372.879614 -170.113014)
			(xy 372.902254 -170.06344) (xy 372.931719 -170.017592) (xy 372.967409 -169.976404) (xy 373.008597 -169.940715)
			(xy 373.054445 -169.911251) (xy 373.10402 -169.888612) (xy 373.156312 -169.873258) (xy 373.210256 -169.865503)
			(xy 373.237506 -169.86504) (xy 373.263769 -169.865487) (xy 373.315801 -169.872681) (xy 373.366353 -169.886947)
			(xy 373.41447 -169.908014) (xy 373.459241 -169.935484) (xy 373.49982 -169.968837) (xy 373.535438 -170.007442)
			(xy 373.565422 -170.05057) (xy 373.589205 -170.097404) (xy 373.598186 -170.122088) (xy 373.603029 -170.134699)
			(xy 373.618255 -170.157) (xy 373.638797 -170.174528) (xy 373.663216 -170.186056) (xy 373.689803 -170.190778)
			(xy 373.716698 -170.188363) (xy 373.729504 -170.184064) (xy 373.758027 -170.173888) (xy 373.816887 -170.159637)
			(xy 373.877023 -170.152479) (xy 373.907304 -170.15206) (xy 373.907812 -170.15206) (xy 373.941031 -170.152606)
			(xy 374.006903 -170.161264) (xy 374.071088 -170.178419) (xy 374.132496 -170.203778) (xy 374.161558 -170.219878)
			(xy 375.08561 -170.753532) (xy 375.11334 -170.770141) (xy 375.164778 -170.809287) (xy 375.210847 -170.854629)
			(xy 375.250808 -170.905436) (xy 375.284017 -170.960893) (xy 375.30994 -171.020106) (xy 375.32816 -171.082125)
			(xy 375.333768 -171.113958) (xy 375.336406 -171.127741) (xy 375.348162 -171.153212) (xy 375.366406 -171.174521)
			(xy 375.389761 -171.19006) (xy 375.416463 -171.198656) (xy 375.444497 -171.199661) (xy 375.458228 -171.196762)
			(xy 375.480551 -171.191663) (xy 375.526011 -171.186182) (xy 375.548906 -171.18584) (xy 375.57616 -171.18623)
			(xy 375.630114 -171.193988) (xy 375.682415 -171.209346) (xy 375.731998 -171.23199) (xy 375.777853 -171.261461)
			(xy 375.819048 -171.297157) (xy 375.854743 -171.338352) (xy 375.884212 -171.384208) (xy 375.906856 -171.433791)
			(xy 375.922213 -171.486092) (xy 375.92997 -171.540046) (xy 375.92997 -171.594554) (xy 375.922213 -171.648508)
			(xy 375.906856 -171.700809) (xy 375.884212 -171.750392) (xy 375.854743 -171.796248) (xy 375.819048 -171.837443)
			(xy 375.777853 -171.873139) (xy 375.731998 -171.90261) (xy 375.682415 -171.925254) (xy 375.630114 -171.940612)
			(xy 375.57616 -171.94837) (xy 375.548906 -171.948856) (xy 375.520287 -171.948377) (xy 375.463693 -171.939806)
			(xy 375.409013 -171.922885) (xy 375.35747 -171.897993) (xy 375.310219 -171.865687) (xy 375.268318 -171.826692)
			(xy 375.232707 -171.78188) (xy 375.204181 -171.732256) (xy 375.193306 -171.705778) (xy 375.187869 -171.692836)
			(xy 375.170968 -171.670431) (xy 375.14861 -171.653468) (xy 375.122481 -171.643226) (xy 375.094551 -171.640477)
			(xy 375.066927 -171.645429) (xy 375.054114 -171.651168) (xy 375.02802 -171.66343) (xy 374.973662 -171.682655)
			(xy 374.917476 -171.695598) (xy 374.860185 -171.702092) (xy 374.831356 -171.702476) (xy 374.830848 -171.702476)
			(xy 374.797629 -171.701942) (xy 374.731757 -171.69328) (xy 374.667571 -171.676122) (xy 374.606164 -171.650759)
			(xy 374.577102 -171.634658) (xy 373.65305 -171.101004) (xy 373.627375 -171.085656) (xy 373.579425 -171.049891)
			(xy 373.536004 -171.008747) (xy 373.497711 -170.962791) (xy 373.465076 -170.912659) (xy 373.43855 -170.859043)
			(xy 373.4185 -170.802685) (xy 373.405201 -170.744364) (xy 373.40159 -170.71467) (xy 373.399745 -170.701262)
			(xy 373.389879 -170.676069) (xy 373.373746 -170.654348) (xy 373.352479 -170.637622) (xy 373.327568 -170.627065)
			(xy 373.300758 -170.623415) (xy 373.28729 -170.624754) (xy 373.274902 -170.626295) (xy 373.249989 -170.627948)
			(xy 373.237506 -170.628056) (xy 373.210256 -170.627497) (xy 373.156312 -170.619742) (xy 373.10402 -170.604388)
			(xy 373.054445 -170.581749) (xy 373.008597 -170.552285) (xy 372.967409 -170.516596) (xy 372.931719 -170.475408)
			(xy 372.902254 -170.42956) (xy 372.879614 -170.379986) (xy 372.864259 -170.327694) (xy 372.856503 -170.27375)
			(xy 370.53437 -170.27375) (xy 370.376958 -170.364658) (xy 370.34791 -170.380786) (xy 370.2865 -170.40615)
			(xy 370.22231 -170.423299) (xy 370.156433 -170.431942) (xy 370.123212 -170.432476) (xy 370.122704 -170.432476)
			(xy 370.093774 -170.432082) (xy 370.036284 -170.425549) (xy 369.979905 -170.412543) (xy 369.925363 -170.393233)
			(xy 369.899184 -170.380914) (xy 369.884862 -170.374501) (xy 369.853834 -170.369911) (xy 369.822879 -170.374966)
			(xy 369.794923 -170.389189) (xy 369.772612 -170.411235) (xy 369.764818 -170.424856) (xy 369.750534 -170.450755)
			(xy 369.715143 -170.498141) (xy 369.672866 -170.5395) (xy 369.624715 -170.573842) (xy 369.571842 -170.600346)
			(xy 369.515513 -170.618375) (xy 369.457078 -170.6275) (xy 369.427506 -170.628056) (xy 369.400256 -170.627497)
			(xy 369.346312 -170.619742) (xy 369.29402 -170.604388) (xy 369.244445 -170.581749) (xy 369.198597 -170.552285)
			(xy 369.157409 -170.516596) (xy 369.121719 -170.475408) (xy 369.092254 -170.42956) (xy 369.069614 -170.379986)
			(xy 369.054259 -170.327694) (xy 369.046503 -170.27375) (xy 350.559549 -170.27375) (xy 350.547594 -170.303091)
			(xy 350.514252 -170.361466) (xy 350.473517 -170.414944) (xy 350.426096 -170.462595) (xy 350.372815 -170.503589)
			(xy 350.343978 -170.520868) (xy 349.419926 -171.054522) (xy 349.390862 -171.07062) (xy 349.329459 -171.095992)
			(xy 349.265273 -171.11315) (xy 349.1994 -171.121802) (xy 349.16618 -171.12234) (xy 349.165672 -171.12234)
			(xy 349.136742 -171.121962) (xy 349.079251 -171.115424) (xy 349.022872 -171.102414) (xy 348.968331 -171.083099)
			(xy 348.942152 -171.070778) (xy 348.927794 -171.064457) (xy 348.896786 -171.059854) (xy 348.865844 -171.064891)
			(xy 348.837896 -171.07909) (xy 348.815584 -171.101111) (xy 348.807786 -171.11472) (xy 348.793438 -171.140581)
			(xy 348.758059 -171.187968) (xy 348.715793 -171.22933) (xy 348.667652 -171.263677) (xy 348.61479 -171.290187)
			(xy 348.55847 -171.308225) (xy 348.500043 -171.317359) (xy 348.470474 -171.31792) (xy 348.443225 -171.317408)
			(xy 348.389282 -171.309649) (xy 348.336992 -171.294292) (xy 348.287419 -171.27165) (xy 348.241574 -171.242184)
			(xy 348.200388 -171.206494) (xy 348.1647 -171.165305) (xy 348.135238 -171.119458) (xy 348.112599 -171.069884)
			(xy 348.097246 -171.017593) (xy 348.08949 -170.963649) (xy 345.45778 -170.963649) (xy 345.45778 -171.598649)
			(xy 351.89949 -171.598649) (xy 351.89949 -171.544151) (xy 351.907246 -171.490207) (xy 351.922599 -171.437916)
			(xy 351.945238 -171.388342) (xy 351.9747 -171.342495) (xy 352.010388 -171.301306) (xy 352.051574 -171.265616)
			(xy 352.097419 -171.23615) (xy 352.146992 -171.213508) (xy 352.199282 -171.198151) (xy 352.253225 -171.190392)
			(xy 352.280474 -171.189904) (xy 352.306738 -171.190336) (xy 352.358773 -171.197527) (xy 352.409327 -171.211792)
			(xy 352.457446 -171.232859) (xy 352.502219 -171.260331) (xy 352.542798 -171.293687) (xy 352.578415 -171.332296)
			(xy 352.608397 -171.375428) (xy 352.632176 -171.422266) (xy 352.641154 -171.446952) (xy 352.646004 -171.459558)
			(xy 352.661235 -171.481851) (xy 352.681776 -171.499374) (xy 352.706191 -171.510901) (xy 352.732774 -171.515626)
			(xy 352.759666 -171.51322) (xy 352.772472 -171.508928) (xy 352.800997 -171.49876) (xy 352.859856 -171.484506)
			(xy 352.919992 -171.477345) (xy 352.950272 -171.476924) (xy 352.95078 -171.476924) (xy 352.983998 -171.477489)
			(xy 353.049869 -171.486142) (xy 353.114055 -171.503291) (xy 353.175463 -171.528645) (xy 353.204526 -171.544742)
			(xy 354.128578 -172.078396) (xy 354.156324 -172.09498) (xy 354.207763 -172.134129) (xy 354.253832 -172.179474)
			(xy 354.293791 -172.230286) (xy 354.326998 -172.285746) (xy 354.352917 -172.344964) (xy 354.371132 -172.406987)
			(xy 354.376736 -172.438822) (xy 354.379368 -172.452605) (xy 354.391133 -172.478068) (xy 354.40938 -172.499372)
			(xy 354.432734 -172.514909) (xy 354.459434 -172.523507) (xy 354.487465 -172.524519) (xy 354.501196 -172.521626)
			(xy 354.523516 -172.516515) (xy 354.568979 -172.511042) (xy 354.591874 -172.510704) (xy 354.619129 -172.511141)
			(xy 354.673084 -172.518895) (xy 354.725387 -172.53425) (xy 354.774972 -172.556891) (xy 354.82083 -172.58636)
			(xy 354.862027 -172.622054) (xy 354.897725 -172.663249) (xy 354.927196 -172.709105) (xy 354.949841 -172.758688)
			(xy 354.965199 -172.81099) (xy 354.972957 -172.864945) (xy 354.972957 -172.919455) (xy 354.965199 -172.97341)
			(xy 354.949841 -173.025712) (xy 354.927196 -173.075295) (xy 354.897725 -173.121151) (xy 354.862027 -173.162346)
			(xy 354.82083 -173.19804) (xy 354.774972 -173.227509) (xy 354.725387 -173.25015) (xy 354.673084 -173.265505)
			(xy 354.619129 -173.273259) (xy 354.591874 -173.27372) (xy 354.563256 -173.273227) (xy 354.506665 -173.264653)
			(xy 354.451987 -173.247731) (xy 354.400446 -173.22284) (xy 354.353196 -173.190537) (xy 354.311295 -173.151545)
			(xy 354.275681 -173.106737) (xy 354.247152 -173.057117) (xy 354.236274 -173.030642) (xy 354.230732 -173.017749)
			(xy 354.213857 -172.995344) (xy 354.191522 -172.978376) (xy 354.165414 -172.968124) (xy 354.137501 -172.965363)
			(xy 354.10989 -172.970301) (xy 354.097082 -172.976032) (xy 354.070995 -172.98831) (xy 354.016634 -173.00753)
			(xy 353.960446 -173.020468) (xy 353.903154 -173.026957) (xy 353.874324 -173.02734) (xy 353.873816 -173.02734)
			(xy 353.840597 -173.026782) (xy 353.774726 -173.018127) (xy 353.710541 -173.000976) (xy 353.649132 -172.975621)
			(xy 353.62007 -172.959522) (xy 352.696018 -172.425868) (xy 352.670322 -172.410554) (xy 352.622373 -172.374784)
			(xy 352.578954 -172.333634) (xy 352.540663 -172.287673) (xy 352.508031 -172.237536) (xy 352.481508 -172.183916)
			(xy 352.461461 -172.127554) (xy 352.448167 -172.069229) (xy 352.444558 -172.039534) (xy 352.4427 -172.026127)
			(xy 352.432844 -172.000929) (xy 352.416717 -171.979203) (xy 352.39545 -171.962474) (xy 352.370537 -171.951918)
			(xy 352.343726 -171.948274) (xy 352.330258 -171.949618) (xy 352.31787 -171.951163) (xy 352.292958 -171.952813)
			(xy 352.280474 -171.95292) (xy 352.253225 -171.952408) (xy 352.199282 -171.944649) (xy 352.146992 -171.929292)
			(xy 352.097419 -171.90665) (xy 352.051574 -171.877184) (xy 352.010388 -171.841494) (xy 351.9747 -171.800305)
			(xy 351.945238 -171.754458) (xy 351.922599 -171.704884) (xy 351.907246 -171.652593) (xy 351.89949 -171.598649)
			(xy 345.45778 -171.598649) (xy 345.45778 -172.526452) (xy 345.458247 -172.541039) (xy 345.466484 -172.569025)
			(xy 345.4823 -172.593538) (xy 345.504403 -172.612578) (xy 345.530989 -172.62459) (xy 345.559886 -172.628592)
			(xy 345.588735 -172.624258) (xy 345.615181 -172.611942) (xy 345.626436 -172.602652) (xy 345.647441 -172.584789)
			(xy 345.693628 -172.554671) (xy 345.743669 -172.531518) (xy 345.796524 -172.515812) (xy 345.851089 -172.50788)
			(xy 345.878658 -172.507402) (xy 345.905912 -172.507862) (xy 345.959866 -172.515614) (xy 346.012168 -172.530966)
			(xy 346.061752 -172.553606) (xy 346.107609 -172.583072) (xy 346.148806 -172.618765) (xy 346.184503 -172.659957)
			(xy 346.213974 -172.705811) (xy 346.236619 -172.755393) (xy 346.251977 -172.807693) (xy 346.259735 -172.861646)
			(xy 346.259735 -172.916154) (xy 346.251977 -172.970107) (xy 346.236619 -173.022407) (xy 346.213974 -173.071989)
			(xy 346.184503 -173.117843) (xy 346.148806 -173.159035) (xy 346.107609 -173.194728) (xy 346.061752 -173.224194)
			(xy 346.012168 -173.246834) (xy 345.959866 -173.262186) (xy 345.905912 -173.269938) (xy 345.878658 -173.270418)
			(xy 345.847603 -173.269805) (xy 345.786313 -173.25974) (xy 345.727462 -173.239883) (xy 345.672604 -173.210757)
			(xy 345.647518 -173.19244) (xy 345.63562 -173.183954) (xy 345.608336 -173.173516) (xy 345.579215 -173.171215)
			(xy 345.55063 -173.177239) (xy 345.524913 -173.191096) (xy 345.504162 -173.211657) (xy 345.496642 -173.22419)
			(xy 345.488105 -173.239366) (xy 345.468646 -173.268243) (xy 345.45778 -173.281848) (xy 345.45778 -173.29023)
			(xy 347.65056 -173.29023) (xy 347.654631 -173.234608) (xy 347.666757 -173.180171) (xy 347.68668 -173.12808)
			(xy 347.713976 -173.079445) (xy 347.748062 -173.035302) (xy 347.788211 -172.996593) (xy 347.833569 -172.964142)
			(xy 347.883169 -172.938641) (xy 347.935953 -172.920634) (xy 347.990796 -172.910504) (xy 348.04653 -172.908467)
			(xy 348.101967 -172.914567) (xy 348.155924 -172.928673) (xy 348.207253 -172.950485) (xy 348.254859 -172.979539)
			(xy 348.297727 -173.015214) (xy 348.334944 -173.056751) (xy 348.365717 -173.103264) (xy 348.389389 -173.153761)
			(xy 348.405457 -173.207168) (xy 348.413577 -173.262344) (xy 348.414086 -173.29023) (xy 348.413577 -173.318116)
			(xy 348.405457 -173.373292) (xy 348.389389 -173.426699) (xy 348.365717 -173.477196) (xy 348.334944 -173.523709)
			(xy 348.297727 -173.565246) (xy 348.254859 -173.600921) (xy 348.207253 -173.629975) (xy 348.155924 -173.651787)
			(xy 348.101967 -173.665893) (xy 348.04653 -173.671993) (xy 347.990796 -173.669956) (xy 347.935953 -173.659826)
			(xy 347.883169 -173.641819) (xy 347.833569 -173.616318) (xy 347.788211 -173.583867) (xy 347.748062 -173.545158)
			(xy 347.713976 -173.501015) (xy 347.68668 -173.45238) (xy 347.666757 -173.400289) (xy 347.654631 -173.345852)
			(xy 347.65056 -173.29023) (xy 345.45778 -173.29023) (xy 345.45778 -174.087849) (xy 348.08949 -174.087849)
			(xy 348.08949 -174.033351) (xy 348.097246 -173.979407) (xy 348.112599 -173.927116) (xy 348.135238 -173.877542)
			(xy 348.1647 -173.831695) (xy 348.200388 -173.790506) (xy 348.241574 -173.754816) (xy 348.287419 -173.72535)
			(xy 348.336992 -173.702708) (xy 348.389282 -173.687351) (xy 348.443225 -173.679592) (xy 348.470474 -173.679104)
			(xy 348.488296 -173.679301) (xy 348.523787 -173.682611) (xy 348.54134 -173.685708) (xy 348.555025 -173.687816)
			(xy 348.582601 -173.685458) (xy 348.60853 -173.675777) (xy 348.630903 -173.659484) (xy 348.648076 -173.637779)
			(xy 348.658784 -173.612258) (xy 348.660974 -173.598586) (xy 348.665673 -173.565385) (xy 348.682716 -173.500531)
			(xy 348.708127 -173.438476) (xy 348.741466 -173.380294) (xy 348.782155 -173.326994) (xy 348.82949 -173.279497)
			(xy 348.882652 -173.238627) (xy 348.911418 -173.221396) (xy 349.83547 -172.687742) (xy 349.864533 -172.671642)
			(xy 349.925937 -172.646271) (xy 349.990123 -172.629114) (xy 350.055996 -172.620463) (xy 350.089216 -172.619924)
			(xy 350.089724 -172.619924) (xy 350.120006 -172.620335) (xy 350.180144 -172.627488) (xy 350.23901 -172.641725)
			(xy 350.29577 -172.662846) (xy 350.322896 -172.676312) (xy 350.335224 -172.682209) (xy 350.361952 -172.687853)
			(xy 350.389221 -172.68621) (xy 350.415079 -172.677398) (xy 350.437676 -172.662046) (xy 350.455395 -172.641254)
			(xy 350.46158 -172.629068) (xy 350.473451 -172.604764) (xy 350.503058 -172.559497) (xy 350.538758 -172.518863)
			(xy 350.579838 -172.483676) (xy 350.625473 -172.454641) (xy 350.67475 -172.432338) (xy 350.726682 -172.417216)
			(xy 350.780229 -172.409576) (xy 350.807274 -172.409104) (xy 350.834529 -172.409541) (xy 350.888484 -172.417295)
			(xy 350.940787 -172.43265) (xy 350.990372 -172.455291) (xy 351.03623 -172.48476) (xy 351.077427 -172.520454)
			(xy 351.113125 -172.561649) (xy 351.142596 -172.607505) (xy 351.165241 -172.657088) (xy 351.180599 -172.70939)
			(xy 351.188357 -172.763345) (xy 351.188357 -172.817855) (xy 351.180599 -172.87181) (xy 351.165241 -172.924112)
			(xy 351.142596 -172.973695) (xy 351.113125 -173.019551) (xy 351.077427 -173.060746) (xy 351.03623 -173.09644)
			(xy 350.990372 -173.125909) (xy 350.940787 -173.14855) (xy 350.888484 -173.163905) (xy 350.834529 -173.171659)
			(xy 350.807274 -173.17212) (xy 350.783067 -173.171751) (xy 350.735042 -173.16564) (xy 350.711516 -173.159928)
			(xy 350.698202 -173.156862) (xy 350.670891 -173.157255) (xy 350.644665 -173.164883) (xy 350.621404 -173.179199)
			(xy 350.602777 -173.199177) (xy 350.590122 -173.223381) (xy 350.586802 -173.236636) (xy 350.579972 -173.266132)
			(xy 350.560162 -173.323349) (xy 350.533691 -173.377804) (xy 350.520731 -173.39795) (xy 369.046503 -173.39795)
			(xy 369.046503 -173.34345) (xy 369.054259 -173.289506) (xy 369.069614 -173.237214) (xy 369.092254 -173.18764)
			(xy 369.121719 -173.141792) (xy 369.157409 -173.100604) (xy 369.198597 -173.064915) (xy 369.244445 -173.035451)
			(xy 369.29402 -173.012812) (xy 369.346312 -172.997458) (xy 369.400256 -172.989703) (xy 369.427506 -172.98924)
			(xy 369.445328 -172.989447) (xy 369.480819 -172.992751) (xy 369.498372 -172.995844) (xy 369.512061 -172.997936)
			(xy 369.53964 -172.995594) (xy 369.565573 -172.985921) (xy 369.58795 -172.96963) (xy 369.605121 -172.947922)
			(xy 369.615822 -172.922396) (xy 369.618006 -172.908722) (xy 369.622714 -172.875522) (xy 369.639754 -172.810667)
			(xy 369.665162 -172.748612) (xy 369.698499 -172.69043) (xy 369.739187 -172.637129) (xy 369.786522 -172.589632)
			(xy 369.839683 -172.548763) (xy 369.86845 -172.531532) (xy 370.792502 -171.997878) (xy 370.82156 -171.981769)
			(xy 370.882966 -171.9564) (xy 370.947153 -171.939245) (xy 371.013028 -171.930597) (xy 371.046248 -171.93006)
			(xy 371.046756 -171.93006) (xy 371.077038 -171.930454) (xy 371.137178 -171.937611) (xy 371.196043 -171.951854)
			(xy 371.252803 -171.97298) (xy 371.279928 -171.986448) (xy 371.292278 -171.992298) (xy 371.318999 -171.99796)
			(xy 371.346264 -171.99633) (xy 371.372121 -171.987527) (xy 371.394716 -171.97218) (xy 371.41243 -171.95139)
			(xy 371.418612 -171.939204) (xy 371.430507 -171.914913) (xy 371.460114 -171.86965) (xy 371.495813 -171.829018)
			(xy 371.536889 -171.793833) (xy 371.58252 -171.764796) (xy 371.631793 -171.742491) (xy 371.68372 -171.727364)
			(xy 371.737263 -171.719717) (xy 371.764306 -171.71924) (xy 371.79156 -171.71963) (xy 371.845514 -171.727388)
			(xy 371.897815 -171.742746) (xy 371.947398 -171.76539) (xy 371.993253 -171.794861) (xy 372.034448 -171.830557)
			(xy 372.070143 -171.871752) (xy 372.099612 -171.917608) (xy 372.122256 -171.967191) (xy 372.137613 -172.019492)
			(xy 372.14537 -172.073446) (xy 372.14537 -172.127954) (xy 372.137613 -172.181908) (xy 372.122256 -172.234209)
			(xy 372.099612 -172.283792) (xy 372.070143 -172.329648) (xy 372.034448 -172.370843) (xy 371.993253 -172.406539)
			(xy 371.947398 -172.43601) (xy 371.897815 -172.458654) (xy 371.845514 -172.474012) (xy 371.79156 -172.48177)
			(xy 371.764306 -172.482256) (xy 371.740099 -172.481899) (xy 371.692073 -172.47578) (xy 371.668548 -172.470064)
			(xy 371.65522 -172.467082) (xy 371.627922 -172.467468) (xy 371.601706 -172.475084) (xy 371.578451 -172.489383)
			(xy 371.559824 -172.509341) (xy 371.547161 -172.533526) (xy 371.543834 -172.546772) (xy 371.536953 -172.576256)
			(xy 371.517151 -172.633471) (xy 371.490688 -172.687927) (xy 371.457939 -172.73885) (xy 371.419368 -172.785519)
			(xy 371.375522 -172.827271) (xy 371.327023 -172.863514) (xy 371.30101 -172.879004) (xy 370.376958 -173.412658)
			(xy 370.34791 -173.428786) (xy 370.2865 -173.45415) (xy 370.22231 -173.471299) (xy 370.156433 -173.479942)
			(xy 370.123212 -173.480476) (xy 370.122704 -173.480476) (xy 370.088408 -173.479937) (xy 370.020431 -173.470779)
			(xy 369.954307 -173.452548) (xy 369.922552 -173.439582) (xy 369.909674 -173.434488) (xy 369.882228 -173.430832)
			(xy 369.85481 -173.434688) (xy 369.829437 -173.44577) (xy 369.807976 -173.463264) (xy 369.792006 -173.485882)
			(xy 369.786916 -173.498764) (xy 369.776578 -173.526198) (xy 369.748686 -173.577763) (xy 369.713234 -173.624455)
			(xy 369.671058 -173.665175) (xy 369.623149 -173.698964) (xy 369.570636 -173.725027) (xy 369.514754 -173.742751)
			(xy 369.456819 -173.75172) (xy 369.427506 -173.752256) (xy 369.400256 -173.751697) (xy 369.346312 -173.743942)
			(xy 369.29402 -173.728588) (xy 369.244445 -173.705949) (xy 369.198597 -173.676485) (xy 369.157409 -173.640796)
			(xy 369.121719 -173.599608) (xy 369.092254 -173.55376) (xy 369.069614 -173.504186) (xy 369.054259 -173.451894)
			(xy 369.046503 -173.39795) (xy 350.520731 -173.39795) (xy 350.500933 -173.428726) (xy 350.462354 -173.475392)
			(xy 350.4185 -173.517141) (xy 350.369994 -173.55338) (xy 350.343978 -173.568868) (xy 349.571041 -174.015251)
			(xy 372.910346 -174.015251) (xy 372.910346 -173.960749) (xy 372.918102 -173.9068) (xy 372.933456 -173.854505)
			(xy 372.956095 -173.804927) (xy 372.98556 -173.759075) (xy 373.021249 -173.717882) (xy 373.062438 -173.682188)
			(xy 373.108286 -173.652718) (xy 373.157862 -173.630072) (xy 373.210155 -173.614711) (xy 373.264103 -173.606949)
			(xy 373.291354 -173.60646) (xy 373.319727 -173.606978) (xy 373.375847 -173.615391) (xy 373.430102 -173.632023)
			(xy 373.481295 -173.656507) (xy 373.528297 -173.688303) (xy 373.570071 -173.72671) (xy 373.605696 -173.770881)
			(xy 373.634386 -173.819841) (xy 373.64543 -173.845982) (xy 373.649555 -173.855205) (xy 373.663696 -173.869614)
			(xy 373.682312 -173.877426) (xy 373.7025 -173.877423) (xy 373.711978 -173.873922) (xy 373.743057 -173.861621)
			(xy 373.807615 -173.844305) (xy 373.873884 -173.835579) (xy 373.907304 -173.83506) (xy 373.907812 -173.83506)
			(xy 373.941031 -173.835606) (xy 374.006903 -173.844264) (xy 374.071088 -173.861419) (xy 374.132496 -173.886778)
			(xy 374.161558 -173.902878) (xy 375.08561 -174.436532) (xy 375.114227 -174.453663) (xy 375.167141 -174.494264)
			(xy 375.214298 -174.54143) (xy 375.25489 -174.594352) (xy 375.288221 -174.652122) (xy 375.313719 -174.713752)
			(xy 375.330949 -174.778184) (xy 375.3358 -174.811182) (xy 375.337563 -174.821112) (xy 375.347644 -174.838558)
			(xy 375.363672 -174.850767) (xy 375.383168 -174.855853) (xy 375.393204 -174.85487) (xy 375.406657 -174.853077)
			(xy 375.433734 -174.851171) (xy 375.447306 -174.85106) (xy 375.474555 -174.851611) (xy 375.528497 -174.859367)
			(xy 375.580787 -174.874721) (xy 375.630359 -174.897361) (xy 375.676205 -174.926825) (xy 375.717391 -174.962513)
			(xy 375.753079 -175.0037) (xy 375.782542 -175.049546) (xy 375.805181 -175.099119) (xy 375.820534 -175.151409)
			(xy 375.82829 -175.205351) (xy 375.82829 -175.259849) (xy 375.820534 -175.313791) (xy 375.805181 -175.366081)
			(xy 375.782542 -175.415654) (xy 375.753079 -175.4615) (xy 375.717391 -175.502687) (xy 375.676205 -175.538375)
			(xy 375.630359 -175.567839) (xy 375.580787 -175.590479) (xy 375.528497 -175.605833) (xy 375.474555 -175.613589)
			(xy 375.447306 -175.614076) (xy 375.418933 -175.613569) (xy 375.362813 -175.605152) (xy 375.30856 -175.588516)
			(xy 375.257368 -175.56403) (xy 375.210366 -175.532232) (xy 375.168592 -175.493824) (xy 375.132966 -175.449654)
			(xy 375.104275 -175.400695) (xy 375.09323 -175.374554) (xy 375.089063 -175.365357) (xy 375.07493 -175.350961)
			(xy 375.056331 -175.343146) (xy 375.036158 -175.343128) (xy 375.026682 -175.346614) (xy 374.995609 -175.358929)
			(xy 374.931047 -175.376239) (xy 374.864777 -175.38496) (xy 374.831356 -175.385476) (xy 374.830848 -175.385476)
			(xy 374.797629 -175.384942) (xy 374.731757 -175.37628) (xy 374.667571 -175.359122) (xy 374.606164 -175.333759)
			(xy 374.577102 -175.317658) (xy 373.65305 -174.784004) (xy 373.624423 -174.766889) (xy 373.571507 -174.726287)
			(xy 373.524348 -174.67912) (xy 373.483757 -174.626196) (xy 373.450428 -174.568422) (xy 373.424932 -174.506789)
			(xy 373.407708 -174.442353) (xy 373.40286 -174.409354) (xy 373.401115 -174.399418) (xy 373.391034 -174.381964)
			(xy 373.374999 -174.369753) (xy 373.355494 -174.364676) (xy 373.345456 -174.365666) (xy 373.332002 -174.367453)
			(xy 373.304926 -174.369363) (xy 373.291354 -174.369476) (xy 373.264103 -174.369051) (xy 373.210155 -174.361289)
			(xy 373.157862 -174.345928) (xy 373.108286 -174.323282) (xy 373.062438 -174.293812) (xy 373.021249 -174.258118)
			(xy 372.98556 -174.216925) (xy 372.956095 -174.171073) (xy 372.933456 -174.121495) (xy 372.918102 -174.0692)
			(xy 372.910346 -174.015251) (xy 349.571041 -174.015251) (xy 349.419926 -174.102522) (xy 349.390862 -174.11862)
			(xy 349.329459 -174.143992) (xy 349.265273 -174.16115) (xy 349.1994 -174.169802) (xy 349.16618 -174.17034)
			(xy 349.165672 -174.17034) (xy 349.131376 -174.169807) (xy 349.063399 -174.160645) (xy 348.997275 -174.142412)
			(xy 348.96552 -174.129446) (xy 348.952607 -174.124451) (xy 348.925179 -174.120784) (xy 348.897775 -174.124623)
			(xy 348.87241 -174.135686) (xy 348.850952 -174.153159) (xy 348.834978 -174.175755) (xy 348.829884 -174.188628)
			(xy 348.819554 -174.216066) (xy 348.791663 -174.267633) (xy 348.756211 -174.314327) (xy 348.714034 -174.355047)
			(xy 348.666124 -174.388837) (xy 348.613609 -174.414899) (xy 348.557725 -174.432621) (xy 348.499787 -174.441586)
			(xy 348.470474 -174.44212) (xy 348.443225 -174.441608) (xy 348.389282 -174.433849) (xy 348.336992 -174.418492)
			(xy 348.287419 -174.39585) (xy 348.241574 -174.366384) (xy 348.200388 -174.330694) (xy 348.1647 -174.289505)
			(xy 348.135238 -174.243658) (xy 348.112599 -174.194084) (xy 348.097246 -174.141793) (xy 348.08949 -174.087849)
			(xy 345.45778 -174.087849) (xy 345.45778 -175.340052) (xy 351.953287 -175.340052) (xy 351.953287 -175.285548)
			(xy 351.961044 -175.2316) (xy 351.9764 -175.179305) (xy 351.999042 -175.129727) (xy 352.02851 -175.083877)
			(xy 352.064203 -175.042687) (xy 352.105395 -175.006997) (xy 352.151247 -174.977532) (xy 352.200826 -174.954892)
			(xy 352.253122 -174.93954) (xy 352.30707 -174.931786) (xy 352.334322 -174.931324) (xy 352.362693 -174.931892)
			(xy 352.41881 -174.940299) (xy 352.473062 -174.956925) (xy 352.524254 -174.981402) (xy 352.571256 -175.013191)
			(xy 352.613031 -175.051591) (xy 352.648658 -175.095755) (xy 352.677352 -175.144708) (xy 352.688398 -175.170846)
			(xy 352.692535 -175.18006) (xy 352.706677 -175.194458) (xy 352.725286 -175.202269) (xy 352.745468 -175.202278)
			(xy 352.754946 -175.198786) (xy 352.786016 -175.186462) (xy 352.850579 -175.169156) (xy 352.916851 -175.160439)
			(xy 352.950272 -175.159924) (xy 352.95078 -175.159924) (xy 352.983998 -175.160489) (xy 353.049869 -175.169142)
			(xy 353.114055 -175.186291) (xy 353.175463 -175.211645) (xy 353.204526 -175.227742) (xy 354.128578 -175.761396)
			(xy 354.157211 -175.778501) (xy 354.210127 -175.819105) (xy 354.257284 -175.866274) (xy 354.297874 -175.9192)
			(xy 354.331202 -175.976976) (xy 354.356697 -176.03861) (xy 354.37392 -176.103047) (xy 354.378768 -176.136046)
			(xy 354.380484 -176.14599) (xy 354.390571 -176.163448) (xy 354.406616 -176.175659) (xy 354.42613 -176.180729)
			(xy 354.436172 -176.179734) (xy 354.449626 -176.177944) (xy 354.476702 -176.176036) (xy 354.490274 -176.175924)
			(xy 354.51753 -176.176321) (xy 354.571489 -176.184076) (xy 354.623794 -176.199431) (xy 354.673382 -176.222074)
			(xy 354.719242 -176.251544) (xy 354.760441 -176.28724) (xy 354.796141 -176.328437) (xy 354.825614 -176.374295)
			(xy 354.838656 -176.402851) (xy 369.125746 -176.402851) (xy 369.125746 -176.348349) (xy 369.133502 -176.2944)
			(xy 369.148856 -176.242105) (xy 369.171495 -176.192527) (xy 369.20096 -176.146675) (xy 369.236649 -176.105482)
			(xy 369.277838 -176.069788) (xy 369.323686 -176.040318) (xy 369.373262 -176.017672) (xy 369.425555 -176.002311)
			(xy 369.479503 -175.994549) (xy 369.506754 -175.99406) (xy 369.520326 -175.994163) (xy 369.547403 -175.99607)
			(xy 369.560856 -175.99787) (xy 369.570892 -175.998782) (xy 369.59037 -175.993694) (xy 369.606397 -175.981511)
			(xy 369.616511 -175.964104) (xy 369.61826 -175.954182) (xy 369.623113 -175.921183) (xy 369.640328 -175.856744)
			(xy 369.665818 -175.795108) (xy 369.699145 -175.737332) (xy 369.739739 -175.684409) (xy 369.786902 -175.637245)
			(xy 369.839824 -175.59665) (xy 369.86845 -175.579532) (xy 370.792502 -175.045878) (xy 370.82156 -175.029769)
			(xy 370.882966 -175.0044) (xy 370.947153 -174.987245) (xy 371.013028 -174.978597) (xy 371.046248 -174.97806)
			(xy 371.046756 -174.97806) (xy 371.080179 -174.978555) (xy 371.146455 -174.987258) (xy 371.211015 -175.004587)
			(xy 371.242082 -175.016922) (xy 371.251563 -175.020338) (xy 371.271699 -175.020246) (xy 371.290265 -175.012452)
			(xy 371.304434 -174.998144) (xy 371.30863 -174.988982) (xy 371.319681 -174.962843) (xy 371.348365 -174.913879)
			(xy 371.383986 -174.869704) (xy 371.425758 -174.831294) (xy 371.47276 -174.799497) (xy 371.523955 -174.775014)
			(xy 371.578211 -174.758386) (xy 371.634332 -174.74998) (xy 371.662706 -174.74946) (xy 371.689955 -174.750011)
			(xy 371.743897 -174.757767) (xy 371.796187 -174.773121) (xy 371.845759 -174.795761) (xy 371.891605 -174.825225)
			(xy 371.932791 -174.860913) (xy 371.968479 -174.9021) (xy 371.997942 -174.947946) (xy 372.020581 -174.997519)
			(xy 372.035934 -175.049809) (xy 372.04369 -175.103751) (xy 372.04369 -175.158249) (xy 372.035934 -175.212191)
			(xy 372.020581 -175.264481) (xy 371.997942 -175.314054) (xy 371.968479 -175.3599) (xy 371.932791 -175.401087)
			(xy 371.891605 -175.436775) (xy 371.845759 -175.466239) (xy 371.796187 -175.488879) (xy 371.743897 -175.504233)
			(xy 371.689955 -175.511989) (xy 371.662706 -175.512476) (xy 371.649134 -175.512377) (xy 371.622057 -175.510468)
			(xy 371.608604 -175.508666) (xy 371.59857 -175.507685) (xy 371.57908 -175.512791) (xy 371.56305 -175.524995)
			(xy 371.552942 -175.542423) (xy 371.5512 -175.552354) (xy 371.546342 -175.585352) (xy 371.529125 -175.649789)
			(xy 371.503635 -175.711424) (xy 371.470307 -175.769199) (xy 371.429715 -175.822123) (xy 371.382554 -175.869287)
			(xy 371.329634 -175.909884) (xy 371.30101 -175.927004) (xy 370.376958 -176.460658) (xy 370.34791 -176.476786)
			(xy 370.2865 -176.50215) (xy 370.22231 -176.519299) (xy 370.156433 -176.527942) (xy 370.123212 -176.528476)
			(xy 370.122704 -176.528476) (xy 370.089281 -176.527991) (xy 370.023005 -176.519283) (xy 369.958445 -176.501951)
			(xy 369.927378 -176.489614) (xy 369.917888 -176.486261) (xy 369.897781 -176.486367) (xy 369.879243 -176.494152)
			(xy 369.86509 -176.508435) (xy 369.86083 -176.517554) (xy 369.84983 -176.543715) (xy 369.821138 -176.59268)
			(xy 369.785509 -176.636854) (xy 369.743729 -176.675262) (xy 369.69672 -176.707056) (xy 369.645519 -176.731535)
			(xy 369.591256 -176.748158) (xy 369.53513 -176.756559) (xy 369.506754 -176.757076) (xy 369.479503 -176.756651)
			(xy 369.425555 -176.748889) (xy 369.373262 -176.733528) (xy 369.323686 -176.710882) (xy 369.277838 -176.681412)
			(xy 369.236649 -176.645718) (xy 369.20096 -176.604525) (xy 369.171495 -176.558673) (xy 369.148856 -176.509095)
			(xy 369.133502 -176.4568) (xy 369.125746 -176.402851) (xy 354.838656 -176.402851) (xy 354.84826 -176.423881)
			(xy 354.863619 -176.476186) (xy 354.871377 -176.530144) (xy 354.871377 -176.584656) (xy 354.863619 -176.638614)
			(xy 354.84826 -176.690919) (xy 354.825614 -176.740505) (xy 354.796141 -176.786363) (xy 354.760441 -176.82756)
			(xy 354.719242 -176.863256) (xy 354.673382 -176.892726) (xy 354.623794 -176.915369) (xy 354.571489 -176.930724)
			(xy 354.51753 -176.938479) (xy 354.490274 -176.93894) (xy 354.461901 -176.938398) (xy 354.405783 -176.929989)
			(xy 354.351529 -176.913361) (xy 354.300336 -176.888881) (xy 354.253333 -176.857088) (xy 354.211559 -176.818684)
			(xy 354.175933 -176.774516) (xy 354.147242 -176.725558) (xy 354.136198 -176.699418) (xy 354.132042 -176.690212)
			(xy 354.117911 -176.675805) (xy 354.099306 -176.667989) (xy 354.079126 -176.667983) (xy 354.06965 -176.671478)
			(xy 354.038579 -176.683801) (xy 353.974017 -176.701109) (xy 353.907745 -176.709826) (xy 353.874324 -176.71034)
			(xy 353.873816 -176.71034) (xy 353.840597 -176.709782) (xy 353.774726 -176.701127) (xy 353.710541 -176.683976)
			(xy 353.649132 -176.658621) (xy 353.62007 -176.642522) (xy 352.696018 -176.108868) (xy 352.667408 -176.091727)
			(xy 352.614492 -176.051128) (xy 352.567334 -176.003964) (xy 352.526741 -175.951044) (xy 352.493409 -175.893275)
			(xy 352.46791 -175.831647) (xy 352.450679 -175.767215) (xy 352.445828 -175.734218) (xy 352.444141 -175.724268)
			(xy 352.434042 -175.706811) (xy 352.417989 -175.694603) (xy 352.398468 -175.689534) (xy 352.388424 -175.69053)
			(xy 352.37497 -175.69232) (xy 352.347894 -175.694228) (xy 352.334322 -175.69434) (xy 352.30707 -175.693814)
			(xy 352.253122 -175.68606) (xy 352.200826 -175.670708) (xy 352.151247 -175.648068) (xy 352.105395 -175.618603)
			(xy 352.064203 -175.582913) (xy 352.02851 -175.541723) (xy 351.999042 -175.495873) (xy 351.9764 -175.446295)
			(xy 351.961044 -175.394) (xy 351.953287 -175.340052) (xy 345.45778 -175.340052) (xy 345.45778 -177.092652)
			(xy 348.168687 -177.092652) (xy 348.168687 -177.038148) (xy 348.176444 -176.9842) (xy 348.1918 -176.931905)
			(xy 348.214442 -176.882327) (xy 348.24391 -176.836477) (xy 348.279603 -176.795287) (xy 348.320795 -176.759597)
			(xy 348.366647 -176.730132) (xy 348.416226 -176.707492) (xy 348.468522 -176.69214) (xy 348.52247 -176.684386)
			(xy 348.549722 -176.683924) (xy 348.563294 -176.684031) (xy 348.590371 -176.685935) (xy 348.603824 -176.687734)
			(xy 348.613857 -176.688741) (xy 348.633349 -176.683626) (xy 348.649379 -176.671414) (xy 348.659486 -176.65398)
			(xy 348.661228 -176.644046) (xy 348.666073 -176.611046) (xy 348.683291 -176.546607) (xy 348.708783 -176.484972)
			(xy 348.742112 -176.427197) (xy 348.782707 -176.374274) (xy 348.82987 -176.32711) (xy 348.882793 -176.286515)
			(xy 348.911418 -176.269396) (xy 349.83547 -175.735742) (xy 349.864533 -175.719642) (xy 349.925937 -175.694271)
			(xy 349.990123 -175.677114) (xy 350.055996 -175.668463) (xy 350.089216 -175.667924) (xy 350.089724 -175.667924)
			(xy 350.123147 -175.668432) (xy 350.189422 -175.677131) (xy 350.253982 -175.694454) (xy 350.28505 -175.706786)
			(xy 350.294564 -175.710061) (xy 350.314654 -175.709978) (xy 350.333184 -175.702215) (xy 350.347335 -175.687955)
			(xy 350.351598 -175.678846) (xy 350.362657 -175.652711) (xy 350.391341 -175.603749) (xy 350.426963 -175.559576)
			(xy 350.468734 -175.521167) (xy 350.515735 -175.48937) (xy 350.566927 -175.464886) (xy 350.621182 -175.448256)
			(xy 350.677301 -175.439846) (xy 350.705674 -175.439324) (xy 350.73293 -175.439721) (xy 350.786889 -175.447476)
			(xy 350.839194 -175.462831) (xy 350.888782 -175.485474) (xy 350.934642 -175.514944) (xy 350.975841 -175.55064)
			(xy 351.011541 -175.591837) (xy 351.041014 -175.637695) (xy 351.06366 -175.687281) (xy 351.079019 -175.739586)
			(xy 351.086777 -175.793544) (xy 351.086777 -175.848056) (xy 351.079019 -175.902014) (xy 351.06366 -175.954319)
			(xy 351.041014 -176.003905) (xy 351.011541 -176.049763) (xy 350.975841 -176.09096) (xy 350.934642 -176.126656)
			(xy 350.888782 -176.156126) (xy 350.839194 -176.178769) (xy 350.786889 -176.194124) (xy 350.73293 -176.201879)
			(xy 350.705674 -176.20234) (xy 350.692102 -176.202234) (xy 350.665025 -176.200329) (xy 350.651572 -176.19853)
			(xy 350.641539 -176.19755) (xy 350.622054 -176.202663) (xy 350.606027 -176.214866) (xy 350.595915 -176.232289)
			(xy 350.594168 -176.242218) (xy 350.589301 -176.275214) (xy 350.572088 -176.339653) (xy 350.5466 -176.401288)
			(xy 350.513274 -176.459064) (xy 350.472683 -176.511988) (xy 350.425523 -176.559153) (xy 350.372602 -176.599749)
			(xy 350.343978 -176.616868) (xy 349.419926 -177.150522) (xy 349.390862 -177.16662) (xy 349.329459 -177.191992)
			(xy 349.265273 -177.20915) (xy 349.1994 -177.217802) (xy 349.16618 -177.21834) (xy 349.165672 -177.21834)
			(xy 349.132249 -177.217836) (xy 349.065974 -177.209136) (xy 349.001414 -177.191811) (xy 348.970346 -177.179478)
			(xy 348.960856 -177.176093) (xy 348.940727 -177.176176) (xy 348.922163 -177.183961) (xy 348.907995 -177.19826)
			(xy 348.903798 -177.207418) (xy 348.892724 -177.233546) (xy 348.864043 -177.28251) (xy 348.828425 -177.326684)
			(xy 348.786656 -177.365094) (xy 348.739657 -177.396893) (xy 348.688466 -177.421377) (xy 348.634213 -177.438008)
			(xy 348.578095 -177.446418) (xy 348.549722 -177.44694) (xy 348.52247 -177.446414) (xy 348.468522 -177.43866)
			(xy 348.416226 -177.423308) (xy 348.366647 -177.400668) (xy 348.320795 -177.371203) (xy 348.279603 -177.335513)
			(xy 348.24391 -177.294323) (xy 348.214442 -177.248473) (xy 348.1918 -177.198895) (xy 348.176444 -177.1466)
			(xy 348.168687 -177.092652) (xy 345.45778 -177.092652) (xy 345.45778 -180.140652) (xy 348.168687 -180.140652)
			(xy 348.168687 -180.086148) (xy 348.176444 -180.0322) (xy 348.1918 -179.979905) (xy 348.214442 -179.930327)
			(xy 348.24391 -179.884477) (xy 348.279603 -179.843287) (xy 348.320795 -179.807597) (xy 348.366647 -179.778132)
			(xy 348.416226 -179.755492) (xy 348.468522 -179.74014) (xy 348.52247 -179.732386) (xy 348.549722 -179.731924)
			(xy 348.563294 -179.732031) (xy 348.590371 -179.733935) (xy 348.603824 -179.735734) (xy 348.613857 -179.736741)
			(xy 348.633349 -179.731626) (xy 348.649379 -179.719414) (xy 348.659486 -179.70198) (xy 348.661228 -179.692046)
			(xy 348.666073 -179.659046) (xy 348.683291 -179.594607) (xy 348.708783 -179.532972) (xy 348.742112 -179.475197)
			(xy 348.782707 -179.422274) (xy 348.82987 -179.37511) (xy 348.882793 -179.334515) (xy 348.911418 -179.317396)
			(xy 349.83547 -178.783742) (xy 349.864533 -178.767642) (xy 349.925937 -178.742271) (xy 349.990123 -178.725114)
			(xy 350.055996 -178.716463) (xy 350.089216 -178.715924) (xy 350.089724 -178.715924) (xy 350.123147 -178.716432)
			(xy 350.189422 -178.725131) (xy 350.253982 -178.742454) (xy 350.28505 -178.754786) (xy 350.294564 -178.758061)
			(xy 350.314654 -178.757978) (xy 350.333184 -178.750215) (xy 350.347335 -178.735955) (xy 350.351598 -178.726846)
			(xy 350.362657 -178.700711) (xy 350.391341 -178.651749) (xy 350.426963 -178.607576) (xy 350.468734 -178.569167)
			(xy 350.515735 -178.53737) (xy 350.566927 -178.512886) (xy 350.621182 -178.496256) (xy 350.677301 -178.487846)
			(xy 350.705674 -178.487324) (xy 350.73293 -178.487721) (xy 350.786889 -178.495476) (xy 350.839194 -178.510831)
			(xy 350.888782 -178.533474) (xy 350.934642 -178.562944) (xy 350.975841 -178.59864) (xy 351.011541 -178.639837)
			(xy 351.041014 -178.685695) (xy 351.06366 -178.735281) (xy 351.079019 -178.787586) (xy 351.086777 -178.841544)
			(xy 351.086777 -178.896056) (xy 351.079019 -178.950014) (xy 351.06366 -179.002319) (xy 351.054191 -179.023052)
			(xy 351.953287 -179.023052) (xy 351.953287 -178.968548) (xy 351.961044 -178.9146) (xy 351.9764 -178.862305)
			(xy 351.999042 -178.812727) (xy 352.02851 -178.766877) (xy 352.064203 -178.725687) (xy 352.105395 -178.689997)
			(xy 352.151247 -178.660532) (xy 352.200826 -178.637892) (xy 352.253122 -178.62254) (xy 352.30707 -178.614786)
			(xy 352.334322 -178.614324) (xy 352.362693 -178.614892) (xy 352.41881 -178.623299) (xy 352.473062 -178.639925)
			(xy 352.524254 -178.664402) (xy 352.571256 -178.696191) (xy 352.613031 -178.734591) (xy 352.648658 -178.778755)
			(xy 352.677352 -178.827708) (xy 352.688398 -178.853846) (xy 352.692535 -178.86306) (xy 352.706677 -178.877458)
			(xy 352.725286 -178.885269) (xy 352.745468 -178.885278) (xy 352.754946 -178.881786) (xy 352.786016 -178.869462)
			(xy 352.850579 -178.852156) (xy 352.916851 -178.843439) (xy 352.950272 -178.842924) (xy 352.95078 -178.842924)
			(xy 352.983998 -178.843489) (xy 353.049869 -178.852142) (xy 353.114055 -178.869291) (xy 353.175463 -178.894645)
			(xy 353.204526 -178.910742) (xy 354.128578 -179.444396) (xy 354.157211 -179.461501) (xy 354.210127 -179.502105)
			(xy 354.257284 -179.549274) (xy 354.297874 -179.6022) (xy 354.331202 -179.659976) (xy 354.356697 -179.72161)
			(xy 354.37392 -179.786047) (xy 354.378768 -179.819046) (xy 354.380484 -179.82899) (xy 354.390571 -179.846448)
			(xy 354.406616 -179.858659) (xy 354.42613 -179.863729) (xy 354.436172 -179.862734) (xy 354.449626 -179.860944)
			(xy 354.476702 -179.859036) (xy 354.490274 -179.858924) (xy 354.51753 -179.859321) (xy 354.571489 -179.867076)
			(xy 354.623794 -179.882431) (xy 354.673382 -179.905074) (xy 354.719242 -179.934544) (xy 354.760441 -179.97024)
			(xy 354.796141 -180.011437) (xy 354.825614 -180.057295) (xy 354.84826 -180.106881) (xy 354.863619 -180.159186)
			(xy 354.871377 -180.213144) (xy 354.871377 -180.267656) (xy 354.863619 -180.321614) (xy 354.84826 -180.373919)
			(xy 354.825614 -180.423505) (xy 354.796141 -180.469363) (xy 354.760441 -180.51056) (xy 354.719242 -180.546256)
			(xy 354.673382 -180.575726) (xy 354.623794 -180.598369) (xy 354.571489 -180.613724) (xy 354.51753 -180.621479)
			(xy 354.490274 -180.62194) (xy 354.461901 -180.621398) (xy 354.405783 -180.612989) (xy 354.351529 -180.596361)
			(xy 354.300336 -180.571881) (xy 354.253333 -180.540088) (xy 354.211559 -180.501684) (xy 354.175933 -180.457516)
			(xy 354.147242 -180.408558) (xy 354.136198 -180.382418) (xy 354.132042 -180.373212) (xy 354.117911 -180.358805)
			(xy 354.099306 -180.350989) (xy 354.079126 -180.350983) (xy 354.06965 -180.354478) (xy 354.038579 -180.366801)
			(xy 353.974017 -180.384109) (xy 353.907745 -180.392826) (xy 353.874324 -180.39334) (xy 353.873816 -180.39334)
			(xy 353.840597 -180.392782) (xy 353.774726 -180.384127) (xy 353.710541 -180.366976) (xy 353.649132 -180.341621)
			(xy 353.62007 -180.325522) (xy 352.696018 -179.791868) (xy 352.667408 -179.774727) (xy 352.614492 -179.734128)
			(xy 352.567334 -179.686964) (xy 352.526741 -179.634044) (xy 352.493409 -179.576275) (xy 352.46791 -179.514647)
			(xy 352.450679 -179.450215) (xy 352.445828 -179.417218) (xy 352.444141 -179.407268) (xy 352.434042 -179.389811)
			(xy 352.417989 -179.377603) (xy 352.398468 -179.372534) (xy 352.388424 -179.37353) (xy 352.37497 -179.37532)
			(xy 352.347894 -179.377228) (xy 352.334322 -179.37734) (xy 352.30707 -179.376814) (xy 352.253122 -179.36906)
			(xy 352.200826 -179.353708) (xy 352.151247 -179.331068) (xy 352.105395 -179.301603) (xy 352.064203 -179.265913)
			(xy 352.02851 -179.224723) (xy 351.999042 -179.178873) (xy 351.9764 -179.129295) (xy 351.961044 -179.077)
			(xy 351.953287 -179.023052) (xy 351.054191 -179.023052) (xy 351.041014 -179.051905) (xy 351.011541 -179.097763)
			(xy 350.975841 -179.13896) (xy 350.934642 -179.174656) (xy 350.888782 -179.204126) (xy 350.839194 -179.226769)
			(xy 350.786889 -179.242124) (xy 350.73293 -179.249879) (xy 350.705674 -179.25034) (xy 350.692102 -179.250234)
			(xy 350.665025 -179.248329) (xy 350.651572 -179.24653) (xy 350.641539 -179.24555) (xy 350.622054 -179.250663)
			(xy 350.606027 -179.262866) (xy 350.595915 -179.280289) (xy 350.594168 -179.290218) (xy 350.589301 -179.323214)
			(xy 350.572088 -179.387653) (xy 350.5466 -179.449288) (xy 350.513274 -179.507064) (xy 350.472683 -179.559988)
			(xy 350.425523 -179.607153) (xy 350.372602 -179.647749) (xy 350.343978 -179.664868) (xy 349.419926 -180.198522)
			(xy 349.390862 -180.21462) (xy 349.329459 -180.239992) (xy 349.265273 -180.25715) (xy 349.1994 -180.265802)
			(xy 349.16618 -180.26634) (xy 349.165672 -180.26634) (xy 349.132249 -180.265836) (xy 349.065974 -180.257136)
			(xy 349.001414 -180.239811) (xy 348.970346 -180.227478) (xy 348.960856 -180.224093) (xy 348.940727 -180.224176)
			(xy 348.922163 -180.231961) (xy 348.907995 -180.24626) (xy 348.903798 -180.255418) (xy 348.892724 -180.281546)
			(xy 348.864043 -180.33051) (xy 348.828425 -180.374684) (xy 348.786656 -180.413094) (xy 348.739657 -180.444893)
			(xy 348.688466 -180.469377) (xy 348.634213 -180.486008) (xy 348.578095 -180.494418) (xy 348.549722 -180.49494)
			(xy 348.52247 -180.494414) (xy 348.468522 -180.48666) (xy 348.416226 -180.471308) (xy 348.366647 -180.448668)
			(xy 348.320795 -180.419203) (xy 348.279603 -180.383513) (xy 348.24391 -180.342323) (xy 348.214442 -180.296473)
			(xy 348.1918 -180.246895) (xy 348.176444 -180.1946) (xy 348.168687 -180.140652) (xy 345.45778 -180.140652)
			(xy 345.45778 -183.188652) (xy 348.168687 -183.188652) (xy 348.168687 -183.134148) (xy 348.176444 -183.0802)
			(xy 348.1918 -183.027905) (xy 348.214442 -182.978327) (xy 348.24391 -182.932477) (xy 348.279603 -182.891287)
			(xy 348.320795 -182.855597) (xy 348.366647 -182.826132) (xy 348.416226 -182.803492) (xy 348.468522 -182.78814)
			(xy 348.52247 -182.780386) (xy 348.549722 -182.779924) (xy 348.563294 -182.780031) (xy 348.590371 -182.781935)
			(xy 348.603824 -182.783734) (xy 348.613857 -182.784741) (xy 348.633349 -182.779626) (xy 348.649379 -182.767414)
			(xy 348.659486 -182.74998) (xy 348.661228 -182.740046) (xy 348.666073 -182.707046) (xy 348.683291 -182.642607)
			(xy 348.708783 -182.580972) (xy 348.742112 -182.523197) (xy 348.782707 -182.470274) (xy 348.82987 -182.42311)
			(xy 348.882793 -182.382515) (xy 348.911418 -182.365396) (xy 349.83547 -181.831742) (xy 349.864533 -181.815642)
			(xy 349.925937 -181.790271) (xy 349.990123 -181.773114) (xy 350.055996 -181.764463) (xy 350.089216 -181.763924)
			(xy 350.089724 -181.763924) (xy 350.123147 -181.764432) (xy 350.189422 -181.773131) (xy 350.253982 -181.790454)
			(xy 350.28505 -181.802786) (xy 350.294564 -181.806061) (xy 350.314654 -181.805978) (xy 350.333184 -181.798215)
			(xy 350.347335 -181.783955) (xy 350.351598 -181.774846) (xy 350.362657 -181.748711) (xy 350.391341 -181.699749)
			(xy 350.426963 -181.655576) (xy 350.468734 -181.617167) (xy 350.515735 -181.58537) (xy 350.566927 -181.560886)
			(xy 350.621182 -181.544256) (xy 350.677301 -181.535846) (xy 350.705674 -181.535324) (xy 350.73293 -181.535721)
			(xy 350.786889 -181.543476) (xy 350.839194 -181.558831) (xy 350.888782 -181.581474) (xy 350.934642 -181.610944)
			(xy 350.975841 -181.64664) (xy 351.011541 -181.687837) (xy 351.041014 -181.733695) (xy 351.06366 -181.783281)
			(xy 351.079019 -181.835586) (xy 351.086777 -181.889544) (xy 351.086777 -181.944056) (xy 351.079019 -181.998014)
			(xy 351.06366 -182.050319) (xy 351.041014 -182.099905) (xy 351.011541 -182.145763) (xy 350.975841 -182.18696)
			(xy 350.934642 -182.222656) (xy 350.888782 -182.252126) (xy 350.839194 -182.274769) (xy 350.786889 -182.290124)
			(xy 350.73293 -182.297879) (xy 350.705674 -182.29834) (xy 350.692102 -182.298234) (xy 350.665025 -182.296329)
			(xy 350.651572 -182.29453) (xy 350.641539 -182.29355) (xy 350.622054 -182.298663) (xy 350.606027 -182.310866)
			(xy 350.595915 -182.328289) (xy 350.594168 -182.338218) (xy 350.589301 -182.371214) (xy 350.572088 -182.435653)
			(xy 350.5466 -182.497288) (xy 350.513274 -182.555064) (xy 350.472683 -182.607988) (xy 350.425523 -182.655153)
			(xy 350.372602 -182.695749) (xy 350.343978 -182.712868) (xy 350.343827 -182.712955) (xy 351.953245 -182.712955)
			(xy 351.953245 -182.658445) (xy 351.961003 -182.604491) (xy 351.97636 -182.55219) (xy 351.999005 -182.502607)
			(xy 352.028476 -182.456752) (xy 352.064173 -182.415557) (xy 352.105369 -182.379863) (xy 352.151226 -182.350394)
			(xy 352.200811 -182.327753) (xy 352.253113 -182.312398) (xy 352.307067 -182.304643) (xy 352.334322 -182.304182)
			(xy 352.362695 -182.304714) (xy 352.418815 -182.313122) (xy 352.47307 -182.329751) (xy 352.524264 -182.354233)
			(xy 352.571266 -182.386027) (xy 352.613041 -182.424433) (xy 352.648666 -182.468603) (xy 352.677355 -182.517563)
			(xy 352.688398 -182.543704) (xy 352.69255 -182.552911) (xy 352.706684 -182.567315) (xy 352.72529 -182.575129)
			(xy 352.74547 -182.575138) (xy 352.754946 -182.571644) (xy 352.78601 -182.559279) (xy 352.850563 -182.541869)
			(xy 352.916842 -182.533073) (xy 352.950272 -182.532528) (xy 352.95078 -182.532528) (xy 352.984007 -182.533118)
			(xy 353.049889 -182.541823) (xy 353.114077 -182.559036) (xy 353.175475 -182.584464) (xy 353.204526 -182.6006)
			(xy 354.112745 -183.12511) (xy 364.66094 -183.12511) (xy 364.665011 -183.069488) (xy 364.677137 -183.015051)
			(xy 364.69706 -182.96296) (xy 364.724356 -182.914325) (xy 364.758442 -182.870182) (xy 364.798591 -182.831473)
			(xy 364.843949 -182.799022) (xy 364.893549 -182.773521) (xy 364.946333 -182.755514) (xy 365.001176 -182.745384)
			(xy 365.05691 -182.743347) (xy 365.112347 -182.749447) (xy 365.166304 -182.763553) (xy 365.217633 -182.785365)
			(xy 365.265239 -182.814419) (xy 365.308107 -182.850094) (xy 365.345324 -182.891631) (xy 365.376097 -182.938144)
			(xy 365.399769 -182.988641) (xy 365.415837 -183.042048) (xy 365.423957 -183.097224) (xy 365.424466 -183.12511)
			(xy 365.423957 -183.152996) (xy 365.415837 -183.208172) (xy 365.399769 -183.261579) (xy 365.376097 -183.312076)
			(xy 365.345324 -183.358589) (xy 365.308107 -183.400126) (xy 365.265239 -183.435801) (xy 365.217633 -183.464855)
			(xy 365.166304 -183.486667) (xy 365.112347 -183.500773) (xy 365.05691 -183.506873) (xy 365.001176 -183.504836)
			(xy 364.946333 -183.494706) (xy 364.893549 -183.476699) (xy 364.843949 -183.451198) (xy 364.798591 -183.418747)
			(xy 364.758442 -183.380038) (xy 364.724356 -183.335895) (xy 364.69706 -183.28726) (xy 364.677137 -183.235169)
			(xy 364.665011 -183.180732) (xy 364.66094 -183.12511) (xy 354.112745 -183.12511) (xy 354.128578 -183.134254)
			(xy 354.157196 -183.151384) (xy 354.210111 -183.191984) (xy 354.257269 -183.239149) (xy 354.297861 -183.292071)
			(xy 354.331192 -183.349843) (xy 354.35669 -183.411473) (xy 354.373918 -183.475906) (xy 354.378768 -183.508904)
			(xy 354.380444 -183.518856) (xy 354.390549 -183.536311) (xy 354.406605 -183.548518) (xy 354.426127 -183.553588)
			(xy 354.436172 -183.552592) (xy 354.449626 -183.550802) (xy 354.476702 -183.548894) (xy 354.490274 -183.548782)
			(xy 354.517527 -183.549264) (xy 354.57148 -183.557017) (xy 354.623779 -183.572371) (xy 354.673361 -183.595011)
			(xy 354.719217 -183.624478) (xy 354.760411 -183.66017) (xy 354.796107 -183.701363) (xy 354.825576 -183.747216)
			(xy 354.84822 -183.796796) (xy 354.863577 -183.849095) (xy 354.871335 -183.903047) (xy 354.871335 -183.957553)
			(xy 354.863577 -184.011505) (xy 354.84822 -184.063804) (xy 354.825576 -184.113384) (xy 354.796107 -184.159237)
			(xy 354.760411 -184.20043) (xy 354.719217 -184.236122) (xy 354.673361 -184.265589) (xy 354.623779 -184.288229)
			(xy 354.57148 -184.303583) (xy 354.517527 -184.311336) (xy 354.490274 -184.311798) (xy 354.461903 -184.31122)
			(xy 354.405788 -184.302812) (xy 354.351537 -184.286187) (xy 354.300345 -184.261711) (xy 354.253344 -184.229923)
			(xy 354.211568 -184.191525) (xy 354.17594 -184.147364) (xy 354.147245 -184.098413) (xy 354.136198 -184.072276)
			(xy 354.132057 -184.063063) (xy 354.117918 -184.048662) (xy 354.099309 -184.04085) (xy 354.079127 -184.040843)
			(xy 354.06965 -184.044336) (xy 354.038586 -184.056701) (xy 353.974033 -184.074111) (xy 353.907754 -184.082907)
			(xy 353.874324 -184.083452) (xy 353.873816 -184.083452) (xy 353.840589 -184.082867) (xy 353.774706 -184.07416)
			(xy 353.710519 -184.056946) (xy 353.649121 -184.031517) (xy 353.62007 -184.01538) (xy 352.696018 -183.481726)
			(xy 352.667392 -183.46461) (xy 352.614477 -183.424007) (xy 352.567319 -183.376839) (xy 352.526728 -183.323915)
			(xy 352.493399 -183.266142) (xy 352.467903 -183.20451) (xy 352.450677 -183.140075) (xy 352.445828 -183.107076)
			(xy 352.444169 -183.09712) (xy 352.434057 -183.079665) (xy 352.417996 -183.06746) (xy 352.39847 -183.062392)
			(xy 352.388424 -183.063388) (xy 352.37497 -183.065179) (xy 352.347894 -183.067086) (xy 352.334322 -183.067198)
			(xy 352.307067 -183.066757) (xy 352.253113 -183.059002) (xy 352.200811 -183.043647) (xy 352.151226 -183.021006)
			(xy 352.105369 -182.991537) (xy 352.064173 -182.955843) (xy 352.028476 -182.914648) (xy 351.999005 -182.868793)
			(xy 351.97636 -182.81921) (xy 351.961003 -182.766909) (xy 351.953245 -182.712955) (xy 350.343827 -182.712955)
			(xy 349.419926 -183.246522) (xy 349.390862 -183.26262) (xy 349.329459 -183.287992) (xy 349.265273 -183.30515)
			(xy 349.1994 -183.313802) (xy 349.16618 -183.31434) (xy 349.165672 -183.31434) (xy 349.132249 -183.313836)
			(xy 349.065974 -183.305136) (xy 349.001414 -183.287811) (xy 348.970346 -183.275478) (xy 348.960856 -183.272093)
			(xy 348.940727 -183.272176) (xy 348.922163 -183.279961) (xy 348.907995 -183.29426) (xy 348.903798 -183.303418)
			(xy 348.892724 -183.329546) (xy 348.864043 -183.37851) (xy 348.828425 -183.422684) (xy 348.786656 -183.461094)
			(xy 348.739657 -183.492893) (xy 348.688466 -183.517377) (xy 348.634213 -183.534008) (xy 348.578095 -183.542418)
			(xy 348.549722 -183.54294) (xy 348.52247 -183.542414) (xy 348.468522 -183.53466) (xy 348.416226 -183.519308)
			(xy 348.366647 -183.496668) (xy 348.320795 -183.467203) (xy 348.279603 -183.431513) (xy 348.24391 -183.390323)
			(xy 348.214442 -183.344473) (xy 348.1918 -183.294895) (xy 348.176444 -183.2426) (xy 348.168687 -183.188652)
			(xy 345.45778 -183.188652) (xy 345.45778 -185.192416) (xy 363.706154 -185.192416) (xy 363.710225 -185.136794)
			(xy 363.722351 -185.082357) (xy 363.742274 -185.030266) (xy 363.76957 -184.981631) (xy 363.803656 -184.937488)
			(xy 363.843805 -184.898779) (xy 363.889163 -184.866328) (xy 363.938763 -184.840827) (xy 363.991547 -184.82282)
			(xy 364.04639 -184.81269) (xy 364.102124 -184.810653) (xy 364.157561 -184.816753) (xy 364.211518 -184.830859)
			(xy 364.262847 -184.852671) (xy 364.310453 -184.881725) (xy 364.353321 -184.9174) (xy 364.390538 -184.958937)
			(xy 364.421311 -185.00545) (xy 364.444983 -185.055947) (xy 364.461051 -185.109354) (xy 364.469171 -185.16453)
			(xy 364.46968 -185.192416) (xy 364.469171 -185.220302) (xy 364.461051 -185.275478) (xy 364.444983 -185.328885)
			(xy 364.421311 -185.379382) (xy 364.390538 -185.425895) (xy 364.353321 -185.467432) (xy 364.310453 -185.503107)
			(xy 364.262847 -185.532161) (xy 364.211518 -185.553973) (xy 364.157561 -185.568079) (xy 364.102124 -185.574179)
			(xy 364.04639 -185.572142) (xy 363.991547 -185.562012) (xy 363.938763 -185.544005) (xy 363.889163 -185.518504)
			(xy 363.843805 -185.486053) (xy 363.803656 -185.447344) (xy 363.76957 -185.403201) (xy 363.742274 -185.354566)
			(xy 363.722351 -185.302475) (xy 363.710225 -185.248038) (xy 363.706154 -185.192416) (xy 345.45778 -185.192416)
			(xy 345.45778 -186.393347) (xy 350.880728 -186.393347) (xy 350.880728 -186.338853) (xy 350.888483 -186.284914)
			(xy 350.903835 -186.232628) (xy 350.926472 -186.183059) (xy 350.955932 -186.137215) (xy 350.991617 -186.096031)
			(xy 351.032799 -186.060344) (xy 351.078641 -186.030881) (xy 351.128209 -186.008242) (xy 351.180495 -185.992887)
			(xy 351.234433 -185.98513) (xy 351.26168 -185.984642) (xy 351.289661 -185.985174) (xy 351.34502 -185.993367)
			(xy 351.398591 -186.00955) (xy 351.449227 -186.033378) (xy 351.495844 -186.06434) (xy 351.537444 -186.101773)
			(xy 351.573136 -186.144876) (xy 351.602156 -186.192726) (xy 351.61347 -186.218322) (xy 351.61772 -186.227378)
			(xy 351.631901 -186.241466) (xy 351.650395 -186.24905) (xy 351.670384 -186.248975) (xy 351.679764 -186.2455)
			(xy 351.710941 -186.233076) (xy 351.775753 -186.215642) (xy 351.842294 -186.206886) (xy 351.875852 -186.206384)
			(xy 351.87636 -186.206384) (xy 351.90958 -186.206906) (xy 351.975453 -186.215571) (xy 352.039638 -186.232732)
			(xy 352.101045 -186.258098) (xy 352.130106 -186.274202) (xy 353.054158 -186.807856) (xy 353.08065 -186.823654)
			(xy 353.129955 -186.860717) (xy 353.174415 -186.903474) (xy 353.213374 -186.951295) (xy 353.246261 -187.00348)
			(xy 353.272592 -187.059259) (xy 353.291981 -187.117815) (xy 353.298506 -187.147962) (xy 353.301786 -187.161972)
			(xy 353.315066 -187.187483) (xy 353.334939 -187.208274) (xy 353.359827 -187.22269) (xy 353.387749 -187.229586)
			(xy 353.402138 -187.229496) (xy 353.417632 -187.229242) (xy 353.444885 -187.22963) (xy 353.498837 -187.237391)
			(xy 353.551134 -187.252751) (xy 353.600714 -187.275397) (xy 353.646566 -187.304868) (xy 353.687758 -187.340564)
			(xy 353.723451 -187.381759) (xy 353.752918 -187.427614) (xy 353.77556 -187.477196) (xy 353.790915 -187.529495)
			(xy 353.798672 -187.583447) (xy 353.798672 -187.637953) (xy 353.790915 -187.691905) (xy 353.77556 -187.744204)
			(xy 353.752918 -187.793786) (xy 353.723451 -187.839641) (xy 353.687758 -187.880836) (xy 353.646566 -187.916532)
			(xy 353.600714 -187.946003) (xy 353.551134 -187.968649) (xy 353.498837 -187.984009) (xy 353.444885 -187.99177)
			(xy 353.417632 -187.992258) (xy 353.391345 -187.991845) (xy 353.339268 -187.984642) (xy 353.288674 -187.970354)
			(xy 353.240522 -187.949252) (xy 353.195725 -187.921736) (xy 353.155132 -187.888328) (xy 353.119513 -187.849661)
			(xy 353.089542 -187.806467) (xy 353.077272 -187.783216) (xy 353.070331 -187.770624) (xy 353.050692 -187.749638)
			(xy 353.025989 -187.734948) (xy 352.998173 -187.727713) (xy 352.969443 -187.728506) (xy 352.955606 -187.732416)
			(xy 352.917691 -187.7438) (xy 352.839484 -187.756045) (xy 352.799904 -187.7568) (xy 352.799396 -187.7568)
			(xy 352.766177 -187.756256) (xy 352.700305 -187.747598) (xy 352.636119 -187.730443) (xy 352.574711 -187.705083)
			(xy 352.54565 -187.688982) (xy 351.621598 -187.155328) (xy 351.593378 -187.138436) (xy 351.54113 -187.098489)
			(xy 351.494468 -187.05214) (xy 351.454171 -187.000161) (xy 351.420912 -186.94342) (xy 351.395246 -186.882865)
			(xy 351.377601 -186.819507) (xy 351.372424 -186.787028) (xy 351.370546 -186.77718) (xy 351.36038 -186.759925)
			(xy 351.344384 -186.747876) (xy 351.324994 -186.742866) (xy 351.31502 -186.743848) (xy 351.301755 -186.745615)
			(xy 351.275061 -186.747521) (xy 351.26168 -186.747658) (xy 351.234433 -186.74707) (xy 351.180495 -186.739313)
			(xy 351.128209 -186.723958) (xy 351.078641 -186.701319) (xy 351.032799 -186.671856) (xy 350.991617 -186.636169)
			(xy 350.955932 -186.594985) (xy 350.926472 -186.549141) (xy 350.903835 -186.499572) (xy 350.888483 -186.447286)
			(xy 350.880728 -186.393347) (xy 345.45778 -186.393347) (xy 345.45778 -201.628248) (xy 352.30308 -208.473548)
			(xy 352.30308 -213.292944) (xy 352.303488 -213.30641) (xy 352.310522 -213.332405) (xy 352.324115 -213.355654)
			(xy 352.343318 -213.374535) (xy 352.366794 -213.387732) (xy 352.392905 -213.394324) (xy 352.419832 -213.393853)
			(xy 352.432874 -213.39048) (xy 352.457112 -213.383924) (xy 352.506829 -213.376905) (xy 352.531934 -213.37651)
			(xy 352.55858 -213.377011) (xy 352.611277 -213.384958) (xy 352.662201 -213.40067) (xy 352.710214 -213.423796)
			(xy 352.754245 -213.45382) (xy 352.793309 -213.49007) (xy 352.826535 -213.531737) (xy 352.85318 -213.577891)
			(xy 352.872649 -213.6275) (xy 352.884507 -213.679456) (xy 352.888489 -213.7326) (xy 352.888488 -213.732618)
			(xy 353.115626 -213.732618) (xy 353.116124 -213.705969) (xy 353.124067 -213.653265) (xy 353.139777 -213.602335)
			(xy 353.162903 -213.554314) (xy 353.192927 -213.510277) (xy 353.229179 -213.471206) (xy 353.27085 -213.437975)
			(xy 353.317008 -213.411326) (xy 353.366622 -213.391854) (xy 353.418584 -213.379994) (xy 353.471734 -213.376011)
			(xy 353.524884 -213.379994) (xy 353.576846 -213.391854) (xy 353.62646 -213.411326) (xy 353.672618 -213.437975)
			(xy 353.714289 -213.471206) (xy 353.750541 -213.510277) (xy 353.780565 -213.554314) (xy 353.803691 -213.602335)
			(xy 353.819401 -213.653265) (xy 353.827344 -213.705969) (xy 353.827842 -213.732618) (xy 353.827324 -213.759267)
			(xy 354.055924 -213.759267) (xy 354.055924 -213.705969) (xy 354.063867 -213.653265) (xy 354.079577 -213.602335)
			(xy 354.102703 -213.554314) (xy 354.132727 -213.510277) (xy 354.168979 -213.471206) (xy 354.21065 -213.437975)
			(xy 354.256808 -213.411326) (xy 354.306422 -213.391854) (xy 354.358384 -213.379994) (xy 354.411534 -213.376011)
			(xy 354.464684 -213.379994) (xy 354.516646 -213.391854) (xy 354.56626 -213.411326) (xy 354.612418 -213.437975)
			(xy 354.654089 -213.471206) (xy 354.690341 -213.510277) (xy 354.720365 -213.554314) (xy 354.743491 -213.602335)
			(xy 354.759201 -213.653265) (xy 354.767144 -213.705969) (xy 354.767642 -213.732618) (xy 354.995226 -213.732618)
			(xy 354.995724 -213.705969) (xy 355.003667 -213.653265) (xy 355.019377 -213.602335) (xy 355.042503 -213.554314)
			(xy 355.072527 -213.510277) (xy 355.108779 -213.471206) (xy 355.15045 -213.437975) (xy 355.196608 -213.411326)
			(xy 355.246222 -213.391854) (xy 355.298184 -213.379994) (xy 355.351334 -213.376011) (xy 355.404484 -213.379994)
			(xy 355.456446 -213.391854) (xy 355.50606 -213.411326) (xy 355.552218 -213.437975) (xy 355.593889 -213.471206)
			(xy 355.630141 -213.510277) (xy 355.660165 -213.554314) (xy 355.683291 -213.602335) (xy 355.699001 -213.653265)
			(xy 355.706944 -213.705969) (xy 355.707442 -213.732618) (xy 355.706924 -213.759267) (xy 355.935524 -213.759267)
			(xy 355.935524 -213.705969) (xy 355.943467 -213.653265) (xy 355.959177 -213.602335) (xy 355.982303 -213.554314)
			(xy 356.012327 -213.510277) (xy 356.048579 -213.471206) (xy 356.09025 -213.437975) (xy 356.136408 -213.411326)
			(xy 356.186022 -213.391854) (xy 356.237984 -213.379994) (xy 356.291134 -213.376011) (xy 356.344284 -213.379994)
			(xy 356.396246 -213.391854) (xy 356.44586 -213.411326) (xy 356.492018 -213.437975) (xy 356.533689 -213.471206)
			(xy 356.569941 -213.510277) (xy 356.599965 -213.554314) (xy 356.623091 -213.602335) (xy 356.638801 -213.653265)
			(xy 356.646744 -213.705969) (xy 356.647242 -213.732618) (xy 356.646744 -213.759267) (xy 356.638801 -213.811971)
			(xy 356.623091 -213.862901) (xy 356.599965 -213.910922) (xy 356.569941 -213.954959) (xy 356.533689 -213.99403)
			(xy 356.492018 -214.027261) (xy 356.44586 -214.05391) (xy 356.396246 -214.073382) (xy 356.344284 -214.085242)
			(xy 356.291134 -214.089226) (xy 356.237984 -214.085242) (xy 356.186022 -214.073382) (xy 356.136408 -214.05391)
			(xy 356.09025 -214.027261) (xy 356.048579 -213.99403) (xy 356.012327 -213.954959) (xy 355.982303 -213.910922)
			(xy 355.959177 -213.862901) (xy 355.943467 -213.811971) (xy 355.935524 -213.759267) (xy 355.706924 -213.759267)
			(xy 355.706901 -213.760435) (xy 355.698257 -213.815393) (xy 355.681168 -213.868337) (xy 355.669088 -213.8934)
			(xy 355.65715 -213.916768) (xy 355.841554 -214.266272) (xy 355.867462 -214.269574) (xy 355.892807 -214.273456)
			(xy 355.942143 -214.287405) (xy 355.988969 -214.308285) (xy 356.032317 -214.335665) (xy 356.07129 -214.368977)
			(xy 356.105084 -214.407534) (xy 356.133 -214.450538) (xy 356.15446 -214.497101) (xy 356.169022 -214.54626)
			(xy 356.176383 -214.596999) (xy 356.176834 -214.622634) (xy 356.176336 -214.649283) (xy 356.168393 -214.701987)
			(xy 356.152683 -214.752917) (xy 356.129557 -214.800938) (xy 356.099533 -214.844975) (xy 356.063281 -214.884046)
			(xy 356.02161 -214.917277) (xy 355.975452 -214.943926) (xy 355.925838 -214.963398) (xy 355.873876 -214.975258)
			(xy 355.820726 -214.979242) (xy 355.767576 -214.975258) (xy 355.715614 -214.963398) (xy 355.666 -214.943926)
			(xy 355.619842 -214.917277) (xy 355.578171 -214.884046) (xy 355.541919 -214.844975) (xy 355.511895 -214.800938)
			(xy 355.488769 -214.752917) (xy 355.473059 -214.701987) (xy 355.465116 -214.649283) (xy 355.464618 -214.622634)
			(xy 355.465146 -214.594816) (xy 355.473795 -214.539858) (xy 355.490889 -214.486914) (xy 355.502972 -214.461852)
			(xy 355.51491 -214.438484) (xy 355.330506 -214.08898) (xy 355.304598 -214.085678) (xy 355.27924 -214.081874)
			(xy 355.2299 -214.067917) (xy 355.183071 -214.047028) (xy 355.139722 -214.01964) (xy 355.100748 -213.986319)
			(xy 355.066955 -213.947753) (xy 355.039042 -213.90474) (xy 355.017586 -213.858169) (xy 355.003029 -213.809002)
			(xy 354.995674 -213.758256) (xy 354.995226 -213.732618) (xy 354.767642 -213.732618) (xy 354.767144 -213.759267)
			(xy 354.759201 -213.811971) (xy 354.743491 -213.862901) (xy 354.720365 -213.910922) (xy 354.690341 -213.954959)
			(xy 354.654089 -213.99403) (xy 354.612418 -214.027261) (xy 354.56626 -214.05391) (xy 354.516646 -214.073382)
			(xy 354.464684 -214.085242) (xy 354.411534 -214.089226) (xy 354.358384 -214.085242) (xy 354.306422 -214.073382)
			(xy 354.256808 -214.05391) (xy 354.21065 -214.027261) (xy 354.168979 -213.99403) (xy 354.132727 -213.954959)
			(xy 354.102703 -213.910922) (xy 354.079577 -213.862901) (xy 354.063867 -213.811971) (xy 354.055924 -213.759267)
			(xy 353.827324 -213.759267) (xy 353.827301 -213.760435) (xy 353.818657 -213.815393) (xy 353.801568 -213.868337)
			(xy 353.789488 -213.8934) (xy 353.77755 -213.916768) (xy 353.961954 -214.266272) (xy 353.987862 -214.269574)
			(xy 354.013207 -214.273456) (xy 354.062543 -214.287405) (xy 354.109369 -214.308285) (xy 354.152717 -214.335665)
			(xy 354.19169 -214.368977) (xy 354.225484 -214.407534) (xy 354.2534 -214.450538) (xy 354.27486 -214.497101)
			(xy 354.289422 -214.54626) (xy 354.296783 -214.596999) (xy 354.297234 -214.622634) (xy 354.296736 -214.649283)
			(xy 354.288793 -214.701987) (xy 354.273083 -214.752917) (xy 354.249957 -214.800938) (xy 354.219933 -214.844975)
			(xy 354.183681 -214.884046) (xy 354.14201 -214.917277) (xy 354.095852 -214.943926) (xy 354.046238 -214.963398)
			(xy 353.994276 -214.975258) (xy 353.941126 -214.979242) (xy 353.887976 -214.975258) (xy 353.836014 -214.963398)
			(xy 353.7864 -214.943926) (xy 353.740242 -214.917277) (xy 353.698571 -214.884046) (xy 353.662319 -214.844975)
			(xy 353.632295 -214.800938) (xy 353.609169 -214.752917) (xy 353.593459 -214.701987) (xy 353.585516 -214.649283)
			(xy 353.585018 -214.622634) (xy 353.585546 -214.594816) (xy 353.594195 -214.539858) (xy 353.611289 -214.486914)
			(xy 353.623372 -214.461852) (xy 353.63531 -214.438484) (xy 353.450906 -214.08898) (xy 353.424998 -214.085678)
			(xy 353.39964 -214.081874) (xy 353.3503 -214.067917) (xy 353.303471 -214.047028) (xy 353.260122 -214.01964)
			(xy 353.221148 -213.986319) (xy 353.187355 -213.947753) (xy 353.159442 -213.90474) (xy 353.137986 -213.858169)
			(xy 353.123429 -213.809002) (xy 353.116074 -213.758256) (xy 353.115626 -213.732618) (xy 352.888488 -213.732618)
			(xy 352.884507 -213.785744) (xy 352.872649 -213.8377) (xy 352.85318 -213.887309) (xy 352.826535 -213.933463)
			(xy 352.793309 -213.97513) (xy 352.754245 -214.01138) (xy 352.710214 -214.041404) (xy 352.662201 -214.06453)
			(xy 352.611277 -214.080242) (xy 352.55858 -214.088189) (xy 352.531934 -214.088726) (xy 352.506829 -214.088315)
			(xy 352.457112 -214.081307) (xy 352.432874 -214.074756) (xy 352.419829 -214.071422) (xy 352.392917 -214.070977)
			(xy 352.366824 -214.07758) (xy 352.343363 -214.090772) (xy 352.324164 -214.109636) (xy 352.310561 -214.132862)
			(xy 352.3035 -214.158835) (xy 352.30308 -214.172292) (xy 352.30308 -214.361014) (xy 352.322389 -214.379498)
			(xy 352.355796 -214.421226) (xy 352.38259 -214.467478) (xy 352.402169 -214.517215) (xy 352.414095 -214.569321)
			(xy 352.418097 -214.622623) (xy 352.414088 -214.675925) (xy 352.402156 -214.728029) (xy 352.38257 -214.777764)
			(xy 352.35577 -214.824012) (xy 352.322358 -214.865735) (xy 352.30308 -214.884254) (xy 352.30308 -214.99703)
			(xy 352.303487 -215.010497) (xy 352.310518 -215.036496) (xy 352.32411 -215.059748) (xy 352.343314 -215.078632)
			(xy 352.366792 -215.091831) (xy 352.392906 -215.098424) (xy 352.419835 -215.097953) (xy 352.432874 -215.094566)
			(xy 352.445638 -215.091) (xy 352.471572 -215.085531) (xy 352.48469 -215.083644) (xy 352.509328 -215.080342)
			(xy 352.681794 -214.781638) (xy 352.672142 -214.758524) (xy 352.663628 -214.736892) (xy 352.651645 -214.691974)
			(xy 352.645607 -214.645879) (xy 352.645218 -214.622634) (xy 352.645716 -214.595985) (xy 352.653659 -214.543281)
			(xy 352.669369 -214.492351) (xy 352.692495 -214.44433) (xy 352.722519 -214.400293) (xy 352.758771 -214.361222)
			(xy 352.800442 -214.327991) (xy 352.8466 -214.301342) (xy 352.896214 -214.28187) (xy 352.948176 -214.27001)
			(xy 353.001326 -214.266027) (xy 353.054476 -214.27001) (xy 353.106438 -214.28187) (xy 353.156052 -214.301342)
			(xy 353.20221 -214.327991) (xy 353.243881 -214.361222) (xy 353.280133 -214.400293) (xy 353.310157 -214.44433)
			(xy 353.333283 -214.492351) (xy 353.348993 -214.543281) (xy 353.356936 -214.595985) (xy 353.357434 -214.622634)
			(xy 353.356986 -214.64826) (xy 353.349637 -214.698983) (xy 353.335094 -214.748129) (xy 353.313658 -214.794683)
			(xy 353.285771 -214.837685) (xy 353.25201 -214.876247) (xy 353.213071 -214.909572) (xy 353.169758 -214.936973)
			(xy 353.122966 -214.957884) (xy 353.07366 -214.971874) (xy 353.048316 -214.975694) (xy 353.023678 -214.978996)
			(xy 352.851212 -215.2777) (xy 352.860864 -215.300814) (xy 352.869382 -215.322446) (xy 352.881372 -215.367363)
			(xy 352.887418 -215.413459) (xy 352.887788 -215.436704) (xy 352.887292 -215.463353) (xy 353.11587 -215.463353)
			(xy 353.11587 -215.410055) (xy 353.123813 -215.357351) (xy 353.139523 -215.306421) (xy 353.162649 -215.2584)
			(xy 353.192673 -215.214363) (xy 353.228925 -215.175292) (xy 353.270596 -215.142061) (xy 353.316754 -215.115412)
			(xy 353.366368 -215.09594) (xy 353.41833 -215.08408) (xy 353.47148 -215.080097) (xy 353.52463 -215.08408)
			(xy 353.576592 -215.09594) (xy 353.626206 -215.115412) (xy 353.672364 -215.142061) (xy 353.714035 -215.175292)
			(xy 353.750287 -215.214363) (xy 353.780311 -215.2584) (xy 353.803437 -215.306421) (xy 353.819147 -215.357351)
			(xy 353.82709 -215.410055) (xy 353.827588 -215.436704) (xy 354.055172 -215.436704) (xy 354.055579 -215.411074)
			(xy 354.062915 -215.360342) (xy 354.07745 -215.311186) (xy 354.098884 -215.264623) (xy 354.126773 -215.221614)
			(xy 354.160541 -215.183049) (xy 354.199491 -215.149725) (xy 354.242817 -215.122331) (xy 354.289623 -215.101433)
			(xy 354.338942 -215.087463) (xy 354.36429 -215.083644) (xy 354.388928 -215.080342) (xy 354.561394 -214.781638)
			(xy 354.551742 -214.758524) (xy 354.543237 -214.736888) (xy 354.531245 -214.691972) (xy 354.525196 -214.645878)
			(xy 354.524818 -214.622634) (xy 354.525316 -214.595985) (xy 354.533259 -214.543281) (xy 354.548969 -214.492351)
			(xy 354.572095 -214.44433) (xy 354.602119 -214.400293) (xy 354.638371 -214.361222) (xy 354.680042 -214.327991)
			(xy 354.7262 -214.301342) (xy 354.775814 -214.28187) (xy 354.827776 -214.27001) (xy 354.880926 -214.266027)
			(xy 354.934076 -214.27001) (xy 354.986038 -214.28187) (xy 355.035652 -214.301342) (xy 355.08181 -214.327991)
			(xy 355.123481 -214.361222) (xy 355.159733 -214.400293) (xy 355.189757 -214.44433) (xy 355.212883 -214.492351)
			(xy 355.228593 -214.543281) (xy 355.236536 -214.595985) (xy 355.237034 -214.622634) (xy 355.236564 -214.648262)
			(xy 355.229237 -214.698991) (xy 355.214711 -214.748146) (xy 355.193285 -214.794708) (xy 355.165403 -214.837717)
			(xy 355.131641 -214.876282) (xy 355.092698 -214.909607) (xy 355.049378 -214.937003) (xy 355.002576 -214.957902)
			(xy 354.953262 -214.971874) (xy 354.927916 -214.975694) (xy 354.903278 -214.978996) (xy 354.730812 -215.2777)
			(xy 354.740464 -215.300814) (xy 354.748981 -215.322446) (xy 354.760968 -215.367364) (xy 354.767013 -215.413459)
			(xy 354.767388 -215.436704) (xy 354.76689 -215.463353) (xy 354.99547 -215.463353) (xy 354.99547 -215.410055)
			(xy 355.003413 -215.357351) (xy 355.019123 -215.306421) (xy 355.042249 -215.2584) (xy 355.072273 -215.214363)
			(xy 355.108525 -215.175292) (xy 355.150196 -215.142061) (xy 355.196354 -215.115412) (xy 355.245968 -215.09594)
			(xy 355.29793 -215.08408) (xy 355.35108 -215.080097) (xy 355.40423 -215.08408) (xy 355.456192 -215.09594)
			(xy 355.505806 -215.115412) (xy 355.551964 -215.142061) (xy 355.593635 -215.175292) (xy 355.629887 -215.214363)
			(xy 355.659911 -215.2584) (xy 355.683037 -215.306421) (xy 355.698747 -215.357351) (xy 355.70669 -215.410055)
			(xy 355.707188 -215.436704) (xy 355.934772 -215.436704) (xy 355.935179 -215.411074) (xy 355.942515 -215.360342)
			(xy 355.95705 -215.311186) (xy 355.978484 -215.264623) (xy 356.006373 -215.221614) (xy 356.040141 -215.183049)
			(xy 356.079091 -215.149725) (xy 356.122417 -215.122331) (xy 356.169223 -215.101433) (xy 356.218542 -215.087463)
			(xy 356.24389 -215.083644) (xy 356.268528 -215.080342) (xy 356.440994 -214.781638) (xy 356.431342 -214.758524)
			(xy 356.422837 -214.736888) (xy 356.410845 -214.691972) (xy 356.404796 -214.645878) (xy 356.404418 -214.622634)
			(xy 356.404916 -214.595985) (xy 356.412859 -214.543281) (xy 356.428569 -214.492351) (xy 356.451695 -214.44433)
			(xy 356.481719 -214.400293) (xy 356.517971 -214.361222) (xy 356.559642 -214.327991) (xy 356.6058 -214.301342)
			(xy 356.655414 -214.28187) (xy 356.707376 -214.27001) (xy 356.760526 -214.266027) (xy 356.813676 -214.27001)
			(xy 356.865638 -214.28187) (xy 356.915252 -214.301342) (xy 356.96141 -214.327991) (xy 357.003081 -214.361222)
			(xy 357.039333 -214.400293) (xy 357.069357 -214.44433) (xy 357.092483 -214.492351) (xy 357.108193 -214.543281)
			(xy 357.116136 -214.595985) (xy 357.116634 -214.622634) (xy 357.116164 -214.648262) (xy 357.116017 -214.649283)
			(xy 357.344716 -214.649283) (xy 357.344716 -214.595985) (xy 357.352659 -214.543281) (xy 357.368369 -214.492351)
			(xy 357.391495 -214.44433) (xy 357.421519 -214.400293) (xy 357.457771 -214.361222) (xy 357.499442 -214.327991)
			(xy 357.5456 -214.301342) (xy 357.595214 -214.28187) (xy 357.647176 -214.27001) (xy 357.700326 -214.266027)
			(xy 357.753476 -214.27001) (xy 357.805438 -214.28187) (xy 357.855052 -214.301342) (xy 357.90121 -214.327991)
			(xy 357.942881 -214.361222) (xy 357.979133 -214.400293) (xy 358.009157 -214.44433) (xy 358.032283 -214.492351)
			(xy 358.047993 -214.543281) (xy 358.055936 -214.595985) (xy 358.056434 -214.622634) (xy 358.055936 -214.649283)
			(xy 358.047993 -214.701987) (xy 358.032283 -214.752917) (xy 358.009157 -214.800938) (xy 357.979133 -214.844975)
			(xy 357.942881 -214.884046) (xy 357.90121 -214.917277) (xy 357.855052 -214.943926) (xy 357.805438 -214.963398)
			(xy 357.753476 -214.975258) (xy 357.700326 -214.979242) (xy 357.647176 -214.975258) (xy 357.595214 -214.963398)
			(xy 357.5456 -214.943926) (xy 357.499442 -214.917277) (xy 357.457771 -214.884046) (xy 357.421519 -214.844975)
			(xy 357.391495 -214.800938) (xy 357.368369 -214.752917) (xy 357.352659 -214.701987) (xy 357.344716 -214.649283)
			(xy 357.116017 -214.649283) (xy 357.108837 -214.698991) (xy 357.094311 -214.748146) (xy 357.072885 -214.794708)
			(xy 357.045003 -214.837717) (xy 357.011241 -214.876282) (xy 356.972298 -214.909607) (xy 356.928978 -214.937003)
			(xy 356.882176 -214.957902) (xy 356.832862 -214.971874) (xy 356.807516 -214.975694) (xy 356.782878 -214.978996)
			(xy 356.610412 -215.2777) (xy 356.620064 -215.300814) (xy 356.628581 -215.322446) (xy 356.640568 -215.367364)
			(xy 356.646613 -215.413459) (xy 356.646988 -215.4367) (xy 356.874096 -215.4367) (xy 356.878079 -215.383553)
			(xy 356.889938 -215.331593) (xy 356.909409 -215.281981) (xy 356.936056 -215.235824) (xy 356.969285 -215.194155)
			(xy 357.008352 -215.157903) (xy 357.052387 -215.127879) (xy 357.100404 -215.104753) (xy 357.151332 -215.089041)
			(xy 357.204032 -215.081095) (xy 357.23068 -215.080596) (xy 357.255693 -215.081056) (xy 357.305229 -215.088037)
			(xy 357.353301 -215.10188) (xy 357.398964 -215.122312) (xy 357.44132 -215.148931) (xy 357.479535 -215.181213)
			(xy 357.512858 -215.218524) (xy 357.527098 -215.239092) (xy 357.874062 -215.239092) (xy 357.888292 -215.218516)
			(xy 357.921622 -215.181209) (xy 357.959841 -215.148928) (xy 358.002198 -215.122307) (xy 358.04786 -215.10187)
			(xy 358.095931 -215.088016) (xy 358.145466 -215.081019) (xy 358.17048 -215.080596) (xy 358.197132 -215.08106)
			(xy 358.249842 -215.089002) (xy 358.30078 -215.104711) (xy 358.348806 -215.127837) (xy 358.39285 -215.157864)
			(xy 358.431926 -215.194119) (xy 358.465162 -215.235793) (xy 358.491815 -215.281956) (xy 358.511291 -215.331576)
			(xy 358.523152 -215.383544) (xy 358.527136 -215.4367) (xy 358.523152 -215.489856) (xy 358.511291 -215.541824)
			(xy 358.491815 -215.591444) (xy 358.465162 -215.637607) (xy 358.431926 -215.679281) (xy 358.39285 -215.715536)
			(xy 358.348806 -215.745563) (xy 358.30078 -215.768689) (xy 358.249842 -215.784398) (xy 358.197132 -215.79234)
			(xy 358.17048 -215.792812) (xy 358.145466 -215.792379) (xy 358.095929 -215.785392) (xy 358.047857 -215.771545)
			(xy 358.002194 -215.751108) (xy 357.959839 -215.724486) (xy 357.921624 -215.6922) (xy 357.888301 -215.654885)
			(xy 357.874062 -215.634316) (xy 357.527098 -215.634316) (xy 357.512832 -215.654865) (xy 357.479507 -215.692173)
			(xy 357.441295 -215.724455) (xy 357.398944 -215.751079) (xy 357.353288 -215.771521) (xy 357.305223 -215.785381)
			(xy 357.255692 -215.792385) (xy 357.23068 -215.792812) (xy 357.204032 -215.792305) (xy 357.151332 -215.784359)
			(xy 357.100404 -215.768647) (xy 357.052387 -215.745521) (xy 357.008352 -215.715497) (xy 356.969285 -215.679245)
			(xy 356.936056 -215.637576) (xy 356.909409 -215.591419) (xy 356.889938 -215.541807) (xy 356.878079 -215.489847)
			(xy 356.874096 -215.4367) (xy 356.646988 -215.4367) (xy 356.646988 -215.436704) (xy 356.64649 -215.463353)
			(xy 356.638547 -215.516057) (xy 356.622837 -215.566987) (xy 356.599711 -215.615008) (xy 356.569687 -215.659045)
			(xy 356.533435 -215.698116) (xy 356.491764 -215.731347) (xy 356.445606 -215.757996) (xy 356.395992 -215.777468)
			(xy 356.34403 -215.789328) (xy 356.29088 -215.793312) (xy 356.23773 -215.789328) (xy 356.185768 -215.777468)
			(xy 356.136154 -215.757996) (xy 356.089996 -215.731347) (xy 356.048325 -215.698116) (xy 356.012073 -215.659045)
			(xy 355.982049 -215.615008) (xy 355.958923 -215.566987) (xy 355.943213 -215.516057) (xy 355.93527 -215.463353)
			(xy 355.934772 -215.436704) (xy 355.707188 -215.436704) (xy 355.70669 -215.463353) (xy 355.698747 -215.516057)
			(xy 355.683037 -215.566987) (xy 355.659911 -215.615008) (xy 355.629887 -215.659045) (xy 355.593635 -215.698116)
			(xy 355.551964 -215.731347) (xy 355.505806 -215.757996) (xy 355.456192 -215.777468) (xy 355.40423 -215.789328)
			(xy 355.35108 -215.793312) (xy 355.29793 -215.789328) (xy 355.245968 -215.777468) (xy 355.196354 -215.757996)
			(xy 355.150196 -215.731347) (xy 355.108525 -215.698116) (xy 355.072273 -215.659045) (xy 355.042249 -215.615008)
			(xy 355.019123 -215.566987) (xy 355.003413 -215.516057) (xy 354.99547 -215.463353) (xy 354.76689 -215.463353)
			(xy 354.758947 -215.516057) (xy 354.743237 -215.566987) (xy 354.720111 -215.615008) (xy 354.690087 -215.659045)
			(xy 354.653835 -215.698116) (xy 354.612164 -215.731347) (xy 354.566006 -215.757996) (xy 354.516392 -215.777468)
			(xy 354.46443 -215.789328) (xy 354.41128 -215.793312) (xy 354.35813 -215.789328) (xy 354.306168 -215.777468)
			(xy 354.256554 -215.757996) (xy 354.210396 -215.731347) (xy 354.168725 -215.698116) (xy 354.132473 -215.659045)
			(xy 354.102449 -215.615008) (xy 354.079323 -215.566987) (xy 354.063613 -215.516057) (xy 354.05567 -215.463353)
			(xy 354.055172 -215.436704) (xy 353.827588 -215.436704) (xy 353.82709 -215.463353) (xy 353.819147 -215.516057)
			(xy 353.803437 -215.566987) (xy 353.780311 -215.615008) (xy 353.750287 -215.659045) (xy 353.714035 -215.698116)
			(xy 353.672364 -215.731347) (xy 353.626206 -215.757996) (xy 353.576592 -215.777468) (xy 353.52463 -215.789328)
			(xy 353.47148 -215.793312) (xy 353.41833 -215.789328) (xy 353.366368 -215.777468) (xy 353.316754 -215.757996)
			(xy 353.270596 -215.731347) (xy 353.228925 -215.698116) (xy 353.192673 -215.659045) (xy 353.162649 -215.615008)
			(xy 353.139523 -215.566987) (xy 353.123813 -215.516057) (xy 353.11587 -215.463353) (xy 352.887292 -215.463353)
			(xy 352.887267 -215.464689) (xy 352.878511 -215.519968) (xy 352.861214 -215.573198) (xy 352.835804 -215.623066)
			(xy 352.802904 -215.668345) (xy 352.763327 -215.70792) (xy 352.718046 -215.740816) (xy 352.668176 -215.766223)
			(xy 352.614945 -215.783516) (xy 352.559665 -215.792269) (xy 352.53168 -215.792812) (xy 352.506639 -215.792386)
			(xy 352.457052 -215.785372) (xy 352.432874 -215.778842) (xy 352.419829 -215.775508) (xy 352.392915 -215.775063)
			(xy 352.366821 -215.781666) (xy 352.343358 -215.794858) (xy 352.324157 -215.813721) (xy 352.310552 -215.836947)
			(xy 352.303488 -215.86292) (xy 352.30308 -215.876378) (xy 352.30308 -215.988392) (xy 352.322473 -216.006887)
			(xy 352.356034 -216.048665) (xy 352.382957 -216.095) (xy 352.402633 -216.144845) (xy 352.414618 -216.197076)
			(xy 352.418642 -216.250514) (xy 352.416633 -216.277169) (xy 352.646224 -216.277169) (xy 352.646224 -216.223871)
			(xy 352.654167 -216.171167) (xy 352.669877 -216.120237) (xy 352.693003 -216.072216) (xy 352.723027 -216.028179)
			(xy 352.759279 -215.989108) (xy 352.80095 -215.955877) (xy 352.847108 -215.929228) (xy 352.896722 -215.909756)
			(xy 352.948684 -215.897896) (xy 353.001834 -215.893913) (xy 353.054984 -215.897896) (xy 353.106946 -215.909756)
			(xy 353.15656 -215.929228) (xy 353.202718 -215.955877) (xy 353.244389 -215.989108) (xy 353.280641 -216.028179)
			(xy 353.310665 -216.072216) (xy 353.333791 -216.120237) (xy 353.349501 -216.171167) (xy 353.357444 -216.223871)
			(xy 353.357942 -216.25052) (xy 353.357444 -216.277169) (xy 353.586024 -216.277169) (xy 353.586024 -216.223871)
			(xy 353.593967 -216.171167) (xy 353.609677 -216.120237) (xy 353.632803 -216.072216) (xy 353.662827 -216.028179)
			(xy 353.699079 -215.989108) (xy 353.74075 -215.955877) (xy 353.786908 -215.929228) (xy 353.836522 -215.909756)
			(xy 353.888484 -215.897896) (xy 353.941634 -215.893913) (xy 353.994784 -215.897896) (xy 354.046746 -215.909756)
			(xy 354.09636 -215.929228) (xy 354.142518 -215.955877) (xy 354.184189 -215.989108) (xy 354.220441 -216.028179)
			(xy 354.250465 -216.072216) (xy 354.273591 -216.120237) (xy 354.289301 -216.171167) (xy 354.297244 -216.223871)
			(xy 354.297742 -216.25052) (xy 354.297244 -216.277169) (xy 354.525824 -216.277169) (xy 354.525824 -216.223871)
			(xy 354.533767 -216.171167) (xy 354.549477 -216.120237) (xy 354.572603 -216.072216) (xy 354.602627 -216.028179)
			(xy 354.638879 -215.989108) (xy 354.68055 -215.955877) (xy 354.726708 -215.929228) (xy 354.776322 -215.909756)
			(xy 354.828284 -215.897896) (xy 354.881434 -215.893913) (xy 354.934584 -215.897896) (xy 354.986546 -215.909756)
			(xy 355.03616 -215.929228) (xy 355.082318 -215.955877) (xy 355.123989 -215.989108) (xy 355.160241 -216.028179)
			(xy 355.190265 -216.072216) (xy 355.213391 -216.120237) (xy 355.229101 -216.171167) (xy 355.237044 -216.223871)
			(xy 355.237542 -216.25052) (xy 355.237044 -216.277169) (xy 355.465624 -216.277169) (xy 355.465624 -216.223871)
			(xy 355.473567 -216.171167) (xy 355.489277 -216.120237) (xy 355.512403 -216.072216) (xy 355.542427 -216.028179)
			(xy 355.578679 -215.989108) (xy 355.62035 -215.955877) (xy 355.666508 -215.929228) (xy 355.716122 -215.909756)
			(xy 355.768084 -215.897896) (xy 355.821234 -215.893913) (xy 355.874384 -215.897896) (xy 355.926346 -215.909756)
			(xy 355.97596 -215.929228) (xy 356.022118 -215.955877) (xy 356.063789 -215.989108) (xy 356.100041 -216.028179)
			(xy 356.130065 -216.072216) (xy 356.153191 -216.120237) (xy 356.168901 -216.171167) (xy 356.176844 -216.223871)
			(xy 356.177342 -216.25052) (xy 356.176844 -216.277169) (xy 356.405424 -216.277169) (xy 356.405424 -216.223871)
			(xy 356.413367 -216.171167) (xy 356.429077 -216.120237) (xy 356.452203 -216.072216) (xy 356.482227 -216.028179)
			(xy 356.518479 -215.989108) (xy 356.56015 -215.955877) (xy 356.606308 -215.929228) (xy 356.655922 -215.909756)
			(xy 356.707884 -215.897896) (xy 356.761034 -215.893913) (xy 356.814184 -215.897896) (xy 356.866146 -215.909756)
			(xy 356.91576 -215.929228) (xy 356.961918 -215.955877) (xy 357.003589 -215.989108) (xy 357.039841 -216.028179)
			(xy 357.069865 -216.072216) (xy 357.092991 -216.120237) (xy 357.108701 -216.171167) (xy 357.116644 -216.223871)
			(xy 357.117142 -216.25052) (xy 357.116644 -216.277169) (xy 357.345224 -216.277169) (xy 357.345224 -216.223871)
			(xy 357.353167 -216.171167) (xy 357.368877 -216.120237) (xy 357.392003 -216.072216) (xy 357.422027 -216.028179)
			(xy 357.458279 -215.989108) (xy 357.49995 -215.955877) (xy 357.546108 -215.929228) (xy 357.595722 -215.909756)
			(xy 357.647684 -215.897896) (xy 357.700834 -215.893913) (xy 357.753984 -215.897896) (xy 357.805946 -215.909756)
			(xy 357.85556 -215.929228) (xy 357.901718 -215.955877) (xy 357.943389 -215.989108) (xy 357.979641 -216.028179)
			(xy 358.009665 -216.072216) (xy 358.032791 -216.120237) (xy 358.048501 -216.171167) (xy 358.056444 -216.223871)
			(xy 358.056942 -216.25052) (xy 358.056444 -216.277169) (xy 358.285024 -216.277169) (xy 358.285024 -216.223871)
			(xy 358.292967 -216.171167) (xy 358.308677 -216.120237) (xy 358.331803 -216.072216) (xy 358.361827 -216.028179)
			(xy 358.398079 -215.989108) (xy 358.43975 -215.955877) (xy 358.485908 -215.929228) (xy 358.535522 -215.909756)
			(xy 358.587484 -215.897896) (xy 358.640634 -215.893913) (xy 358.693784 -215.897896) (xy 358.745746 -215.909756)
			(xy 358.79536 -215.929228) (xy 358.841518 -215.955877) (xy 358.883189 -215.989108) (xy 358.919441 -216.028179)
			(xy 358.949465 -216.072216) (xy 358.972591 -216.120237) (xy 358.988301 -216.171167) (xy 358.996244 -216.223871)
			(xy 358.996742 -216.25052) (xy 358.996244 -216.277169) (xy 358.988301 -216.329873) (xy 358.972591 -216.380803)
			(xy 358.949465 -216.428824) (xy 358.919441 -216.472861) (xy 358.883189 -216.511932) (xy 358.841518 -216.545163)
			(xy 358.79536 -216.571812) (xy 358.745746 -216.591284) (xy 358.693784 -216.603144) (xy 358.640634 -216.607128)
			(xy 358.587484 -216.603144) (xy 358.535522 -216.591284) (xy 358.485908 -216.571812) (xy 358.43975 -216.545163)
			(xy 358.398079 -216.511932) (xy 358.361827 -216.472861) (xy 358.331803 -216.428824) (xy 358.308677 -216.380803)
			(xy 358.292967 -216.329873) (xy 358.285024 -216.277169) (xy 358.056444 -216.277169) (xy 358.048501 -216.329873)
			(xy 358.032791 -216.380803) (xy 358.009665 -216.428824) (xy 357.979641 -216.472861) (xy 357.943389 -216.511932)
			(xy 357.901718 -216.545163) (xy 357.85556 -216.571812) (xy 357.805946 -216.591284) (xy 357.753984 -216.603144)
			(xy 357.700834 -216.607128) (xy 357.647684 -216.603144) (xy 357.595722 -216.591284) (xy 357.546108 -216.571812)
			(xy 357.49995 -216.545163) (xy 357.458279 -216.511932) (xy 357.422027 -216.472861) (xy 357.392003 -216.428824)
			(xy 357.368877 -216.380803) (xy 357.353167 -216.329873) (xy 357.345224 -216.277169) (xy 357.116644 -216.277169)
			(xy 357.108701 -216.329873) (xy 357.092991 -216.380803) (xy 357.069865 -216.428824) (xy 357.039841 -216.472861)
			(xy 357.003589 -216.511932) (xy 356.961918 -216.545163) (xy 356.91576 -216.571812) (xy 356.866146 -216.591284)
			(xy 356.814184 -216.603144) (xy 356.761034 -216.607128) (xy 356.707884 -216.603144) (xy 356.655922 -216.591284)
			(xy 356.606308 -216.571812) (xy 356.56015 -216.545163) (xy 356.518479 -216.511932) (xy 356.482227 -216.472861)
			(xy 356.452203 -216.428824) (xy 356.429077 -216.380803) (xy 356.413367 -216.329873) (xy 356.405424 -216.277169)
			(xy 356.176844 -216.277169) (xy 356.168901 -216.329873) (xy 356.153191 -216.380803) (xy 356.130065 -216.428824)
			(xy 356.100041 -216.472861) (xy 356.063789 -216.511932) (xy 356.022118 -216.545163) (xy 355.97596 -216.571812)
			(xy 355.926346 -216.591284) (xy 355.874384 -216.603144) (xy 355.821234 -216.607128) (xy 355.768084 -216.603144)
			(xy 355.716122 -216.591284) (xy 355.666508 -216.571812) (xy 355.62035 -216.545163) (xy 355.578679 -216.511932)
			(xy 355.542427 -216.472861) (xy 355.512403 -216.428824) (xy 355.489277 -216.380803) (xy 355.473567 -216.329873)
			(xy 355.465624 -216.277169) (xy 355.237044 -216.277169) (xy 355.229101 -216.329873) (xy 355.213391 -216.380803)
			(xy 355.190265 -216.428824) (xy 355.160241 -216.472861) (xy 355.123989 -216.511932) (xy 355.082318 -216.545163)
			(xy 355.03616 -216.571812) (xy 354.986546 -216.591284) (xy 354.934584 -216.603144) (xy 354.881434 -216.607128)
			(xy 354.828284 -216.603144) (xy 354.776322 -216.591284) (xy 354.726708 -216.571812) (xy 354.68055 -216.545163)
			(xy 354.638879 -216.511932) (xy 354.602627 -216.472861) (xy 354.572603 -216.428824) (xy 354.549477 -216.380803)
			(xy 354.533767 -216.329873) (xy 354.525824 -216.277169) (xy 354.297244 -216.277169) (xy 354.289301 -216.329873)
			(xy 354.273591 -216.380803) (xy 354.250465 -216.428824) (xy 354.220441 -216.472861) (xy 354.184189 -216.511932)
			(xy 354.142518 -216.545163) (xy 354.09636 -216.571812) (xy 354.046746 -216.591284) (xy 353.994784 -216.603144)
			(xy 353.941634 -216.607128) (xy 353.888484 -216.603144) (xy 353.836522 -216.591284) (xy 353.786908 -216.571812)
			(xy 353.74075 -216.545163) (xy 353.699079 -216.511932) (xy 353.662827 -216.472861) (xy 353.632803 -216.428824)
			(xy 353.609677 -216.380803) (xy 353.593967 -216.329873) (xy 353.586024 -216.277169) (xy 353.357444 -216.277169)
			(xy 353.349501 -216.329873) (xy 353.333791 -216.380803) (xy 353.310665 -216.428824) (xy 353.280641 -216.472861)
			(xy 353.244389 -216.511932) (xy 353.202718 -216.545163) (xy 353.15656 -216.571812) (xy 353.106946 -216.591284)
			(xy 353.054984 -216.603144) (xy 353.001834 -216.607128) (xy 352.948684 -216.603144) (xy 352.896722 -216.591284)
			(xy 352.847108 -216.571812) (xy 352.80095 -216.545163) (xy 352.759279 -216.511932) (xy 352.723027 -216.472861)
			(xy 352.693003 -216.428824) (xy 352.669877 -216.380803) (xy 352.654167 -216.329873) (xy 352.646224 -216.277169)
			(xy 352.416633 -216.277169) (xy 352.414614 -216.30395) (xy 352.402625 -216.356181) (xy 352.382945 -216.406025)
			(xy 352.356019 -216.452358) (xy 352.322455 -216.494133) (xy 352.30308 -216.512648) (xy 352.30308 -216.624662)
			(xy 352.30349 -216.638126) (xy 352.310527 -216.664118) (xy 352.324121 -216.687362) (xy 352.343324 -216.706239)
			(xy 352.366797 -216.719433) (xy 352.392905 -216.726024) (xy 352.419829 -216.725554) (xy 352.432874 -216.722198)
			(xy 352.457112 -216.715641) (xy 352.506829 -216.708623) (xy 352.531934 -216.708228) (xy 352.558579 -216.708728)
			(xy 352.611273 -216.716675) (xy 352.662194 -216.732387) (xy 352.710205 -216.755512) (xy 352.754234 -216.785534)
			(xy 352.793296 -216.821782) (xy 352.82652 -216.863447) (xy 352.853164 -216.909598) (xy 352.872631 -216.959205)
			(xy 352.884489 -217.011159) (xy 352.888471 -217.0643) (xy 352.884489 -217.117441) (xy 352.872631 -217.169395)
			(xy 352.853164 -217.219002) (xy 352.82652 -217.265153) (xy 352.793296 -217.306818) (xy 352.754234 -217.343066)
			(xy 352.710205 -217.373088) (xy 352.662194 -217.396213) (xy 352.611273 -217.411925) (xy 352.558579 -217.419872)
			(xy 352.531934 -217.420444) (xy 352.506829 -217.420033) (xy 352.457112 -217.413025) (xy 352.432874 -217.406474)
			(xy 352.41983 -217.40314) (xy 352.392919 -217.402694) (xy 352.366827 -217.409297) (xy 352.343368 -217.42249)
			(xy 352.324171 -217.441354) (xy 352.310572 -217.46458) (xy 352.303515 -217.490553) (xy 352.30308 -217.50401)
			(xy 352.30308 -217.616278) (xy 352.320878 -217.633207) (xy 352.352119 -217.671111) (xy 352.377854 -217.71295)
			(xy 352.397595 -217.757928) (xy 352.410967 -217.805192) (xy 352.417717 -217.853846) (xy 352.418142 -217.878406)
			(xy 352.645726 -217.878406) (xy 352.646175 -217.852778) (xy 352.653509 -217.802049) (xy 352.668042 -217.752897)
			(xy 352.689472 -217.706336) (xy 352.717357 -217.663329) (xy 352.75112 -217.624765) (xy 352.790064 -217.59144)
			(xy 352.833384 -217.564044) (xy 352.880185 -217.543143) (xy 352.929499 -217.529168) (xy 352.954844 -217.525346)
			(xy 352.979482 -217.522044) (xy 353.151948 -217.22334) (xy 353.142296 -217.200226) (xy 353.133789 -217.178591)
			(xy 353.121799 -217.133674) (xy 353.11575 -217.087581) (xy 353.115372 -217.064336) (xy 353.11587 -217.037687)
			(xy 353.123813 -216.984983) (xy 353.139523 -216.934053) (xy 353.162649 -216.886032) (xy 353.192673 -216.841995)
			(xy 353.228925 -216.802924) (xy 353.270596 -216.769693) (xy 353.316754 -216.743044) (xy 353.366368 -216.723572)
			(xy 353.41833 -216.711712) (xy 353.47148 -216.707729) (xy 353.52463 -216.711712) (xy 353.576592 -216.723572)
			(xy 353.626206 -216.743044) (xy 353.672364 -216.769693) (xy 353.714035 -216.802924) (xy 353.750287 -216.841995)
			(xy 353.780311 -216.886032) (xy 353.803437 -216.934053) (xy 353.819147 -216.984983) (xy 353.82709 -217.037687)
			(xy 353.827588 -217.064336) (xy 353.827074 -217.089962) (xy 353.826926 -217.090985) (xy 354.055924 -217.090985)
			(xy 354.055924 -217.037687) (xy 354.063867 -216.984983) (xy 354.079577 -216.934053) (xy 354.102703 -216.886032)
			(xy 354.132727 -216.841995) (xy 354.168979 -216.802924) (xy 354.21065 -216.769693) (xy 354.256808 -216.743044)
			(xy 354.306422 -216.723572) (xy 354.358384 -216.711712) (xy 354.411534 -216.707729) (xy 354.464684 -216.711712)
			(xy 354.516646 -216.723572) (xy 354.56626 -216.743044) (xy 354.612418 -216.769693) (xy 354.654089 -216.802924)
			(xy 354.690341 -216.841995) (xy 354.720365 -216.886032) (xy 354.743491 -216.934053) (xy 354.759201 -216.984983)
			(xy 354.767144 -217.037687) (xy 354.767642 -217.064336) (xy 354.767144 -217.090985) (xy 354.759201 -217.143689)
			(xy 354.743491 -217.194619) (xy 354.720365 -217.24264) (xy 354.690341 -217.286677) (xy 354.654089 -217.325748)
			(xy 354.612418 -217.358979) (xy 354.56626 -217.385628) (xy 354.516646 -217.4051) (xy 354.464684 -217.41696)
			(xy 354.411534 -217.420944) (xy 354.358384 -217.41696) (xy 354.306422 -217.4051) (xy 354.256808 -217.385628)
			(xy 354.21065 -217.358979) (xy 354.168979 -217.325748) (xy 354.132727 -217.286677) (xy 354.102703 -217.24264)
			(xy 354.079577 -217.194619) (xy 354.063867 -217.143689) (xy 354.055924 -217.090985) (xy 353.826926 -217.090985)
			(xy 353.819748 -217.140687) (xy 353.805223 -217.189838) (xy 353.783801 -217.236398) (xy 353.755924 -217.279404)
			(xy 353.722168 -217.317969) (xy 353.68323 -217.351295) (xy 353.639917 -217.378692) (xy 353.593122 -217.399596)
			(xy 353.543813 -217.413573) (xy 353.51847 -217.417396) (xy 353.493832 -217.420698) (xy 353.321366 -217.719402)
			(xy 353.331018 -217.742516) (xy 353.339538 -217.764146) (xy 353.351523 -217.809065) (xy 353.357567 -217.855161)
			(xy 353.357942 -217.878406) (xy 353.585526 -217.878406) (xy 353.586024 -217.851757) (xy 353.593967 -217.799053)
			(xy 353.609677 -217.748123) (xy 353.632803 -217.700102) (xy 353.662827 -217.656065) (xy 353.699079 -217.616994)
			(xy 353.74075 -217.583763) (xy 353.786908 -217.557114) (xy 353.836522 -217.537642) (xy 353.888484 -217.525782)
			(xy 353.941634 -217.521799) (xy 353.994784 -217.525782) (xy 354.046746 -217.537642) (xy 354.09636 -217.557114)
			(xy 354.142518 -217.583763) (xy 354.184189 -217.616994) (xy 354.220441 -217.656065) (xy 354.250465 -217.700102)
			(xy 354.273591 -217.748123) (xy 354.289301 -217.799053) (xy 354.297244 -217.851757) (xy 354.297742 -217.878406)
			(xy 354.525326 -217.878406) (xy 354.525775 -217.852778) (xy 354.533109 -217.802049) (xy 354.547642 -217.752897)
			(xy 354.569072 -217.706336) (xy 354.596957 -217.663329) (xy 354.63072 -217.624765) (xy 354.669664 -217.59144)
			(xy 354.712984 -217.564044) (xy 354.759785 -217.543143) (xy 354.809099 -217.529168) (xy 354.834444 -217.525346)
			(xy 354.859082 -217.522044) (xy 355.031548 -217.22334) (xy 355.021896 -217.200226) (xy 355.013389 -217.178591)
			(xy 355.001399 -217.133674) (xy 354.99535 -217.087581) (xy 354.994972 -217.064336) (xy 354.99547 -217.037687)
			(xy 355.003413 -216.984983) (xy 355.019123 -216.934053) (xy 355.042249 -216.886032) (xy 355.072273 -216.841995)
			(xy 355.108525 -216.802924) (xy 355.150196 -216.769693) (xy 355.196354 -216.743044) (xy 355.245968 -216.723572)
			(xy 355.29793 -216.711712) (xy 355.35108 -216.707729) (xy 355.40423 -216.711712) (xy 355.456192 -216.723572)
			(xy 355.505806 -216.743044) (xy 355.551964 -216.769693) (xy 355.593635 -216.802924) (xy 355.629887 -216.841995)
			(xy 355.659911 -216.886032) (xy 355.683037 -216.934053) (xy 355.698747 -216.984983) (xy 355.70669 -217.037687)
			(xy 355.707188 -217.064336) (xy 355.706674 -217.089962) (xy 355.706526 -217.090985) (xy 355.935524 -217.090985)
			(xy 355.935524 -217.037687) (xy 355.943467 -216.984983) (xy 355.959177 -216.934053) (xy 355.982303 -216.886032)
			(xy 356.012327 -216.841995) (xy 356.048579 -216.802924) (xy 356.09025 -216.769693) (xy 356.136408 -216.743044)
			(xy 356.186022 -216.723572) (xy 356.237984 -216.711712) (xy 356.291134 -216.707729) (xy 356.344284 -216.711712)
			(xy 356.396246 -216.723572) (xy 356.44586 -216.743044) (xy 356.492018 -216.769693) (xy 356.533689 -216.802924)
			(xy 356.569941 -216.841995) (xy 356.599965 -216.886032) (xy 356.623091 -216.934053) (xy 356.638801 -216.984983)
			(xy 356.646744 -217.037687) (xy 356.647242 -217.064336) (xy 356.646744 -217.090985) (xy 356.638801 -217.143689)
			(xy 356.623091 -217.194619) (xy 356.599965 -217.24264) (xy 356.569941 -217.286677) (xy 356.533689 -217.325748)
			(xy 356.492018 -217.358979) (xy 356.44586 -217.385628) (xy 356.396246 -217.4051) (xy 356.344284 -217.41696)
			(xy 356.291134 -217.420944) (xy 356.237984 -217.41696) (xy 356.186022 -217.4051) (xy 356.136408 -217.385628)
			(xy 356.09025 -217.358979) (xy 356.048579 -217.325748) (xy 356.012327 -217.286677) (xy 355.982303 -217.24264)
			(xy 355.959177 -217.194619) (xy 355.943467 -217.143689) (xy 355.935524 -217.090985) (xy 355.706526 -217.090985)
			(xy 355.699348 -217.140687) (xy 355.684823 -217.189838) (xy 355.663401 -217.236398) (xy 355.635524 -217.279404)
			(xy 355.601768 -217.317969) (xy 355.56283 -217.351295) (xy 355.519517 -217.378692) (xy 355.472722 -217.399596)
			(xy 355.423413 -217.413573) (xy 355.39807 -217.417396) (xy 355.373432 -217.420698) (xy 355.200966 -217.719402)
			(xy 355.210618 -217.742516) (xy 355.219138 -217.764146) (xy 355.231123 -217.809065) (xy 355.237167 -217.855161)
			(xy 355.237542 -217.878406) (xy 355.465126 -217.878406) (xy 355.465624 -217.851757) (xy 355.473567 -217.799053)
			(xy 355.489277 -217.748123) (xy 355.512403 -217.700102) (xy 355.542427 -217.656065) (xy 355.578679 -217.616994)
			(xy 355.62035 -217.583763) (xy 355.666508 -217.557114) (xy 355.716122 -217.537642) (xy 355.768084 -217.525782)
			(xy 355.821234 -217.521799) (xy 355.874384 -217.525782) (xy 355.926346 -217.537642) (xy 355.97596 -217.557114)
			(xy 356.022118 -217.583763) (xy 356.063789 -217.616994) (xy 356.100041 -217.656065) (xy 356.130065 -217.700102)
			(xy 356.153191 -217.748123) (xy 356.168901 -217.799053) (xy 356.176844 -217.851757) (xy 356.177342 -217.878406)
			(xy 356.404926 -217.878406) (xy 356.405375 -217.852778) (xy 356.412709 -217.802049) (xy 356.427242 -217.752897)
			(xy 356.448672 -217.706336) (xy 356.476557 -217.663329) (xy 356.51032 -217.624765) (xy 356.549264 -217.59144)
			(xy 356.592584 -217.564044) (xy 356.639385 -217.543143) (xy 356.688699 -217.529168) (xy 356.714044 -217.525346)
			(xy 356.738682 -217.522044) (xy 356.911148 -217.22334) (xy 356.901496 -217.200226) (xy 356.892989 -217.178591)
			(xy 356.880999 -217.133674) (xy 356.87495 -217.087581) (xy 356.874572 -217.064336) (xy 356.87507 -217.037687)
			(xy 356.883013 -216.984983) (xy 356.898723 -216.934053) (xy 356.921849 -216.886032) (xy 356.951873 -216.841995)
			(xy 356.988125 -216.802924) (xy 357.029796 -216.769693) (xy 357.075954 -216.743044) (xy 357.125568 -216.723572)
			(xy 357.17753 -216.711712) (xy 357.23068 -216.707729) (xy 357.28383 -216.711712) (xy 357.335792 -216.723572)
			(xy 357.385406 -216.743044) (xy 357.431564 -216.769693) (xy 357.473235 -216.802924) (xy 357.509487 -216.841995)
			(xy 357.539511 -216.886032) (xy 357.562637 -216.934053) (xy 357.578347 -216.984983) (xy 357.58629 -217.037687)
			(xy 357.586788 -217.064336) (xy 357.586274 -217.089962) (xy 357.586126 -217.090985) (xy 357.815124 -217.090985)
			(xy 357.815124 -217.037687) (xy 357.823067 -216.984983) (xy 357.838777 -216.934053) (xy 357.861903 -216.886032)
			(xy 357.891927 -216.841995) (xy 357.928179 -216.802924) (xy 357.96985 -216.769693) (xy 358.016008 -216.743044)
			(xy 358.065622 -216.723572) (xy 358.117584 -216.711712) (xy 358.170734 -216.707729) (xy 358.223884 -216.711712)
			(xy 358.275846 -216.723572) (xy 358.32546 -216.743044) (xy 358.371618 -216.769693) (xy 358.413289 -216.802924)
			(xy 358.449541 -216.841995) (xy 358.479565 -216.886032) (xy 358.502691 -216.934053) (xy 358.518401 -216.984983)
			(xy 358.526344 -217.037687) (xy 358.526842 -217.064336) (xy 358.526344 -217.090985) (xy 358.518401 -217.143689)
			(xy 358.502691 -217.194619) (xy 358.479565 -217.24264) (xy 358.449541 -217.286677) (xy 358.413289 -217.325748)
			(xy 358.371618 -217.358979) (xy 358.32546 -217.385628) (xy 358.275846 -217.4051) (xy 358.223884 -217.41696)
			(xy 358.170734 -217.420944) (xy 358.117584 -217.41696) (xy 358.065622 -217.4051) (xy 358.016008 -217.385628)
			(xy 357.96985 -217.358979) (xy 357.928179 -217.325748) (xy 357.891927 -217.286677) (xy 357.861903 -217.24264)
			(xy 357.838777 -217.194619) (xy 357.823067 -217.143689) (xy 357.815124 -217.090985) (xy 357.586126 -217.090985)
			(xy 357.578948 -217.140687) (xy 357.564423 -217.189838) (xy 357.543001 -217.236398) (xy 357.515124 -217.279404)
			(xy 357.481368 -217.317969) (xy 357.44243 -217.351295) (xy 357.399117 -217.378692) (xy 357.352322 -217.399596)
			(xy 357.303013 -217.413573) (xy 357.27767 -217.417396) (xy 357.253032 -217.420698) (xy 357.080566 -217.719402)
			(xy 357.090218 -217.742516) (xy 357.098738 -217.764146) (xy 357.110723 -217.809065) (xy 357.116767 -217.855161)
			(xy 357.117142 -217.878406) (xy 357.344726 -217.878406) (xy 357.345224 -217.851757) (xy 357.353167 -217.799053)
			(xy 357.368877 -217.748123) (xy 357.392003 -217.700102) (xy 357.422027 -217.656065) (xy 357.458279 -217.616994)
			(xy 357.49995 -217.583763) (xy 357.546108 -217.557114) (xy 357.595722 -217.537642) (xy 357.647684 -217.525782)
			(xy 357.700834 -217.521799) (xy 357.753984 -217.525782) (xy 357.805946 -217.537642) (xy 357.85556 -217.557114)
			(xy 357.901718 -217.583763) (xy 357.943389 -217.616994) (xy 357.979641 -217.656065) (xy 358.009665 -217.700102)
			(xy 358.032791 -217.748123) (xy 358.048501 -217.799053) (xy 358.056444 -217.851757) (xy 358.056942 -217.878406)
			(xy 358.05656 -217.901609) (xy 358.05051 -217.947619) (xy 358.038527 -217.992452) (xy 358.030018 -218.014042)
			(xy 358.02062 -218.037156) (xy 358.193086 -218.33586) (xy 358.217724 -218.339162) (xy 358.243061 -218.343019)
			(xy 358.292364 -218.357007) (xy 358.339154 -218.377915) (xy 358.382465 -218.405313) (xy 358.421402 -218.438634)
			(xy 358.455164 -218.477192) (xy 358.483051 -218.520189) (xy 358.50449 -218.566738) (xy 358.519036 -218.615879)
			(xy 358.526391 -218.666598) (xy 358.526842 -218.692222) (xy 358.526344 -218.718871) (xy 358.518401 -218.771575)
			(xy 358.502691 -218.822505) (xy 358.479565 -218.870526) (xy 358.449541 -218.914563) (xy 358.413289 -218.953634)
			(xy 358.371618 -218.986865) (xy 358.32546 -219.013514) (xy 358.275846 -219.032986) (xy 358.223884 -219.044846)
			(xy 358.170734 -219.04883) (xy 358.117584 -219.044846) (xy 358.065622 -219.032986) (xy 358.016008 -219.013514)
			(xy 357.96985 -218.986865) (xy 357.928179 -218.953634) (xy 357.891927 -218.914563) (xy 357.861903 -218.870526)
			(xy 357.838777 -218.822505) (xy 357.823067 -218.771575) (xy 357.815124 -218.718871) (xy 357.814626 -218.692222)
			(xy 357.815 -218.668977) (xy 357.821045 -218.622882) (xy 357.833033 -218.577964) (xy 357.84155 -218.556332)
			(xy 357.851202 -218.533218) (xy 357.678736 -218.234768) (xy 357.654098 -218.231466) (xy 357.628738 -218.227674)
			(xy 357.579397 -218.213716) (xy 357.532567 -218.192826) (xy 357.489218 -218.165437) (xy 357.450244 -218.132114)
			(xy 357.416451 -218.093547) (xy 357.388538 -218.050533) (xy 357.367082 -218.00396) (xy 357.352527 -217.954792)
			(xy 357.345173 -217.904045) (xy 357.344726 -217.878406) (xy 357.117142 -217.878406) (xy 357.116644 -217.905055)
			(xy 357.108701 -217.957759) (xy 357.092991 -218.008689) (xy 357.069865 -218.05671) (xy 357.039841 -218.100747)
			(xy 357.003589 -218.139818) (xy 356.961918 -218.173049) (xy 356.91576 -218.199698) (xy 356.866146 -218.21917)
			(xy 356.814184 -218.23103) (xy 356.761034 -218.235014) (xy 356.707884 -218.23103) (xy 356.655922 -218.21917)
			(xy 356.606308 -218.199698) (xy 356.56015 -218.173049) (xy 356.518479 -218.139818) (xy 356.482227 -218.100747)
			(xy 356.452203 -218.05671) (xy 356.429077 -218.008689) (xy 356.413367 -217.957759) (xy 356.405424 -217.905055)
			(xy 356.404926 -217.878406) (xy 356.177342 -217.878406) (xy 356.176972 -217.901651) (xy 356.170925 -217.947747)
			(xy 356.158935 -217.992664) (xy 356.150418 -218.014296) (xy 356.140766 -218.03741) (xy 356.313232 -218.33586)
			(xy 356.33787 -218.339162) (xy 356.363213 -218.342982) (xy 356.412516 -218.356977) (xy 356.459306 -218.377891)
			(xy 356.502616 -218.405294) (xy 356.541553 -218.438619) (xy 356.575313 -218.47718) (xy 356.603199 -218.52018)
			(xy 356.624637 -218.566732) (xy 356.639183 -218.615876) (xy 356.646537 -218.666597) (xy 356.646988 -218.692222)
			(xy 356.64649 -218.718871) (xy 356.87507 -218.718871) (xy 356.87507 -218.665573) (xy 356.883013 -218.612869)
			(xy 356.898723 -218.561939) (xy 356.921849 -218.513918) (xy 356.951873 -218.469881) (xy 356.988125 -218.43081)
			(xy 357.029796 -218.397579) (xy 357.075954 -218.37093) (xy 357.125568 -218.351458) (xy 357.17753 -218.339598)
			(xy 357.23068 -218.335615) (xy 357.28383 -218.339598) (xy 357.335792 -218.351458) (xy 357.385406 -218.37093)
			(xy 357.431564 -218.397579) (xy 357.473235 -218.43081) (xy 357.509487 -218.469881) (xy 357.539511 -218.513918)
			(xy 357.562637 -218.561939) (xy 357.578347 -218.612869) (xy 357.58629 -218.665573) (xy 357.586788 -218.692222)
			(xy 357.58629 -218.718871) (xy 357.578347 -218.771575) (xy 357.562637 -218.822505) (xy 357.539511 -218.870526)
			(xy 357.509487 -218.914563) (xy 357.473235 -218.953634) (xy 357.431564 -218.986865) (xy 357.385406 -219.013514)
			(xy 357.335792 -219.032986) (xy 357.28383 -219.044846) (xy 357.23068 -219.04883) (xy 357.17753 -219.044846)
			(xy 357.125568 -219.032986) (xy 357.075954 -219.013514) (xy 357.029796 -218.986865) (xy 356.988125 -218.953634)
			(xy 356.951873 -218.914563) (xy 356.921849 -218.870526) (xy 356.898723 -218.822505) (xy 356.883013 -218.771575)
			(xy 356.87507 -218.718871) (xy 356.64649 -218.718871) (xy 356.638547 -218.771575) (xy 356.622837 -218.822505)
			(xy 356.599711 -218.870526) (xy 356.569687 -218.914563) (xy 356.533435 -218.953634) (xy 356.491764 -218.986865)
			(xy 356.445606 -219.013514) (xy 356.395992 -219.032986) (xy 356.34403 -219.044846) (xy 356.29088 -219.04883)
			(xy 356.23773 -219.044846) (xy 356.185768 -219.032986) (xy 356.136154 -219.013514) (xy 356.089996 -218.986865)
			(xy 356.048325 -218.953634) (xy 356.012073 -218.914563) (xy 355.982049 -218.870526) (xy 355.958923 -218.822505)
			(xy 355.943213 -218.771575) (xy 355.93527 -218.718871) (xy 355.934772 -218.692222) (xy 355.93515 -218.668977)
			(xy 355.941193 -218.622882) (xy 355.95318 -218.577964) (xy 355.961696 -218.556332) (xy 355.971348 -218.533218)
			(xy 355.798882 -218.234768) (xy 355.774244 -218.231466) (xy 355.748891 -218.227704) (xy 355.699582 -218.213708)
			(xy 355.652788 -218.19279) (xy 355.609474 -218.165382) (xy 355.570536 -218.13205) (xy 355.536776 -218.093481)
			(xy 355.508891 -218.050473) (xy 355.487458 -218.003913) (xy 355.472918 -217.954762) (xy 355.465572 -217.904034)
			(xy 355.465126 -217.878406) (xy 355.237542 -217.878406) (xy 355.237044 -217.905055) (xy 355.229101 -217.957759)
			(xy 355.213391 -218.008689) (xy 355.190265 -218.05671) (xy 355.160241 -218.100747) (xy 355.123989 -218.139818)
			(xy 355.082318 -218.173049) (xy 355.03616 -218.199698) (xy 354.986546 -218.21917) (xy 354.934584 -218.23103)
			(xy 354.881434 -218.235014) (xy 354.828284 -218.23103) (xy 354.776322 -218.21917) (xy 354.726708 -218.199698)
			(xy 354.68055 -218.173049) (xy 354.638879 -218.139818) (xy 354.602627 -218.100747) (xy 354.572603 -218.05671)
			(xy 354.549477 -218.008689) (xy 354.533767 -217.957759) (xy 354.525824 -217.905055) (xy 354.525326 -217.878406)
			(xy 354.297742 -217.878406) (xy 354.297372 -217.901651) (xy 354.291325 -217.947747) (xy 354.279335 -217.992664)
			(xy 354.270818 -218.014296) (xy 354.261166 -218.03741) (xy 354.433632 -218.33586) (xy 354.45827 -218.339162)
			(xy 354.483613 -218.342982) (xy 354.532916 -218.356977) (xy 354.579706 -218.377891) (xy 354.623016 -218.405294)
			(xy 354.661953 -218.438619) (xy 354.695713 -218.47718) (xy 354.723599 -218.52018) (xy 354.745037 -218.566732)
			(xy 354.759583 -218.615876) (xy 354.766937 -218.666597) (xy 354.767388 -218.692222) (xy 354.76689 -218.718871)
			(xy 354.99547 -218.718871) (xy 354.99547 -218.665573) (xy 355.003413 -218.612869) (xy 355.019123 -218.561939)
			(xy 355.042249 -218.513918) (xy 355.072273 -218.469881) (xy 355.108525 -218.43081) (xy 355.150196 -218.397579)
			(xy 355.196354 -218.37093) (xy 355.245968 -218.351458) (xy 355.29793 -218.339598) (xy 355.35108 -218.335615)
			(xy 355.40423 -218.339598) (xy 355.456192 -218.351458) (xy 355.505806 -218.37093) (xy 355.551964 -218.397579)
			(xy 355.593635 -218.43081) (xy 355.629887 -218.469881) (xy 355.659911 -218.513918) (xy 355.683037 -218.561939)
			(xy 355.698747 -218.612869) (xy 355.70669 -218.665573) (xy 355.707188 -218.692222) (xy 355.70669 -218.718871)
			(xy 355.698747 -218.771575) (xy 355.683037 -218.822505) (xy 355.659911 -218.870526) (xy 355.629887 -218.914563)
			(xy 355.593635 -218.953634) (xy 355.551964 -218.986865) (xy 355.505806 -219.013514) (xy 355.456192 -219.032986)
			(xy 355.40423 -219.044846) (xy 355.35108 -219.04883) (xy 355.29793 -219.044846) (xy 355.245968 -219.032986)
			(xy 355.196354 -219.013514) (xy 355.150196 -218.986865) (xy 355.108525 -218.953634) (xy 355.072273 -218.914563)
			(xy 355.042249 -218.870526) (xy 355.019123 -218.822505) (xy 355.003413 -218.771575) (xy 354.99547 -218.718871)
			(xy 354.76689 -218.718871) (xy 354.758947 -218.771575) (xy 354.743237 -218.822505) (xy 354.720111 -218.870526)
			(xy 354.690087 -218.914563) (xy 354.653835 -218.953634) (xy 354.612164 -218.986865) (xy 354.566006 -219.013514)
			(xy 354.516392 -219.032986) (xy 354.46443 -219.044846) (xy 354.41128 -219.04883) (xy 354.35813 -219.044846)
			(xy 354.306168 -219.032986) (xy 354.256554 -219.013514) (xy 354.210396 -218.986865) (xy 354.168725 -218.953634)
			(xy 354.132473 -218.914563) (xy 354.102449 -218.870526) (xy 354.079323 -218.822505) (xy 354.063613 -218.771575)
			(xy 354.05567 -218.718871) (xy 354.055172 -218.692222) (xy 354.05555 -218.668977) (xy 354.061593 -218.622882)
			(xy 354.07358 -218.577964) (xy 354.082096 -218.556332) (xy 354.091748 -218.533218) (xy 353.919282 -218.234768)
			(xy 353.894644 -218.231466) (xy 353.869291 -218.227704) (xy 353.819982 -218.213708) (xy 353.773188 -218.19279)
			(xy 353.729874 -218.165382) (xy 353.690936 -218.13205) (xy 353.657176 -218.093481) (xy 353.629291 -218.050473)
			(xy 353.607858 -218.003913) (xy 353.593318 -217.954762) (xy 353.585972 -217.904034) (xy 353.585526 -217.878406)
			(xy 353.357942 -217.878406) (xy 353.357444 -217.905055) (xy 353.349501 -217.957759) (xy 353.333791 -218.008689)
			(xy 353.310665 -218.05671) (xy 353.280641 -218.100747) (xy 353.244389 -218.139818) (xy 353.202718 -218.173049)
			(xy 353.15656 -218.199698) (xy 353.106946 -218.21917) (xy 353.054984 -218.23103) (xy 353.001834 -218.235014)
			(xy 352.948684 -218.23103) (xy 352.896722 -218.21917) (xy 352.847108 -218.199698) (xy 352.80095 -218.173049)
			(xy 352.759279 -218.139818) (xy 352.723027 -218.100747) (xy 352.693003 -218.05671) (xy 352.669877 -218.008689)
			(xy 352.654167 -217.957759) (xy 352.646224 -217.905055) (xy 352.645726 -217.878406) (xy 352.418142 -217.878406)
			(xy 352.417766 -217.901651) (xy 352.411721 -217.947746) (xy 352.399735 -217.992664) (xy 352.391218 -218.014296)
			(xy 352.381566 -218.03741) (xy 352.554032 -218.33586) (xy 352.57867 -218.339162) (xy 352.604014 -218.342985)
			(xy 352.653326 -218.356961) (xy 352.700123 -218.377864) (xy 352.74344 -218.405261) (xy 352.782382 -218.438586)
			(xy 352.816142 -218.47715) (xy 352.844024 -218.520157) (xy 352.865451 -218.566717) (xy 352.87998 -218.615868)
			(xy 352.887312 -218.666595) (xy 352.887788 -218.692222) (xy 352.887263 -218.718871) (xy 353.11587 -218.718871)
			(xy 353.11587 -218.665573) (xy 353.123813 -218.612869) (xy 353.139523 -218.561939) (xy 353.162649 -218.513918)
			(xy 353.192673 -218.469881) (xy 353.228925 -218.43081) (xy 353.270596 -218.397579) (xy 353.316754 -218.37093)
			(xy 353.366368 -218.351458) (xy 353.41833 -218.339598) (xy 353.47148 -218.335615) (xy 353.52463 -218.339598)
			(xy 353.576592 -218.351458) (xy 353.626206 -218.37093) (xy 353.672364 -218.397579) (xy 353.714035 -218.43081)
			(xy 353.750287 -218.469881) (xy 353.780311 -218.513918) (xy 353.803437 -218.561939) (xy 353.819147 -218.612869)
			(xy 353.82709 -218.665573) (xy 353.827588 -218.692222) (xy 353.82709 -218.718871) (xy 353.819147 -218.771575)
			(xy 353.803437 -218.822505) (xy 353.780311 -218.870526) (xy 353.750287 -218.914563) (xy 353.714035 -218.953634)
			(xy 353.672364 -218.986865) (xy 353.626206 -219.013514) (xy 353.576592 -219.032986) (xy 353.52463 -219.044846)
			(xy 353.47148 -219.04883) (xy 353.41833 -219.044846) (xy 353.366368 -219.032986) (xy 353.316754 -219.013514)
			(xy 353.270596 -218.986865) (xy 353.228925 -218.953634) (xy 353.192673 -218.914563) (xy 353.162649 -218.870526)
			(xy 353.139523 -218.822505) (xy 353.123813 -218.771575) (xy 353.11587 -218.718871) (xy 352.887263 -218.718871)
			(xy 352.887237 -218.720203) (xy 352.878479 -218.775477) (xy 352.861183 -218.8287) (xy 352.835773 -218.878561)
			(xy 352.802876 -218.923834) (xy 352.763302 -218.963404) (xy 352.718025 -218.996295) (xy 352.668161 -219.021699)
			(xy 352.614936 -219.038989) (xy 352.559661 -219.047741) (xy 352.53168 -219.04833) (xy 352.506639 -219.047904)
			(xy 352.457052 -219.040891) (xy 352.432874 -219.03436) (xy 352.419829 -219.031026) (xy 352.392918 -219.030581)
			(xy 352.366825 -219.037184) (xy 352.343364 -219.050376) (xy 352.324165 -219.06924) (xy 352.310564 -219.092466)
			(xy 352.303504 -219.118439) (xy 352.30308 -219.131896) (xy 352.30308 -219.24391) (xy 352.320876 -219.260839)
			(xy 352.352114 -219.298745) (xy 352.377845 -219.340584) (xy 352.397582 -219.385562) (xy 352.41095 -219.432826)
			(xy 352.417696 -219.481479) (xy 352.418142 -219.506038) (xy 352.417604 -219.532687) (xy 352.646224 -219.532687)
			(xy 352.646224 -219.479389) (xy 352.654167 -219.426685) (xy 352.669877 -219.375755) (xy 352.693003 -219.327734)
			(xy 352.723027 -219.283697) (xy 352.759279 -219.244626) (xy 352.80095 -219.211395) (xy 352.847108 -219.184746)
			(xy 352.896722 -219.165274) (xy 352.948684 -219.153414) (xy 353.001834 -219.149431) (xy 353.054984 -219.153414)
			(xy 353.106946 -219.165274) (xy 353.15656 -219.184746) (xy 353.202718 -219.211395) (xy 353.244389 -219.244626)
			(xy 353.280641 -219.283697) (xy 353.310665 -219.327734) (xy 353.333791 -219.375755) (xy 353.349501 -219.426685)
			(xy 353.357444 -219.479389) (xy 353.357942 -219.506038) (xy 353.357444 -219.532687) (xy 353.586024 -219.532687)
			(xy 353.586024 -219.479389) (xy 353.593967 -219.426685) (xy 353.609677 -219.375755) (xy 353.632803 -219.327734)
			(xy 353.662827 -219.283697) (xy 353.699079 -219.244626) (xy 353.74075 -219.211395) (xy 353.786908 -219.184746)
			(xy 353.836522 -219.165274) (xy 353.888484 -219.153414) (xy 353.941634 -219.149431) (xy 353.994784 -219.153414)
			(xy 354.046746 -219.165274) (xy 354.09636 -219.184746) (xy 354.142518 -219.211395) (xy 354.184189 -219.244626)
			(xy 354.220441 -219.283697) (xy 354.250465 -219.327734) (xy 354.273591 -219.375755) (xy 354.289301 -219.426685)
			(xy 354.297244 -219.479389) (xy 354.297742 -219.506038) (xy 354.297244 -219.532687) (xy 354.525824 -219.532687)
			(xy 354.525824 -219.479389) (xy 354.533767 -219.426685) (xy 354.549477 -219.375755) (xy 354.572603 -219.327734)
			(xy 354.602627 -219.283697) (xy 354.638879 -219.244626) (xy 354.68055 -219.211395) (xy 354.726708 -219.184746)
			(xy 354.776322 -219.165274) (xy 354.828284 -219.153414) (xy 354.881434 -219.149431) (xy 354.934584 -219.153414)
			(xy 354.986546 -219.165274) (xy 355.03616 -219.184746) (xy 355.082318 -219.211395) (xy 355.123989 -219.244626)
			(xy 355.160241 -219.283697) (xy 355.190265 -219.327734) (xy 355.213391 -219.375755) (xy 355.229101 -219.426685)
			(xy 355.237044 -219.479389) (xy 355.237542 -219.506038) (xy 355.237044 -219.532687) (xy 355.465624 -219.532687)
			(xy 355.465624 -219.479389) (xy 355.473567 -219.426685) (xy 355.489277 -219.375755) (xy 355.512403 -219.327734)
			(xy 355.542427 -219.283697) (xy 355.578679 -219.244626) (xy 355.62035 -219.211395) (xy 355.666508 -219.184746)
			(xy 355.716122 -219.165274) (xy 355.768084 -219.153414) (xy 355.821234 -219.149431) (xy 355.874384 -219.153414)
			(xy 355.926346 -219.165274) (xy 355.97596 -219.184746) (xy 356.022118 -219.211395) (xy 356.063789 -219.244626)
			(xy 356.100041 -219.283697) (xy 356.130065 -219.327734) (xy 356.153191 -219.375755) (xy 356.168901 -219.426685)
			(xy 356.176844 -219.479389) (xy 356.177342 -219.506038) (xy 356.176844 -219.532687) (xy 356.405424 -219.532687)
			(xy 356.405424 -219.479389) (xy 356.413367 -219.426685) (xy 356.429077 -219.375755) (xy 356.452203 -219.327734)
			(xy 356.482227 -219.283697) (xy 356.518479 -219.244626) (xy 356.56015 -219.211395) (xy 356.606308 -219.184746)
			(xy 356.655922 -219.165274) (xy 356.707884 -219.153414) (xy 356.761034 -219.149431) (xy 356.814184 -219.153414)
			(xy 356.866146 -219.165274) (xy 356.91576 -219.184746) (xy 356.961918 -219.211395) (xy 357.003589 -219.244626)
			(xy 357.039841 -219.283697) (xy 357.069865 -219.327734) (xy 357.092991 -219.375755) (xy 357.108701 -219.426685)
			(xy 357.116644 -219.479389) (xy 357.117142 -219.506038) (xy 357.116644 -219.532687) (xy 357.345224 -219.532687)
			(xy 357.345224 -219.479389) (xy 357.353167 -219.426685) (xy 357.368877 -219.375755) (xy 357.392003 -219.327734)
			(xy 357.422027 -219.283697) (xy 357.458279 -219.244626) (xy 357.49995 -219.211395) (xy 357.546108 -219.184746)
			(xy 357.595722 -219.165274) (xy 357.647684 -219.153414) (xy 357.700834 -219.149431) (xy 357.753984 -219.153414)
			(xy 357.805946 -219.165274) (xy 357.85556 -219.184746) (xy 357.901718 -219.211395) (xy 357.943389 -219.244626)
			(xy 357.979641 -219.283697) (xy 358.009665 -219.327734) (xy 358.032791 -219.375755) (xy 358.048501 -219.426685)
			(xy 358.056444 -219.479389) (xy 358.056942 -219.506038) (xy 358.056444 -219.532687) (xy 358.285024 -219.532687)
			(xy 358.285024 -219.479389) (xy 358.292967 -219.426685) (xy 358.308677 -219.375755) (xy 358.331803 -219.327734)
			(xy 358.361827 -219.283697) (xy 358.398079 -219.244626) (xy 358.43975 -219.211395) (xy 358.485908 -219.184746)
			(xy 358.535522 -219.165274) (xy 358.587484 -219.153414) (xy 358.640634 -219.149431) (xy 358.693784 -219.153414)
			(xy 358.745746 -219.165274) (xy 358.79536 -219.184746) (xy 358.841518 -219.211395) (xy 358.883189 -219.244626)
			(xy 358.919441 -219.283697) (xy 358.949465 -219.327734) (xy 358.972591 -219.375755) (xy 358.988301 -219.426685)
			(xy 358.996244 -219.479389) (xy 358.996742 -219.506038) (xy 358.996244 -219.532687) (xy 358.988301 -219.585391)
			(xy 358.972591 -219.636321) (xy 358.949465 -219.684342) (xy 358.919441 -219.728379) (xy 358.883189 -219.76745)
			(xy 358.841518 -219.800681) (xy 358.79536 -219.82733) (xy 358.745746 -219.846802) (xy 358.693784 -219.858662)
			(xy 358.640634 -219.862646) (xy 358.587484 -219.858662) (xy 358.535522 -219.846802) (xy 358.485908 -219.82733)
			(xy 358.43975 -219.800681) (xy 358.398079 -219.76745) (xy 358.361827 -219.728379) (xy 358.331803 -219.684342)
			(xy 358.308677 -219.636321) (xy 358.292967 -219.585391) (xy 358.285024 -219.532687) (xy 358.056444 -219.532687)
			(xy 358.048501 -219.585391) (xy 358.032791 -219.636321) (xy 358.009665 -219.684342) (xy 357.979641 -219.728379)
			(xy 357.943389 -219.76745) (xy 357.901718 -219.800681) (xy 357.85556 -219.82733) (xy 357.805946 -219.846802)
			(xy 357.753984 -219.858662) (xy 357.700834 -219.862646) (xy 357.647684 -219.858662) (xy 357.595722 -219.846802)
			(xy 357.546108 -219.82733) (xy 357.49995 -219.800681) (xy 357.458279 -219.76745) (xy 357.422027 -219.728379)
			(xy 357.392003 -219.684342) (xy 357.368877 -219.636321) (xy 357.353167 -219.585391) (xy 357.345224 -219.532687)
			(xy 357.116644 -219.532687) (xy 357.108701 -219.585391) (xy 357.092991 -219.636321) (xy 357.069865 -219.684342)
			(xy 357.039841 -219.728379) (xy 357.003589 -219.76745) (xy 356.961918 -219.800681) (xy 356.91576 -219.82733)
			(xy 356.866146 -219.846802) (xy 356.814184 -219.858662) (xy 356.761034 -219.862646) (xy 356.707884 -219.858662)
			(xy 356.655922 -219.846802) (xy 356.606308 -219.82733) (xy 356.56015 -219.800681) (xy 356.518479 -219.76745)
			(xy 356.482227 -219.728379) (xy 356.452203 -219.684342) (xy 356.429077 -219.636321) (xy 356.413367 -219.585391)
			(xy 356.405424 -219.532687) (xy 356.176844 -219.532687) (xy 356.168901 -219.585391) (xy 356.153191 -219.636321)
			(xy 356.130065 -219.684342) (xy 356.100041 -219.728379) (xy 356.063789 -219.76745) (xy 356.022118 -219.800681)
			(xy 355.97596 -219.82733) (xy 355.926346 -219.846802) (xy 355.874384 -219.858662) (xy 355.821234 -219.862646)
			(xy 355.768084 -219.858662) (xy 355.716122 -219.846802) (xy 355.666508 -219.82733) (xy 355.62035 -219.800681)
			(xy 355.578679 -219.76745) (xy 355.542427 -219.728379) (xy 355.512403 -219.684342) (xy 355.489277 -219.636321)
			(xy 355.473567 -219.585391) (xy 355.465624 -219.532687) (xy 355.237044 -219.532687) (xy 355.229101 -219.585391)
			(xy 355.213391 -219.636321) (xy 355.190265 -219.684342) (xy 355.160241 -219.728379) (xy 355.123989 -219.76745)
			(xy 355.082318 -219.800681) (xy 355.03616 -219.82733) (xy 354.986546 -219.846802) (xy 354.934584 -219.858662)
			(xy 354.881434 -219.862646) (xy 354.828284 -219.858662) (xy 354.776322 -219.846802) (xy 354.726708 -219.82733)
			(xy 354.68055 -219.800681) (xy 354.638879 -219.76745) (xy 354.602627 -219.728379) (xy 354.572603 -219.684342)
			(xy 354.549477 -219.636321) (xy 354.533767 -219.585391) (xy 354.525824 -219.532687) (xy 354.297244 -219.532687)
			(xy 354.289301 -219.585391) (xy 354.273591 -219.636321) (xy 354.250465 -219.684342) (xy 354.220441 -219.728379)
			(xy 354.184189 -219.76745) (xy 354.142518 -219.800681) (xy 354.09636 -219.82733) (xy 354.046746 -219.846802)
			(xy 353.994784 -219.858662) (xy 353.941634 -219.862646) (xy 353.888484 -219.858662) (xy 353.836522 -219.846802)
			(xy 353.786908 -219.82733) (xy 353.74075 -219.800681) (xy 353.699079 -219.76745) (xy 353.662827 -219.728379)
			(xy 353.632803 -219.684342) (xy 353.609677 -219.636321) (xy 353.593967 -219.585391) (xy 353.586024 -219.532687)
			(xy 353.357444 -219.532687) (xy 353.349501 -219.585391) (xy 353.333791 -219.636321) (xy 353.310665 -219.684342)
			(xy 353.280641 -219.728379) (xy 353.244389 -219.76745) (xy 353.202718 -219.800681) (xy 353.15656 -219.82733)
			(xy 353.106946 -219.846802) (xy 353.054984 -219.858662) (xy 353.001834 -219.862646) (xy 352.948684 -219.858662)
			(xy 352.896722 -219.846802) (xy 352.847108 -219.82733) (xy 352.80095 -219.800681) (xy 352.759279 -219.76745)
			(xy 352.723027 -219.728379) (xy 352.693003 -219.684342) (xy 352.669877 -219.636321) (xy 352.654167 -219.585391)
			(xy 352.646224 -219.532687) (xy 352.417604 -219.532687) (xy 352.41755 -219.535369) (xy 352.40795 -219.593239)
			(xy 352.388998 -219.648755) (xy 352.361208 -219.700416) (xy 352.34372 -219.72397) (xy 352.372427 -219.761122)
			(xy 352.423266 -219.840063) (xy 352.46615 -219.923593) (xy 352.483928 -219.967048) (xy 352.495871 -219.965518)
			(xy 352.519894 -219.963864) (xy 352.531934 -219.963746) (xy 352.558585 -219.964246) (xy 352.611291 -219.972195)
			(xy 352.662224 -219.98791) (xy 352.710246 -220.01104) (xy 352.754285 -220.041069) (xy 352.793357 -220.077326)
			(xy 352.826588 -220.119001) (xy 352.853238 -220.165163) (xy 352.87271 -220.214781) (xy 352.88457 -220.266747)
			(xy 352.888551 -220.319854) (xy 353.115372 -220.319854) (xy 353.11587 -220.293205) (xy 353.123813 -220.240501)
			(xy 353.139523 -220.189571) (xy 353.162649 -220.14155) (xy 353.192673 -220.097513) (xy 353.228925 -220.058442)
			(xy 353.270596 -220.025211) (xy 353.316754 -219.998562) (xy 353.366368 -219.97909) (xy 353.41833 -219.96723)
			(xy 353.47148 -219.963247) (xy 353.52463 -219.96723) (xy 353.576592 -219.97909) (xy 353.626206 -219.998562)
			(xy 353.672364 -220.025211) (xy 353.714035 -220.058442) (xy 353.750287 -220.097513) (xy 353.780311 -220.14155)
			(xy 353.803437 -220.189571) (xy 353.819147 -220.240501) (xy 353.82709 -220.293205) (xy 353.827588 -220.319854)
			(xy 353.827193 -220.343057) (xy 353.82674 -220.346503) (xy 354.055924 -220.346503) (xy 354.055924 -220.293205)
			(xy 354.063867 -220.240501) (xy 354.079577 -220.189571) (xy 354.102703 -220.14155) (xy 354.132727 -220.097513)
			(xy 354.168979 -220.058442) (xy 354.21065 -220.025211) (xy 354.256808 -219.998562) (xy 354.306422 -219.97909)
			(xy 354.358384 -219.96723) (xy 354.411534 -219.963247) (xy 354.464684 -219.96723) (xy 354.516646 -219.97909)
			(xy 354.56626 -219.998562) (xy 354.612418 -220.025211) (xy 354.654089 -220.058442) (xy 354.690341 -220.097513)
			(xy 354.720365 -220.14155) (xy 354.743491 -220.189571) (xy 354.759201 -220.240501) (xy 354.767144 -220.293205)
			(xy 354.767642 -220.319854) (xy 354.994972 -220.319854) (xy 354.99547 -220.293205) (xy 355.003413 -220.240501)
			(xy 355.019123 -220.189571) (xy 355.042249 -220.14155) (xy 355.072273 -220.097513) (xy 355.108525 -220.058442)
			(xy 355.150196 -220.025211) (xy 355.196354 -219.998562) (xy 355.245968 -219.97909) (xy 355.29793 -219.96723)
			(xy 355.35108 -219.963247) (xy 355.40423 -219.96723) (xy 355.456192 -219.97909) (xy 355.505806 -219.998562)
			(xy 355.551964 -220.025211) (xy 355.593635 -220.058442) (xy 355.629887 -220.097513) (xy 355.659911 -220.14155)
			(xy 355.683037 -220.189571) (xy 355.698747 -220.240501) (xy 355.70669 -220.293205) (xy 355.707188 -220.319854)
			(xy 355.706793 -220.343057) (xy 355.70634 -220.346503) (xy 355.935524 -220.346503) (xy 355.935524 -220.293205)
			(xy 355.943467 -220.240501) (xy 355.959177 -220.189571) (xy 355.982303 -220.14155) (xy 356.012327 -220.097513)
			(xy 356.048579 -220.058442) (xy 356.09025 -220.025211) (xy 356.136408 -219.998562) (xy 356.186022 -219.97909)
			(xy 356.237984 -219.96723) (xy 356.291134 -219.963247) (xy 356.344284 -219.96723) (xy 356.396246 -219.97909)
			(xy 356.44586 -219.998562) (xy 356.492018 -220.025211) (xy 356.533689 -220.058442) (xy 356.569941 -220.097513)
			(xy 356.599965 -220.14155) (xy 356.623091 -220.189571) (xy 356.638801 -220.240501) (xy 356.646744 -220.293205)
			(xy 356.647242 -220.319854) (xy 356.874572 -220.319854) (xy 356.87507 -220.293205) (xy 356.883013 -220.240501)
			(xy 356.898723 -220.189571) (xy 356.921849 -220.14155) (xy 356.951873 -220.097513) (xy 356.988125 -220.058442)
			(xy 357.029796 -220.025211) (xy 357.075954 -219.998562) (xy 357.125568 -219.97909) (xy 357.17753 -219.96723)
			(xy 357.23068 -219.963247) (xy 357.28383 -219.96723) (xy 357.335792 -219.97909) (xy 357.385406 -219.998562)
			(xy 357.431564 -220.025211) (xy 357.473235 -220.058442) (xy 357.509487 -220.097513) (xy 357.539511 -220.14155)
			(xy 357.562637 -220.189571) (xy 357.578347 -220.240501) (xy 357.58629 -220.293205) (xy 357.586788 -220.319854)
			(xy 357.586393 -220.343057) (xy 357.58594 -220.346503) (xy 357.815124 -220.346503) (xy 357.815124 -220.293205)
			(xy 357.823067 -220.240501) (xy 357.838777 -220.189571) (xy 357.861903 -220.14155) (xy 357.891927 -220.097513)
			(xy 357.928179 -220.058442) (xy 357.96985 -220.025211) (xy 358.016008 -219.998562) (xy 358.065622 -219.97909)
			(xy 358.117584 -219.96723) (xy 358.170734 -219.963247) (xy 358.223884 -219.96723) (xy 358.275846 -219.97909)
			(xy 358.32546 -219.998562) (xy 358.371618 -220.025211) (xy 358.413289 -220.058442) (xy 358.449541 -220.097513)
			(xy 358.479565 -220.14155) (xy 358.502691 -220.189571) (xy 358.518401 -220.240501) (xy 358.526344 -220.293205)
			(xy 358.526842 -220.319854) (xy 358.526344 -220.346503) (xy 358.518401 -220.399207) (xy 358.502691 -220.450137)
			(xy 358.479565 -220.498158) (xy 358.449541 -220.542195) (xy 358.413289 -220.581266) (xy 358.371618 -220.614497)
			(xy 358.32546 -220.641146) (xy 358.275846 -220.660618) (xy 358.223884 -220.672478) (xy 358.170734 -220.676462)
			(xy 358.117584 -220.672478) (xy 358.065622 -220.660618) (xy 358.016008 -220.641146) (xy 357.96985 -220.614497)
			(xy 357.928179 -220.581266) (xy 357.891927 -220.542195) (xy 357.861903 -220.498158) (xy 357.838777 -220.450137)
			(xy 357.823067 -220.399207) (xy 357.815124 -220.346503) (xy 357.58594 -220.346503) (xy 357.580349 -220.389067)
			(xy 357.568371 -220.4339) (xy 357.559864 -220.45549) (xy 357.550466 -220.478604) (xy 357.723186 -220.777562)
			(xy 357.747824 -220.780864) (xy 357.773161 -220.784719) (xy 357.822465 -220.798707) (xy 357.869255 -220.819616)
			(xy 357.912565 -220.847014) (xy 357.951503 -220.880335) (xy 357.985264 -220.918892) (xy 358.013152 -220.96189)
			(xy 358.03459 -221.008439) (xy 358.049137 -221.057581) (xy 358.056491 -221.1083) (xy 358.056942 -221.133924)
			(xy 358.056444 -221.160573) (xy 358.048501 -221.213277) (xy 358.032791 -221.264207) (xy 358.009665 -221.312228)
			(xy 357.979641 -221.356265) (xy 357.943389 -221.395336) (xy 357.901718 -221.428567) (xy 357.85556 -221.455216)
			(xy 357.805946 -221.474688) (xy 357.753984 -221.486548) (xy 357.700834 -221.490532) (xy 357.647684 -221.486548)
			(xy 357.595722 -221.474688) (xy 357.546108 -221.455216) (xy 357.49995 -221.428567) (xy 357.458279 -221.395336)
			(xy 357.422027 -221.356265) (xy 357.392003 -221.312228) (xy 357.368877 -221.264207) (xy 357.353167 -221.213277)
			(xy 357.345224 -221.160573) (xy 357.344726 -221.133924) (xy 357.345101 -221.110679) (xy 357.351145 -221.064584)
			(xy 357.363133 -221.019666) (xy 357.37165 -220.998034) (xy 357.381302 -220.97492) (xy 357.208836 -220.676216)
			(xy 357.183944 -220.672914) (xy 357.158598 -220.669039) (xy 357.109261 -220.65509) (xy 357.062434 -220.634209)
			(xy 357.019086 -220.60683) (xy 356.980112 -220.573517) (xy 356.946318 -220.534959) (xy 356.918402 -220.491954)
			(xy 356.896943 -220.44539) (xy 356.882382 -220.39623) (xy 356.875022 -220.345489) (xy 356.874572 -220.319854)
			(xy 356.647242 -220.319854) (xy 356.646744 -220.346503) (xy 356.638801 -220.399207) (xy 356.623091 -220.450137)
			(xy 356.599965 -220.498158) (xy 356.569941 -220.542195) (xy 356.533689 -220.581266) (xy 356.492018 -220.614497)
			(xy 356.44586 -220.641146) (xy 356.396246 -220.660618) (xy 356.344284 -220.672478) (xy 356.291134 -220.676462)
			(xy 356.237984 -220.672478) (xy 356.186022 -220.660618) (xy 356.136408 -220.641146) (xy 356.09025 -220.614497)
			(xy 356.048579 -220.581266) (xy 356.012327 -220.542195) (xy 355.982303 -220.498158) (xy 355.959177 -220.450137)
			(xy 355.943467 -220.399207) (xy 355.935524 -220.346503) (xy 355.70634 -220.346503) (xy 355.700749 -220.389067)
			(xy 355.688771 -220.4339) (xy 355.680264 -220.45549) (xy 355.670866 -220.478604) (xy 355.843586 -220.777562)
			(xy 355.868224 -220.780864) (xy 355.893561 -220.784719) (xy 355.942865 -220.798707) (xy 355.989655 -220.819616)
			(xy 356.032965 -220.847014) (xy 356.071903 -220.880335) (xy 356.105664 -220.918892) (xy 356.133552 -220.96189)
			(xy 356.15499 -221.008439) (xy 356.169537 -221.057581) (xy 356.176891 -221.1083) (xy 356.177342 -221.133924)
			(xy 356.176844 -221.160573) (xy 356.168901 -221.213277) (xy 356.153191 -221.264207) (xy 356.130065 -221.312228)
			(xy 356.100041 -221.356265) (xy 356.063789 -221.395336) (xy 356.022118 -221.428567) (xy 355.97596 -221.455216)
			(xy 355.926346 -221.474688) (xy 355.874384 -221.486548) (xy 355.821234 -221.490532) (xy 355.768084 -221.486548)
			(xy 355.716122 -221.474688) (xy 355.666508 -221.455216) (xy 355.62035 -221.428567) (xy 355.578679 -221.395336)
			(xy 355.542427 -221.356265) (xy 355.512403 -221.312228) (xy 355.489277 -221.264207) (xy 355.473567 -221.213277)
			(xy 355.465624 -221.160573) (xy 355.465126 -221.133924) (xy 355.465501 -221.110679) (xy 355.471545 -221.064584)
			(xy 355.483533 -221.019666) (xy 355.49205 -220.998034) (xy 355.501702 -220.97492) (xy 355.329236 -220.676216)
			(xy 355.304344 -220.672914) (xy 355.278998 -220.669039) (xy 355.229661 -220.65509) (xy 355.182834 -220.634209)
			(xy 355.139486 -220.60683) (xy 355.100512 -220.573517) (xy 355.066718 -220.534959) (xy 355.038802 -220.491954)
			(xy 355.017343 -220.44539) (xy 355.002782 -220.39623) (xy 354.995422 -220.345489) (xy 354.994972 -220.319854)
			(xy 354.767642 -220.319854) (xy 354.767144 -220.346503) (xy 354.759201 -220.399207) (xy 354.743491 -220.450137)
			(xy 354.720365 -220.498158) (xy 354.690341 -220.542195) (xy 354.654089 -220.581266) (xy 354.612418 -220.614497)
			(xy 354.56626 -220.641146) (xy 354.516646 -220.660618) (xy 354.464684 -220.672478) (xy 354.411534 -220.676462)
			(xy 354.358384 -220.672478) (xy 354.306422 -220.660618) (xy 354.256808 -220.641146) (xy 354.21065 -220.614497)
			(xy 354.168979 -220.581266) (xy 354.132727 -220.542195) (xy 354.102703 -220.498158) (xy 354.079577 -220.450137)
			(xy 354.063867 -220.399207) (xy 354.055924 -220.346503) (xy 353.82674 -220.346503) (xy 353.821149 -220.389067)
			(xy 353.809171 -220.4339) (xy 353.800664 -220.45549) (xy 353.791266 -220.478604) (xy 353.963986 -220.777562)
			(xy 353.988624 -220.780864) (xy 354.013961 -220.784719) (xy 354.063265 -220.798707) (xy 354.110055 -220.819616)
			(xy 354.153365 -220.847014) (xy 354.192303 -220.880335) (xy 354.226064 -220.918892) (xy 354.253952 -220.96189)
			(xy 354.27539 -221.008439) (xy 354.289937 -221.057581) (xy 354.297291 -221.1083) (xy 354.297742 -221.133924)
			(xy 354.297244 -221.160573) (xy 354.289301 -221.213277) (xy 354.273591 -221.264207) (xy 354.250465 -221.312228)
			(xy 354.220441 -221.356265) (xy 354.184189 -221.395336) (xy 354.142518 -221.428567) (xy 354.09636 -221.455216)
			(xy 354.046746 -221.474688) (xy 353.994784 -221.486548) (xy 353.941634 -221.490532) (xy 353.888484 -221.486548)
			(xy 353.836522 -221.474688) (xy 353.786908 -221.455216) (xy 353.74075 -221.428567) (xy 353.699079 -221.395336)
			(xy 353.662827 -221.356265) (xy 353.632803 -221.312228) (xy 353.609677 -221.264207) (xy 353.593967 -221.213277)
			(xy 353.586024 -221.160573) (xy 353.585526 -221.133924) (xy 353.585901 -221.110679) (xy 353.591945 -221.064584)
			(xy 353.603933 -221.019666) (xy 353.61245 -220.998034) (xy 353.622102 -220.97492) (xy 353.449636 -220.676216)
			(xy 353.424744 -220.672914) (xy 353.399398 -220.669039) (xy 353.350061 -220.65509) (xy 353.303234 -220.634209)
			(xy 353.259886 -220.60683) (xy 353.220912 -220.573517) (xy 353.187118 -220.534959) (xy 353.159202 -220.491954)
			(xy 353.137743 -220.44539) (xy 353.123182 -220.39623) (xy 353.115822 -220.345489) (xy 353.115372 -220.319854)
			(xy 352.888551 -220.319854) (xy 352.888554 -220.3199) (xy 352.88457 -220.373053) (xy 352.87271 -220.425019)
			(xy 352.853238 -220.474637) (xy 352.826588 -220.520799) (xy 352.793357 -220.562474) (xy 352.754285 -220.598731)
			(xy 352.710246 -220.62876) (xy 352.662224 -220.65189) (xy 352.611291 -220.667605) (xy 352.558585 -220.675554)
			(xy 352.531934 -220.675962) (xy 352.519894 -220.675854) (xy 352.49587 -220.674199) (xy 352.483928 -220.67266)
			(xy 352.470674 -220.705297) (xy 352.440034 -220.768733) (xy 352.422714 -220.799406) (xy 352.350832 -220.923612)
			(xy 352.36658 -220.949266) (xy 352.378809 -220.970239) (xy 352.398098 -221.014791) (xy 352.411159 -221.06155)
			(xy 352.417748 -221.10965) (xy 352.418142 -221.133924) (xy 352.417729 -221.158484) (xy 352.410975 -221.207137)
			(xy 352.397599 -221.254401) (xy 352.377855 -221.299378) (xy 352.352117 -221.341215) (xy 352.320873 -221.379118)
			(xy 352.30308 -221.396052) (xy 352.30308 -221.508066) (xy 352.303491 -221.521529) (xy 352.310529 -221.54752)
			(xy 352.324122 -221.570764) (xy 352.343325 -221.58964) (xy 352.366798 -221.602833) (xy 352.392905 -221.609424)
			(xy 352.419828 -221.608954) (xy 352.432874 -221.605602) (xy 352.445638 -221.602036) (xy 352.471572 -221.596568)
			(xy 352.48469 -221.59468) (xy 352.509328 -221.591378) (xy 352.681794 -221.29242) (xy 352.672396 -221.269306)
			(xy 352.663955 -221.247745) (xy 352.652078 -221.20299) (xy 352.646088 -221.157076) (xy 352.645726 -221.133924)
			(xy 352.646224 -221.107275) (xy 352.654167 -221.054571) (xy 352.669877 -221.003641) (xy 352.693003 -220.95562)
			(xy 352.723027 -220.911583) (xy 352.759279 -220.872512) (xy 352.80095 -220.839281) (xy 352.847108 -220.812632)
			(xy 352.896722 -220.79316) (xy 352.948684 -220.7813) (xy 353.001834 -220.777317) (xy 353.054984 -220.7813)
			(xy 353.106946 -220.79316) (xy 353.15656 -220.812632) (xy 353.202718 -220.839281) (xy 353.244389 -220.872512)
			(xy 353.280641 -220.911583) (xy 353.310665 -220.95562) (xy 353.333791 -221.003641) (xy 353.349501 -221.054571)
			(xy 353.357444 -221.107275) (xy 353.357942 -221.133924) (xy 353.357493 -221.159574) (xy 353.350129 -221.210342)
			(xy 353.335558 -221.259528) (xy 353.31408 -221.306115) (xy 353.28614 -221.349138) (xy 353.252316 -221.387708)
			(xy 353.213309 -221.421025) (xy 353.169924 -221.448401) (xy 353.123061 -221.469269) (xy 353.073689 -221.483198)
			(xy 353.048316 -221.486984) (xy 353.023424 -221.490286) (xy 352.851212 -221.788736) (xy 352.860864 -221.81185)
			(xy 352.869379 -221.833482) (xy 352.881365 -221.8784) (xy 352.887407 -221.924495) (xy 352.887788 -221.94774)
			(xy 352.887262 -221.974389) (xy 353.11587 -221.974389) (xy 353.11587 -221.921091) (xy 353.123813 -221.868387)
			(xy 353.139523 -221.817457) (xy 353.162649 -221.769436) (xy 353.192673 -221.725399) (xy 353.228925 -221.686328)
			(xy 353.270596 -221.653097) (xy 353.316754 -221.626448) (xy 353.366368 -221.606976) (xy 353.41833 -221.595116)
			(xy 353.47148 -221.591133) (xy 353.52463 -221.595116) (xy 353.576592 -221.606976) (xy 353.626206 -221.626448)
			(xy 353.672364 -221.653097) (xy 353.714035 -221.686328) (xy 353.750287 -221.725399) (xy 353.780311 -221.769436)
			(xy 353.803437 -221.817457) (xy 353.819147 -221.868387) (xy 353.82709 -221.921091) (xy 353.827588 -221.94774)
			(xy 354.055172 -221.94774) (xy 354.055612 -221.922111) (xy 354.062943 -221.87138) (xy 354.077473 -221.822225)
			(xy 354.098903 -221.775662) (xy 354.126788 -221.732653) (xy 354.160553 -221.694088) (xy 354.1995 -221.660763)
			(xy 354.242823 -221.633369) (xy 354.289626 -221.61247) (xy 354.338943 -221.598499) (xy 354.36429 -221.59468)
			(xy 354.388928 -221.591378) (xy 354.561394 -221.29242) (xy 354.551996 -221.269306) (xy 354.543526 -221.247754)
			(xy 354.531643 -221.202998) (xy 354.525675 -221.157078) (xy 354.525326 -221.133924) (xy 354.525824 -221.107275)
			(xy 354.533767 -221.054571) (xy 354.549477 -221.003641) (xy 354.572603 -220.95562) (xy 354.602627 -220.911583)
			(xy 354.638879 -220.872512) (xy 354.68055 -220.839281) (xy 354.726708 -220.812632) (xy 354.776322 -220.79316)
			(xy 354.828284 -220.7813) (xy 354.881434 -220.777317) (xy 354.934584 -220.7813) (xy 354.986546 -220.79316)
			(xy 355.03616 -220.812632) (xy 355.082318 -220.839281) (xy 355.123989 -220.872512) (xy 355.160241 -220.911583)
			(xy 355.190265 -220.95562) (xy 355.213391 -221.003641) (xy 355.229101 -221.054571) (xy 355.237044 -221.107275)
			(xy 355.237542 -221.133924) (xy 355.237086 -221.159573) (xy 355.229722 -221.21034) (xy 355.215151 -221.259526)
			(xy 355.193674 -221.306112) (xy 355.165734 -221.349134) (xy 355.131911 -221.387703) (xy 355.092904 -221.421019)
			(xy 355.049521 -221.448395) (xy 355.002659 -221.469263) (xy 354.953287 -221.483191) (xy 354.927916 -221.486984)
			(xy 354.903024 -221.490286) (xy 354.730812 -221.788736) (xy 354.740464 -221.81185) (xy 354.748992 -221.833478)
			(xy 354.760975 -221.878398) (xy 354.767015 -221.924495) (xy 354.767388 -221.94774) (xy 354.76689 -221.974389)
			(xy 354.99547 -221.974389) (xy 354.99547 -221.921091) (xy 355.003413 -221.868387) (xy 355.019123 -221.817457)
			(xy 355.042249 -221.769436) (xy 355.072273 -221.725399) (xy 355.108525 -221.686328) (xy 355.150196 -221.653097)
			(xy 355.196354 -221.626448) (xy 355.245968 -221.606976) (xy 355.29793 -221.595116) (xy 355.35108 -221.591133)
			(xy 355.40423 -221.595116) (xy 355.456192 -221.606976) (xy 355.505806 -221.626448) (xy 355.551964 -221.653097)
			(xy 355.593635 -221.686328) (xy 355.629887 -221.725399) (xy 355.659911 -221.769436) (xy 355.683037 -221.817457)
			(xy 355.698747 -221.868387) (xy 355.70669 -221.921091) (xy 355.707188 -221.94774) (xy 355.934772 -221.94774)
			(xy 355.935212 -221.922111) (xy 355.942543 -221.87138) (xy 355.957073 -221.822225) (xy 355.978503 -221.775662)
			(xy 356.006388 -221.732653) (xy 356.040153 -221.694088) (xy 356.0791 -221.660763) (xy 356.122423 -221.633369)
			(xy 356.169226 -221.61247) (xy 356.218543 -221.598499) (xy 356.24389 -221.59468) (xy 356.268528 -221.591378)
			(xy 356.440994 -221.29242) (xy 356.431596 -221.269306) (xy 356.423126 -221.247754) (xy 356.411243 -221.202998)
			(xy 356.405275 -221.157078) (xy 356.404926 -221.133924) (xy 356.405424 -221.107275) (xy 356.413367 -221.054571)
			(xy 356.429077 -221.003641) (xy 356.452203 -220.95562) (xy 356.482227 -220.911583) (xy 356.518479 -220.872512)
			(xy 356.56015 -220.839281) (xy 356.606308 -220.812632) (xy 356.655922 -220.79316) (xy 356.707884 -220.7813)
			(xy 356.761034 -220.777317) (xy 356.814184 -220.7813) (xy 356.866146 -220.79316) (xy 356.91576 -220.812632)
			(xy 356.961918 -220.839281) (xy 357.003589 -220.872512) (xy 357.039841 -220.911583) (xy 357.069865 -220.95562)
			(xy 357.092991 -221.003641) (xy 357.108701 -221.054571) (xy 357.116644 -221.107275) (xy 357.117142 -221.133924)
			(xy 357.116686 -221.159573) (xy 357.109322 -221.21034) (xy 357.094751 -221.259526) (xy 357.073274 -221.306112)
			(xy 357.045334 -221.349134) (xy 357.011511 -221.387703) (xy 356.972504 -221.421019) (xy 356.929121 -221.448395)
			(xy 356.882259 -221.469263) (xy 356.832887 -221.483191) (xy 356.807516 -221.486984) (xy 356.782624 -221.490286)
			(xy 356.610412 -221.788736) (xy 356.620064 -221.81185) (xy 356.628592 -221.833478) (xy 356.640575 -221.878398)
			(xy 356.646615 -221.924495) (xy 356.646988 -221.94774) (xy 356.64649 -221.974389) (xy 356.87507 -221.974389)
			(xy 356.87507 -221.921091) (xy 356.883013 -221.868387) (xy 356.898723 -221.817457) (xy 356.921849 -221.769436)
			(xy 356.951873 -221.725399) (xy 356.988125 -221.686328) (xy 357.029796 -221.653097) (xy 357.075954 -221.626448)
			(xy 357.125568 -221.606976) (xy 357.17753 -221.595116) (xy 357.23068 -221.591133) (xy 357.28383 -221.595116)
			(xy 357.335792 -221.606976) (xy 357.385406 -221.626448) (xy 357.431564 -221.653097) (xy 357.473235 -221.686328)
			(xy 357.509487 -221.725399) (xy 357.539511 -221.769436) (xy 357.562637 -221.817457) (xy 357.578347 -221.868387)
			(xy 357.58629 -221.921091) (xy 357.586788 -221.94774) (xy 357.814626 -221.94774) (xy 357.815106 -221.922113)
			(xy 357.822436 -221.871386) (xy 357.836964 -221.822234) (xy 357.85839 -221.775673) (xy 357.886271 -221.732666)
			(xy 357.920031 -221.694101) (xy 357.958972 -221.660776) (xy 358.00229 -221.63338) (xy 358.049088 -221.612478)
			(xy 358.0984 -221.598502) (xy 358.123744 -221.59468) (xy 358.148382 -221.591378) (xy 358.320848 -221.292674)
			(xy 358.31145 -221.26956) (xy 358.302955 -221.247966) (xy 358.290979 -221.203133) (xy 358.284919 -221.157126)
			(xy 358.284526 -221.133924) (xy 358.285024 -221.107275) (xy 358.292967 -221.054571) (xy 358.308677 -221.003641)
			(xy 358.331803 -220.95562) (xy 358.361827 -220.911583) (xy 358.398079 -220.872512) (xy 358.43975 -220.839281)
			(xy 358.485908 -220.812632) (xy 358.535522 -220.79316) (xy 358.587484 -220.7813) (xy 358.640634 -220.777317)
			(xy 358.693784 -220.7813) (xy 358.745746 -220.79316) (xy 358.79536 -220.812632) (xy 358.841518 -220.839281)
			(xy 358.883189 -220.872512) (xy 358.919441 -220.911583) (xy 358.949465 -220.95562) (xy 358.972591 -221.003641)
			(xy 358.988301 -221.054571) (xy 358.996244 -221.107275) (xy 358.996742 -221.133924) (xy 358.996314 -221.159564)
			(xy 358.988968 -221.210316) (xy 358.974418 -221.259489) (xy 358.952963 -221.306066) (xy 358.925049 -221.349083)
			(xy 358.891252 -221.38765) (xy 358.852272 -221.420971) (xy 358.808915 -221.448354) (xy 358.762078 -221.469235)
			(xy 358.71273 -221.48318) (xy 358.68737 -221.486984) (xy 358.662478 -221.490286) (xy 358.490266 -221.788736)
			(xy 358.499918 -221.81185) (xy 358.508448 -221.833477) (xy 358.52043 -221.878397) (xy 358.526469 -221.924494)
			(xy 358.526842 -221.94774) (xy 358.526344 -221.974389) (xy 358.518401 -222.027093) (xy 358.502691 -222.078023)
			(xy 358.479565 -222.126044) (xy 358.449541 -222.170081) (xy 358.413289 -222.209152) (xy 358.371618 -222.242383)
			(xy 358.32546 -222.269032) (xy 358.275846 -222.288504) (xy 358.223884 -222.300364) (xy 358.170734 -222.304348)
			(xy 358.117584 -222.300364) (xy 358.065622 -222.288504) (xy 358.016008 -222.269032) (xy 357.96985 -222.242383)
			(xy 357.928179 -222.209152) (xy 357.891927 -222.170081) (xy 357.861903 -222.126044) (xy 357.838777 -222.078023)
			(xy 357.823067 -222.027093) (xy 357.815124 -221.974389) (xy 357.814626 -221.94774) (xy 357.586788 -221.94774)
			(xy 357.58629 -221.974389) (xy 357.578347 -222.027093) (xy 357.562637 -222.078023) (xy 357.539511 -222.126044)
			(xy 357.509487 -222.170081) (xy 357.473235 -222.209152) (xy 357.431564 -222.242383) (xy 357.385406 -222.269032)
			(xy 357.335792 -222.288504) (xy 357.28383 -222.300364) (xy 357.23068 -222.304348) (xy 357.17753 -222.300364)
			(xy 357.125568 -222.288504) (xy 357.075954 -222.269032) (xy 357.029796 -222.242383) (xy 356.988125 -222.209152)
			(xy 356.951873 -222.170081) (xy 356.921849 -222.126044) (xy 356.898723 -222.078023) (xy 356.883013 -222.027093)
			(xy 356.87507 -221.974389) (xy 356.64649 -221.974389) (xy 356.638547 -222.027093) (xy 356.622837 -222.078023)
			(xy 356.599711 -222.126044) (xy 356.569687 -222.170081) (xy 356.533435 -222.209152) (xy 356.491764 -222.242383)
			(xy 356.445606 -222.269032) (xy 356.395992 -222.288504) (xy 356.34403 -222.300364) (xy 356.29088 -222.304348)
			(xy 356.23773 -222.300364) (xy 356.185768 -222.288504) (xy 356.136154 -222.269032) (xy 356.089996 -222.242383)
			(xy 356.048325 -222.209152) (xy 356.012073 -222.170081) (xy 355.982049 -222.126044) (xy 355.958923 -222.078023)
			(xy 355.943213 -222.027093) (xy 355.93527 -221.974389) (xy 355.934772 -221.94774) (xy 355.707188 -221.94774)
			(xy 355.70669 -221.974389) (xy 355.698747 -222.027093) (xy 355.683037 -222.078023) (xy 355.659911 -222.126044)
			(xy 355.629887 -222.170081) (xy 355.593635 -222.209152) (xy 355.551964 -222.242383) (xy 355.505806 -222.269032)
			(xy 355.456192 -222.288504) (xy 355.40423 -222.300364) (xy 355.35108 -222.304348) (xy 355.29793 -222.300364)
			(xy 355.245968 -222.288504) (xy 355.196354 -222.269032) (xy 355.150196 -222.242383) (xy 355.108525 -222.209152)
			(xy 355.072273 -222.170081) (xy 355.042249 -222.126044) (xy 355.019123 -222.078023) (xy 355.003413 -222.027093)
			(xy 354.99547 -221.974389) (xy 354.76689 -221.974389) (xy 354.758947 -222.027093) (xy 354.743237 -222.078023)
			(xy 354.720111 -222.126044) (xy 354.690087 -222.170081) (xy 354.653835 -222.209152) (xy 354.612164 -222.242383)
			(xy 354.566006 -222.269032) (xy 354.516392 -222.288504) (xy 354.46443 -222.300364) (xy 354.41128 -222.304348)
			(xy 354.35813 -222.300364) (xy 354.306168 -222.288504) (xy 354.256554 -222.269032) (xy 354.210396 -222.242383)
			(xy 354.168725 -222.209152) (xy 354.132473 -222.170081) (xy 354.102449 -222.126044) (xy 354.079323 -222.078023)
			(xy 354.063613 -222.027093) (xy 354.05567 -221.974389) (xy 354.055172 -221.94774) (xy 353.827588 -221.94774)
			(xy 353.82709 -221.974389) (xy 353.819147 -222.027093) (xy 353.803437 -222.078023) (xy 353.780311 -222.126044)
			(xy 353.750287 -222.170081) (xy 353.714035 -222.209152) (xy 353.672364 -222.242383) (xy 353.626206 -222.269032)
			(xy 353.576592 -222.288504) (xy 353.52463 -222.300364) (xy 353.47148 -222.304348) (xy 353.41833 -222.300364)
			(xy 353.366368 -222.288504) (xy 353.316754 -222.269032) (xy 353.270596 -222.242383) (xy 353.228925 -222.209152)
			(xy 353.192673 -222.170081) (xy 353.162649 -222.126044) (xy 353.139523 -222.078023) (xy 353.123813 -222.027093)
			(xy 353.11587 -221.974389) (xy 352.887262 -221.974389) (xy 352.887236 -221.97572) (xy 352.878476 -222.030992)
			(xy 352.861178 -222.084212) (xy 352.835767 -222.134071) (xy 352.80287 -222.179342) (xy 352.763296 -222.218909)
			(xy 352.71802 -222.251798) (xy 352.668157 -222.277201) (xy 352.614933 -222.29449) (xy 352.559661 -222.303241)
			(xy 352.53168 -222.303848) (xy 352.505761 -222.303373) (xy 352.454472 -222.295845) (xy 352.404815 -222.280964)
			(xy 352.357838 -222.259046) (xy 352.314533 -222.230553) (xy 352.275813 -222.196085) (xy 352.242496 -222.156371)
			(xy 352.215285 -222.112249) (xy 352.194754 -222.064649) (xy 352.181337 -222.014577) (xy 352.177858 -221.988888)
			(xy 352.175731 -221.974795) (xy 352.164736 -221.948514) (xy 352.146912 -221.92629) (xy 352.123644 -221.909851)
			(xy 352.096742 -221.900476) (xy 352.068298 -221.898894) (xy 352.040522 -221.905227) (xy 352.015574 -221.918983)
			(xy 352.005138 -221.92869) (xy 351.94621 -221.987618) (xy 351.943416 -222.003874) (xy 351.938474 -222.031354)
			(xy 351.921164 -222.084434) (xy 351.895781 -222.134161) (xy 351.862945 -222.179315) (xy 351.823463 -222.21879)
			(xy 351.778302 -222.251617) (xy 351.72857 -222.276991) (xy 351.675487 -222.29429) (xy 351.648014 -222.299276)
			(xy 351.631758 -222.30207) (xy 351.442274 -222.491554) (xy 351.433074 -222.504853) (xy 351.413892 -222.530893)
			(xy 351.40392 -222.543624) (xy 351.421384 -222.567194) (xy 351.449173 -222.618852) (xy 351.468129 -222.674362)
			(xy 351.47774 -222.732227) (xy 351.478342 -222.761556) (xy 351.47785 -222.788205) (xy 351.706424 -222.788205)
			(xy 351.706424 -222.734907) (xy 351.714367 -222.682203) (xy 351.730077 -222.631273) (xy 351.753203 -222.583252)
			(xy 351.783227 -222.539215) (xy 351.819479 -222.500144) (xy 351.86115 -222.466913) (xy 351.907308 -222.440264)
			(xy 351.956922 -222.420792) (xy 352.008884 -222.408932) (xy 352.062034 -222.404949) (xy 352.115184 -222.408932)
			(xy 352.167146 -222.420792) (xy 352.21676 -222.440264) (xy 352.262918 -222.466913) (xy 352.304589 -222.500144)
			(xy 352.340841 -222.539215) (xy 352.370865 -222.583252) (xy 352.393991 -222.631273) (xy 352.409701 -222.682203)
			(xy 352.417644 -222.734907) (xy 352.418142 -222.761556) (xy 352.417644 -222.788205) (xy 352.646224 -222.788205)
			(xy 352.646224 -222.734907) (xy 352.654167 -222.682203) (xy 352.669877 -222.631273) (xy 352.693003 -222.583252)
			(xy 352.723027 -222.539215) (xy 352.759279 -222.500144) (xy 352.80095 -222.466913) (xy 352.847108 -222.440264)
			(xy 352.896722 -222.420792) (xy 352.948684 -222.408932) (xy 353.001834 -222.404949) (xy 353.054984 -222.408932)
			(xy 353.106946 -222.420792) (xy 353.15656 -222.440264) (xy 353.202718 -222.466913) (xy 353.244389 -222.500144)
			(xy 353.280641 -222.539215) (xy 353.310665 -222.583252) (xy 353.333791 -222.631273) (xy 353.349501 -222.682203)
			(xy 353.357444 -222.734907) (xy 353.357942 -222.761556) (xy 353.357444 -222.788205) (xy 353.586024 -222.788205)
			(xy 353.586024 -222.734907) (xy 353.593967 -222.682203) (xy 353.609677 -222.631273) (xy 353.632803 -222.583252)
			(xy 353.662827 -222.539215) (xy 353.699079 -222.500144) (xy 353.74075 -222.466913) (xy 353.786908 -222.440264)
			(xy 353.836522 -222.420792) (xy 353.888484 -222.408932) (xy 353.941634 -222.404949) (xy 353.994784 -222.408932)
			(xy 354.046746 -222.420792) (xy 354.09636 -222.440264) (xy 354.142518 -222.466913) (xy 354.184189 -222.500144)
			(xy 354.220441 -222.539215) (xy 354.250465 -222.583252) (xy 354.273591 -222.631273) (xy 354.289301 -222.682203)
			(xy 354.297244 -222.734907) (xy 354.297742 -222.761556) (xy 354.297244 -222.788205) (xy 354.525824 -222.788205)
			(xy 354.525824 -222.734907) (xy 354.533767 -222.682203) (xy 354.549477 -222.631273) (xy 354.572603 -222.583252)
			(xy 354.602627 -222.539215) (xy 354.638879 -222.500144) (xy 354.68055 -222.466913) (xy 354.726708 -222.440264)
			(xy 354.776322 -222.420792) (xy 354.828284 -222.408932) (xy 354.881434 -222.404949) (xy 354.934584 -222.408932)
			(xy 354.986546 -222.420792) (xy 355.03616 -222.440264) (xy 355.082318 -222.466913) (xy 355.123989 -222.500144)
			(xy 355.160241 -222.539215) (xy 355.190265 -222.583252) (xy 355.213391 -222.631273) (xy 355.229101 -222.682203)
			(xy 355.237044 -222.734907) (xy 355.237542 -222.761556) (xy 355.237044 -222.788205) (xy 355.465624 -222.788205)
			(xy 355.465624 -222.734907) (xy 355.473567 -222.682203) (xy 355.489277 -222.631273) (xy 355.512403 -222.583252)
			(xy 355.542427 -222.539215) (xy 355.578679 -222.500144) (xy 355.62035 -222.466913) (xy 355.666508 -222.440264)
			(xy 355.716122 -222.420792) (xy 355.768084 -222.408932) (xy 355.821234 -222.404949) (xy 355.874384 -222.408932)
			(xy 355.926346 -222.420792) (xy 355.97596 -222.440264) (xy 356.022118 -222.466913) (xy 356.063789 -222.500144)
			(xy 356.100041 -222.539215) (xy 356.130065 -222.583252) (xy 356.153191 -222.631273) (xy 356.168901 -222.682203)
			(xy 356.176844 -222.734907) (xy 356.177342 -222.761556) (xy 356.176844 -222.788205) (xy 356.405424 -222.788205)
			(xy 356.405424 -222.734907) (xy 356.413367 -222.682203) (xy 356.429077 -222.631273) (xy 356.452203 -222.583252)
			(xy 356.482227 -222.539215) (xy 356.518479 -222.500144) (xy 356.56015 -222.466913) (xy 356.606308 -222.440264)
			(xy 356.655922 -222.420792) (xy 356.707884 -222.408932) (xy 356.761034 -222.404949) (xy 356.814184 -222.408932)
			(xy 356.866146 -222.420792) (xy 356.91576 -222.440264) (xy 356.961918 -222.466913) (xy 357.003589 -222.500144)
			(xy 357.039841 -222.539215) (xy 357.069865 -222.583252) (xy 357.092991 -222.631273) (xy 357.108701 -222.682203)
			(xy 357.116644 -222.734907) (xy 357.117142 -222.761556) (xy 357.116644 -222.788205) (xy 357.345224 -222.788205)
			(xy 357.345224 -222.734907) (xy 357.353167 -222.682203) (xy 357.368877 -222.631273) (xy 357.392003 -222.583252)
			(xy 357.422027 -222.539215) (xy 357.458279 -222.500144) (xy 357.49995 -222.466913) (xy 357.546108 -222.440264)
			(xy 357.595722 -222.420792) (xy 357.647684 -222.408932) (xy 357.700834 -222.404949) (xy 357.753984 -222.408932)
			(xy 357.805946 -222.420792) (xy 357.85556 -222.440264) (xy 357.901718 -222.466913) (xy 357.943389 -222.500144)
			(xy 357.979641 -222.539215) (xy 358.009665 -222.583252) (xy 358.032791 -222.631273) (xy 358.048501 -222.682203)
			(xy 358.056444 -222.734907) (xy 358.056942 -222.761556) (xy 358.056444 -222.788205) (xy 358.285024 -222.788205)
			(xy 358.285024 -222.734907) (xy 358.292967 -222.682203) (xy 358.308677 -222.631273) (xy 358.331803 -222.583252)
			(xy 358.361827 -222.539215) (xy 358.398079 -222.500144) (xy 358.43975 -222.466913) (xy 358.485908 -222.440264)
			(xy 358.535522 -222.420792) (xy 358.587484 -222.408932) (xy 358.640634 -222.404949) (xy 358.693784 -222.408932)
			(xy 358.745746 -222.420792) (xy 358.79536 -222.440264) (xy 358.841518 -222.466913) (xy 358.883189 -222.500144)
			(xy 358.919441 -222.539215) (xy 358.949465 -222.583252) (xy 358.972591 -222.631273) (xy 358.988301 -222.682203)
			(xy 358.996244 -222.734907) (xy 358.996742 -222.761556) (xy 358.996244 -222.788205) (xy 358.988301 -222.840909)
			(xy 358.972591 -222.891839) (xy 358.949465 -222.93986) (xy 358.919441 -222.983897) (xy 358.883189 -223.022968)
			(xy 358.841518 -223.056199) (xy 358.79536 -223.082848) (xy 358.745746 -223.10232) (xy 358.693784 -223.11418)
			(xy 358.640634 -223.118164) (xy 358.587484 -223.11418) (xy 358.535522 -223.10232) (xy 358.485908 -223.082848)
			(xy 358.43975 -223.056199) (xy 358.398079 -223.022968) (xy 358.361827 -222.983897) (xy 358.331803 -222.93986)
			(xy 358.308677 -222.891839) (xy 358.292967 -222.840909) (xy 358.285024 -222.788205) (xy 358.056444 -222.788205)
			(xy 358.048501 -222.840909) (xy 358.032791 -222.891839) (xy 358.009665 -222.93986) (xy 357.979641 -222.983897)
			(xy 357.943389 -223.022968) (xy 357.901718 -223.056199) (xy 357.85556 -223.082848) (xy 357.805946 -223.10232)
			(xy 357.753984 -223.11418) (xy 357.700834 -223.118164) (xy 357.647684 -223.11418) (xy 357.595722 -223.10232)
			(xy 357.546108 -223.082848) (xy 357.49995 -223.056199) (xy 357.458279 -223.022968) (xy 357.422027 -222.983897)
			(xy 357.392003 -222.93986) (xy 357.368877 -222.891839) (xy 357.353167 -222.840909) (xy 357.345224 -222.788205)
			(xy 357.116644 -222.788205) (xy 357.108701 -222.840909) (xy 357.092991 -222.891839) (xy 357.069865 -222.93986)
			(xy 357.039841 -222.983897) (xy 357.003589 -223.022968) (xy 356.961918 -223.056199) (xy 356.91576 -223.082848)
			(xy 356.866146 -223.10232) (xy 356.814184 -223.11418) (xy 356.761034 -223.118164) (xy 356.707884 -223.11418)
			(xy 356.655922 -223.10232) (xy 356.606308 -223.082848) (xy 356.56015 -223.056199) (xy 356.518479 -223.022968)
			(xy 356.482227 -222.983897) (xy 356.452203 -222.93986) (xy 356.429077 -222.891839) (xy 356.413367 -222.840909)
			(xy 356.405424 -222.788205) (xy 356.176844 -222.788205) (xy 356.168901 -222.840909) (xy 356.153191 -222.891839)
			(xy 356.130065 -222.93986) (xy 356.100041 -222.983897) (xy 356.063789 -223.022968) (xy 356.022118 -223.056199)
			(xy 355.97596 -223.082848) (xy 355.926346 -223.10232) (xy 355.874384 -223.11418) (xy 355.821234 -223.118164)
			(xy 355.768084 -223.11418) (xy 355.716122 -223.10232) (xy 355.666508 -223.082848) (xy 355.62035 -223.056199)
			(xy 355.578679 -223.022968) (xy 355.542427 -222.983897) (xy 355.512403 -222.93986) (xy 355.489277 -222.891839)
			(xy 355.473567 -222.840909) (xy 355.465624 -222.788205) (xy 355.237044 -222.788205) (xy 355.229101 -222.840909)
			(xy 355.213391 -222.891839) (xy 355.190265 -222.93986) (xy 355.160241 -222.983897) (xy 355.123989 -223.022968)
			(xy 355.082318 -223.056199) (xy 355.03616 -223.082848) (xy 354.986546 -223.10232) (xy 354.934584 -223.11418)
			(xy 354.881434 -223.118164) (xy 354.828284 -223.11418) (xy 354.776322 -223.10232) (xy 354.726708 -223.082848)
			(xy 354.68055 -223.056199) (xy 354.638879 -223.022968) (xy 354.602627 -222.983897) (xy 354.572603 -222.93986)
			(xy 354.549477 -222.891839) (xy 354.533767 -222.840909) (xy 354.525824 -222.788205) (xy 354.297244 -222.788205)
			(xy 354.289301 -222.840909) (xy 354.273591 -222.891839) (xy 354.250465 -222.93986) (xy 354.220441 -222.983897)
			(xy 354.184189 -223.022968) (xy 354.142518 -223.056199) (xy 354.09636 -223.082848) (xy 354.046746 -223.10232)
			(xy 353.994784 -223.11418) (xy 353.941634 -223.118164) (xy 353.888484 -223.11418) (xy 353.836522 -223.10232)
			(xy 353.786908 -223.082848) (xy 353.74075 -223.056199) (xy 353.699079 -223.022968) (xy 353.662827 -222.983897)
			(xy 353.632803 -222.93986) (xy 353.609677 -222.891839) (xy 353.593967 -222.840909) (xy 353.586024 -222.788205)
			(xy 353.357444 -222.788205) (xy 353.349501 -222.840909) (xy 353.333791 -222.891839) (xy 353.310665 -222.93986)
			(xy 353.280641 -222.983897) (xy 353.244389 -223.022968) (xy 353.202718 -223.056199) (xy 353.15656 -223.082848)
			(xy 353.106946 -223.10232) (xy 353.054984 -223.11418) (xy 353.001834 -223.118164) (xy 352.948684 -223.11418)
			(xy 352.896722 -223.10232) (xy 352.847108 -223.082848) (xy 352.80095 -223.056199) (xy 352.759279 -223.022968)
			(xy 352.723027 -222.983897) (xy 352.693003 -222.93986) (xy 352.669877 -222.891839) (xy 352.654167 -222.840909)
			(xy 352.646224 -222.788205) (xy 352.417644 -222.788205) (xy 352.409701 -222.840909) (xy 352.393991 -222.891839)
			(xy 352.370865 -222.93986) (xy 352.340841 -222.983897) (xy 352.304589 -223.022968) (xy 352.262918 -223.056199)
			(xy 352.21676 -223.082848) (xy 352.167146 -223.10232) (xy 352.115184 -223.11418) (xy 352.062034 -223.118164)
			(xy 352.008884 -223.11418) (xy 351.956922 -223.10232) (xy 351.907308 -223.082848) (xy 351.86115 -223.056199)
			(xy 351.819479 -223.022968) (xy 351.783227 -222.983897) (xy 351.753203 -222.93986) (xy 351.730077 -222.891839)
			(xy 351.714367 -222.840909) (xy 351.706424 -222.788205) (xy 351.47785 -222.788205) (xy 351.477825 -222.789545)
			(xy 351.469075 -222.844834) (xy 351.451784 -222.898073) (xy 351.426376 -222.947952) (xy 351.393479 -222.993242)
			(xy 351.353901 -223.032828) (xy 351.308619 -223.065735) (xy 351.258745 -223.091154) (xy 351.20551 -223.108457)
			(xy 351.150223 -223.117219) (xy 351.122234 -223.117664) (xy 351.096759 -223.117233) (xy 351.046327 -223.109983)
			(xy 350.99744 -223.095627) (xy 350.951096 -223.074457) (xy 350.929448 -223.061022) (xy 350.894904 -223.038924)
			(xy 350.819974 -223.113854) (xy 350.809554 -223.125064) (xy 350.795363 -223.152167) (xy 350.789827 -223.182254)
			(xy 350.793442 -223.212633) (xy 350.805884 -223.240581) (xy 350.826039 -223.263597) (xy 350.83877 -223.272096)
			(xy 350.860634 -223.286097) (xy 350.90044 -223.319427) (xy 350.934989 -223.358179) (xy 350.963551 -223.401533)
			(xy 350.985522 -223.448572) (xy 351.000436 -223.498301) (xy 351.007978 -223.549668) (xy 351.008442 -223.575626)
			(xy 351.007891 -223.603609) (xy 350.999133 -223.658885) (xy 350.981837 -223.71211) (xy 350.956428 -223.761976)
			(xy 350.923532 -223.807252) (xy 350.883959 -223.846827) (xy 350.838682 -223.879724) (xy 350.788818 -223.905134)
			(xy 350.735593 -223.922431) (xy 350.680317 -223.93119) (xy 350.652334 -223.931734) (xy 350.626374 -223.931267)
			(xy 350.575002 -223.923737) (xy 350.525268 -223.908831) (xy 350.478223 -223.886866) (xy 350.434864 -223.858305)
			(xy 350.396109 -223.823754) (xy 350.362778 -223.783945) (xy 350.348804 -223.762062) (xy 350.340367 -223.749277)
			(xy 350.317357 -223.729077) (xy 350.28939 -223.716613) (xy 350.258985 -223.713005) (xy 350.228878 -223.718579)
			(xy 350.20178 -223.732834) (xy 350.190562 -223.743266) (xy 350.06788 -223.865948) (xy 349.918528 -223.865948)
			(xy 349.894703 -223.882185) (xy 349.842939 -223.907571) (xy 349.787768 -223.924307) (xy 349.75927 -223.928686)
			(xy 349.734378 -223.931988) (xy 349.562166 -224.230438) (xy 349.571818 -224.253552) (xy 349.580333 -224.275184)
			(xy 349.592316 -224.320102) (xy 349.598357 -224.366197) (xy 349.598742 -224.389442) (xy 349.826326 -224.389442)
			(xy 349.826824 -224.362793) (xy 349.834767 -224.310089) (xy 349.850477 -224.259159) (xy 349.873603 -224.211138)
			(xy 349.903627 -224.167101) (xy 349.939879 -224.12803) (xy 349.98155 -224.094799) (xy 350.027708 -224.06815)
			(xy 350.077322 -224.048678) (xy 350.129284 -224.036818) (xy 350.182434 -224.032835) (xy 350.235584 -224.036818)
			(xy 350.287546 -224.048678) (xy 350.33716 -224.06815) (xy 350.383318 -224.094799) (xy 350.424989 -224.12803)
			(xy 350.461241 -224.167101) (xy 350.491265 -224.211138) (xy 350.514391 -224.259159) (xy 350.530101 -224.310089)
			(xy 350.538044 -224.362793) (xy 350.538542 -224.389442) (xy 350.766126 -224.389442) (xy 350.766608 -224.363815)
			(xy 350.773937 -224.313088) (xy 350.788465 -224.263936) (xy 350.809891 -224.217375) (xy 350.837772 -224.174368)
			(xy 350.871532 -224.135803) (xy 350.910473 -224.102478) (xy 350.95379 -224.075082) (xy 351.000588 -224.05418)
			(xy 351.0499 -224.040204) (xy 351.075244 -224.036382) (xy 351.099882 -224.03308) (xy 351.272094 -223.734376)
			(xy 351.262696 -223.711516) (xy 351.254186 -223.689882) (xy 351.242197 -223.644965) (xy 351.236149 -223.598871)
			(xy 351.235772 -223.575626) (xy 351.23627 -223.548977) (xy 351.244213 -223.496273) (xy 351.259923 -223.445343)
			(xy 351.283049 -223.397322) (xy 351.313073 -223.353285) (xy 351.349325 -223.314214) (xy 351.390996 -223.280983)
			(xy 351.437154 -223.254334) (xy 351.486768 -223.234862) (xy 351.53873 -223.223002) (xy 351.59188 -223.219019)
			(xy 351.64503 -223.223002) (xy 351.696992 -223.234862) (xy 351.746606 -223.254334) (xy 351.792764 -223.280983)
			(xy 351.834435 -223.314214) (xy 351.870687 -223.353285) (xy 351.900711 -223.397322) (xy 351.923837 -223.445343)
			(xy 351.939547 -223.496273) (xy 351.94749 -223.548977) (xy 351.947988 -223.575626) (xy 351.947557 -223.601254)
			(xy 351.947409 -223.602275) (xy 352.176324 -223.602275) (xy 352.176324 -223.548977) (xy 352.184267 -223.496273)
			(xy 352.199977 -223.445343) (xy 352.223103 -223.397322) (xy 352.253127 -223.353285) (xy 352.289379 -223.314214)
			(xy 352.33105 -223.280983) (xy 352.377208 -223.254334) (xy 352.426822 -223.234862) (xy 352.478784 -223.223002)
			(xy 352.531934 -223.219019) (xy 352.585084 -223.223002) (xy 352.637046 -223.234862) (xy 352.68666 -223.254334)
			(xy 352.732818 -223.280983) (xy 352.774489 -223.314214) (xy 352.810741 -223.353285) (xy 352.840765 -223.397322)
			(xy 352.863891 -223.445343) (xy 352.879601 -223.496273) (xy 352.887544 -223.548977) (xy 352.888042 -223.575626)
			(xy 352.887544 -223.602275) (xy 352.879601 -223.654979) (xy 352.863891 -223.705909) (xy 352.840765 -223.75393)
			(xy 352.810741 -223.797967) (xy 352.774489 -223.837038) (xy 352.732818 -223.870269) (xy 352.68666 -223.896918)
			(xy 352.637046 -223.91639) (xy 352.585084 -223.92825) (xy 352.531934 -223.932234) (xy 352.478784 -223.92825)
			(xy 352.426822 -223.91639) (xy 352.377208 -223.896918) (xy 352.33105 -223.870269) (xy 352.289379 -223.837038)
			(xy 352.253127 -223.797967) (xy 352.223103 -223.75393) (xy 352.199977 -223.705909) (xy 352.184267 -223.654979)
			(xy 352.176324 -223.602275) (xy 351.947409 -223.602275) (xy 351.940219 -223.651983) (xy 351.925683 -223.701135)
			(xy 351.90425 -223.747696) (xy 351.876363 -223.790702) (xy 351.842598 -223.829266) (xy 351.803652 -223.86259)
			(xy 351.760331 -223.889986) (xy 351.71353 -223.910888) (xy 351.664216 -223.924864) (xy 351.63887 -223.928686)
			(xy 351.613978 -223.931988) (xy 351.441766 -224.230438) (xy 351.451418 -224.253552) (xy 351.459949 -224.275178)
			(xy 351.47193 -224.320099) (xy 351.477969 -224.366196) (xy 351.478342 -224.389442) (xy 351.705926 -224.389442)
			(xy 351.706424 -224.362793) (xy 351.714367 -224.310089) (xy 351.730077 -224.259159) (xy 351.753203 -224.211138)
			(xy 351.783227 -224.167101) (xy 351.819479 -224.12803) (xy 351.86115 -224.094799) (xy 351.907308 -224.06815)
			(xy 351.956922 -224.048678) (xy 352.008884 -224.036818) (xy 352.062034 -224.032835) (xy 352.115184 -224.036818)
			(xy 352.167146 -224.048678) (xy 352.21676 -224.06815) (xy 352.262918 -224.094799) (xy 352.304589 -224.12803)
			(xy 352.340841 -224.167101) (xy 352.370865 -224.211138) (xy 352.393991 -224.259159) (xy 352.409701 -224.310089)
			(xy 352.417644 -224.362793) (xy 352.418142 -224.389442) (xy 352.645726 -224.389442) (xy 352.646208 -224.363815)
			(xy 352.653537 -224.313088) (xy 352.668065 -224.263936) (xy 352.689491 -224.217375) (xy 352.717372 -224.174368)
			(xy 352.751132 -224.135803) (xy 352.790073 -224.102478) (xy 352.83339 -224.075082) (xy 352.880188 -224.05418)
			(xy 352.9295 -224.040204) (xy 352.954844 -224.036382) (xy 352.979482 -224.03308) (xy 353.151694 -223.734376)
			(xy 353.142296 -223.711516) (xy 353.133786 -223.689882) (xy 353.121797 -223.644965) (xy 353.115749 -223.598871)
			(xy 353.115372 -223.575626) (xy 353.11587 -223.548977) (xy 353.123813 -223.496273) (xy 353.139523 -223.445343)
			(xy 353.162649 -223.397322) (xy 353.192673 -223.353285) (xy 353.228925 -223.314214) (xy 353.270596 -223.280983)
			(xy 353.316754 -223.254334) (xy 353.366368 -223.234862) (xy 353.41833 -223.223002) (xy 353.47148 -223.219019)
			(xy 353.52463 -223.223002) (xy 353.576592 -223.234862) (xy 353.626206 -223.254334) (xy 353.672364 -223.280983)
			(xy 353.714035 -223.314214) (xy 353.750287 -223.353285) (xy 353.780311 -223.397322) (xy 353.803437 -223.445343)
			(xy 353.819147 -223.496273) (xy 353.82709 -223.548977) (xy 353.827588 -223.575626) (xy 353.827157 -223.601254)
			(xy 353.827009 -223.602275) (xy 354.055924 -223.602275) (xy 354.055924 -223.548977) (xy 354.063867 -223.496273)
			(xy 354.079577 -223.445343) (xy 354.102703 -223.397322) (xy 354.132727 -223.353285) (xy 354.168979 -223.314214)
			(xy 354.21065 -223.280983) (xy 354.256808 -223.254334) (xy 354.306422 -223.234862) (xy 354.358384 -223.223002)
			(xy 354.411534 -223.219019) (xy 354.464684 -223.223002) (xy 354.516646 -223.234862) (xy 354.56626 -223.254334)
			(xy 354.612418 -223.280983) (xy 354.654089 -223.314214) (xy 354.690341 -223.353285) (xy 354.720365 -223.397322)
			(xy 354.743491 -223.445343) (xy 354.759201 -223.496273) (xy 354.767144 -223.548977) (xy 354.767642 -223.575626)
			(xy 354.767144 -223.602275) (xy 354.759201 -223.654979) (xy 354.743491 -223.705909) (xy 354.720365 -223.75393)
			(xy 354.690341 -223.797967) (xy 354.654089 -223.837038) (xy 354.612418 -223.870269) (xy 354.56626 -223.896918)
			(xy 354.516646 -223.91639) (xy 354.464684 -223.92825) (xy 354.411534 -223.932234) (xy 354.358384 -223.92825)
			(xy 354.306422 -223.91639) (xy 354.256808 -223.896918) (xy 354.21065 -223.870269) (xy 354.168979 -223.837038)
			(xy 354.132727 -223.797967) (xy 354.102703 -223.75393) (xy 354.079577 -223.705909) (xy 354.063867 -223.654979)
			(xy 354.055924 -223.602275) (xy 353.827009 -223.602275) (xy 353.819819 -223.651983) (xy 353.805283 -223.701135)
			(xy 353.78385 -223.747696) (xy 353.755963 -223.790702) (xy 353.722198 -223.829266) (xy 353.683252 -223.86259)
			(xy 353.639931 -223.889986) (xy 353.59313 -223.910888) (xy 353.543816 -223.924864) (xy 353.51847 -223.928686)
			(xy 353.493578 -223.931988) (xy 353.321366 -224.230438) (xy 353.331018 -224.253552) (xy 353.339549 -224.275178)
			(xy 353.35153 -224.320099) (xy 353.357569 -224.366196) (xy 353.357942 -224.389442) (xy 353.585526 -224.389442)
			(xy 353.586024 -224.362793) (xy 353.593967 -224.310089) (xy 353.609677 -224.259159) (xy 353.632803 -224.211138)
			(xy 353.662827 -224.167101) (xy 353.699079 -224.12803) (xy 353.74075 -224.094799) (xy 353.786908 -224.06815)
			(xy 353.836522 -224.048678) (xy 353.888484 -224.036818) (xy 353.941634 -224.032835) (xy 353.994784 -224.036818)
			(xy 354.046746 -224.048678) (xy 354.09636 -224.06815) (xy 354.142518 -224.094799) (xy 354.184189 -224.12803)
			(xy 354.220441 -224.167101) (xy 354.250465 -224.211138) (xy 354.273591 -224.259159) (xy 354.289301 -224.310089)
			(xy 354.297244 -224.362793) (xy 354.297742 -224.389442) (xy 354.525326 -224.389442) (xy 354.525808 -224.363815)
			(xy 354.533137 -224.313088) (xy 354.547665 -224.263936) (xy 354.569091 -224.217375) (xy 354.596972 -224.174368)
			(xy 354.630732 -224.135803) (xy 354.669673 -224.102478) (xy 354.71299 -224.075082) (xy 354.759788 -224.05418)
			(xy 354.8091 -224.040204) (xy 354.834444 -224.036382) (xy 354.859082 -224.03308) (xy 355.031294 -223.734376)
			(xy 355.021896 -223.711516) (xy 355.013386 -223.689882) (xy 355.001397 -223.644965) (xy 354.995349 -223.598871)
			(xy 354.994972 -223.575626) (xy 354.99547 -223.548977) (xy 355.003413 -223.496273) (xy 355.019123 -223.445343)
			(xy 355.042249 -223.397322) (xy 355.072273 -223.353285) (xy 355.108525 -223.314214) (xy 355.150196 -223.280983)
			(xy 355.196354 -223.254334) (xy 355.245968 -223.234862) (xy 355.29793 -223.223002) (xy 355.35108 -223.219019)
			(xy 355.40423 -223.223002) (xy 355.456192 -223.234862) (xy 355.505806 -223.254334) (xy 355.551964 -223.280983)
			(xy 355.593635 -223.314214) (xy 355.629887 -223.353285) (xy 355.659911 -223.397322) (xy 355.683037 -223.445343)
			(xy 355.698747 -223.496273) (xy 355.70669 -223.548977) (xy 355.707188 -223.575626) (xy 355.706757 -223.601254)
			(xy 355.706609 -223.602275) (xy 355.935524 -223.602275) (xy 355.935524 -223.548977) (xy 355.943467 -223.496273)
			(xy 355.959177 -223.445343) (xy 355.982303 -223.397322) (xy 356.012327 -223.353285) (xy 356.048579 -223.314214)
			(xy 356.09025 -223.280983) (xy 356.136408 -223.254334) (xy 356.186022 -223.234862) (xy 356.237984 -223.223002)
			(xy 356.291134 -223.219019) (xy 356.344284 -223.223002) (xy 356.396246 -223.234862) (xy 356.44586 -223.254334)
			(xy 356.492018 -223.280983) (xy 356.533689 -223.314214) (xy 356.569941 -223.353285) (xy 356.599965 -223.397322)
			(xy 356.623091 -223.445343) (xy 356.638801 -223.496273) (xy 356.646744 -223.548977) (xy 356.647242 -223.575626)
			(xy 356.646744 -223.602275) (xy 356.638801 -223.654979) (xy 356.623091 -223.705909) (xy 356.599965 -223.75393)
			(xy 356.569941 -223.797967) (xy 356.533689 -223.837038) (xy 356.492018 -223.870269) (xy 356.44586 -223.896918)
			(xy 356.396246 -223.91639) (xy 356.344284 -223.92825) (xy 356.291134 -223.932234) (xy 356.237984 -223.92825)
			(xy 356.186022 -223.91639) (xy 356.136408 -223.896918) (xy 356.09025 -223.870269) (xy 356.048579 -223.837038)
			(xy 356.012327 -223.797967) (xy 355.982303 -223.75393) (xy 355.959177 -223.705909) (xy 355.943467 -223.654979)
			(xy 355.935524 -223.602275) (xy 355.706609 -223.602275) (xy 355.699419 -223.651983) (xy 355.684883 -223.701135)
			(xy 355.66345 -223.747696) (xy 355.635563 -223.790702) (xy 355.601798 -223.829266) (xy 355.562852 -223.86259)
			(xy 355.519531 -223.889986) (xy 355.47273 -223.910888) (xy 355.423416 -223.924864) (xy 355.39807 -223.928686)
			(xy 355.373178 -223.931988) (xy 355.200966 -224.230438) (xy 355.210618 -224.253552) (xy 355.219149 -224.275178)
			(xy 355.23113 -224.320099) (xy 355.237169 -224.366196) (xy 355.237542 -224.389442) (xy 355.465126 -224.389442)
			(xy 355.465624 -224.362793) (xy 355.473567 -224.310089) (xy 355.489277 -224.259159) (xy 355.512403 -224.211138)
			(xy 355.542427 -224.167101) (xy 355.578679 -224.12803) (xy 355.62035 -224.094799) (xy 355.666508 -224.06815)
			(xy 355.716122 -224.048678) (xy 355.768084 -224.036818) (xy 355.821234 -224.032835) (xy 355.874384 -224.036818)
			(xy 355.926346 -224.048678) (xy 355.97596 -224.06815) (xy 356.022118 -224.094799) (xy 356.063789 -224.12803)
			(xy 356.100041 -224.167101) (xy 356.130065 -224.211138) (xy 356.153191 -224.259159) (xy 356.168901 -224.310089)
			(xy 356.176844 -224.362793) (xy 356.177342 -224.389442) (xy 356.404926 -224.389442) (xy 356.405408 -224.363815)
			(xy 356.412737 -224.313088) (xy 356.427265 -224.263936) (xy 356.448691 -224.217375) (xy 356.476572 -224.174368)
			(xy 356.510332 -224.135803) (xy 356.549273 -224.102478) (xy 356.59259 -224.075082) (xy 356.639388 -224.05418)
			(xy 356.6887 -224.040204) (xy 356.714044 -224.036382) (xy 356.738682 -224.03308) (xy 356.910894 -223.734376)
			(xy 356.901496 -223.711516) (xy 356.892986 -223.689882) (xy 356.880997 -223.644965) (xy 356.874949 -223.598871)
			(xy 356.874572 -223.575626) (xy 356.87507 -223.548977) (xy 356.883013 -223.496273) (xy 356.898723 -223.445343)
			(xy 356.921849 -223.397322) (xy 356.951873 -223.353285) (xy 356.988125 -223.314214) (xy 357.029796 -223.280983)
			(xy 357.075954 -223.254334) (xy 357.125568 -223.234862) (xy 357.17753 -223.223002) (xy 357.23068 -223.219019)
			(xy 357.28383 -223.223002) (xy 357.335792 -223.234862) (xy 357.385406 -223.254334) (xy 357.431564 -223.280983)
			(xy 357.473235 -223.314214) (xy 357.509487 -223.353285) (xy 357.539511 -223.397322) (xy 357.562637 -223.445343)
			(xy 357.578347 -223.496273) (xy 357.58629 -223.548977) (xy 357.586788 -223.575626) (xy 357.586357 -223.601254)
			(xy 357.586209 -223.602275) (xy 357.815124 -223.602275) (xy 357.815124 -223.548977) (xy 357.823067 -223.496273)
			(xy 357.838777 -223.445343) (xy 357.861903 -223.397322) (xy 357.891927 -223.353285) (xy 357.928179 -223.314214)
			(xy 357.96985 -223.280983) (xy 358.016008 -223.254334) (xy 358.065622 -223.234862) (xy 358.117584 -223.223002)
			(xy 358.170734 -223.219019) (xy 358.223884 -223.223002) (xy 358.275846 -223.234862) (xy 358.32546 -223.254334)
			(xy 358.371618 -223.280983) (xy 358.413289 -223.314214) (xy 358.449541 -223.353285) (xy 358.479565 -223.397322)
			(xy 358.502691 -223.445343) (xy 358.518401 -223.496273) (xy 358.526344 -223.548977) (xy 358.526842 -223.575626)
			(xy 358.526344 -223.602275) (xy 358.518401 -223.654979) (xy 358.502691 -223.705909) (xy 358.479565 -223.75393)
			(xy 358.449541 -223.797967) (xy 358.413289 -223.837038) (xy 358.371618 -223.870269) (xy 358.32546 -223.896918)
			(xy 358.275846 -223.91639) (xy 358.223884 -223.92825) (xy 358.170734 -223.932234) (xy 358.117584 -223.92825)
			(xy 358.065622 -223.91639) (xy 358.016008 -223.896918) (xy 357.96985 -223.870269) (xy 357.928179 -223.837038)
			(xy 357.891927 -223.797967) (xy 357.861903 -223.75393) (xy 357.838777 -223.705909) (xy 357.823067 -223.654979)
			(xy 357.815124 -223.602275) (xy 357.586209 -223.602275) (xy 357.579019 -223.651983) (xy 357.564483 -223.701135)
			(xy 357.54305 -223.747696) (xy 357.515163 -223.790702) (xy 357.481398 -223.829266) (xy 357.442452 -223.86259)
			(xy 357.399131 -223.889986) (xy 357.35233 -223.910888) (xy 357.303016 -223.924864) (xy 357.27767 -223.928686)
			(xy 357.252778 -223.931988) (xy 357.080566 -224.230438) (xy 357.090218 -224.253552) (xy 357.098749 -224.275178)
			(xy 357.11073 -224.320099) (xy 357.116769 -224.366196) (xy 357.117142 -224.389442) (xy 357.344726 -224.389442)
			(xy 357.345224 -224.362793) (xy 357.353167 -224.310089) (xy 357.368877 -224.259159) (xy 357.392003 -224.211138)
			(xy 357.422027 -224.167101) (xy 357.458279 -224.12803) (xy 357.49995 -224.094799) (xy 357.546108 -224.06815)
			(xy 357.595722 -224.048678) (xy 357.647684 -224.036818) (xy 357.700834 -224.032835) (xy 357.753984 -224.036818)
			(xy 357.805946 -224.048678) (xy 357.85556 -224.06815) (xy 357.901718 -224.094799) (xy 357.943389 -224.12803)
			(xy 357.979641 -224.167101) (xy 358.009665 -224.211138) (xy 358.032791 -224.259159) (xy 358.048501 -224.310089)
			(xy 358.056444 -224.362793) (xy 358.056942 -224.389442) (xy 358.056552 -224.412686) (xy 358.050513 -224.458781)
			(xy 358.038532 -224.5037) (xy 358.030018 -224.525332) (xy 358.020366 -224.548446) (xy 358.192832 -224.846896)
			(xy 358.21747 -224.850198) (xy 358.242819 -224.853984) (xy 358.292125 -224.86798) (xy 358.338917 -224.888897)
			(xy 358.382229 -224.916303) (xy 358.421166 -224.949633) (xy 358.454926 -224.988198) (xy 358.482811 -225.031202)
			(xy 358.504247 -225.077759) (xy 358.51879 -225.126907) (xy 358.52614 -225.177631) (xy 358.526588 -225.203258)
			(xy 358.52609 -225.229907) (xy 358.518147 -225.282611) (xy 358.502437 -225.333541) (xy 358.479311 -225.381562)
			(xy 358.449287 -225.425599) (xy 358.413035 -225.46467) (xy 358.371364 -225.497901) (xy 358.325206 -225.52455)
			(xy 358.275592 -225.544022) (xy 358.22363 -225.555882) (xy 358.17048 -225.559866) (xy 358.11733 -225.555882)
			(xy 358.065368 -225.544022) (xy 358.015754 -225.52455) (xy 357.969596 -225.497901) (xy 357.927925 -225.46467)
			(xy 357.891673 -225.425599) (xy 357.861649 -225.381562) (xy 357.838523 -225.333541) (xy 357.822813 -225.282611)
			(xy 357.81487 -225.229907) (xy 357.814372 -225.203258) (xy 357.814761 -225.180014) (xy 357.8208 -225.133918)
			(xy 357.832782 -225.089) (xy 357.841296 -225.067368) (xy 357.850948 -225.044254) (xy 357.678482 -224.745804)
			(xy 357.653844 -224.742502) (xy 357.628497 -224.738705) (xy 357.579191 -224.724711) (xy 357.532399 -224.703796)
			(xy 357.489087 -224.676391) (xy 357.450149 -224.643063) (xy 357.416389 -224.604499) (xy 357.388503 -224.561495)
			(xy 357.367068 -224.514939) (xy 357.352525 -224.465792) (xy 357.345174 -224.415069) (xy 357.344726 -224.389442)
			(xy 357.117142 -224.389442) (xy 357.116644 -224.416091) (xy 357.108701 -224.468795) (xy 357.092991 -224.519725)
			(xy 357.069865 -224.567746) (xy 357.039841 -224.611783) (xy 357.003589 -224.650854) (xy 356.961918 -224.684085)
			(xy 356.91576 -224.710734) (xy 356.866146 -224.730206) (xy 356.814184 -224.742066) (xy 356.761034 -224.74605)
			(xy 356.707884 -224.742066) (xy 356.655922 -224.730206) (xy 356.606308 -224.710734) (xy 356.56015 -224.684085)
			(xy 356.518479 -224.650854) (xy 356.482227 -224.611783) (xy 356.452203 -224.567746) (xy 356.429077 -224.519725)
			(xy 356.413367 -224.468795) (xy 356.405424 -224.416091) (xy 356.404926 -224.389442) (xy 356.177342 -224.389442)
			(xy 356.176952 -224.412686) (xy 356.170913 -224.458781) (xy 356.158932 -224.5037) (xy 356.150418 -224.525332)
			(xy 356.140766 -224.548446) (xy 356.313232 -224.846896) (xy 356.33787 -224.850198) (xy 356.363219 -224.853984)
			(xy 356.412525 -224.86798) (xy 356.459317 -224.888897) (xy 356.502629 -224.916303) (xy 356.541566 -224.949633)
			(xy 356.575326 -224.988198) (xy 356.603211 -225.031202) (xy 356.624647 -225.077759) (xy 356.63919 -225.126907)
			(xy 356.64654 -225.177631) (xy 356.646988 -225.203258) (xy 356.64649 -225.229907) (xy 356.87507 -225.229907)
			(xy 356.87507 -225.176609) (xy 356.883013 -225.123905) (xy 356.898723 -225.072975) (xy 356.921849 -225.024954)
			(xy 356.951873 -224.980917) (xy 356.988125 -224.941846) (xy 357.029796 -224.908615) (xy 357.075954 -224.881966)
			(xy 357.125568 -224.862494) (xy 357.17753 -224.850634) (xy 357.23068 -224.846651) (xy 357.28383 -224.850634)
			(xy 357.335792 -224.862494) (xy 357.385406 -224.881966) (xy 357.431564 -224.908615) (xy 357.473235 -224.941846)
			(xy 357.509487 -224.980917) (xy 357.539511 -225.024954) (xy 357.562637 -225.072975) (xy 357.578347 -225.123905)
			(xy 357.58629 -225.176609) (xy 357.586788 -225.203258) (xy 357.58629 -225.229907) (xy 357.578347 -225.282611)
			(xy 357.562637 -225.333541) (xy 357.539511 -225.381562) (xy 357.509487 -225.425599) (xy 357.473235 -225.46467)
			(xy 357.431564 -225.497901) (xy 357.385406 -225.52455) (xy 357.335792 -225.544022) (xy 357.28383 -225.555882)
			(xy 357.23068 -225.559866) (xy 357.17753 -225.555882) (xy 357.125568 -225.544022) (xy 357.075954 -225.52455)
			(xy 357.029796 -225.497901) (xy 356.988125 -225.46467) (xy 356.951873 -225.425599) (xy 356.921849 -225.381562)
			(xy 356.898723 -225.333541) (xy 356.883013 -225.282611) (xy 356.87507 -225.229907) (xy 356.64649 -225.229907)
			(xy 356.638547 -225.282611) (xy 356.622837 -225.333541) (xy 356.599711 -225.381562) (xy 356.569687 -225.425599)
			(xy 356.533435 -225.46467) (xy 356.491764 -225.497901) (xy 356.445606 -225.52455) (xy 356.395992 -225.544022)
			(xy 356.34403 -225.555882) (xy 356.29088 -225.559866) (xy 356.23773 -225.555882) (xy 356.185768 -225.544022)
			(xy 356.136154 -225.52455) (xy 356.089996 -225.497901) (xy 356.048325 -225.46467) (xy 356.012073 -225.425599)
			(xy 355.982049 -225.381562) (xy 355.958923 -225.333541) (xy 355.943213 -225.282611) (xy 355.93527 -225.229907)
			(xy 355.934772 -225.203258) (xy 355.935161 -225.180014) (xy 355.9412 -225.133918) (xy 355.953182 -225.089)
			(xy 355.961696 -225.067368) (xy 355.971348 -225.044254) (xy 355.798882 -224.745804) (xy 355.774244 -224.742502)
			(xy 355.748897 -224.738705) (xy 355.699591 -224.724711) (xy 355.652799 -224.703796) (xy 355.609487 -224.676391)
			(xy 355.570549 -224.643063) (xy 355.536789 -224.604499) (xy 355.508903 -224.561495) (xy 355.487468 -224.514939)
			(xy 355.472925 -224.465792) (xy 355.465574 -224.415069) (xy 355.465126 -224.389442) (xy 355.237542 -224.389442)
			(xy 355.237044 -224.416091) (xy 355.229101 -224.468795) (xy 355.213391 -224.519725) (xy 355.190265 -224.567746)
			(xy 355.160241 -224.611783) (xy 355.123989 -224.650854) (xy 355.082318 -224.684085) (xy 355.03616 -224.710734)
			(xy 354.986546 -224.730206) (xy 354.934584 -224.742066) (xy 354.881434 -224.74605) (xy 354.828284 -224.742066)
			(xy 354.776322 -224.730206) (xy 354.726708 -224.710734) (xy 354.68055 -224.684085) (xy 354.638879 -224.650854)
			(xy 354.602627 -224.611783) (xy 354.572603 -224.567746) (xy 354.549477 -224.519725) (xy 354.533767 -224.468795)
			(xy 354.525824 -224.416091) (xy 354.525326 -224.389442) (xy 354.297742 -224.389442) (xy 354.297352 -224.412686)
			(xy 354.291313 -224.458781) (xy 354.279332 -224.5037) (xy 354.270818 -224.525332) (xy 354.261166 -224.548446)
			(xy 354.433632 -224.846896) (xy 354.45827 -224.850198) (xy 354.483619 -224.853984) (xy 354.532925 -224.86798)
			(xy 354.579717 -224.888897) (xy 354.623029 -224.916303) (xy 354.661966 -224.949633) (xy 354.695726 -224.988198)
			(xy 354.723611 -225.031202) (xy 354.745047 -225.077759) (xy 354.75959 -225.126907) (xy 354.76694 -225.177631)
			(xy 354.767388 -225.203258) (xy 354.76689 -225.229907) (xy 354.99547 -225.229907) (xy 354.99547 -225.176609)
			(xy 355.003413 -225.123905) (xy 355.019123 -225.072975) (xy 355.042249 -225.024954) (xy 355.072273 -224.980917)
			(xy 355.108525 -224.941846) (xy 355.150196 -224.908615) (xy 355.196354 -224.881966) (xy 355.245968 -224.862494)
			(xy 355.29793 -224.850634) (xy 355.35108 -224.846651) (xy 355.40423 -224.850634) (xy 355.456192 -224.862494)
			(xy 355.505806 -224.881966) (xy 355.551964 -224.908615) (xy 355.593635 -224.941846) (xy 355.629887 -224.980917)
			(xy 355.659911 -225.024954) (xy 355.683037 -225.072975) (xy 355.698747 -225.123905) (xy 355.70669 -225.176609)
			(xy 355.707188 -225.203258) (xy 355.70669 -225.229907) (xy 355.698747 -225.282611) (xy 355.683037 -225.333541)
			(xy 355.659911 -225.381562) (xy 355.629887 -225.425599) (xy 355.593635 -225.46467) (xy 355.551964 -225.497901)
			(xy 355.505806 -225.52455) (xy 355.456192 -225.544022) (xy 355.40423 -225.555882) (xy 355.35108 -225.559866)
			(xy 355.29793 -225.555882) (xy 355.245968 -225.544022) (xy 355.196354 -225.52455) (xy 355.150196 -225.497901)
			(xy 355.108525 -225.46467) (xy 355.072273 -225.425599) (xy 355.042249 -225.381562) (xy 355.019123 -225.333541)
			(xy 355.003413 -225.282611) (xy 354.99547 -225.229907) (xy 354.76689 -225.229907) (xy 354.758947 -225.282611)
			(xy 354.743237 -225.333541) (xy 354.720111 -225.381562) (xy 354.690087 -225.425599) (xy 354.653835 -225.46467)
			(xy 354.612164 -225.497901) (xy 354.566006 -225.52455) (xy 354.516392 -225.544022) (xy 354.46443 -225.555882)
			(xy 354.41128 -225.559866) (xy 354.35813 -225.555882) (xy 354.306168 -225.544022) (xy 354.256554 -225.52455)
			(xy 354.210396 -225.497901) (xy 354.168725 -225.46467) (xy 354.132473 -225.425599) (xy 354.102449 -225.381562)
			(xy 354.079323 -225.333541) (xy 354.063613 -225.282611) (xy 354.05567 -225.229907) (xy 354.055172 -225.203258)
			(xy 354.055561 -225.180014) (xy 354.0616 -225.133918) (xy 354.073582 -225.089) (xy 354.082096 -225.067368)
			(xy 354.091748 -225.044254) (xy 353.919282 -224.745804) (xy 353.894644 -224.742502) (xy 353.869297 -224.738705)
			(xy 353.819991 -224.724711) (xy 353.773199 -224.703796) (xy 353.729887 -224.676391) (xy 353.690949 -224.643063)
			(xy 353.657189 -224.604499) (xy 353.629303 -224.561495) (xy 353.607868 -224.514939) (xy 353.593325 -224.465792)
			(xy 353.585974 -224.415069) (xy 353.585526 -224.389442) (xy 353.357942 -224.389442) (xy 353.357444 -224.416091)
			(xy 353.349501 -224.468795) (xy 353.333791 -224.519725) (xy 353.310665 -224.567746) (xy 353.280641 -224.611783)
			(xy 353.244389 -224.650854) (xy 353.202718 -224.684085) (xy 353.15656 -224.710734) (xy 353.106946 -224.730206)
			(xy 353.054984 -224.742066) (xy 353.001834 -224.74605) (xy 352.948684 -224.742066) (xy 352.896722 -224.730206)
			(xy 352.847108 -224.710734) (xy 352.80095 -224.684085) (xy 352.759279 -224.650854) (xy 352.723027 -224.611783)
			(xy 352.693003 -224.567746) (xy 352.669877 -224.519725) (xy 352.654167 -224.468795) (xy 352.646224 -224.416091)
			(xy 352.645726 -224.389442) (xy 352.418142 -224.389442) (xy 352.417752 -224.412686) (xy 352.411713 -224.458781)
			(xy 352.399732 -224.5037) (xy 352.391218 -224.525332) (xy 352.381566 -224.548446) (xy 352.554032 -224.846896)
			(xy 352.57867 -224.850198) (xy 352.604019 -224.853984) (xy 352.653325 -224.86798) (xy 352.700117 -224.888897)
			(xy 352.743429 -224.916303) (xy 352.782366 -224.949633) (xy 352.816126 -224.988198) (xy 352.844011 -225.031202)
			(xy 352.865447 -225.077759) (xy 352.87999 -225.126907) (xy 352.88734 -225.177631) (xy 352.887788 -225.203258)
			(xy 352.88729 -225.229907) (xy 353.11587 -225.229907) (xy 353.11587 -225.176609) (xy 353.123813 -225.123905)
			(xy 353.139523 -225.072975) (xy 353.162649 -225.024954) (xy 353.192673 -224.980917) (xy 353.228925 -224.941846)
			(xy 353.270596 -224.908615) (xy 353.316754 -224.881966) (xy 353.366368 -224.862494) (xy 353.41833 -224.850634)
			(xy 353.47148 -224.846651) (xy 353.52463 -224.850634) (xy 353.576592 -224.862494) (xy 353.626206 -224.881966)
			(xy 353.672364 -224.908615) (xy 353.714035 -224.941846) (xy 353.750287 -224.980917) (xy 353.780311 -225.024954)
			(xy 353.803437 -225.072975) (xy 353.819147 -225.123905) (xy 353.82709 -225.176609) (xy 353.827588 -225.203258)
			(xy 353.82709 -225.229907) (xy 353.819147 -225.282611) (xy 353.803437 -225.333541) (xy 353.780311 -225.381562)
			(xy 353.750287 -225.425599) (xy 353.714035 -225.46467) (xy 353.672364 -225.497901) (xy 353.626206 -225.52455)
			(xy 353.576592 -225.544022) (xy 353.52463 -225.555882) (xy 353.47148 -225.559866) (xy 353.41833 -225.555882)
			(xy 353.366368 -225.544022) (xy 353.316754 -225.52455) (xy 353.270596 -225.497901) (xy 353.228925 -225.46467)
			(xy 353.192673 -225.425599) (xy 353.162649 -225.381562) (xy 353.139523 -225.333541) (xy 353.123813 -225.282611)
			(xy 353.11587 -225.229907) (xy 352.88729 -225.229907) (xy 352.879347 -225.282611) (xy 352.863637 -225.333541)
			(xy 352.840511 -225.381562) (xy 352.810487 -225.425599) (xy 352.774235 -225.46467) (xy 352.732564 -225.497901)
			(xy 352.686406 -225.52455) (xy 352.636792 -225.544022) (xy 352.58483 -225.555882) (xy 352.53168 -225.559866)
			(xy 352.47853 -225.555882) (xy 352.426568 -225.544022) (xy 352.376954 -225.52455) (xy 352.330796 -225.497901)
			(xy 352.289125 -225.46467) (xy 352.252873 -225.425599) (xy 352.222849 -225.381562) (xy 352.199723 -225.333541)
			(xy 352.184013 -225.282611) (xy 352.17607 -225.229907) (xy 352.175572 -225.203258) (xy 352.175961 -225.180014)
			(xy 352.182 -225.133918) (xy 352.193982 -225.089) (xy 352.202496 -225.067368) (xy 352.212148 -225.044254)
			(xy 352.039682 -224.745804) (xy 352.015044 -224.742502) (xy 351.989697 -224.738705) (xy 351.940391 -224.724711)
			(xy 351.893599 -224.703796) (xy 351.850287 -224.676391) (xy 351.811349 -224.643063) (xy 351.777589 -224.604499)
			(xy 351.749703 -224.561495) (xy 351.728268 -224.514939) (xy 351.713725 -224.465792) (xy 351.706374 -224.415069)
			(xy 351.705926 -224.389442) (xy 351.478342 -224.389442) (xy 351.477844 -224.416091) (xy 351.469901 -224.468795)
			(xy 351.454191 -224.519725) (xy 351.431065 -224.567746) (xy 351.401041 -224.611783) (xy 351.364789 -224.650854)
			(xy 351.323118 -224.684085) (xy 351.27696 -224.710734) (xy 351.227346 -224.730206) (xy 351.175384 -224.742066)
			(xy 351.122234 -224.74605) (xy 351.069084 -224.742066) (xy 351.017122 -224.730206) (xy 350.967508 -224.710734)
			(xy 350.92135 -224.684085) (xy 350.879679 -224.650854) (xy 350.843427 -224.611783) (xy 350.813403 -224.567746)
			(xy 350.790277 -224.519725) (xy 350.774567 -224.468795) (xy 350.766624 -224.416091) (xy 350.766126 -224.389442)
			(xy 350.538542 -224.389442) (xy 350.538152 -224.412686) (xy 350.532113 -224.458781) (xy 350.520132 -224.5037)
			(xy 350.511618 -224.525332) (xy 350.501966 -224.548446) (xy 350.674432 -224.846896) (xy 350.69907 -224.850198)
			(xy 350.724419 -224.853984) (xy 350.773725 -224.86798) (xy 350.820517 -224.888897) (xy 350.863829 -224.916303)
			(xy 350.902766 -224.949633) (xy 350.936526 -224.988198) (xy 350.964411 -225.031202) (xy 350.985847 -225.077759)
			(xy 351.00039 -225.126907) (xy 351.00774 -225.177631) (xy 351.008188 -225.203258) (xy 351.00769 -225.229907)
			(xy 351.23627 -225.229907) (xy 351.23627 -225.176609) (xy 351.244213 -225.123905) (xy 351.259923 -225.072975)
			(xy 351.283049 -225.024954) (xy 351.313073 -224.980917) (xy 351.349325 -224.941846) (xy 351.390996 -224.908615)
			(xy 351.437154 -224.881966) (xy 351.486768 -224.862494) (xy 351.53873 -224.850634) (xy 351.59188 -224.846651)
			(xy 351.64503 -224.850634) (xy 351.696992 -224.862494) (xy 351.746606 -224.881966) (xy 351.792764 -224.908615)
			(xy 351.834435 -224.941846) (xy 351.870687 -224.980917) (xy 351.900711 -225.024954) (xy 351.923837 -225.072975)
			(xy 351.939547 -225.123905) (xy 351.94749 -225.176609) (xy 351.947988 -225.203258) (xy 351.94749 -225.229907)
			(xy 351.939547 -225.282611) (xy 351.923837 -225.333541) (xy 351.900711 -225.381562) (xy 351.870687 -225.425599)
			(xy 351.834435 -225.46467) (xy 351.792764 -225.497901) (xy 351.746606 -225.52455) (xy 351.696992 -225.544022)
			(xy 351.64503 -225.555882) (xy 351.59188 -225.559866) (xy 351.53873 -225.555882) (xy 351.486768 -225.544022)
			(xy 351.437154 -225.52455) (xy 351.390996 -225.497901) (xy 351.349325 -225.46467) (xy 351.313073 -225.425599)
			(xy 351.283049 -225.381562) (xy 351.259923 -225.333541) (xy 351.244213 -225.282611) (xy 351.23627 -225.229907)
			(xy 351.00769 -225.229907) (xy 350.999747 -225.282611) (xy 350.984037 -225.333541) (xy 350.960911 -225.381562)
			(xy 350.930887 -225.425599) (xy 350.894635 -225.46467) (xy 350.852964 -225.497901) (xy 350.806806 -225.52455)
			(xy 350.757192 -225.544022) (xy 350.70523 -225.555882) (xy 350.65208 -225.559866) (xy 350.59893 -225.555882)
			(xy 350.546968 -225.544022) (xy 350.497354 -225.52455) (xy 350.451196 -225.497901) (xy 350.409525 -225.46467)
			(xy 350.373273 -225.425599) (xy 350.343249 -225.381562) (xy 350.320123 -225.333541) (xy 350.304413 -225.282611)
			(xy 350.29647 -225.229907) (xy 350.295972 -225.203258) (xy 350.296361 -225.180014) (xy 350.3024 -225.133918)
			(xy 350.314382 -225.089) (xy 350.322896 -225.067368) (xy 350.332548 -225.044254) (xy 350.160082 -224.745804)
			(xy 350.135444 -224.742502) (xy 350.110097 -224.738705) (xy 350.060791 -224.724711) (xy 350.013999 -224.703796)
			(xy 349.970687 -224.676391) (xy 349.931749 -224.643063) (xy 349.897989 -224.604499) (xy 349.870103 -224.561495)
			(xy 349.848668 -224.514939) (xy 349.834125 -224.465792) (xy 349.826774 -224.415069) (xy 349.826326 -224.389442)
			(xy 349.598742 -224.389442) (xy 349.598244 -224.416091) (xy 349.590301 -224.468795) (xy 349.574591 -224.519725)
			(xy 349.551465 -224.567746) (xy 349.521441 -224.611783) (xy 349.485189 -224.650854) (xy 349.443518 -224.684085)
			(xy 349.39736 -224.710734) (xy 349.347746 -224.730206) (xy 349.295784 -224.742066) (xy 349.242634 -224.74605)
			(xy 349.189484 -224.742066) (xy 349.137522 -224.730206) (xy 349.087908 -224.710734) (xy 349.04175 -224.684085)
			(xy 349.000079 -224.650854) (xy 348.963827 -224.611783) (xy 348.933803 -224.567746) (xy 348.910677 -224.519725)
			(xy 348.894967 -224.468795) (xy 348.887024 -224.416091) (xy 348.886526 -224.389442) (xy 348.886975 -224.363816)
			(xy 348.894328 -224.313094) (xy 348.908872 -224.263949) (xy 348.930309 -224.217395) (xy 348.958195 -224.174393)
			(xy 348.991955 -224.135831) (xy 349.030893 -224.102505) (xy 349.074204 -224.075102) (xy 349.120995 -224.054188)
			(xy 349.1703 -224.040194) (xy 349.195644 -224.036382) (xy 349.220282 -224.03308) (xy 349.27286 -223.942148)
			(xy 349.277812 -223.932651) (xy 349.280071 -223.911369) (xy 349.273474 -223.89101) (xy 349.259165 -223.875096)
			(xy 349.239618 -223.866381) (xy 349.228918 -223.865948) (xy 348.978982 -223.865948) (xy 348.956257 -223.881464)
			(xy 348.907034 -223.906052) (xy 348.854614 -223.922776) (xy 348.800246 -223.931239) (xy 348.745222 -223.931239)
			(xy 348.690854 -223.922776) (xy 348.638434 -223.906052) (xy 348.589211 -223.881464) (xy 348.566486 -223.865948)
			(xy 348.038928 -223.865948) (xy 348.015103 -223.882185) (xy 347.963339 -223.907571) (xy 347.908168 -223.924307)
			(xy 347.87967 -223.928686) (xy 347.854778 -223.931988) (xy 347.682566 -224.230438) (xy 347.692218 -224.253552)
			(xy 347.700733 -224.275184) (xy 347.712716 -224.320102) (xy 347.718757 -224.366197) (xy 347.719142 -224.389442)
			(xy 347.946726 -224.389442) (xy 347.947224 -224.362793) (xy 347.955167 -224.310089) (xy 347.970877 -224.259159)
			(xy 347.994003 -224.211138) (xy 348.024027 -224.167101) (xy 348.060279 -224.12803) (xy 348.10195 -224.094799)
			(xy 348.148108 -224.06815) (xy 348.197722 -224.048678) (xy 348.249684 -224.036818) (xy 348.302834 -224.032835)
			(xy 348.355984 -224.036818) (xy 348.407946 -224.048678) (xy 348.45756 -224.06815) (xy 348.503718 -224.094799)
			(xy 348.545389 -224.12803) (xy 348.581641 -224.167101) (xy 348.611665 -224.211138) (xy 348.634791 -224.259159)
			(xy 348.650501 -224.310089) (xy 348.658444 -224.362793) (xy 348.658942 -224.389442) (xy 348.658552 -224.412686)
			(xy 348.652513 -224.458781) (xy 348.640532 -224.5037) (xy 348.632018 -224.525332) (xy 348.622366 -224.548446)
			(xy 348.794832 -224.846896) (xy 348.81947 -224.850198) (xy 348.844819 -224.853984) (xy 348.894125 -224.86798)
			(xy 348.940917 -224.888897) (xy 348.984229 -224.916303) (xy 349.023166 -224.949633) (xy 349.056926 -224.988198)
			(xy 349.084811 -225.031202) (xy 349.106247 -225.077759) (xy 349.12079 -225.126907) (xy 349.12814 -225.177631)
			(xy 349.128588 -225.203258) (xy 349.12809 -225.229907) (xy 349.35667 -225.229907) (xy 349.35667 -225.176609)
			(xy 349.364613 -225.123905) (xy 349.380323 -225.072975) (xy 349.403449 -225.024954) (xy 349.433473 -224.980917)
			(xy 349.469725 -224.941846) (xy 349.511396 -224.908615) (xy 349.557554 -224.881966) (xy 349.607168 -224.862494)
			(xy 349.65913 -224.850634) (xy 349.71228 -224.846651) (xy 349.76543 -224.850634) (xy 349.817392 -224.862494)
			(xy 349.867006 -224.881966) (xy 349.913164 -224.908615) (xy 349.954835 -224.941846) (xy 349.991087 -224.980917)
			(xy 350.021111 -225.024954) (xy 350.044237 -225.072975) (xy 350.059947 -225.123905) (xy 350.06789 -225.176609)
			(xy 350.068388 -225.203258) (xy 350.06789 -225.229907) (xy 350.059947 -225.282611) (xy 350.044237 -225.333541)
			(xy 350.021111 -225.381562) (xy 349.991087 -225.425599) (xy 349.954835 -225.46467) (xy 349.913164 -225.497901)
			(xy 349.867006 -225.52455) (xy 349.817392 -225.544022) (xy 349.76543 -225.555882) (xy 349.71228 -225.559866)
			(xy 349.65913 -225.555882) (xy 349.607168 -225.544022) (xy 349.557554 -225.52455) (xy 349.511396 -225.497901)
			(xy 349.469725 -225.46467) (xy 349.433473 -225.425599) (xy 349.403449 -225.381562) (xy 349.380323 -225.333541)
			(xy 349.364613 -225.282611) (xy 349.35667 -225.229907) (xy 349.12809 -225.229907) (xy 349.120147 -225.282611)
			(xy 349.104437 -225.333541) (xy 349.081311 -225.381562) (xy 349.051287 -225.425599) (xy 349.015035 -225.46467)
			(xy 348.973364 -225.497901) (xy 348.927206 -225.52455) (xy 348.877592 -225.544022) (xy 348.82563 -225.555882)
			(xy 348.77248 -225.559866) (xy 348.71933 -225.555882) (xy 348.667368 -225.544022) (xy 348.617754 -225.52455)
			(xy 348.571596 -225.497901) (xy 348.529925 -225.46467) (xy 348.493673 -225.425599) (xy 348.463649 -225.381562)
			(xy 348.440523 -225.333541) (xy 348.424813 -225.282611) (xy 348.41687 -225.229907) (xy 348.416372 -225.203258)
			(xy 348.416761 -225.180014) (xy 348.4228 -225.133918) (xy 348.434782 -225.089) (xy 348.443296 -225.067368)
			(xy 348.452948 -225.044254) (xy 348.280482 -224.745804) (xy 348.255844 -224.742502) (xy 348.230497 -224.738705)
			(xy 348.181191 -224.724711) (xy 348.134399 -224.703796) (xy 348.091087 -224.676391) (xy 348.052149 -224.643063)
			(xy 348.018389 -224.604499) (xy 347.990503 -224.561495) (xy 347.969068 -224.514939) (xy 347.954525 -224.465792)
			(xy 347.947174 -224.415069) (xy 347.946726 -224.389442) (xy 347.719142 -224.389442) (xy 347.718644 -224.416091)
			(xy 347.710701 -224.468795) (xy 347.694991 -224.519725) (xy 347.671865 -224.567746) (xy 347.641841 -224.611783)
			(xy 347.605589 -224.650854) (xy 347.563918 -224.684085) (xy 347.51776 -224.710734) (xy 347.468146 -224.730206)
			(xy 347.416184 -224.742066) (xy 347.363034 -224.74605) (xy 347.309884 -224.742066) (xy 347.257922 -224.730206)
			(xy 347.208308 -224.710734) (xy 347.16215 -224.684085) (xy 347.120479 -224.650854) (xy 347.084227 -224.611783)
			(xy 347.054203 -224.567746) (xy 347.031077 -224.519725) (xy 347.015367 -224.468795) (xy 347.007424 -224.416091)
			(xy 347.006926 -224.389442) (xy 347.007375 -224.363816) (xy 347.014728 -224.313094) (xy 347.029272 -224.263949)
			(xy 347.050709 -224.217395) (xy 347.078595 -224.174393) (xy 347.112355 -224.135831) (xy 347.151293 -224.102505)
			(xy 347.194604 -224.075102) (xy 347.241395 -224.054188) (xy 347.2907 -224.040194) (xy 347.316044 -224.036382)
			(xy 347.340682 -224.03308) (xy 347.39326 -223.942148) (xy 347.398212 -223.932651) (xy 347.400471 -223.911369)
			(xy 347.393874 -223.89101) (xy 347.379565 -223.875096) (xy 347.360018 -223.866381) (xy 347.349318 -223.865948)
			(xy 347.099382 -223.865948) (xy 347.076657 -223.881464) (xy 347.027434 -223.906052) (xy 346.975014 -223.922776)
			(xy 346.920646 -223.931239) (xy 346.865622 -223.931239) (xy 346.811254 -223.922776) (xy 346.758834 -223.906052)
			(xy 346.709611 -223.881464) (xy 346.686886 -223.865948) (xy 346.159328 -223.865948) (xy 346.135503 -223.882185)
			(xy 346.083739 -223.907571) (xy 346.028568 -223.924307) (xy 346.00007 -223.928686) (xy 345.975178 -223.931988)
			(xy 345.802966 -224.230438) (xy 345.812618 -224.253552) (xy 345.821133 -224.275184) (xy 345.833116 -224.320102)
			(xy 345.839157 -224.366197) (xy 345.839542 -224.389442) (xy 346.067126 -224.389442) (xy 346.067624 -224.362793)
			(xy 346.075567 -224.310089) (xy 346.091277 -224.259159) (xy 346.114403 -224.211138) (xy 346.144427 -224.167101)
			(xy 346.180679 -224.12803) (xy 346.22235 -224.094799) (xy 346.268508 -224.06815) (xy 346.318122 -224.048678)
			(xy 346.370084 -224.036818) (xy 346.423234 -224.032835) (xy 346.476384 -224.036818) (xy 346.528346 -224.048678)
			(xy 346.57796 -224.06815) (xy 346.624118 -224.094799) (xy 346.665789 -224.12803) (xy 346.702041 -224.167101)
			(xy 346.732065 -224.211138) (xy 346.755191 -224.259159) (xy 346.770901 -224.310089) (xy 346.778844 -224.362793)
			(xy 346.779342 -224.389442) (xy 346.778952 -224.412686) (xy 346.772913 -224.458781) (xy 346.760932 -224.5037)
			(xy 346.752418 -224.525332) (xy 346.742766 -224.548446) (xy 346.915232 -224.846896) (xy 346.93987 -224.850198)
			(xy 346.965219 -224.853984) (xy 347.014525 -224.86798) (xy 347.061317 -224.888897) (xy 347.104629 -224.916303)
			(xy 347.143566 -224.949633) (xy 347.177326 -224.988198) (xy 347.205211 -225.031202) (xy 347.226647 -225.077759)
			(xy 347.24119 -225.126907) (xy 347.24854 -225.177631) (xy 347.248988 -225.203258) (xy 347.24849 -225.229907)
			(xy 347.47707 -225.229907) (xy 347.47707 -225.176609) (xy 347.485013 -225.123905) (xy 347.500723 -225.072975)
			(xy 347.523849 -225.024954) (xy 347.553873 -224.980917) (xy 347.590125 -224.941846) (xy 347.631796 -224.908615)
			(xy 347.677954 -224.881966) (xy 347.727568 -224.862494) (xy 347.77953 -224.850634) (xy 347.83268 -224.846651)
			(xy 347.88583 -224.850634) (xy 347.937792 -224.862494) (xy 347.987406 -224.881966) (xy 348.033564 -224.908615)
			(xy 348.075235 -224.941846) (xy 348.111487 -224.980917) (xy 348.141511 -225.024954) (xy 348.164637 -225.072975)
			(xy 348.180347 -225.123905) (xy 348.18829 -225.176609) (xy 348.188788 -225.203258) (xy 348.18829 -225.229907)
			(xy 348.180347 -225.282611) (xy 348.164637 -225.333541) (xy 348.141511 -225.381562) (xy 348.111487 -225.425599)
			(xy 348.075235 -225.46467) (xy 348.033564 -225.497901) (xy 347.987406 -225.52455) (xy 347.937792 -225.544022)
			(xy 347.88583 -225.555882) (xy 347.83268 -225.559866) (xy 347.77953 -225.555882) (xy 347.727568 -225.544022)
			(xy 347.677954 -225.52455) (xy 347.631796 -225.497901) (xy 347.590125 -225.46467) (xy 347.553873 -225.425599)
			(xy 347.523849 -225.381562) (xy 347.500723 -225.333541) (xy 347.485013 -225.282611) (xy 347.47707 -225.229907)
			(xy 347.24849 -225.229907) (xy 347.240547 -225.282611) (xy 347.224837 -225.333541) (xy 347.201711 -225.381562)
			(xy 347.171687 -225.425599) (xy 347.135435 -225.46467) (xy 347.093764 -225.497901) (xy 347.047606 -225.52455)
			(xy 346.997992 -225.544022) (xy 346.94603 -225.555882) (xy 346.89288 -225.559866) (xy 346.83973 -225.555882)
			(xy 346.787768 -225.544022) (xy 346.738154 -225.52455) (xy 346.691996 -225.497901) (xy 346.650325 -225.46467)
			(xy 346.614073 -225.425599) (xy 346.584049 -225.381562) (xy 346.560923 -225.333541) (xy 346.545213 -225.282611)
			(xy 346.53727 -225.229907) (xy 346.536772 -225.203258) (xy 346.537161 -225.180014) (xy 346.5432 -225.133918)
			(xy 346.555182 -225.089) (xy 346.563696 -225.067368) (xy 346.573348 -225.044254) (xy 346.400882 -224.745804)
			(xy 346.376244 -224.742502) (xy 346.350897 -224.738705) (xy 346.301591 -224.724711) (xy 346.254799 -224.703796)
			(xy 346.211487 -224.676391) (xy 346.172549 -224.643063) (xy 346.138789 -224.604499) (xy 346.110903 -224.561495)
			(xy 346.089468 -224.514939) (xy 346.074925 -224.465792) (xy 346.067574 -224.415069) (xy 346.067126 -224.389442)
			(xy 345.839542 -224.389442) (xy 345.839044 -224.416091) (xy 345.831101 -224.468795) (xy 345.815391 -224.519725)
			(xy 345.792265 -224.567746) (xy 345.762241 -224.611783) (xy 345.725989 -224.650854) (xy 345.684318 -224.684085)
			(xy 345.63816 -224.710734) (xy 345.588546 -224.730206) (xy 345.536584 -224.742066) (xy 345.483434 -224.74605)
			(xy 345.430284 -224.742066) (xy 345.378322 -224.730206) (xy 345.328708 -224.710734) (xy 345.28255 -224.684085)
			(xy 345.240879 -224.650854) (xy 345.204627 -224.611783) (xy 345.174603 -224.567746) (xy 345.151477 -224.519725)
			(xy 345.135767 -224.468795) (xy 345.127824 -224.416091) (xy 345.127326 -224.389442) (xy 345.127775 -224.363816)
			(xy 345.135128 -224.313094) (xy 345.149672 -224.263949) (xy 345.171109 -224.217395) (xy 345.198995 -224.174393)
			(xy 345.232755 -224.135831) (xy 345.271693 -224.102505) (xy 345.315004 -224.075102) (xy 345.361795 -224.054188)
			(xy 345.4111 -224.040194) (xy 345.436444 -224.036382) (xy 345.461082 -224.03308) (xy 345.51366 -223.942148)
			(xy 345.518612 -223.932651) (xy 345.520871 -223.911369) (xy 345.514274 -223.89101) (xy 345.499965 -223.875096)
			(xy 345.480418 -223.866381) (xy 345.469718 -223.865948) (xy 345.219782 -223.865948) (xy 345.197057 -223.881464)
			(xy 345.147834 -223.906052) (xy 345.095414 -223.922776) (xy 345.041046 -223.931239) (xy 344.986022 -223.931239)
			(xy 344.931654 -223.922776) (xy 344.879234 -223.906052) (xy 344.830011 -223.881464) (xy 344.807286 -223.865948)
			(xy 344.279728 -223.865948) (xy 344.255903 -223.882185) (xy 344.204139 -223.907571) (xy 344.148968 -223.924307)
			(xy 344.12047 -223.928686) (xy 344.095578 -223.931988) (xy 343.923366 -224.230438) (xy 343.933018 -224.253552)
			(xy 343.941533 -224.275184) (xy 343.953516 -224.320102) (xy 343.959557 -224.366197) (xy 343.959942 -224.389442)
			(xy 344.187526 -224.389442) (xy 344.188024 -224.362793) (xy 344.195967 -224.310089) (xy 344.211677 -224.259159)
			(xy 344.234803 -224.211138) (xy 344.264827 -224.167101) (xy 344.301079 -224.12803) (xy 344.34275 -224.094799)
			(xy 344.388908 -224.06815) (xy 344.438522 -224.048678) (xy 344.490484 -224.036818) (xy 344.543634 -224.032835)
			(xy 344.596784 -224.036818) (xy 344.648746 -224.048678) (xy 344.69836 -224.06815) (xy 344.744518 -224.094799)
			(xy 344.786189 -224.12803) (xy 344.822441 -224.167101) (xy 344.852465 -224.211138) (xy 344.875591 -224.259159)
			(xy 344.891301 -224.310089) (xy 344.899244 -224.362793) (xy 344.899742 -224.389442) (xy 344.899352 -224.412686)
			(xy 344.893313 -224.458781) (xy 344.881332 -224.5037) (xy 344.872818 -224.525332) (xy 344.863166 -224.548446)
			(xy 345.035632 -224.846896) (xy 345.06027 -224.850198) (xy 345.085619 -224.853984) (xy 345.134925 -224.86798)
			(xy 345.181717 -224.888897) (xy 345.225029 -224.916303) (xy 345.263966 -224.949633) (xy 345.297726 -224.988198)
			(xy 345.325611 -225.031202) (xy 345.347047 -225.077759) (xy 345.36159 -225.126907) (xy 345.36894 -225.177631)
			(xy 345.369388 -225.203258) (xy 345.36889 -225.229907) (xy 345.59747 -225.229907) (xy 345.59747 -225.176609)
			(xy 345.605413 -225.123905) (xy 345.621123 -225.072975) (xy 345.644249 -225.024954) (xy 345.674273 -224.980917)
			(xy 345.710525 -224.941846) (xy 345.752196 -224.908615) (xy 345.798354 -224.881966) (xy 345.847968 -224.862494)
			(xy 345.89993 -224.850634) (xy 345.95308 -224.846651) (xy 346.00623 -224.850634) (xy 346.058192 -224.862494)
			(xy 346.107806 -224.881966) (xy 346.153964 -224.908615) (xy 346.195635 -224.941846) (xy 346.231887 -224.980917)
			(xy 346.261911 -225.024954) (xy 346.285037 -225.072975) (xy 346.300747 -225.123905) (xy 346.30869 -225.176609)
			(xy 346.309188 -225.203258) (xy 346.30869 -225.229907) (xy 346.300747 -225.282611) (xy 346.285037 -225.333541)
			(xy 346.261911 -225.381562) (xy 346.231887 -225.425599) (xy 346.195635 -225.46467) (xy 346.153964 -225.497901)
			(xy 346.107806 -225.52455) (xy 346.058192 -225.544022) (xy 346.00623 -225.555882) (xy 345.95308 -225.559866)
			(xy 345.89993 -225.555882) (xy 345.847968 -225.544022) (xy 345.798354 -225.52455) (xy 345.752196 -225.497901)
			(xy 345.710525 -225.46467) (xy 345.674273 -225.425599) (xy 345.644249 -225.381562) (xy 345.621123 -225.333541)
			(xy 345.605413 -225.282611) (xy 345.59747 -225.229907) (xy 345.36889 -225.229907) (xy 345.360947 -225.282611)
			(xy 345.345237 -225.333541) (xy 345.322111 -225.381562) (xy 345.292087 -225.425599) (xy 345.255835 -225.46467)
			(xy 345.214164 -225.497901) (xy 345.168006 -225.52455) (xy 345.118392 -225.544022) (xy 345.06643 -225.555882)
			(xy 345.01328 -225.559866) (xy 344.96013 -225.555882) (xy 344.908168 -225.544022) (xy 344.858554 -225.52455)
			(xy 344.812396 -225.497901) (xy 344.770725 -225.46467) (xy 344.734473 -225.425599) (xy 344.704449 -225.381562)
			(xy 344.681323 -225.333541) (xy 344.665613 -225.282611) (xy 344.65767 -225.229907) (xy 344.657172 -225.203258)
			(xy 344.657561 -225.180014) (xy 344.6636 -225.133918) (xy 344.675582 -225.089) (xy 344.684096 -225.067368)
			(xy 344.693748 -225.044254) (xy 344.521282 -224.745804) (xy 344.496644 -224.742502) (xy 344.471297 -224.738705)
			(xy 344.421991 -224.724711) (xy 344.375199 -224.703796) (xy 344.331887 -224.676391) (xy 344.292949 -224.643063)
			(xy 344.259189 -224.604499) (xy 344.231303 -224.561495) (xy 344.209868 -224.514939) (xy 344.195325 -224.465792)
			(xy 344.187974 -224.415069) (xy 344.187526 -224.389442) (xy 343.959942 -224.389442) (xy 343.959444 -224.416091)
			(xy 343.951501 -224.468795) (xy 343.935791 -224.519725) (xy 343.912665 -224.567746) (xy 343.882641 -224.611783)
			(xy 343.846389 -224.650854) (xy 343.804718 -224.684085) (xy 343.75856 -224.710734) (xy 343.708946 -224.730206)
			(xy 343.656984 -224.742066) (xy 343.603834 -224.74605) (xy 343.550684 -224.742066) (xy 343.498722 -224.730206)
			(xy 343.449108 -224.710734) (xy 343.40295 -224.684085) (xy 343.361279 -224.650854) (xy 343.325027 -224.611783)
			(xy 343.295003 -224.567746) (xy 343.271877 -224.519725) (xy 343.256167 -224.468795) (xy 343.248224 -224.416091)
			(xy 343.247726 -224.389442) (xy 343.248175 -224.363816) (xy 343.255528 -224.313094) (xy 343.270072 -224.263949)
			(xy 343.291509 -224.217395) (xy 343.319395 -224.174393) (xy 343.353155 -224.135831) (xy 343.392093 -224.102505)
			(xy 343.435404 -224.075102) (xy 343.482195 -224.054188) (xy 343.5315 -224.040194) (xy 343.556844 -224.036382)
			(xy 343.581482 -224.03308) (xy 343.63406 -223.942148) (xy 343.639012 -223.932651) (xy 343.641271 -223.911369)
			(xy 343.634674 -223.89101) (xy 343.620365 -223.875096) (xy 343.600818 -223.866381) (xy 343.590118 -223.865948)
			(xy 343.340182 -223.865948) (xy 343.317457 -223.881464) (xy 343.268234 -223.906052) (xy 343.215814 -223.922776)
			(xy 343.161446 -223.931239) (xy 343.106422 -223.931239) (xy 343.052054 -223.922776) (xy 342.999634 -223.906052)
			(xy 342.950411 -223.881464) (xy 342.927686 -223.865948) (xy 342.400128 -223.865948) (xy 342.376303 -223.882185)
			(xy 342.324539 -223.907571) (xy 342.269368 -223.924307) (xy 342.24087 -223.928686) (xy 342.215978 -223.931988)
			(xy 342.043766 -224.230438) (xy 342.053418 -224.253552) (xy 342.061933 -224.275184) (xy 342.073916 -224.320102)
			(xy 342.079957 -224.366197) (xy 342.080342 -224.389442) (xy 342.307926 -224.389442) (xy 342.308424 -224.362793)
			(xy 342.316367 -224.310089) (xy 342.332077 -224.259159) (xy 342.355203 -224.211138) (xy 342.385227 -224.167101)
			(xy 342.421479 -224.12803) (xy 342.46315 -224.094799) (xy 342.509308 -224.06815) (xy 342.558922 -224.048678)
			(xy 342.610884 -224.036818) (xy 342.664034 -224.032835) (xy 342.717184 -224.036818) (xy 342.769146 -224.048678)
			(xy 342.81876 -224.06815) (xy 342.864918 -224.094799) (xy 342.906589 -224.12803) (xy 342.942841 -224.167101)
			(xy 342.972865 -224.211138) (xy 342.995991 -224.259159) (xy 343.011701 -224.310089) (xy 343.019644 -224.362793)
			(xy 343.020142 -224.389442) (xy 343.019752 -224.412686) (xy 343.013713 -224.458781) (xy 343.001732 -224.5037)
			(xy 342.993218 -224.525332) (xy 342.983566 -224.548446) (xy 343.156032 -224.846896) (xy 343.18067 -224.850198)
			(xy 343.206019 -224.853984) (xy 343.255325 -224.86798) (xy 343.302117 -224.888897) (xy 343.345429 -224.916303)
			(xy 343.384366 -224.949633) (xy 343.418126 -224.988198) (xy 343.446011 -225.031202) (xy 343.467447 -225.077759)
			(xy 343.48199 -225.126907) (xy 343.48934 -225.177631) (xy 343.489788 -225.203258) (xy 343.48929 -225.229907)
			(xy 343.71787 -225.229907) (xy 343.71787 -225.176609) (xy 343.725813 -225.123905) (xy 343.741523 -225.072975)
			(xy 343.764649 -225.024954) (xy 343.794673 -224.980917) (xy 343.830925 -224.941846) (xy 343.872596 -224.908615)
			(xy 343.918754 -224.881966) (xy 343.968368 -224.862494) (xy 344.02033 -224.850634) (xy 344.07348 -224.846651)
			(xy 344.12663 -224.850634) (xy 344.178592 -224.862494) (xy 344.228206 -224.881966) (xy 344.274364 -224.908615)
			(xy 344.316035 -224.941846) (xy 344.352287 -224.980917) (xy 344.382311 -225.024954) (xy 344.405437 -225.072975)
			(xy 344.421147 -225.123905) (xy 344.42909 -225.176609) (xy 344.429588 -225.203258) (xy 344.42909 -225.229907)
			(xy 344.421147 -225.282611) (xy 344.405437 -225.333541) (xy 344.382311 -225.381562) (xy 344.352287 -225.425599)
			(xy 344.316035 -225.46467) (xy 344.274364 -225.497901) (xy 344.228206 -225.52455) (xy 344.178592 -225.544022)
			(xy 344.12663 -225.555882) (xy 344.07348 -225.559866) (xy 344.02033 -225.555882) (xy 343.968368 -225.544022)
			(xy 343.918754 -225.52455) (xy 343.872596 -225.497901) (xy 343.830925 -225.46467) (xy 343.794673 -225.425599)
			(xy 343.764649 -225.381562) (xy 343.741523 -225.333541) (xy 343.725813 -225.282611) (xy 343.71787 -225.229907)
			(xy 343.48929 -225.229907) (xy 343.481347 -225.282611) (xy 343.465637 -225.333541) (xy 343.442511 -225.381562)
			(xy 343.412487 -225.425599) (xy 343.376235 -225.46467) (xy 343.334564 -225.497901) (xy 343.288406 -225.52455)
			(xy 343.238792 -225.544022) (xy 343.18683 -225.555882) (xy 343.13368 -225.559866) (xy 343.08053 -225.555882)
			(xy 343.028568 -225.544022) (xy 342.978954 -225.52455) (xy 342.932796 -225.497901) (xy 342.891125 -225.46467)
			(xy 342.854873 -225.425599) (xy 342.824849 -225.381562) (xy 342.801723 -225.333541) (xy 342.786013 -225.282611)
			(xy 342.77807 -225.229907) (xy 342.777572 -225.203258) (xy 342.777961 -225.180014) (xy 342.784 -225.133918)
			(xy 342.795982 -225.089) (xy 342.804496 -225.067368) (xy 342.814148 -225.044254) (xy 342.641682 -224.745804)
			(xy 342.617044 -224.742502) (xy 342.591697 -224.738705) (xy 342.542391 -224.724711) (xy 342.495599 -224.703796)
			(xy 342.452287 -224.676391) (xy 342.413349 -224.643063) (xy 342.379589 -224.604499) (xy 342.351703 -224.561495)
			(xy 342.330268 -224.514939) (xy 342.315725 -224.465792) (xy 342.308374 -224.415069) (xy 342.307926 -224.389442)
			(xy 342.080342 -224.389442) (xy 342.079844 -224.416091) (xy 342.071901 -224.468795) (xy 342.056191 -224.519725)
			(xy 342.033065 -224.567746) (xy 342.003041 -224.611783) (xy 341.966789 -224.650854) (xy 341.925118 -224.684085)
			(xy 341.87896 -224.710734) (xy 341.829346 -224.730206) (xy 341.777384 -224.742066) (xy 341.724234 -224.74605)
			(xy 341.671084 -224.742066) (xy 341.619122 -224.730206) (xy 341.569508 -224.710734) (xy 341.52335 -224.684085)
			(xy 341.481679 -224.650854) (xy 341.445427 -224.611783) (xy 341.415403 -224.567746) (xy 341.392277 -224.519725)
			(xy 341.376567 -224.468795) (xy 341.368624 -224.416091) (xy 341.368126 -224.389442) (xy 341.368575 -224.363816)
			(xy 341.375928 -224.313094) (xy 341.390472 -224.263949) (xy 341.411909 -224.217395) (xy 341.439795 -224.174393)
			(xy 341.473555 -224.135831) (xy 341.512493 -224.102505) (xy 341.555804 -224.075102) (xy 341.602595 -224.054188)
			(xy 341.6519 -224.040194) (xy 341.677244 -224.036382) (xy 341.701882 -224.03308) (xy 341.75446 -223.942148)
			(xy 341.759412 -223.932651) (xy 341.761671 -223.911369) (xy 341.755074 -223.89101) (xy 341.740765 -223.875096)
			(xy 341.721218 -223.866381) (xy 341.710518 -223.865948) (xy 341.460582 -223.865948) (xy 341.437857 -223.881464)
			(xy 341.388634 -223.906052) (xy 341.336214 -223.922776) (xy 341.281846 -223.931239) (xy 341.226822 -223.931239)
			(xy 341.172454 -223.922776) (xy 341.120034 -223.906052) (xy 341.070811 -223.881464) (xy 341.048086 -223.865948)
			(xy 340.520528 -223.865948) (xy 340.496703 -223.882185) (xy 340.444939 -223.907571) (xy 340.389768 -223.924307)
			(xy 340.36127 -223.928686) (xy 340.336632 -223.931988) (xy 340.164166 -224.230438) (xy 340.173818 -224.253552)
			(xy 340.182333 -224.275184) (xy 340.194316 -224.320102) (xy 340.200357 -224.366197) (xy 340.200742 -224.389442)
			(xy 340.428326 -224.389442) (xy 340.428824 -224.362793) (xy 340.436767 -224.310089) (xy 340.452477 -224.259159)
			(xy 340.475603 -224.211138) (xy 340.505627 -224.167101) (xy 340.541879 -224.12803) (xy 340.58355 -224.094799)
			(xy 340.629708 -224.06815) (xy 340.679322 -224.048678) (xy 340.731284 -224.036818) (xy 340.784434 -224.032835)
			(xy 340.837584 -224.036818) (xy 340.889546 -224.048678) (xy 340.93916 -224.06815) (xy 340.985318 -224.094799)
			(xy 341.026989 -224.12803) (xy 341.063241 -224.167101) (xy 341.093265 -224.211138) (xy 341.116391 -224.259159)
			(xy 341.132101 -224.310089) (xy 341.140044 -224.362793) (xy 341.140542 -224.389442) (xy 341.140152 -224.412686)
			(xy 341.134113 -224.458781) (xy 341.122132 -224.5037) (xy 341.113618 -224.525332) (xy 341.103966 -224.548446)
			(xy 341.276432 -224.846896) (xy 341.30107 -224.850198) (xy 341.326419 -224.853984) (xy 341.375725 -224.86798)
			(xy 341.422517 -224.888897) (xy 341.465829 -224.916303) (xy 341.504766 -224.949633) (xy 341.538526 -224.988198)
			(xy 341.566411 -225.031202) (xy 341.587847 -225.077759) (xy 341.60239 -225.126907) (xy 341.60974 -225.177631)
			(xy 341.610188 -225.203258) (xy 341.60969 -225.229907) (xy 341.83827 -225.229907) (xy 341.83827 -225.176609)
			(xy 341.846213 -225.123905) (xy 341.861923 -225.072975) (xy 341.885049 -225.024954) (xy 341.915073 -224.980917)
			(xy 341.951325 -224.941846) (xy 341.992996 -224.908615) (xy 342.039154 -224.881966) (xy 342.088768 -224.862494)
			(xy 342.14073 -224.850634) (xy 342.19388 -224.846651) (xy 342.24703 -224.850634) (xy 342.298992 -224.862494)
			(xy 342.348606 -224.881966) (xy 342.394764 -224.908615) (xy 342.436435 -224.941846) (xy 342.472687 -224.980917)
			(xy 342.502711 -225.024954) (xy 342.525837 -225.072975) (xy 342.541547 -225.123905) (xy 342.54949 -225.176609)
			(xy 342.549988 -225.203258) (xy 342.54949 -225.229907) (xy 342.541547 -225.282611) (xy 342.525837 -225.333541)
			(xy 342.502711 -225.381562) (xy 342.472687 -225.425599) (xy 342.436435 -225.46467) (xy 342.394764 -225.497901)
			(xy 342.348606 -225.52455) (xy 342.298992 -225.544022) (xy 342.24703 -225.555882) (xy 342.19388 -225.559866)
			(xy 342.14073 -225.555882) (xy 342.088768 -225.544022) (xy 342.039154 -225.52455) (xy 341.992996 -225.497901)
			(xy 341.951325 -225.46467) (xy 341.915073 -225.425599) (xy 341.885049 -225.381562) (xy 341.861923 -225.333541)
			(xy 341.846213 -225.282611) (xy 341.83827 -225.229907) (xy 341.60969 -225.229907) (xy 341.601747 -225.282611)
			(xy 341.586037 -225.333541) (xy 341.562911 -225.381562) (xy 341.532887 -225.425599) (xy 341.496635 -225.46467)
			(xy 341.454964 -225.497901) (xy 341.408806 -225.52455) (xy 341.359192 -225.544022) (xy 341.30723 -225.555882)
			(xy 341.25408 -225.559866) (xy 341.20093 -225.555882) (xy 341.148968 -225.544022) (xy 341.099354 -225.52455)
			(xy 341.053196 -225.497901) (xy 341.011525 -225.46467) (xy 340.975273 -225.425599) (xy 340.945249 -225.381562)
			(xy 340.922123 -225.333541) (xy 340.906413 -225.282611) (xy 340.89847 -225.229907) (xy 340.897972 -225.203258)
			(xy 340.898361 -225.180014) (xy 340.9044 -225.133918) (xy 340.916382 -225.089) (xy 340.924896 -225.067368)
			(xy 340.934548 -225.044254) (xy 340.762082 -224.745804) (xy 340.737444 -224.742502) (xy 340.712097 -224.738705)
			(xy 340.662791 -224.724711) (xy 340.615999 -224.703796) (xy 340.572687 -224.676391) (xy 340.533749 -224.643063)
			(xy 340.499989 -224.604499) (xy 340.472103 -224.561495) (xy 340.450668 -224.514939) (xy 340.436125 -224.465792)
			(xy 340.428774 -224.415069) (xy 340.428326 -224.389442) (xy 340.200742 -224.389442) (xy 340.200244 -224.416091)
			(xy 340.192301 -224.468795) (xy 340.176591 -224.519725) (xy 340.153465 -224.567746) (xy 340.123441 -224.611783)
			(xy 340.087189 -224.650854) (xy 340.045518 -224.684085) (xy 339.99936 -224.710734) (xy 339.949746 -224.730206)
			(xy 339.897784 -224.742066) (xy 339.844634 -224.74605) (xy 339.791484 -224.742066) (xy 339.739522 -224.730206)
			(xy 339.689908 -224.710734) (xy 339.64375 -224.684085) (xy 339.602079 -224.650854) (xy 339.565827 -224.611783)
			(xy 339.535803 -224.567746) (xy 339.512677 -224.519725) (xy 339.496967 -224.468795) (xy 339.489024 -224.416091)
			(xy 339.488526 -224.389442) (xy 339.488975 -224.363816) (xy 339.496328 -224.313094) (xy 339.510872 -224.263949)
			(xy 339.532309 -224.217395) (xy 339.560195 -224.174393) (xy 339.593955 -224.135831) (xy 339.632893 -224.102505)
			(xy 339.676204 -224.075102) (xy 339.722995 -224.054188) (xy 339.7723 -224.040194) (xy 339.797644 -224.036382)
			(xy 339.822282 -224.03308) (xy 339.87486 -223.942148) (xy 339.879812 -223.932651) (xy 339.882071 -223.911369)
			(xy 339.875474 -223.89101) (xy 339.861165 -223.875096) (xy 339.841618 -223.866381) (xy 339.830918 -223.865948)
			(xy 339.580982 -223.865948) (xy 339.558257 -223.881464) (xy 339.509034 -223.906052) (xy 339.456614 -223.922776)
			(xy 339.402246 -223.931239) (xy 339.347222 -223.931239) (xy 339.292854 -223.922776) (xy 339.240434 -223.906052)
			(xy 339.191211 -223.881464) (xy 339.168486 -223.865948) (xy 338.71408 -223.865948) (xy 338.30387 -224.276158)
			(xy 338.310728 -224.304098) (xy 338.315607 -224.325096) (xy 338.320832 -224.367887) (xy 338.321142 -224.389442)
			(xy 338.548726 -224.389442) (xy 338.549224 -224.362793) (xy 338.557167 -224.310089) (xy 338.572877 -224.259159)
			(xy 338.596003 -224.211138) (xy 338.626027 -224.167101) (xy 338.662279 -224.12803) (xy 338.70395 -224.094799)
			(xy 338.750108 -224.06815) (xy 338.799722 -224.048678) (xy 338.851684 -224.036818) (xy 338.904834 -224.032835)
			(xy 338.957984 -224.036818) (xy 339.009946 -224.048678) (xy 339.05956 -224.06815) (xy 339.105718 -224.094799)
			(xy 339.147389 -224.12803) (xy 339.183641 -224.167101) (xy 339.213665 -224.211138) (xy 339.236791 -224.259159)
			(xy 339.252501 -224.310089) (xy 339.260444 -224.362793) (xy 339.260942 -224.389442) (xy 339.260552 -224.412686)
			(xy 339.254513 -224.458781) (xy 339.242532 -224.5037) (xy 339.234018 -224.525332) (xy 339.224366 -224.548446)
			(xy 339.396832 -224.846896) (xy 339.42147 -224.850198) (xy 339.446819 -224.853984) (xy 339.496125 -224.86798)
			(xy 339.542917 -224.888897) (xy 339.586229 -224.916303) (xy 339.625166 -224.949633) (xy 339.658926 -224.988198)
			(xy 339.686811 -225.031202) (xy 339.708247 -225.077759) (xy 339.72279 -225.126907) (xy 339.73014 -225.177631)
			(xy 339.730588 -225.203258) (xy 339.73009 -225.229907) (xy 339.95867 -225.229907) (xy 339.95867 -225.176609)
			(xy 339.966613 -225.123905) (xy 339.982323 -225.072975) (xy 340.005449 -225.024954) (xy 340.035473 -224.980917)
			(xy 340.071725 -224.941846) (xy 340.113396 -224.908615) (xy 340.159554 -224.881966) (xy 340.209168 -224.862494)
			(xy 340.26113 -224.850634) (xy 340.31428 -224.846651) (xy 340.36743 -224.850634) (xy 340.419392 -224.862494)
			(xy 340.469006 -224.881966) (xy 340.515164 -224.908615) (xy 340.556835 -224.941846) (xy 340.593087 -224.980917)
			(xy 340.623111 -225.024954) (xy 340.646237 -225.072975) (xy 340.661947 -225.123905) (xy 340.66989 -225.176609)
			(xy 340.670388 -225.203258) (xy 340.66989 -225.229907) (xy 340.661947 -225.282611) (xy 340.646237 -225.333541)
			(xy 340.623111 -225.381562) (xy 340.593087 -225.425599) (xy 340.556835 -225.46467) (xy 340.515164 -225.497901)
			(xy 340.469006 -225.52455) (xy 340.419392 -225.544022) (xy 340.36743 -225.555882) (xy 340.31428 -225.559866)
			(xy 340.26113 -225.555882) (xy 340.209168 -225.544022) (xy 340.159554 -225.52455) (xy 340.113396 -225.497901)
			(xy 340.071725 -225.46467) (xy 340.035473 -225.425599) (xy 340.005449 -225.381562) (xy 339.982323 -225.333541)
			(xy 339.966613 -225.282611) (xy 339.95867 -225.229907) (xy 339.73009 -225.229907) (xy 339.722147 -225.282611)
			(xy 339.706437 -225.333541) (xy 339.683311 -225.381562) (xy 339.653287 -225.425599) (xy 339.617035 -225.46467)
			(xy 339.575364 -225.497901) (xy 339.529206 -225.52455) (xy 339.479592 -225.544022) (xy 339.42763 -225.555882)
			(xy 339.37448 -225.559866) (xy 339.32133 -225.555882) (xy 339.269368 -225.544022) (xy 339.219754 -225.52455)
			(xy 339.173596 -225.497901) (xy 339.131925 -225.46467) (xy 339.095673 -225.425599) (xy 339.065649 -225.381562)
			(xy 339.042523 -225.333541) (xy 339.026813 -225.282611) (xy 339.01887 -225.229907) (xy 339.018372 -225.203258)
			(xy 339.018761 -225.180014) (xy 339.0248 -225.133918) (xy 339.036782 -225.089) (xy 339.045296 -225.067368)
			(xy 339.054948 -225.044254) (xy 338.882482 -224.745804) (xy 338.857844 -224.742502) (xy 338.832497 -224.738705)
			(xy 338.783191 -224.724711) (xy 338.736399 -224.703796) (xy 338.693087 -224.676391) (xy 338.654149 -224.643063)
			(xy 338.620389 -224.604499) (xy 338.592503 -224.561495) (xy 338.571068 -224.514939) (xy 338.556525 -224.465792)
			(xy 338.549174 -224.415069) (xy 338.548726 -224.389442) (xy 338.321142 -224.389442) (xy 338.32059 -224.417424)
			(xy 338.31183 -224.472698) (xy 338.294532 -224.525922) (xy 338.269122 -224.575784) (xy 338.236226 -224.621059)
			(xy 338.196653 -224.660631) (xy 338.151378 -224.693526) (xy 338.101514 -224.718935) (xy 338.04829 -224.736232)
			(xy 337.993016 -224.744991) (xy 337.965034 -224.74555) (xy 337.943481 -224.745206) (xy 337.900693 -224.739985)
			(xy 337.87969 -224.735136) (xy 337.85175 -224.728278) (xy 337.759294 -224.820734) (xy 337.748628 -224.832164)
			(xy 337.734189 -224.859874) (xy 337.728796 -224.890651) (xy 337.732951 -224.92162) (xy 337.746268 -224.949886)
			(xy 337.7565 -224.961704) (xy 337.774157 -224.981552) (xy 337.803997 -225.025501) (xy 337.826981 -225.073394)
			(xy 337.8426 -225.124167) (xy 337.850508 -225.176697) (xy 337.850988 -225.203258) (xy 337.850496 -225.229907)
			(xy 338.07907 -225.229907) (xy 338.07907 -225.176609) (xy 338.087013 -225.123905) (xy 338.102723 -225.072975)
			(xy 338.125849 -225.024954) (xy 338.155873 -224.980917) (xy 338.192125 -224.941846) (xy 338.233796 -224.908615)
			(xy 338.279954 -224.881966) (xy 338.329568 -224.862494) (xy 338.38153 -224.850634) (xy 338.43468 -224.846651)
			(xy 338.48783 -224.850634) (xy 338.539792 -224.862494) (xy 338.589406 -224.881966) (xy 338.635564 -224.908615)
			(xy 338.677235 -224.941846) (xy 338.713487 -224.980917) (xy 338.743511 -225.024954) (xy 338.766637 -225.072975)
			(xy 338.782347 -225.123905) (xy 338.79029 -225.176609) (xy 338.790788 -225.203258) (xy 338.79029 -225.229907)
			(xy 338.782347 -225.282611) (xy 338.766637 -225.333541) (xy 338.743511 -225.381562) (xy 338.713487 -225.425599)
			(xy 338.677235 -225.46467) (xy 338.635564 -225.497901) (xy 338.589406 -225.52455) (xy 338.539792 -225.544022)
			(xy 338.48783 -225.555882) (xy 338.43468 -225.559866) (xy 338.38153 -225.555882) (xy 338.329568 -225.544022)
			(xy 338.279954 -225.52455) (xy 338.233796 -225.497901) (xy 338.192125 -225.46467) (xy 338.155873 -225.425599)
			(xy 338.125849 -225.381562) (xy 338.102723 -225.333541) (xy 338.087013 -225.282611) (xy 338.07907 -225.229907)
			(xy 337.850496 -225.229907) (xy 337.850471 -225.231245) (xy 337.84172 -225.28653) (xy 337.824428 -225.339766)
			(xy 337.799019 -225.389641) (xy 337.766121 -225.434926) (xy 337.726543 -225.474507) (xy 337.681259 -225.507408)
			(xy 337.631386 -225.532819) (xy 337.578152 -225.550115) (xy 337.522867 -225.558869) (xy 337.49488 -225.559366)
			(xy 337.468318 -225.55888) (xy 337.415781 -225.550994) (xy 337.365001 -225.535386) (xy 337.317106 -225.512402)
			(xy 337.273159 -225.482554) (xy 337.253326 -225.464878) (xy 337.24149 -225.454664) (xy 337.213235 -225.441324)
			(xy 337.182268 -225.437157) (xy 337.151491 -225.442554) (xy 337.123789 -225.457009) (xy 337.112356 -225.467672)
			(xy 337.075526 -225.504502) (xy 337.065192 -225.515609) (xy 337.050976 -225.542392) (xy 337.045261 -225.572171)
			(xy 337.048549 -225.602314) (xy 337.060552 -225.630159) (xy 337.080208 -225.653246) (xy 337.105782 -225.669537)
			(xy 337.12023 -225.674174) (xy 337.144918 -225.68148) (xy 337.192042 -225.70222) (xy 337.235688 -225.72953)
			(xy 337.274946 -225.762839) (xy 337.308999 -225.801455) (xy 337.337137 -225.844571) (xy 337.358773 -225.89129)
			(xy 337.373456 -225.940638) (xy 337.38088 -225.991585) (xy 337.381342 -226.017328) (xy 337.380817 -226.043977)
			(xy 337.609424 -226.043977) (xy 337.609424 -225.990679) (xy 337.617367 -225.937975) (xy 337.633077 -225.887045)
			(xy 337.656203 -225.839024) (xy 337.686227 -225.794987) (xy 337.722479 -225.755916) (xy 337.76415 -225.722685)
			(xy 337.810308 -225.696036) (xy 337.859922 -225.676564) (xy 337.911884 -225.664704) (xy 337.965034 -225.660721)
			(xy 338.018184 -225.664704) (xy 338.070146 -225.676564) (xy 338.11976 -225.696036) (xy 338.165918 -225.722685)
			(xy 338.207589 -225.755916) (xy 338.243841 -225.794987) (xy 338.273865 -225.839024) (xy 338.296991 -225.887045)
			(xy 338.312701 -225.937975) (xy 338.320644 -225.990679) (xy 338.321142 -226.017328) (xy 338.320644 -226.043977)
			(xy 338.54897 -226.043977) (xy 338.54897 -225.990679) (xy 338.556913 -225.937975) (xy 338.572623 -225.887045)
			(xy 338.595749 -225.839024) (xy 338.625773 -225.794987) (xy 338.662025 -225.755916) (xy 338.703696 -225.722685)
			(xy 338.749854 -225.696036) (xy 338.799468 -225.676564) (xy 338.85143 -225.664704) (xy 338.90458 -225.660721)
			(xy 338.95773 -225.664704) (xy 339.009692 -225.676564) (xy 339.059306 -225.696036) (xy 339.105464 -225.722685)
			(xy 339.147135 -225.755916) (xy 339.183387 -225.794987) (xy 339.213411 -225.839024) (xy 339.236537 -225.887045)
			(xy 339.252247 -225.937975) (xy 339.26019 -225.990679) (xy 339.260688 -226.017328) (xy 339.26019 -226.043977)
			(xy 339.489024 -226.043977) (xy 339.489024 -225.990679) (xy 339.496967 -225.937975) (xy 339.512677 -225.887045)
			(xy 339.535803 -225.839024) (xy 339.565827 -225.794987) (xy 339.602079 -225.755916) (xy 339.64375 -225.722685)
			(xy 339.689908 -225.696036) (xy 339.739522 -225.676564) (xy 339.791484 -225.664704) (xy 339.844634 -225.660721)
			(xy 339.897784 -225.664704) (xy 339.949746 -225.676564) (xy 339.99936 -225.696036) (xy 340.045518 -225.722685)
			(xy 340.087189 -225.755916) (xy 340.123441 -225.794987) (xy 340.153465 -225.839024) (xy 340.176591 -225.887045)
			(xy 340.192301 -225.937975) (xy 340.200244 -225.990679) (xy 340.200742 -226.017328) (xy 340.200244 -226.043977)
			(xy 340.428824 -226.043977) (xy 340.428824 -225.990679) (xy 340.436767 -225.937975) (xy 340.452477 -225.887045)
			(xy 340.475603 -225.839024) (xy 340.505627 -225.794987) (xy 340.541879 -225.755916) (xy 340.58355 -225.722685)
			(xy 340.629708 -225.696036) (xy 340.679322 -225.676564) (xy 340.731284 -225.664704) (xy 340.784434 -225.660721)
			(xy 340.837584 -225.664704) (xy 340.889546 -225.676564) (xy 340.93916 -225.696036) (xy 340.985318 -225.722685)
			(xy 341.026989 -225.755916) (xy 341.063241 -225.794987) (xy 341.093265 -225.839024) (xy 341.116391 -225.887045)
			(xy 341.132101 -225.937975) (xy 341.140044 -225.990679) (xy 341.140542 -226.017328) (xy 341.140044 -226.043977)
			(xy 341.368624 -226.043977) (xy 341.368624 -225.990679) (xy 341.376567 -225.937975) (xy 341.392277 -225.887045)
			(xy 341.415403 -225.839024) (xy 341.445427 -225.794987) (xy 341.481679 -225.755916) (xy 341.52335 -225.722685)
			(xy 341.569508 -225.696036) (xy 341.619122 -225.676564) (xy 341.671084 -225.664704) (xy 341.724234 -225.660721)
			(xy 341.777384 -225.664704) (xy 341.829346 -225.676564) (xy 341.87896 -225.696036) (xy 341.925118 -225.722685)
			(xy 341.966789 -225.755916) (xy 342.003041 -225.794987) (xy 342.033065 -225.839024) (xy 342.056191 -225.887045)
			(xy 342.071901 -225.937975) (xy 342.079844 -225.990679) (xy 342.080342 -226.017328) (xy 342.079844 -226.043977)
			(xy 342.308424 -226.043977) (xy 342.308424 -225.990679) (xy 342.316367 -225.937975) (xy 342.332077 -225.887045)
			(xy 342.355203 -225.839024) (xy 342.385227 -225.794987) (xy 342.421479 -225.755916) (xy 342.46315 -225.722685)
			(xy 342.509308 -225.696036) (xy 342.558922 -225.676564) (xy 342.610884 -225.664704) (xy 342.664034 -225.660721)
			(xy 342.717184 -225.664704) (xy 342.769146 -225.676564) (xy 342.81876 -225.696036) (xy 342.864918 -225.722685)
			(xy 342.906589 -225.755916) (xy 342.942841 -225.794987) (xy 342.972865 -225.839024) (xy 342.995991 -225.887045)
			(xy 343.011701 -225.937975) (xy 343.019644 -225.990679) (xy 343.020142 -226.017328) (xy 343.019644 -226.043977)
			(xy 343.248224 -226.043977) (xy 343.248224 -225.990679) (xy 343.256167 -225.937975) (xy 343.271877 -225.887045)
			(xy 343.295003 -225.839024) (xy 343.325027 -225.794987) (xy 343.361279 -225.755916) (xy 343.40295 -225.722685)
			(xy 343.449108 -225.696036) (xy 343.498722 -225.676564) (xy 343.550684 -225.664704) (xy 343.603834 -225.660721)
			(xy 343.656984 -225.664704) (xy 343.708946 -225.676564) (xy 343.75856 -225.696036) (xy 343.804718 -225.722685)
			(xy 343.846389 -225.755916) (xy 343.882641 -225.794987) (xy 343.912665 -225.839024) (xy 343.935791 -225.887045)
			(xy 343.951501 -225.937975) (xy 343.959444 -225.990679) (xy 343.959942 -226.017328) (xy 343.959444 -226.043977)
			(xy 344.188024 -226.043977) (xy 344.188024 -225.990679) (xy 344.195967 -225.937975) (xy 344.211677 -225.887045)
			(xy 344.234803 -225.839024) (xy 344.264827 -225.794987) (xy 344.301079 -225.755916) (xy 344.34275 -225.722685)
			(xy 344.388908 -225.696036) (xy 344.438522 -225.676564) (xy 344.490484 -225.664704) (xy 344.543634 -225.660721)
			(xy 344.596784 -225.664704) (xy 344.648746 -225.676564) (xy 344.69836 -225.696036) (xy 344.744518 -225.722685)
			(xy 344.786189 -225.755916) (xy 344.822441 -225.794987) (xy 344.852465 -225.839024) (xy 344.875591 -225.887045)
			(xy 344.891301 -225.937975) (xy 344.899244 -225.990679) (xy 344.899742 -226.017328) (xy 344.899244 -226.043977)
			(xy 345.127824 -226.043977) (xy 345.127824 -225.990679) (xy 345.135767 -225.937975) (xy 345.151477 -225.887045)
			(xy 345.174603 -225.839024) (xy 345.204627 -225.794987) (xy 345.240879 -225.755916) (xy 345.28255 -225.722685)
			(xy 345.328708 -225.696036) (xy 345.378322 -225.676564) (xy 345.430284 -225.664704) (xy 345.483434 -225.660721)
			(xy 345.536584 -225.664704) (xy 345.588546 -225.676564) (xy 345.63816 -225.696036) (xy 345.684318 -225.722685)
			(xy 345.725989 -225.755916) (xy 345.762241 -225.794987) (xy 345.792265 -225.839024) (xy 345.815391 -225.887045)
			(xy 345.831101 -225.937975) (xy 345.839044 -225.990679) (xy 345.839542 -226.017328) (xy 345.839044 -226.043977)
			(xy 346.067624 -226.043977) (xy 346.067624 -225.990679) (xy 346.075567 -225.937975) (xy 346.091277 -225.887045)
			(xy 346.114403 -225.839024) (xy 346.144427 -225.794987) (xy 346.180679 -225.755916) (xy 346.22235 -225.722685)
			(xy 346.268508 -225.696036) (xy 346.318122 -225.676564) (xy 346.370084 -225.664704) (xy 346.423234 -225.660721)
			(xy 346.476384 -225.664704) (xy 346.528346 -225.676564) (xy 346.57796 -225.696036) (xy 346.624118 -225.722685)
			(xy 346.665789 -225.755916) (xy 346.702041 -225.794987) (xy 346.732065 -225.839024) (xy 346.755191 -225.887045)
			(xy 346.770901 -225.937975) (xy 346.778844 -225.990679) (xy 346.779342 -226.017328) (xy 346.778844 -226.043977)
			(xy 347.007424 -226.043977) (xy 347.007424 -225.990679) (xy 347.015367 -225.937975) (xy 347.031077 -225.887045)
			(xy 347.054203 -225.839024) (xy 347.084227 -225.794987) (xy 347.120479 -225.755916) (xy 347.16215 -225.722685)
			(xy 347.208308 -225.696036) (xy 347.257922 -225.676564) (xy 347.309884 -225.664704) (xy 347.363034 -225.660721)
			(xy 347.416184 -225.664704) (xy 347.468146 -225.676564) (xy 347.51776 -225.696036) (xy 347.563918 -225.722685)
			(xy 347.605589 -225.755916) (xy 347.641841 -225.794987) (xy 347.671865 -225.839024) (xy 347.694991 -225.887045)
			(xy 347.710701 -225.937975) (xy 347.718644 -225.990679) (xy 347.719142 -226.017328) (xy 347.718644 -226.043977)
			(xy 347.947224 -226.043977) (xy 347.947224 -225.990679) (xy 347.955167 -225.937975) (xy 347.970877 -225.887045)
			(xy 347.994003 -225.839024) (xy 348.024027 -225.794987) (xy 348.060279 -225.755916) (xy 348.10195 -225.722685)
			(xy 348.148108 -225.696036) (xy 348.197722 -225.676564) (xy 348.249684 -225.664704) (xy 348.302834 -225.660721)
			(xy 348.355984 -225.664704) (xy 348.407946 -225.676564) (xy 348.45756 -225.696036) (xy 348.503718 -225.722685)
			(xy 348.545389 -225.755916) (xy 348.581641 -225.794987) (xy 348.611665 -225.839024) (xy 348.634791 -225.887045)
			(xy 348.650501 -225.937975) (xy 348.658444 -225.990679) (xy 348.658942 -226.017328) (xy 348.658444 -226.043977)
			(xy 348.887024 -226.043977) (xy 348.887024 -225.990679) (xy 348.894967 -225.937975) (xy 348.910677 -225.887045)
			(xy 348.933803 -225.839024) (xy 348.963827 -225.794987) (xy 349.000079 -225.755916) (xy 349.04175 -225.722685)
			(xy 349.087908 -225.696036) (xy 349.137522 -225.676564) (xy 349.189484 -225.664704) (xy 349.242634 -225.660721)
			(xy 349.295784 -225.664704) (xy 349.347746 -225.676564) (xy 349.39736 -225.696036) (xy 349.443518 -225.722685)
			(xy 349.485189 -225.755916) (xy 349.521441 -225.794987) (xy 349.551465 -225.839024) (xy 349.574591 -225.887045)
			(xy 349.590301 -225.937975) (xy 349.598244 -225.990679) (xy 349.598742 -226.017328) (xy 349.598244 -226.043977)
			(xy 349.826824 -226.043977) (xy 349.826824 -225.990679) (xy 349.834767 -225.937975) (xy 349.850477 -225.887045)
			(xy 349.873603 -225.839024) (xy 349.903627 -225.794987) (xy 349.939879 -225.755916) (xy 349.98155 -225.722685)
			(xy 350.027708 -225.696036) (xy 350.077322 -225.676564) (xy 350.129284 -225.664704) (xy 350.182434 -225.660721)
			(xy 350.235584 -225.664704) (xy 350.287546 -225.676564) (xy 350.33716 -225.696036) (xy 350.383318 -225.722685)
			(xy 350.424989 -225.755916) (xy 350.461241 -225.794987) (xy 350.491265 -225.839024) (xy 350.514391 -225.887045)
			(xy 350.530101 -225.937975) (xy 350.538044 -225.990679) (xy 350.538542 -226.017328) (xy 350.538044 -226.043977)
			(xy 350.766624 -226.043977) (xy 350.766624 -225.990679) (xy 350.774567 -225.937975) (xy 350.790277 -225.887045)
			(xy 350.813403 -225.839024) (xy 350.843427 -225.794987) (xy 350.879679 -225.755916) (xy 350.92135 -225.722685)
			(xy 350.967508 -225.696036) (xy 351.017122 -225.676564) (xy 351.069084 -225.664704) (xy 351.122234 -225.660721)
			(xy 351.175384 -225.664704) (xy 351.227346 -225.676564) (xy 351.27696 -225.696036) (xy 351.323118 -225.722685)
			(xy 351.364789 -225.755916) (xy 351.401041 -225.794987) (xy 351.431065 -225.839024) (xy 351.454191 -225.887045)
			(xy 351.469901 -225.937975) (xy 351.477844 -225.990679) (xy 351.478342 -226.017328) (xy 351.477844 -226.043977)
			(xy 351.706424 -226.043977) (xy 351.706424 -225.990679) (xy 351.714367 -225.937975) (xy 351.730077 -225.887045)
			(xy 351.753203 -225.839024) (xy 351.783227 -225.794987) (xy 351.819479 -225.755916) (xy 351.86115 -225.722685)
			(xy 351.907308 -225.696036) (xy 351.956922 -225.676564) (xy 352.008884 -225.664704) (xy 352.062034 -225.660721)
			(xy 352.115184 -225.664704) (xy 352.167146 -225.676564) (xy 352.21676 -225.696036) (xy 352.262918 -225.722685)
			(xy 352.304589 -225.755916) (xy 352.340841 -225.794987) (xy 352.370865 -225.839024) (xy 352.393991 -225.887045)
			(xy 352.409701 -225.937975) (xy 352.417644 -225.990679) (xy 352.418142 -226.017328) (xy 352.417644 -226.043977)
			(xy 352.646224 -226.043977) (xy 352.646224 -225.990679) (xy 352.654167 -225.937975) (xy 352.669877 -225.887045)
			(xy 352.693003 -225.839024) (xy 352.723027 -225.794987) (xy 352.759279 -225.755916) (xy 352.80095 -225.722685)
			(xy 352.847108 -225.696036) (xy 352.896722 -225.676564) (xy 352.948684 -225.664704) (xy 353.001834 -225.660721)
			(xy 353.054984 -225.664704) (xy 353.106946 -225.676564) (xy 353.15656 -225.696036) (xy 353.202718 -225.722685)
			(xy 353.244389 -225.755916) (xy 353.280641 -225.794987) (xy 353.310665 -225.839024) (xy 353.333791 -225.887045)
			(xy 353.349501 -225.937975) (xy 353.357444 -225.990679) (xy 353.357942 -226.017328) (xy 353.357444 -226.043977)
			(xy 353.586024 -226.043977) (xy 353.586024 -225.990679) (xy 353.593967 -225.937975) (xy 353.609677 -225.887045)
			(xy 353.632803 -225.839024) (xy 353.662827 -225.794987) (xy 353.699079 -225.755916) (xy 353.74075 -225.722685)
			(xy 353.786908 -225.696036) (xy 353.836522 -225.676564) (xy 353.888484 -225.664704) (xy 353.941634 -225.660721)
			(xy 353.994784 -225.664704) (xy 354.046746 -225.676564) (xy 354.09636 -225.696036) (xy 354.142518 -225.722685)
			(xy 354.184189 -225.755916) (xy 354.220441 -225.794987) (xy 354.250465 -225.839024) (xy 354.273591 -225.887045)
			(xy 354.289301 -225.937975) (xy 354.297244 -225.990679) (xy 354.297742 -226.017328) (xy 354.297244 -226.043977)
			(xy 354.525824 -226.043977) (xy 354.525824 -225.990679) (xy 354.533767 -225.937975) (xy 354.549477 -225.887045)
			(xy 354.572603 -225.839024) (xy 354.602627 -225.794987) (xy 354.638879 -225.755916) (xy 354.68055 -225.722685)
			(xy 354.726708 -225.696036) (xy 354.776322 -225.676564) (xy 354.828284 -225.664704) (xy 354.881434 -225.660721)
			(xy 354.934584 -225.664704) (xy 354.986546 -225.676564) (xy 355.03616 -225.696036) (xy 355.082318 -225.722685)
			(xy 355.123989 -225.755916) (xy 355.160241 -225.794987) (xy 355.190265 -225.839024) (xy 355.213391 -225.887045)
			(xy 355.229101 -225.937975) (xy 355.237044 -225.990679) (xy 355.237542 -226.017328) (xy 355.237044 -226.043977)
			(xy 355.465624 -226.043977) (xy 355.465624 -225.990679) (xy 355.473567 -225.937975) (xy 355.489277 -225.887045)
			(xy 355.512403 -225.839024) (xy 355.542427 -225.794987) (xy 355.578679 -225.755916) (xy 355.62035 -225.722685)
			(xy 355.666508 -225.696036) (xy 355.716122 -225.676564) (xy 355.768084 -225.664704) (xy 355.821234 -225.660721)
			(xy 355.874384 -225.664704) (xy 355.926346 -225.676564) (xy 355.97596 -225.696036) (xy 356.022118 -225.722685)
			(xy 356.063789 -225.755916) (xy 356.100041 -225.794987) (xy 356.130065 -225.839024) (xy 356.153191 -225.887045)
			(xy 356.168901 -225.937975) (xy 356.176844 -225.990679) (xy 356.177342 -226.017328) (xy 356.176844 -226.043977)
			(xy 356.405424 -226.043977) (xy 356.405424 -225.990679) (xy 356.413367 -225.937975) (xy 356.429077 -225.887045)
			(xy 356.452203 -225.839024) (xy 356.482227 -225.794987) (xy 356.518479 -225.755916) (xy 356.56015 -225.722685)
			(xy 356.606308 -225.696036) (xy 356.655922 -225.676564) (xy 356.707884 -225.664704) (xy 356.761034 -225.660721)
			(xy 356.814184 -225.664704) (xy 356.866146 -225.676564) (xy 356.91576 -225.696036) (xy 356.961918 -225.722685)
			(xy 357.003589 -225.755916) (xy 357.039841 -225.794987) (xy 357.069865 -225.839024) (xy 357.092991 -225.887045)
			(xy 357.108701 -225.937975) (xy 357.116644 -225.990679) (xy 357.117142 -226.017328) (xy 357.116644 -226.043977)
			(xy 357.345224 -226.043977) (xy 357.345224 -225.990679) (xy 357.353167 -225.937975) (xy 357.368877 -225.887045)
			(xy 357.392003 -225.839024) (xy 357.422027 -225.794987) (xy 357.458279 -225.755916) (xy 357.49995 -225.722685)
			(xy 357.546108 -225.696036) (xy 357.595722 -225.676564) (xy 357.647684 -225.664704) (xy 357.700834 -225.660721)
			(xy 357.753984 -225.664704) (xy 357.805946 -225.676564) (xy 357.85556 -225.696036) (xy 357.901718 -225.722685)
			(xy 357.943389 -225.755916) (xy 357.979641 -225.794987) (xy 358.009665 -225.839024) (xy 358.032791 -225.887045)
			(xy 358.048501 -225.937975) (xy 358.056444 -225.990679) (xy 358.056942 -226.017328) (xy 358.056444 -226.043977)
			(xy 358.285024 -226.043977) (xy 358.285024 -225.990679) (xy 358.292967 -225.937975) (xy 358.308677 -225.887045)
			(xy 358.331803 -225.839024) (xy 358.361827 -225.794987) (xy 358.398079 -225.755916) (xy 358.43975 -225.722685)
			(xy 358.485908 -225.696036) (xy 358.535522 -225.676564) (xy 358.587484 -225.664704) (xy 358.640634 -225.660721)
			(xy 358.693784 -225.664704) (xy 358.745746 -225.676564) (xy 358.79536 -225.696036) (xy 358.841518 -225.722685)
			(xy 358.883189 -225.755916) (xy 358.919441 -225.794987) (xy 358.949465 -225.839024) (xy 358.972591 -225.887045)
			(xy 358.988301 -225.937975) (xy 358.996244 -225.990679) (xy 358.996742 -226.017328) (xy 358.996244 -226.043977)
			(xy 358.988301 -226.096681) (xy 358.972591 -226.147611) (xy 358.949465 -226.195632) (xy 358.919441 -226.239669)
			(xy 358.883189 -226.27874) (xy 358.841518 -226.311971) (xy 358.79536 -226.33862) (xy 358.745746 -226.358092)
			(xy 358.693784 -226.369952) (xy 358.640634 -226.373936) (xy 358.587484 -226.369952) (xy 358.535522 -226.358092)
			(xy 358.485908 -226.33862) (xy 358.43975 -226.311971) (xy 358.398079 -226.27874) (xy 358.361827 -226.239669)
			(xy 358.331803 -226.195632) (xy 358.308677 -226.147611) (xy 358.292967 -226.096681) (xy 358.285024 -226.043977)
			(xy 358.056444 -226.043977) (xy 358.048501 -226.096681) (xy 358.032791 -226.147611) (xy 358.009665 -226.195632)
			(xy 357.979641 -226.239669) (xy 357.943389 -226.27874) (xy 357.901718 -226.311971) (xy 357.85556 -226.33862)
			(xy 357.805946 -226.358092) (xy 357.753984 -226.369952) (xy 357.700834 -226.373936) (xy 357.647684 -226.369952)
			(xy 357.595722 -226.358092) (xy 357.546108 -226.33862) (xy 357.49995 -226.311971) (xy 357.458279 -226.27874)
			(xy 357.422027 -226.239669) (xy 357.392003 -226.195632) (xy 357.368877 -226.147611) (xy 357.353167 -226.096681)
			(xy 357.345224 -226.043977) (xy 357.116644 -226.043977) (xy 357.108701 -226.096681) (xy 357.092991 -226.147611)
			(xy 357.069865 -226.195632) (xy 357.039841 -226.239669) (xy 357.003589 -226.27874) (xy 356.961918 -226.311971)
			(xy 356.91576 -226.33862) (xy 356.866146 -226.358092) (xy 356.814184 -226.369952) (xy 356.761034 -226.373936)
			(xy 356.707884 -226.369952) (xy 356.655922 -226.358092) (xy 356.606308 -226.33862) (xy 356.56015 -226.311971)
			(xy 356.518479 -226.27874) (xy 356.482227 -226.239669) (xy 356.452203 -226.195632) (xy 356.429077 -226.147611)
			(xy 356.413367 -226.096681) (xy 356.405424 -226.043977) (xy 356.176844 -226.043977) (xy 356.168901 -226.096681)
			(xy 356.153191 -226.147611) (xy 356.130065 -226.195632) (xy 356.100041 -226.239669) (xy 356.063789 -226.27874)
			(xy 356.022118 -226.311971) (xy 355.97596 -226.33862) (xy 355.926346 -226.358092) (xy 355.874384 -226.369952)
			(xy 355.821234 -226.373936) (xy 355.768084 -226.369952) (xy 355.716122 -226.358092) (xy 355.666508 -226.33862)
			(xy 355.62035 -226.311971) (xy 355.578679 -226.27874) (xy 355.542427 -226.239669) (xy 355.512403 -226.195632)
			(xy 355.489277 -226.147611) (xy 355.473567 -226.096681) (xy 355.465624 -226.043977) (xy 355.237044 -226.043977)
			(xy 355.229101 -226.096681) (xy 355.213391 -226.147611) (xy 355.190265 -226.195632) (xy 355.160241 -226.239669)
			(xy 355.123989 -226.27874) (xy 355.082318 -226.311971) (xy 355.03616 -226.33862) (xy 354.986546 -226.358092)
			(xy 354.934584 -226.369952) (xy 354.881434 -226.373936) (xy 354.828284 -226.369952) (xy 354.776322 -226.358092)
			(xy 354.726708 -226.33862) (xy 354.68055 -226.311971) (xy 354.638879 -226.27874) (xy 354.602627 -226.239669)
			(xy 354.572603 -226.195632) (xy 354.549477 -226.147611) (xy 354.533767 -226.096681) (xy 354.525824 -226.043977)
			(xy 354.297244 -226.043977) (xy 354.289301 -226.096681) (xy 354.273591 -226.147611) (xy 354.250465 -226.195632)
			(xy 354.220441 -226.239669) (xy 354.184189 -226.27874) (xy 354.142518 -226.311971) (xy 354.09636 -226.33862)
			(xy 354.046746 -226.358092) (xy 353.994784 -226.369952) (xy 353.941634 -226.373936) (xy 353.888484 -226.369952)
			(xy 353.836522 -226.358092) (xy 353.786908 -226.33862) (xy 353.74075 -226.311971) (xy 353.699079 -226.27874)
			(xy 353.662827 -226.239669) (xy 353.632803 -226.195632) (xy 353.609677 -226.147611) (xy 353.593967 -226.096681)
			(xy 353.586024 -226.043977) (xy 353.357444 -226.043977) (xy 353.349501 -226.096681) (xy 353.333791 -226.147611)
			(xy 353.310665 -226.195632) (xy 353.280641 -226.239669) (xy 353.244389 -226.27874) (xy 353.202718 -226.311971)
			(xy 353.15656 -226.33862) (xy 353.106946 -226.358092) (xy 353.054984 -226.369952) (xy 353.001834 -226.373936)
			(xy 352.948684 -226.369952) (xy 352.896722 -226.358092) (xy 352.847108 -226.33862) (xy 352.80095 -226.311971)
			(xy 352.759279 -226.27874) (xy 352.723027 -226.239669) (xy 352.693003 -226.195632) (xy 352.669877 -226.147611)
			(xy 352.654167 -226.096681) (xy 352.646224 -226.043977) (xy 352.417644 -226.043977) (xy 352.409701 -226.096681)
			(xy 352.393991 -226.147611) (xy 352.370865 -226.195632) (xy 352.340841 -226.239669) (xy 352.304589 -226.27874)
			(xy 352.262918 -226.311971) (xy 352.21676 -226.33862) (xy 352.167146 -226.358092) (xy 352.115184 -226.369952)
			(xy 352.062034 -226.373936) (xy 352.008884 -226.369952) (xy 351.956922 -226.358092) (xy 351.907308 -226.33862)
			(xy 351.86115 -226.311971) (xy 351.819479 -226.27874) (xy 351.783227 -226.239669) (xy 351.753203 -226.195632)
			(xy 351.730077 -226.147611) (xy 351.714367 -226.096681) (xy 351.706424 -226.043977) (xy 351.477844 -226.043977)
			(xy 351.469901 -226.096681) (xy 351.454191 -226.147611) (xy 351.431065 -226.195632) (xy 351.401041 -226.239669)
			(xy 351.364789 -226.27874) (xy 351.323118 -226.311971) (xy 351.27696 -226.33862) (xy 351.227346 -226.358092)
			(xy 351.175384 -226.369952) (xy 351.122234 -226.373936) (xy 351.069084 -226.369952) (xy 351.017122 -226.358092)
			(xy 350.967508 -226.33862) (xy 350.92135 -226.311971) (xy 350.879679 -226.27874) (xy 350.843427 -226.239669)
			(xy 350.813403 -226.195632) (xy 350.790277 -226.147611) (xy 350.774567 -226.096681) (xy 350.766624 -226.043977)
			(xy 350.538044 -226.043977) (xy 350.530101 -226.096681) (xy 350.514391 -226.147611) (xy 350.491265 -226.195632)
			(xy 350.461241 -226.239669) (xy 350.424989 -226.27874) (xy 350.383318 -226.311971) (xy 350.33716 -226.33862)
			(xy 350.287546 -226.358092) (xy 350.235584 -226.369952) (xy 350.182434 -226.373936) (xy 350.129284 -226.369952)
			(xy 350.077322 -226.358092) (xy 350.027708 -226.33862) (xy 349.98155 -226.311971) (xy 349.939879 -226.27874)
			(xy 349.903627 -226.239669) (xy 349.873603 -226.195632) (xy 349.850477 -226.147611) (xy 349.834767 -226.096681)
			(xy 349.826824 -226.043977) (xy 349.598244 -226.043977) (xy 349.590301 -226.096681) (xy 349.574591 -226.147611)
			(xy 349.551465 -226.195632) (xy 349.521441 -226.239669) (xy 349.485189 -226.27874) (xy 349.443518 -226.311971)
			(xy 349.39736 -226.33862) (xy 349.347746 -226.358092) (xy 349.295784 -226.369952) (xy 349.242634 -226.373936)
			(xy 349.189484 -226.369952) (xy 349.137522 -226.358092) (xy 349.087908 -226.33862) (xy 349.04175 -226.311971)
			(xy 349.000079 -226.27874) (xy 348.963827 -226.239669) (xy 348.933803 -226.195632) (xy 348.910677 -226.147611)
			(xy 348.894967 -226.096681) (xy 348.887024 -226.043977) (xy 348.658444 -226.043977) (xy 348.650501 -226.096681)
			(xy 348.634791 -226.147611) (xy 348.611665 -226.195632) (xy 348.581641 -226.239669) (xy 348.545389 -226.27874)
			(xy 348.503718 -226.311971) (xy 348.45756 -226.33862) (xy 348.407946 -226.358092) (xy 348.355984 -226.369952)
			(xy 348.302834 -226.373936) (xy 348.249684 -226.369952) (xy 348.197722 -226.358092) (xy 348.148108 -226.33862)
			(xy 348.10195 -226.311971) (xy 348.060279 -226.27874) (xy 348.024027 -226.239669) (xy 347.994003 -226.195632)
			(xy 347.970877 -226.147611) (xy 347.955167 -226.096681) (xy 347.947224 -226.043977) (xy 347.718644 -226.043977)
			(xy 347.710701 -226.096681) (xy 347.694991 -226.147611) (xy 347.671865 -226.195632) (xy 347.641841 -226.239669)
			(xy 347.605589 -226.27874) (xy 347.563918 -226.311971) (xy 347.51776 -226.33862) (xy 347.468146 -226.358092)
			(xy 347.416184 -226.369952) (xy 347.363034 -226.373936) (xy 347.309884 -226.369952) (xy 347.257922 -226.358092)
			(xy 347.208308 -226.33862) (xy 347.16215 -226.311971) (xy 347.120479 -226.27874) (xy 347.084227 -226.239669)
			(xy 347.054203 -226.195632) (xy 347.031077 -226.147611) (xy 347.015367 -226.096681) (xy 347.007424 -226.043977)
			(xy 346.778844 -226.043977) (xy 346.770901 -226.096681) (xy 346.755191 -226.147611) (xy 346.732065 -226.195632)
			(xy 346.702041 -226.239669) (xy 346.665789 -226.27874) (xy 346.624118 -226.311971) (xy 346.57796 -226.33862)
			(xy 346.528346 -226.358092) (xy 346.476384 -226.369952) (xy 346.423234 -226.373936) (xy 346.370084 -226.369952)
			(xy 346.318122 -226.358092) (xy 346.268508 -226.33862) (xy 346.22235 -226.311971) (xy 346.180679 -226.27874)
			(xy 346.144427 -226.239669) (xy 346.114403 -226.195632) (xy 346.091277 -226.147611) (xy 346.075567 -226.096681)
			(xy 346.067624 -226.043977) (xy 345.839044 -226.043977) (xy 345.831101 -226.096681) (xy 345.815391 -226.147611)
			(xy 345.792265 -226.195632) (xy 345.762241 -226.239669) (xy 345.725989 -226.27874) (xy 345.684318 -226.311971)
			(xy 345.63816 -226.33862) (xy 345.588546 -226.358092) (xy 345.536584 -226.369952) (xy 345.483434 -226.373936)
			(xy 345.430284 -226.369952) (xy 345.378322 -226.358092) (xy 345.328708 -226.33862) (xy 345.28255 -226.311971)
			(xy 345.240879 -226.27874) (xy 345.204627 -226.239669) (xy 345.174603 -226.195632) (xy 345.151477 -226.147611)
			(xy 345.135767 -226.096681) (xy 345.127824 -226.043977) (xy 344.899244 -226.043977) (xy 344.891301 -226.096681)
			(xy 344.875591 -226.147611) (xy 344.852465 -226.195632) (xy 344.822441 -226.239669) (xy 344.786189 -226.27874)
			(xy 344.744518 -226.311971) (xy 344.69836 -226.33862) (xy 344.648746 -226.358092) (xy 344.596784 -226.369952)
			(xy 344.543634 -226.373936) (xy 344.490484 -226.369952) (xy 344.438522 -226.358092) (xy 344.388908 -226.33862)
			(xy 344.34275 -226.311971) (xy 344.301079 -226.27874) (xy 344.264827 -226.239669) (xy 344.234803 -226.195632)
			(xy 344.211677 -226.147611) (xy 344.195967 -226.096681) (xy 344.188024 -226.043977) (xy 343.959444 -226.043977)
			(xy 343.951501 -226.096681) (xy 343.935791 -226.147611) (xy 343.912665 -226.195632) (xy 343.882641 -226.239669)
			(xy 343.846389 -226.27874) (xy 343.804718 -226.311971) (xy 343.75856 -226.33862) (xy 343.708946 -226.358092)
			(xy 343.656984 -226.369952) (xy 343.603834 -226.373936) (xy 343.550684 -226.369952) (xy 343.498722 -226.358092)
			(xy 343.449108 -226.33862) (xy 343.40295 -226.311971) (xy 343.361279 -226.27874) (xy 343.325027 -226.239669)
			(xy 343.295003 -226.195632) (xy 343.271877 -226.147611) (xy 343.256167 -226.096681) (xy 343.248224 -226.043977)
			(xy 343.019644 -226.043977) (xy 343.011701 -226.096681) (xy 342.995991 -226.147611) (xy 342.972865 -226.195632)
			(xy 342.942841 -226.239669) (xy 342.906589 -226.27874) (xy 342.864918 -226.311971) (xy 342.81876 -226.33862)
			(xy 342.769146 -226.358092) (xy 342.717184 -226.369952) (xy 342.664034 -226.373936) (xy 342.610884 -226.369952)
			(xy 342.558922 -226.358092) (xy 342.509308 -226.33862) (xy 342.46315 -226.311971) (xy 342.421479 -226.27874)
			(xy 342.385227 -226.239669) (xy 342.355203 -226.195632) (xy 342.332077 -226.147611) (xy 342.316367 -226.096681)
			(xy 342.308424 -226.043977) (xy 342.079844 -226.043977) (xy 342.071901 -226.096681) (xy 342.056191 -226.147611)
			(xy 342.033065 -226.195632) (xy 342.003041 -226.239669) (xy 341.966789 -226.27874) (xy 341.925118 -226.311971)
			(xy 341.87896 -226.33862) (xy 341.829346 -226.358092) (xy 341.777384 -226.369952) (xy 341.724234 -226.373936)
			(xy 341.671084 -226.369952) (xy 341.619122 -226.358092) (xy 341.569508 -226.33862) (xy 341.52335 -226.311971)
			(xy 341.481679 -226.27874) (xy 341.445427 -226.239669) (xy 341.415403 -226.195632) (xy 341.392277 -226.147611)
			(xy 341.376567 -226.096681) (xy 341.368624 -226.043977) (xy 341.140044 -226.043977) (xy 341.132101 -226.096681)
			(xy 341.116391 -226.147611) (xy 341.093265 -226.195632) (xy 341.063241 -226.239669) (xy 341.026989 -226.27874)
			(xy 340.985318 -226.311971) (xy 340.93916 -226.33862) (xy 340.889546 -226.358092) (xy 340.837584 -226.369952)
			(xy 340.784434 -226.373936) (xy 340.731284 -226.369952) (xy 340.679322 -226.358092) (xy 340.629708 -226.33862)
			(xy 340.58355 -226.311971) (xy 340.541879 -226.27874) (xy 340.505627 -226.239669) (xy 340.475603 -226.195632)
			(xy 340.452477 -226.147611) (xy 340.436767 -226.096681) (xy 340.428824 -226.043977) (xy 340.200244 -226.043977)
			(xy 340.192301 -226.096681) (xy 340.176591 -226.147611) (xy 340.153465 -226.195632) (xy 340.123441 -226.239669)
			(xy 340.087189 -226.27874) (xy 340.045518 -226.311971) (xy 339.99936 -226.33862) (xy 339.949746 -226.358092)
			(xy 339.897784 -226.369952) (xy 339.844634 -226.373936) (xy 339.791484 -226.369952) (xy 339.739522 -226.358092)
			(xy 339.689908 -226.33862) (xy 339.64375 -226.311971) (xy 339.602079 -226.27874) (xy 339.565827 -226.239669)
			(xy 339.535803 -226.195632) (xy 339.512677 -226.147611) (xy 339.496967 -226.096681) (xy 339.489024 -226.043977)
			(xy 339.26019 -226.043977) (xy 339.252247 -226.096681) (xy 339.236537 -226.147611) (xy 339.213411 -226.195632)
			(xy 339.183387 -226.239669) (xy 339.147135 -226.27874) (xy 339.105464 -226.311971) (xy 339.059306 -226.33862)
			(xy 339.009692 -226.358092) (xy 338.95773 -226.369952) (xy 338.90458 -226.373936) (xy 338.85143 -226.369952)
			(xy 338.799468 -226.358092) (xy 338.749854 -226.33862) (xy 338.703696 -226.311971) (xy 338.662025 -226.27874)
			(xy 338.625773 -226.239669) (xy 338.595749 -226.195632) (xy 338.572623 -226.147611) (xy 338.556913 -226.096681)
			(xy 338.54897 -226.043977) (xy 338.320644 -226.043977) (xy 338.312701 -226.096681) (xy 338.296991 -226.147611)
			(xy 338.273865 -226.195632) (xy 338.243841 -226.239669) (xy 338.207589 -226.27874) (xy 338.165918 -226.311971)
			(xy 338.11976 -226.33862) (xy 338.070146 -226.358092) (xy 338.018184 -226.369952) (xy 337.965034 -226.373936)
			(xy 337.911884 -226.369952) (xy 337.859922 -226.358092) (xy 337.810308 -226.33862) (xy 337.76415 -226.311971)
			(xy 337.722479 -226.27874) (xy 337.686227 -226.239669) (xy 337.656203 -226.195632) (xy 337.633077 -226.147611)
			(xy 337.617367 -226.096681) (xy 337.609424 -226.043977) (xy 337.380817 -226.043977) (xy 337.380791 -226.045311)
			(xy 337.372033 -226.100586) (xy 337.354736 -226.153812) (xy 337.329327 -226.203677) (xy 337.296431 -226.248953)
			(xy 337.256858 -226.288527) (xy 337.211582 -226.321424) (xy 337.161717 -226.346834) (xy 337.108492 -226.364131)
			(xy 337.053217 -226.372891) (xy 337.025234 -226.373436) (xy 337.000539 -226.373037) (xy 336.951617 -226.366252)
			(xy 336.904103 -226.352767) (xy 336.858912 -226.332841) (xy 336.81691 -226.306856) (xy 336.79765 -226.291394)
			(xy 336.786262 -226.282618) (xy 336.759891 -226.2712) (xy 336.731383 -226.26758) (xy 336.702994 -226.272045)
			(xy 336.676974 -226.284242) (xy 336.655381 -226.303204) (xy 336.639926 -226.327431) (xy 336.631831 -226.355005)
			(xy 336.63128 -226.369372) (xy 336.63128 -226.481386) (xy 336.666332 -226.492816) (xy 336.691135 -226.501465)
			(xy 336.738081 -226.525024) (xy 336.781058 -226.555224) (xy 336.819132 -226.591409) (xy 336.851478 -226.632795)
			(xy 336.877393 -226.678483) (xy 336.896315 -226.727482) (xy 336.907835 -226.77873) (xy 336.911701 -226.831114)
			(xy 336.90973 -226.857793) (xy 337.13927 -226.857793) (xy 337.13927 -226.804495) (xy 337.147213 -226.751791)
			(xy 337.162923 -226.700861) (xy 337.186049 -226.65284) (xy 337.216073 -226.608803) (xy 337.252325 -226.569732)
			(xy 337.293996 -226.536501) (xy 337.340154 -226.509852) (xy 337.389768 -226.49038) (xy 337.44173 -226.47852)
			(xy 337.49488 -226.474537) (xy 337.54803 -226.47852) (xy 337.599992 -226.49038) (xy 337.649606 -226.509852)
			(xy 337.695764 -226.536501) (xy 337.737435 -226.569732) (xy 337.773687 -226.608803) (xy 337.803711 -226.65284)
			(xy 337.826837 -226.700861) (xy 337.842547 -226.751791) (xy 337.85049 -226.804495) (xy 337.850988 -226.831144)
			(xy 337.85049 -226.857793) (xy 338.07907 -226.857793) (xy 338.07907 -226.804495) (xy 338.087013 -226.751791)
			(xy 338.102723 -226.700861) (xy 338.125849 -226.65284) (xy 338.155873 -226.608803) (xy 338.192125 -226.569732)
			(xy 338.233796 -226.536501) (xy 338.279954 -226.509852) (xy 338.329568 -226.49038) (xy 338.38153 -226.47852)
			(xy 338.43468 -226.474537) (xy 338.48783 -226.47852) (xy 338.539792 -226.49038) (xy 338.589406 -226.509852)
			(xy 338.635564 -226.536501) (xy 338.677235 -226.569732) (xy 338.713487 -226.608803) (xy 338.743511 -226.65284)
			(xy 338.766637 -226.700861) (xy 338.782347 -226.751791) (xy 338.79029 -226.804495) (xy 338.790788 -226.831144)
			(xy 338.79029 -226.857793) (xy 339.019124 -226.857793) (xy 339.019124 -226.804495) (xy 339.027067 -226.751791)
			(xy 339.042777 -226.700861) (xy 339.065903 -226.65284) (xy 339.095927 -226.608803) (xy 339.132179 -226.569732)
			(xy 339.17385 -226.536501) (xy 339.220008 -226.509852) (xy 339.269622 -226.49038) (xy 339.321584 -226.47852)
			(xy 339.374734 -226.474537) (xy 339.427884 -226.47852) (xy 339.479846 -226.49038) (xy 339.52946 -226.509852)
			(xy 339.575618 -226.536501) (xy 339.617289 -226.569732) (xy 339.653541 -226.608803) (xy 339.683565 -226.65284)
			(xy 339.706691 -226.700861) (xy 339.722401 -226.751791) (xy 339.730344 -226.804495) (xy 339.730842 -226.831144)
			(xy 339.730344 -226.857793) (xy 339.958924 -226.857793) (xy 339.958924 -226.804495) (xy 339.966867 -226.751791)
			(xy 339.982577 -226.700861) (xy 340.005703 -226.65284) (xy 340.035727 -226.608803) (xy 340.071979 -226.569732)
			(xy 340.11365 -226.536501) (xy 340.159808 -226.509852) (xy 340.209422 -226.49038) (xy 340.261384 -226.47852)
			(xy 340.314534 -226.474537) (xy 340.367684 -226.47852) (xy 340.419646 -226.49038) (xy 340.46926 -226.509852)
			(xy 340.515418 -226.536501) (xy 340.557089 -226.569732) (xy 340.593341 -226.608803) (xy 340.623365 -226.65284)
			(xy 340.646491 -226.700861) (xy 340.662201 -226.751791) (xy 340.670144 -226.804495) (xy 340.670642 -226.831144)
			(xy 340.670144 -226.857793) (xy 340.898724 -226.857793) (xy 340.898724 -226.804495) (xy 340.906667 -226.751791)
			(xy 340.922377 -226.700861) (xy 340.945503 -226.65284) (xy 340.975527 -226.608803) (xy 341.011779 -226.569732)
			(xy 341.05345 -226.536501) (xy 341.099608 -226.509852) (xy 341.149222 -226.49038) (xy 341.201184 -226.47852)
			(xy 341.254334 -226.474537) (xy 341.307484 -226.47852) (xy 341.359446 -226.49038) (xy 341.40906 -226.509852)
			(xy 341.455218 -226.536501) (xy 341.496889 -226.569732) (xy 341.533141 -226.608803) (xy 341.563165 -226.65284)
			(xy 341.586291 -226.700861) (xy 341.602001 -226.751791) (xy 341.609944 -226.804495) (xy 341.610442 -226.831144)
			(xy 341.609944 -226.857793) (xy 341.83827 -226.857793) (xy 341.83827 -226.804495) (xy 341.846213 -226.751791)
			(xy 341.861923 -226.700861) (xy 341.885049 -226.65284) (xy 341.915073 -226.608803) (xy 341.951325 -226.569732)
			(xy 341.992996 -226.536501) (xy 342.039154 -226.509852) (xy 342.088768 -226.49038) (xy 342.14073 -226.47852)
			(xy 342.19388 -226.474537) (xy 342.24703 -226.47852) (xy 342.298992 -226.49038) (xy 342.348606 -226.509852)
			(xy 342.394764 -226.536501) (xy 342.436435 -226.569732) (xy 342.472687 -226.608803) (xy 342.502711 -226.65284)
			(xy 342.525837 -226.700861) (xy 342.541547 -226.751791) (xy 342.54949 -226.804495) (xy 342.549988 -226.831144)
			(xy 342.54949 -226.857793) (xy 342.77807 -226.857793) (xy 342.77807 -226.804495) (xy 342.786013 -226.751791)
			(xy 342.801723 -226.700861) (xy 342.824849 -226.65284) (xy 342.854873 -226.608803) (xy 342.891125 -226.569732)
			(xy 342.932796 -226.536501) (xy 342.978954 -226.509852) (xy 343.028568 -226.49038) (xy 343.08053 -226.47852)
			(xy 343.13368 -226.474537) (xy 343.18683 -226.47852) (xy 343.238792 -226.49038) (xy 343.288406 -226.509852)
			(xy 343.334564 -226.536501) (xy 343.376235 -226.569732) (xy 343.412487 -226.608803) (xy 343.442511 -226.65284)
			(xy 343.465637 -226.700861) (xy 343.481347 -226.751791) (xy 343.48929 -226.804495) (xy 343.489788 -226.831144)
			(xy 343.48929 -226.857793) (xy 343.718124 -226.857793) (xy 343.718124 -226.804495) (xy 343.726067 -226.751791)
			(xy 343.741777 -226.700861) (xy 343.764903 -226.65284) (xy 343.794927 -226.608803) (xy 343.831179 -226.569732)
			(xy 343.87285 -226.536501) (xy 343.919008 -226.509852) (xy 343.968622 -226.49038) (xy 344.020584 -226.47852)
			(xy 344.073734 -226.474537) (xy 344.126884 -226.47852) (xy 344.178846 -226.49038) (xy 344.22846 -226.509852)
			(xy 344.274618 -226.536501) (xy 344.316289 -226.569732) (xy 344.352541 -226.608803) (xy 344.382565 -226.65284)
			(xy 344.405691 -226.700861) (xy 344.421401 -226.751791) (xy 344.429344 -226.804495) (xy 344.429842 -226.831144)
			(xy 344.429344 -226.857793) (xy 344.65767 -226.857793) (xy 344.65767 -226.804495) (xy 344.665613 -226.751791)
			(xy 344.681323 -226.700861) (xy 344.704449 -226.65284) (xy 344.734473 -226.608803) (xy 344.770725 -226.569732)
			(xy 344.812396 -226.536501) (xy 344.858554 -226.509852) (xy 344.908168 -226.49038) (xy 344.96013 -226.47852)
			(xy 345.01328 -226.474537) (xy 345.06643 -226.47852) (xy 345.118392 -226.49038) (xy 345.168006 -226.509852)
			(xy 345.214164 -226.536501) (xy 345.255835 -226.569732) (xy 345.292087 -226.608803) (xy 345.322111 -226.65284)
			(xy 345.345237 -226.700861) (xy 345.360947 -226.751791) (xy 345.36889 -226.804495) (xy 345.369388 -226.831144)
			(xy 345.36889 -226.857793) (xy 345.59747 -226.857793) (xy 345.59747 -226.804495) (xy 345.605413 -226.751791)
			(xy 345.621123 -226.700861) (xy 345.644249 -226.65284) (xy 345.674273 -226.608803) (xy 345.710525 -226.569732)
			(xy 345.752196 -226.536501) (xy 345.798354 -226.509852) (xy 345.847968 -226.49038) (xy 345.89993 -226.47852)
			(xy 345.95308 -226.474537) (xy 346.00623 -226.47852) (xy 346.058192 -226.49038) (xy 346.107806 -226.509852)
			(xy 346.153964 -226.536501) (xy 346.195635 -226.569732) (xy 346.231887 -226.608803) (xy 346.261911 -226.65284)
			(xy 346.285037 -226.700861) (xy 346.300747 -226.751791) (xy 346.30869 -226.804495) (xy 346.309188 -226.831144)
			(xy 346.30869 -226.857793) (xy 346.537524 -226.857793) (xy 346.537524 -226.804495) (xy 346.545467 -226.751791)
			(xy 346.561177 -226.700861) (xy 346.584303 -226.65284) (xy 346.614327 -226.608803) (xy 346.650579 -226.569732)
			(xy 346.69225 -226.536501) (xy 346.738408 -226.509852) (xy 346.788022 -226.49038) (xy 346.839984 -226.47852)
			(xy 346.893134 -226.474537) (xy 346.946284 -226.47852) (xy 346.998246 -226.49038) (xy 347.04786 -226.509852)
			(xy 347.094018 -226.536501) (xy 347.135689 -226.569732) (xy 347.171941 -226.608803) (xy 347.201965 -226.65284)
			(xy 347.225091 -226.700861) (xy 347.240801 -226.751791) (xy 347.248744 -226.804495) (xy 347.249242 -226.831144)
			(xy 347.248744 -226.857793) (xy 347.477324 -226.857793) (xy 347.477324 -226.804495) (xy 347.485267 -226.751791)
			(xy 347.500977 -226.700861) (xy 347.524103 -226.65284) (xy 347.554127 -226.608803) (xy 347.590379 -226.569732)
			(xy 347.63205 -226.536501) (xy 347.678208 -226.509852) (xy 347.727822 -226.49038) (xy 347.779784 -226.47852)
			(xy 347.832934 -226.474537) (xy 347.886084 -226.47852) (xy 347.938046 -226.49038) (xy 347.98766 -226.509852)
			(xy 348.033818 -226.536501) (xy 348.075489 -226.569732) (xy 348.111741 -226.608803) (xy 348.141765 -226.65284)
			(xy 348.164891 -226.700861) (xy 348.180601 -226.751791) (xy 348.188544 -226.804495) (xy 348.189042 -226.831144)
			(xy 348.188544 -226.857793) (xy 348.417124 -226.857793) (xy 348.417124 -226.804495) (xy 348.425067 -226.751791)
			(xy 348.440777 -226.700861) (xy 348.463903 -226.65284) (xy 348.493927 -226.608803) (xy 348.530179 -226.569732)
			(xy 348.57185 -226.536501) (xy 348.618008 -226.509852) (xy 348.667622 -226.49038) (xy 348.719584 -226.47852)
			(xy 348.772734 -226.474537) (xy 348.825884 -226.47852) (xy 348.877846 -226.49038) (xy 348.92746 -226.509852)
			(xy 348.973618 -226.536501) (xy 349.015289 -226.569732) (xy 349.051541 -226.608803) (xy 349.081565 -226.65284)
			(xy 349.104691 -226.700861) (xy 349.120401 -226.751791) (xy 349.128344 -226.804495) (xy 349.128842 -226.831144)
			(xy 349.128344 -226.857793) (xy 349.35667 -226.857793) (xy 349.35667 -226.804495) (xy 349.364613 -226.751791)
			(xy 349.380323 -226.700861) (xy 349.403449 -226.65284) (xy 349.433473 -226.608803) (xy 349.469725 -226.569732)
			(xy 349.511396 -226.536501) (xy 349.557554 -226.509852) (xy 349.607168 -226.49038) (xy 349.65913 -226.47852)
			(xy 349.71228 -226.474537) (xy 349.76543 -226.47852) (xy 349.817392 -226.49038) (xy 349.867006 -226.509852)
			(xy 349.913164 -226.536501) (xy 349.954835 -226.569732) (xy 349.991087 -226.608803) (xy 350.021111 -226.65284)
			(xy 350.044237 -226.700861) (xy 350.059947 -226.751791) (xy 350.06789 -226.804495) (xy 350.068388 -226.831144)
			(xy 350.06789 -226.857793) (xy 350.29647 -226.857793) (xy 350.29647 -226.804495) (xy 350.304413 -226.751791)
			(xy 350.320123 -226.700861) (xy 350.343249 -226.65284) (xy 350.373273 -226.608803) (xy 350.409525 -226.569732)
			(xy 350.451196 -226.536501) (xy 350.497354 -226.509852) (xy 350.546968 -226.49038) (xy 350.59893 -226.47852)
			(xy 350.65208 -226.474537) (xy 350.70523 -226.47852) (xy 350.757192 -226.49038) (xy 350.806806 -226.509852)
			(xy 350.852964 -226.536501) (xy 350.894635 -226.569732) (xy 350.930887 -226.608803) (xy 350.960911 -226.65284)
			(xy 350.984037 -226.700861) (xy 350.999747 -226.751791) (xy 351.00769 -226.804495) (xy 351.008188 -226.831144)
			(xy 351.00769 -226.857793) (xy 351.236524 -226.857793) (xy 351.236524 -226.804495) (xy 351.244467 -226.751791)
			(xy 351.260177 -226.700861) (xy 351.283303 -226.65284) (xy 351.313327 -226.608803) (xy 351.349579 -226.569732)
			(xy 351.39125 -226.536501) (xy 351.437408 -226.509852) (xy 351.487022 -226.49038) (xy 351.538984 -226.47852)
			(xy 351.592134 -226.474537) (xy 351.645284 -226.47852) (xy 351.697246 -226.49038) (xy 351.74686 -226.509852)
			(xy 351.793018 -226.536501) (xy 351.834689 -226.569732) (xy 351.870941 -226.608803) (xy 351.900965 -226.65284)
			(xy 351.924091 -226.700861) (xy 351.939801 -226.751791) (xy 351.947744 -226.804495) (xy 351.948242 -226.831144)
			(xy 351.947744 -226.857793) (xy 352.176324 -226.857793) (xy 352.176324 -226.804495) (xy 352.184267 -226.751791)
			(xy 352.199977 -226.700861) (xy 352.223103 -226.65284) (xy 352.253127 -226.608803) (xy 352.289379 -226.569732)
			(xy 352.33105 -226.536501) (xy 352.377208 -226.509852) (xy 352.426822 -226.49038) (xy 352.478784 -226.47852)
			(xy 352.531934 -226.474537) (xy 352.585084 -226.47852) (xy 352.637046 -226.49038) (xy 352.68666 -226.509852)
			(xy 352.732818 -226.536501) (xy 352.774489 -226.569732) (xy 352.810741 -226.608803) (xy 352.840765 -226.65284)
			(xy 352.863891 -226.700861) (xy 352.879601 -226.751791) (xy 352.887544 -226.804495) (xy 352.888042 -226.831144)
			(xy 352.887544 -226.857793) (xy 353.11587 -226.857793) (xy 353.11587 -226.804495) (xy 353.123813 -226.751791)
			(xy 353.139523 -226.700861) (xy 353.162649 -226.65284) (xy 353.192673 -226.608803) (xy 353.228925 -226.569732)
			(xy 353.270596 -226.536501) (xy 353.316754 -226.509852) (xy 353.366368 -226.49038) (xy 353.41833 -226.47852)
			(xy 353.47148 -226.474537) (xy 353.52463 -226.47852) (xy 353.576592 -226.49038) (xy 353.626206 -226.509852)
			(xy 353.672364 -226.536501) (xy 353.714035 -226.569732) (xy 353.750287 -226.608803) (xy 353.780311 -226.65284)
			(xy 353.803437 -226.700861) (xy 353.819147 -226.751791) (xy 353.82709 -226.804495) (xy 353.827588 -226.831144)
			(xy 353.82709 -226.857793) (xy 354.055924 -226.857793) (xy 354.055924 -226.804495) (xy 354.063867 -226.751791)
			(xy 354.079577 -226.700861) (xy 354.102703 -226.65284) (xy 354.132727 -226.608803) (xy 354.168979 -226.569732)
			(xy 354.21065 -226.536501) (xy 354.256808 -226.509852) (xy 354.306422 -226.49038) (xy 354.358384 -226.47852)
			(xy 354.411534 -226.474537) (xy 354.464684 -226.47852) (xy 354.516646 -226.49038) (xy 354.56626 -226.509852)
			(xy 354.612418 -226.536501) (xy 354.654089 -226.569732) (xy 354.690341 -226.608803) (xy 354.720365 -226.65284)
			(xy 354.743491 -226.700861) (xy 354.759201 -226.751791) (xy 354.767144 -226.804495) (xy 354.767642 -226.831144)
			(xy 354.767144 -226.857793) (xy 354.99547 -226.857793) (xy 354.99547 -226.804495) (xy 355.003413 -226.751791)
			(xy 355.019123 -226.700861) (xy 355.042249 -226.65284) (xy 355.072273 -226.608803) (xy 355.108525 -226.569732)
			(xy 355.150196 -226.536501) (xy 355.196354 -226.509852) (xy 355.245968 -226.49038) (xy 355.29793 -226.47852)
			(xy 355.35108 -226.474537) (xy 355.40423 -226.47852) (xy 355.456192 -226.49038) (xy 355.505806 -226.509852)
			(xy 355.551964 -226.536501) (xy 355.593635 -226.569732) (xy 355.629887 -226.608803) (xy 355.659911 -226.65284)
			(xy 355.683037 -226.700861) (xy 355.698747 -226.751791) (xy 355.70669 -226.804495) (xy 355.707188 -226.831144)
			(xy 355.70669 -226.857793) (xy 355.935524 -226.857793) (xy 355.935524 -226.804495) (xy 355.943467 -226.751791)
			(xy 355.959177 -226.700861) (xy 355.982303 -226.65284) (xy 356.012327 -226.608803) (xy 356.048579 -226.569732)
			(xy 356.09025 -226.536501) (xy 356.136408 -226.509852) (xy 356.186022 -226.49038) (xy 356.237984 -226.47852)
			(xy 356.291134 -226.474537) (xy 356.344284 -226.47852) (xy 356.396246 -226.49038) (xy 356.44586 -226.509852)
			(xy 356.492018 -226.536501) (xy 356.533689 -226.569732) (xy 356.569941 -226.608803) (xy 356.599965 -226.65284)
			(xy 356.623091 -226.700861) (xy 356.638801 -226.751791) (xy 356.646744 -226.804495) (xy 356.647242 -226.831144)
			(xy 356.646744 -226.857793) (xy 356.87507 -226.857793) (xy 356.87507 -226.804495) (xy 356.883013 -226.751791)
			(xy 356.898723 -226.700861) (xy 356.921849 -226.65284) (xy 356.951873 -226.608803) (xy 356.988125 -226.569732)
			(xy 357.029796 -226.536501) (xy 357.075954 -226.509852) (xy 357.125568 -226.49038) (xy 357.17753 -226.47852)
			(xy 357.23068 -226.474537) (xy 357.28383 -226.47852) (xy 357.335792 -226.49038) (xy 357.385406 -226.509852)
			(xy 357.431564 -226.536501) (xy 357.473235 -226.569732) (xy 357.509487 -226.608803) (xy 357.539511 -226.65284)
			(xy 357.562637 -226.700861) (xy 357.578347 -226.751791) (xy 357.58629 -226.804495) (xy 357.586788 -226.831144)
			(xy 357.58629 -226.857793) (xy 357.815124 -226.857793) (xy 357.815124 -226.804495) (xy 357.823067 -226.751791)
			(xy 357.838777 -226.700861) (xy 357.861903 -226.65284) (xy 357.891927 -226.608803) (xy 357.928179 -226.569732)
			(xy 357.96985 -226.536501) (xy 358.016008 -226.509852) (xy 358.065622 -226.49038) (xy 358.117584 -226.47852)
			(xy 358.170734 -226.474537) (xy 358.223884 -226.47852) (xy 358.275846 -226.49038) (xy 358.32546 -226.509852)
			(xy 358.371618 -226.536501) (xy 358.413289 -226.569732) (xy 358.449541 -226.608803) (xy 358.479565 -226.65284)
			(xy 358.502691 -226.700861) (xy 358.518401 -226.751791) (xy 358.526344 -226.804495) (xy 358.526842 -226.831144)
			(xy 358.526344 -226.857793) (xy 358.518401 -226.910497) (xy 358.502691 -226.961427) (xy 358.479565 -227.009448)
			(xy 358.449541 -227.053485) (xy 358.413289 -227.092556) (xy 358.371618 -227.125787) (xy 358.32546 -227.152436)
			(xy 358.275846 -227.171908) (xy 358.223884 -227.183768) (xy 358.170734 -227.187752) (xy 358.117584 -227.183768)
			(xy 358.065622 -227.171908) (xy 358.016008 -227.152436) (xy 357.96985 -227.125787) (xy 357.928179 -227.092556)
			(xy 357.891927 -227.053485) (xy 357.861903 -227.009448) (xy 357.838777 -226.961427) (xy 357.823067 -226.910497)
			(xy 357.815124 -226.857793) (xy 357.58629 -226.857793) (xy 357.578347 -226.910497) (xy 357.562637 -226.961427)
			(xy 357.539511 -227.009448) (xy 357.509487 -227.053485) (xy 357.473235 -227.092556) (xy 357.431564 -227.125787)
			(xy 357.385406 -227.152436) (xy 357.335792 -227.171908) (xy 357.28383 -227.183768) (xy 357.23068 -227.187752)
			(xy 357.17753 -227.183768) (xy 357.125568 -227.171908) (xy 357.075954 -227.152436) (xy 357.029796 -227.125787)
			(xy 356.988125 -227.092556) (xy 356.951873 -227.053485) (xy 356.921849 -227.009448) (xy 356.898723 -226.961427)
			(xy 356.883013 -226.910497) (xy 356.87507 -226.857793) (xy 356.646744 -226.857793) (xy 356.638801 -226.910497)
			(xy 356.623091 -226.961427) (xy 356.599965 -227.009448) (xy 356.569941 -227.053485) (xy 356.533689 -227.092556)
			(xy 356.492018 -227.125787) (xy 356.44586 -227.152436) (xy 356.396246 -227.171908) (xy 356.344284 -227.183768)
			(xy 356.291134 -227.187752) (xy 356.237984 -227.183768) (xy 356.186022 -227.171908) (xy 356.136408 -227.152436)
			(xy 356.09025 -227.125787) (xy 356.048579 -227.092556) (xy 356.012327 -227.053485) (xy 355.982303 -227.009448)
			(xy 355.959177 -226.961427) (xy 355.943467 -226.910497) (xy 355.935524 -226.857793) (xy 355.70669 -226.857793)
			(xy 355.698747 -226.910497) (xy 355.683037 -226.961427) (xy 355.659911 -227.009448) (xy 355.629887 -227.053485)
			(xy 355.593635 -227.092556) (xy 355.551964 -227.125787) (xy 355.505806 -227.152436) (xy 355.456192 -227.171908)
			(xy 355.40423 -227.183768) (xy 355.35108 -227.187752) (xy 355.29793 -227.183768) (xy 355.245968 -227.171908)
			(xy 355.196354 -227.152436) (xy 355.150196 -227.125787) (xy 355.108525 -227.092556) (xy 355.072273 -227.053485)
			(xy 355.042249 -227.009448) (xy 355.019123 -226.961427) (xy 355.003413 -226.910497) (xy 354.99547 -226.857793)
			(xy 354.767144 -226.857793) (xy 354.759201 -226.910497) (xy 354.743491 -226.961427) (xy 354.720365 -227.009448)
			(xy 354.690341 -227.053485) (xy 354.654089 -227.092556) (xy 354.612418 -227.125787) (xy 354.56626 -227.152436)
			(xy 354.516646 -227.171908) (xy 354.464684 -227.183768) (xy 354.411534 -227.187752) (xy 354.358384 -227.183768)
			(xy 354.306422 -227.171908) (xy 354.256808 -227.152436) (xy 354.21065 -227.125787) (xy 354.168979 -227.092556)
			(xy 354.132727 -227.053485) (xy 354.102703 -227.009448) (xy 354.079577 -226.961427) (xy 354.063867 -226.910497)
			(xy 354.055924 -226.857793) (xy 353.82709 -226.857793) (xy 353.819147 -226.910497) (xy 353.803437 -226.961427)
			(xy 353.780311 -227.009448) (xy 353.750287 -227.053485) (xy 353.714035 -227.092556) (xy 353.672364 -227.125787)
			(xy 353.626206 -227.152436) (xy 353.576592 -227.171908) (xy 353.52463 -227.183768) (xy 353.47148 -227.187752)
			(xy 353.41833 -227.183768) (xy 353.366368 -227.171908) (xy 353.316754 -227.152436) (xy 353.270596 -227.125787)
			(xy 353.228925 -227.092556) (xy 353.192673 -227.053485) (xy 353.162649 -227.009448) (xy 353.139523 -226.961427)
			(xy 353.123813 -226.910497) (xy 353.11587 -226.857793) (xy 352.887544 -226.857793) (xy 352.879601 -226.910497)
			(xy 352.863891 -226.961427) (xy 352.840765 -227.009448) (xy 352.810741 -227.053485) (xy 352.774489 -227.092556)
			(xy 352.732818 -227.125787) (xy 352.68666 -227.152436) (xy 352.637046 -227.171908) (xy 352.585084 -227.183768)
			(xy 352.531934 -227.187752) (xy 352.478784 -227.183768) (xy 352.426822 -227.171908) (xy 352.377208 -227.152436)
			(xy 352.33105 -227.125787) (xy 352.289379 -227.092556) (xy 352.253127 -227.053485) (xy 352.223103 -227.009448)
			(xy 352.199977 -226.961427) (xy 352.184267 -226.910497) (xy 352.176324 -226.857793) (xy 351.947744 -226.857793)
			(xy 351.939801 -226.910497) (xy 351.924091 -226.961427) (xy 351.900965 -227.009448) (xy 351.870941 -227.053485)
			(xy 351.834689 -227.092556) (xy 351.793018 -227.125787) (xy 351.74686 -227.152436) (xy 351.697246 -227.171908)
			(xy 351.645284 -227.183768) (xy 351.592134 -227.187752) (xy 351.538984 -227.183768) (xy 351.487022 -227.171908)
			(xy 351.437408 -227.152436) (xy 351.39125 -227.125787) (xy 351.349579 -227.092556) (xy 351.313327 -227.053485)
			(xy 351.283303 -227.009448) (xy 351.260177 -226.961427) (xy 351.244467 -226.910497) (xy 351.236524 -226.857793)
			(xy 351.00769 -226.857793) (xy 350.999747 -226.910497) (xy 350.984037 -226.961427) (xy 350.960911 -227.009448)
			(xy 350.930887 -227.053485) (xy 350.894635 -227.092556) (xy 350.852964 -227.125787) (xy 350.806806 -227.152436)
			(xy 350.757192 -227.171908) (xy 350.70523 -227.183768) (xy 350.65208 -227.187752) (xy 350.59893 -227.183768)
			(xy 350.546968 -227.171908) (xy 350.497354 -227.152436) (xy 350.451196 -227.125787) (xy 350.409525 -227.092556)
			(xy 350.373273 -227.053485) (xy 350.343249 -227.009448) (xy 350.320123 -226.961427) (xy 350.304413 -226.910497)
			(xy 350.29647 -226.857793) (xy 350.06789 -226.857793) (xy 350.059947 -226.910497) (xy 350.044237 -226.961427)
			(xy 350.021111 -227.009448) (xy 349.991087 -227.053485) (xy 349.954835 -227.092556) (xy 349.913164 -227.125787)
			(xy 349.867006 -227.152436) (xy 349.817392 -227.171908) (xy 349.76543 -227.183768) (xy 349.71228 -227.187752)
			(xy 349.65913 -227.183768) (xy 349.607168 -227.171908) (xy 349.557554 -227.152436) (xy 349.511396 -227.125787)
			(xy 349.469725 -227.092556) (xy 349.433473 -227.053485) (xy 349.403449 -227.009448) (xy 349.380323 -226.961427)
			(xy 349.364613 -226.910497) (xy 349.35667 -226.857793) (xy 349.128344 -226.857793) (xy 349.120401 -226.910497)
			(xy 349.104691 -226.961427) (xy 349.081565 -227.009448) (xy 349.051541 -227.053485) (xy 349.015289 -227.092556)
			(xy 348.973618 -227.125787) (xy 348.92746 -227.152436) (xy 348.877846 -227.171908) (xy 348.825884 -227.183768)
			(xy 348.772734 -227.187752) (xy 348.719584 -227.183768) (xy 348.667622 -227.171908) (xy 348.618008 -227.152436)
			(xy 348.57185 -227.125787) (xy 348.530179 -227.092556) (xy 348.493927 -227.053485) (xy 348.463903 -227.009448)
			(xy 348.440777 -226.961427) (xy 348.425067 -226.910497) (xy 348.417124 -226.857793) (xy 348.188544 -226.857793)
			(xy 348.180601 -226.910497) (xy 348.164891 -226.961427) (xy 348.141765 -227.009448) (xy 348.111741 -227.053485)
			(xy 348.075489 -227.092556) (xy 348.033818 -227.125787) (xy 347.98766 -227.152436) (xy 347.938046 -227.171908)
			(xy 347.886084 -227.183768) (xy 347.832934 -227.187752) (xy 347.779784 -227.183768) (xy 347.727822 -227.171908)
			(xy 347.678208 -227.152436) (xy 347.63205 -227.125787) (xy 347.590379 -227.092556) (xy 347.554127 -227.053485)
			(xy 347.524103 -227.009448) (xy 347.500977 -226.961427) (xy 347.485267 -226.910497) (xy 347.477324 -226.857793)
			(xy 347.248744 -226.857793) (xy 347.240801 -226.910497) (xy 347.225091 -226.961427) (xy 347.201965 -227.009448)
			(xy 347.171941 -227.053485) (xy 347.135689 -227.092556) (xy 347.094018 -227.125787) (xy 347.04786 -227.152436)
			(xy 346.998246 -227.171908) (xy 346.946284 -227.183768) (xy 346.893134 -227.187752) (xy 346.839984 -227.183768)
			(xy 346.788022 -227.171908) (xy 346.738408 -227.152436) (xy 346.69225 -227.125787) (xy 346.650579 -227.092556)
			(xy 346.614327 -227.053485) (xy 346.584303 -227.009448) (xy 346.561177 -226.961427) (xy 346.545467 -226.910497)
			(xy 346.537524 -226.857793) (xy 346.30869 -226.857793) (xy 346.300747 -226.910497) (xy 346.285037 -226.961427)
			(xy 346.261911 -227.009448) (xy 346.231887 -227.053485) (xy 346.195635 -227.092556) (xy 346.153964 -227.125787)
			(xy 346.107806 -227.152436) (xy 346.058192 -227.171908) (xy 346.00623 -227.183768) (xy 345.95308 -227.187752)
			(xy 345.89993 -227.183768) (xy 345.847968 -227.171908) (xy 345.798354 -227.152436) (xy 345.752196 -227.125787)
			(xy 345.710525 -227.092556) (xy 345.674273 -227.053485) (xy 345.644249 -227.009448) (xy 345.621123 -226.961427)
			(xy 345.605413 -226.910497) (xy 345.59747 -226.857793) (xy 345.36889 -226.857793) (xy 345.360947 -226.910497)
			(xy 345.345237 -226.961427) (xy 345.322111 -227.009448) (xy 345.292087 -227.053485) (xy 345.255835 -227.092556)
			(xy 345.214164 -227.125787) (xy 345.168006 -227.152436) (xy 345.118392 -227.171908) (xy 345.06643 -227.183768)
			(xy 345.01328 -227.187752) (xy 344.96013 -227.183768) (xy 344.908168 -227.171908) (xy 344.858554 -227.152436)
			(xy 344.812396 -227.125787) (xy 344.770725 -227.092556) (xy 344.734473 -227.053485) (xy 344.704449 -227.009448)
			(xy 344.681323 -226.961427) (xy 344.665613 -226.910497) (xy 344.65767 -226.857793) (xy 344.429344 -226.857793)
			(xy 344.421401 -226.910497) (xy 344.405691 -226.961427) (xy 344.382565 -227.009448) (xy 344.352541 -227.053485)
			(xy 344.316289 -227.092556) (xy 344.274618 -227.125787) (xy 344.22846 -227.152436) (xy 344.178846 -227.171908)
			(xy 344.126884 -227.183768) (xy 344.073734 -227.187752) (xy 344.020584 -227.183768) (xy 343.968622 -227.171908)
			(xy 343.919008 -227.152436) (xy 343.87285 -227.125787) (xy 343.831179 -227.092556) (xy 343.794927 -227.053485)
			(xy 343.764903 -227.009448) (xy 343.741777 -226.961427) (xy 343.726067 -226.910497) (xy 343.718124 -226.857793)
			(xy 343.48929 -226.857793) (xy 343.481347 -226.910497) (xy 343.465637 -226.961427) (xy 343.442511 -227.009448)
			(xy 343.412487 -227.053485) (xy 343.376235 -227.092556) (xy 343.334564 -227.125787) (xy 343.288406 -227.152436)
			(xy 343.238792 -227.171908) (xy 343.18683 -227.183768) (xy 343.13368 -227.187752) (xy 343.08053 -227.183768)
			(xy 343.028568 -227.171908) (xy 342.978954 -227.152436) (xy 342.932796 -227.125787) (xy 342.891125 -227.092556)
			(xy 342.854873 -227.053485) (xy 342.824849 -227.009448) (xy 342.801723 -226.961427) (xy 342.786013 -226.910497)
			(xy 342.77807 -226.857793) (xy 342.54949 -226.857793) (xy 342.541547 -226.910497) (xy 342.525837 -226.961427)
			(xy 342.502711 -227.009448) (xy 342.472687 -227.053485) (xy 342.436435 -227.092556) (xy 342.394764 -227.125787)
			(xy 342.348606 -227.152436) (xy 342.298992 -227.171908) (xy 342.24703 -227.183768) (xy 342.19388 -227.187752)
			(xy 342.14073 -227.183768) (xy 342.088768 -227.171908) (xy 342.039154 -227.152436) (xy 341.992996 -227.125787)
			(xy 341.951325 -227.092556) (xy 341.915073 -227.053485) (xy 341.885049 -227.009448) (xy 341.861923 -226.961427)
			(xy 341.846213 -226.910497) (xy 341.83827 -226.857793) (xy 341.609944 -226.857793) (xy 341.602001 -226.910497)
			(xy 341.586291 -226.961427) (xy 341.563165 -227.009448) (xy 341.533141 -227.053485) (xy 341.496889 -227.092556)
			(xy 341.455218 -227.125787) (xy 341.40906 -227.152436) (xy 341.359446 -227.171908) (xy 341.307484 -227.183768)
			(xy 341.254334 -227.187752) (xy 341.201184 -227.183768) (xy 341.149222 -227.171908) (xy 341.099608 -227.152436)
			(xy 341.05345 -227.125787) (xy 341.011779 -227.092556) (xy 340.975527 -227.053485) (xy 340.945503 -227.009448)
			(xy 340.922377 -226.961427) (xy 340.906667 -226.910497) (xy 340.898724 -226.857793) (xy 340.670144 -226.857793)
			(xy 340.662201 -226.910497) (xy 340.646491 -226.961427) (xy 340.623365 -227.009448) (xy 340.593341 -227.053485)
			(xy 340.557089 -227.092556) (xy 340.515418 -227.125787) (xy 340.46926 -227.152436) (xy 340.419646 -227.171908)
			(xy 340.367684 -227.183768) (xy 340.314534 -227.187752) (xy 340.261384 -227.183768) (xy 340.209422 -227.171908)
			(xy 340.159808 -227.152436) (xy 340.11365 -227.125787) (xy 340.071979 -227.092556) (xy 340.035727 -227.053485)
			(xy 340.005703 -227.009448) (xy 339.982577 -226.961427) (xy 339.966867 -226.910497) (xy 339.958924 -226.857793)
			(xy 339.730344 -226.857793) (xy 339.722401 -226.910497) (xy 339.706691 -226.961427) (xy 339.683565 -227.009448)
			(xy 339.653541 -227.053485) (xy 339.617289 -227.092556) (xy 339.575618 -227.125787) (xy 339.52946 -227.152436)
			(xy 339.479846 -227.171908) (xy 339.427884 -227.183768) (xy 339.374734 -227.187752) (xy 339.321584 -227.183768)
			(xy 339.269622 -227.171908) (xy 339.220008 -227.152436) (xy 339.17385 -227.125787) (xy 339.132179 -227.092556)
			(xy 339.095927 -227.053485) (xy 339.065903 -227.009448) (xy 339.042777 -226.961427) (xy 339.027067 -226.910497)
			(xy 339.019124 -226.857793) (xy 338.79029 -226.857793) (xy 338.782347 -226.910497) (xy 338.766637 -226.961427)
			(xy 338.743511 -227.009448) (xy 338.713487 -227.053485) (xy 338.677235 -227.092556) (xy 338.635564 -227.125787)
			(xy 338.589406 -227.152436) (xy 338.539792 -227.171908) (xy 338.48783 -227.183768) (xy 338.43468 -227.187752)
			(xy 338.38153 -227.183768) (xy 338.329568 -227.171908) (xy 338.279954 -227.152436) (xy 338.233796 -227.125787)
			(xy 338.192125 -227.092556) (xy 338.155873 -227.053485) (xy 338.125849 -227.009448) (xy 338.102723 -226.961427)
			(xy 338.087013 -226.910497) (xy 338.07907 -226.857793) (xy 337.85049 -226.857793) (xy 337.842547 -226.910497)
			(xy 337.826837 -226.961427) (xy 337.803711 -227.009448) (xy 337.773687 -227.053485) (xy 337.737435 -227.092556)
			(xy 337.695764 -227.125787) (xy 337.649606 -227.152436) (xy 337.599992 -227.171908) (xy 337.54803 -227.183768)
			(xy 337.49488 -227.187752) (xy 337.44173 -227.183768) (xy 337.389768 -227.171908) (xy 337.340154 -227.152436)
			(xy 337.293996 -227.125787) (xy 337.252325 -227.092556) (xy 337.216073 -227.053485) (xy 337.186049 -227.009448)
			(xy 337.162923 -226.961427) (xy 337.147213 -226.910497) (xy 337.13927 -226.857793) (xy 336.90973 -226.857793)
			(xy 336.907831 -226.883497) (xy 336.896307 -226.934744) (xy 336.877381 -226.983742) (xy 336.851462 -227.029428)
			(xy 336.819113 -227.070811) (xy 336.781037 -227.106994) (xy 336.738058 -227.13719) (xy 336.691109 -227.160745)
			(xy 336.666332 -227.169472) (xy 336.63128 -227.180902) (xy 336.63128 -227.292916) (xy 336.631806 -227.307287)
			(xy 336.639881 -227.334874) (xy 336.655329 -227.359114) (xy 336.676925 -227.378085) (xy 336.702954 -227.39028)
			(xy 336.731351 -227.394732) (xy 336.759864 -227.391088) (xy 336.786229 -227.379637) (xy 336.79765 -227.370894)
			(xy 336.816926 -227.355457) (xy 336.858931 -227.329486) (xy 336.90412 -227.309564) (xy 336.951627 -227.296074)
			(xy 337.000541 -227.289273) (xy 337.025234 -227.288852) (xy 337.051885 -227.289352) (xy 337.10459 -227.297301)
			(xy 337.155522 -227.313016) (xy 337.203543 -227.336146) (xy 337.247581 -227.366174) (xy 337.286652 -227.40243)
			(xy 337.319883 -227.444104) (xy 337.346533 -227.490265) (xy 337.366005 -227.539882) (xy 337.377865 -227.591848)
			(xy 337.381848 -227.645) (xy 337.379854 -227.671609) (xy 337.609424 -227.671609) (xy 337.609424 -227.618311)
			(xy 337.617367 -227.565607) (xy 337.633077 -227.514677) (xy 337.656203 -227.466656) (xy 337.686227 -227.422619)
			(xy 337.722479 -227.383548) (xy 337.76415 -227.350317) (xy 337.810308 -227.323668) (xy 337.859922 -227.304196)
			(xy 337.911884 -227.292336) (xy 337.965034 -227.288353) (xy 338.018184 -227.292336) (xy 338.070146 -227.304196)
			(xy 338.11976 -227.323668) (xy 338.165918 -227.350317) (xy 338.207589 -227.383548) (xy 338.243841 -227.422619)
			(xy 338.273865 -227.466656) (xy 338.296991 -227.514677) (xy 338.312701 -227.565607) (xy 338.320644 -227.618311)
			(xy 338.321142 -227.64496) (xy 338.320644 -227.671609) (xy 338.549224 -227.671609) (xy 338.549224 -227.618311)
			(xy 338.557167 -227.565607) (xy 338.572877 -227.514677) (xy 338.596003 -227.466656) (xy 338.626027 -227.422619)
			(xy 338.662279 -227.383548) (xy 338.70395 -227.350317) (xy 338.750108 -227.323668) (xy 338.799722 -227.304196)
			(xy 338.851684 -227.292336) (xy 338.904834 -227.288353) (xy 338.957984 -227.292336) (xy 339.009946 -227.304196)
			(xy 339.05956 -227.323668) (xy 339.105718 -227.350317) (xy 339.147389 -227.383548) (xy 339.183641 -227.422619)
			(xy 339.213665 -227.466656) (xy 339.236791 -227.514677) (xy 339.252501 -227.565607) (xy 339.260444 -227.618311)
			(xy 339.260942 -227.64496) (xy 339.260444 -227.671609) (xy 339.48877 -227.671609) (xy 339.48877 -227.618311)
			(xy 339.496713 -227.565607) (xy 339.512423 -227.514677) (xy 339.535549 -227.466656) (xy 339.565573 -227.422619)
			(xy 339.601825 -227.383548) (xy 339.643496 -227.350317) (xy 339.689654 -227.323668) (xy 339.739268 -227.304196)
			(xy 339.79123 -227.292336) (xy 339.84438 -227.288353) (xy 339.89753 -227.292336) (xy 339.949492 -227.304196)
			(xy 339.999106 -227.323668) (xy 340.045264 -227.350317) (xy 340.086935 -227.383548) (xy 340.123187 -227.422619)
			(xy 340.153211 -227.466656) (xy 340.176337 -227.514677) (xy 340.192047 -227.565607) (xy 340.19999 -227.618311)
			(xy 340.200488 -227.64496) (xy 340.19999 -227.671609) (xy 340.428824 -227.671609) (xy 340.428824 -227.618311)
			(xy 340.436767 -227.565607) (xy 340.452477 -227.514677) (xy 340.475603 -227.466656) (xy 340.505627 -227.422619)
			(xy 340.541879 -227.383548) (xy 340.58355 -227.350317) (xy 340.629708 -227.323668) (xy 340.679322 -227.304196)
			(xy 340.731284 -227.292336) (xy 340.784434 -227.288353) (xy 340.837584 -227.292336) (xy 340.889546 -227.304196)
			(xy 340.93916 -227.323668) (xy 340.985318 -227.350317) (xy 341.026989 -227.383548) (xy 341.063241 -227.422619)
			(xy 341.093265 -227.466656) (xy 341.116391 -227.514677) (xy 341.132101 -227.565607) (xy 341.140044 -227.618311)
			(xy 341.140542 -227.64496) (xy 341.140044 -227.671609) (xy 341.368624 -227.671609) (xy 341.368624 -227.618311)
			(xy 341.376567 -227.565607) (xy 341.392277 -227.514677) (xy 341.415403 -227.466656) (xy 341.445427 -227.422619)
			(xy 341.481679 -227.383548) (xy 341.52335 -227.350317) (xy 341.569508 -227.323668) (xy 341.619122 -227.304196)
			(xy 341.671084 -227.292336) (xy 341.724234 -227.288353) (xy 341.777384 -227.292336) (xy 341.829346 -227.304196)
			(xy 341.87896 -227.323668) (xy 341.925118 -227.350317) (xy 341.966789 -227.383548) (xy 342.003041 -227.422619)
			(xy 342.033065 -227.466656) (xy 342.056191 -227.514677) (xy 342.071901 -227.565607) (xy 342.079844 -227.618311)
			(xy 342.080342 -227.64496) (xy 342.079844 -227.671609) (xy 342.308424 -227.671609) (xy 342.308424 -227.618311)
			(xy 342.316367 -227.565607) (xy 342.332077 -227.514677) (xy 342.355203 -227.466656) (xy 342.385227 -227.422619)
			(xy 342.421479 -227.383548) (xy 342.46315 -227.350317) (xy 342.509308 -227.323668) (xy 342.558922 -227.304196)
			(xy 342.610884 -227.292336) (xy 342.664034 -227.288353) (xy 342.717184 -227.292336) (xy 342.769146 -227.304196)
			(xy 342.81876 -227.323668) (xy 342.864918 -227.350317) (xy 342.906589 -227.383548) (xy 342.942841 -227.422619)
			(xy 342.972865 -227.466656) (xy 342.995991 -227.514677) (xy 343.011701 -227.565607) (xy 343.019644 -227.618311)
			(xy 343.020142 -227.64496) (xy 343.019644 -227.671609) (xy 343.248224 -227.671609) (xy 343.248224 -227.618311)
			(xy 343.256167 -227.565607) (xy 343.271877 -227.514677) (xy 343.295003 -227.466656) (xy 343.325027 -227.422619)
			(xy 343.361279 -227.383548) (xy 343.40295 -227.350317) (xy 343.449108 -227.323668) (xy 343.498722 -227.304196)
			(xy 343.550684 -227.292336) (xy 343.603834 -227.288353) (xy 343.656984 -227.292336) (xy 343.708946 -227.304196)
			(xy 343.75856 -227.323668) (xy 343.804718 -227.350317) (xy 343.846389 -227.383548) (xy 343.882641 -227.422619)
			(xy 343.912665 -227.466656) (xy 343.935791 -227.514677) (xy 343.951501 -227.565607) (xy 343.959444 -227.618311)
			(xy 343.959942 -227.64496) (xy 343.959444 -227.671609) (xy 344.188024 -227.671609) (xy 344.188024 -227.618311)
			(xy 344.195967 -227.565607) (xy 344.211677 -227.514677) (xy 344.234803 -227.466656) (xy 344.264827 -227.422619)
			(xy 344.301079 -227.383548) (xy 344.34275 -227.350317) (xy 344.388908 -227.323668) (xy 344.438522 -227.304196)
			(xy 344.490484 -227.292336) (xy 344.543634 -227.288353) (xy 344.596784 -227.292336) (xy 344.648746 -227.304196)
			(xy 344.69836 -227.323668) (xy 344.744518 -227.350317) (xy 344.786189 -227.383548) (xy 344.822441 -227.422619)
			(xy 344.852465 -227.466656) (xy 344.875591 -227.514677) (xy 344.891301 -227.565607) (xy 344.899244 -227.618311)
			(xy 344.899742 -227.64496) (xy 344.899244 -227.671609) (xy 345.127824 -227.671609) (xy 345.127824 -227.618311)
			(xy 345.135767 -227.565607) (xy 345.151477 -227.514677) (xy 345.174603 -227.466656) (xy 345.204627 -227.422619)
			(xy 345.240879 -227.383548) (xy 345.28255 -227.350317) (xy 345.328708 -227.323668) (xy 345.378322 -227.304196)
			(xy 345.430284 -227.292336) (xy 345.483434 -227.288353) (xy 345.536584 -227.292336) (xy 345.588546 -227.304196)
			(xy 345.63816 -227.323668) (xy 345.684318 -227.350317) (xy 345.725989 -227.383548) (xy 345.762241 -227.422619)
			(xy 345.792265 -227.466656) (xy 345.815391 -227.514677) (xy 345.831101 -227.565607) (xy 345.839044 -227.618311)
			(xy 345.839542 -227.64496) (xy 345.839044 -227.671609) (xy 346.067624 -227.671609) (xy 346.067624 -227.618311)
			(xy 346.075567 -227.565607) (xy 346.091277 -227.514677) (xy 346.114403 -227.466656) (xy 346.144427 -227.422619)
			(xy 346.180679 -227.383548) (xy 346.22235 -227.350317) (xy 346.268508 -227.323668) (xy 346.318122 -227.304196)
			(xy 346.370084 -227.292336) (xy 346.423234 -227.288353) (xy 346.476384 -227.292336) (xy 346.528346 -227.304196)
			(xy 346.57796 -227.323668) (xy 346.624118 -227.350317) (xy 346.665789 -227.383548) (xy 346.702041 -227.422619)
			(xy 346.732065 -227.466656) (xy 346.755191 -227.514677) (xy 346.770901 -227.565607) (xy 346.778844 -227.618311)
			(xy 346.779342 -227.64496) (xy 346.778844 -227.671609) (xy 347.00717 -227.671609) (xy 347.00717 -227.618311)
			(xy 347.015113 -227.565607) (xy 347.030823 -227.514677) (xy 347.053949 -227.466656) (xy 347.083973 -227.422619)
			(xy 347.120225 -227.383548) (xy 347.161896 -227.350317) (xy 347.208054 -227.323668) (xy 347.257668 -227.304196)
			(xy 347.30963 -227.292336) (xy 347.36278 -227.288353) (xy 347.41593 -227.292336) (xy 347.467892 -227.304196)
			(xy 347.517506 -227.323668) (xy 347.563664 -227.350317) (xy 347.605335 -227.383548) (xy 347.641587 -227.422619)
			(xy 347.671611 -227.466656) (xy 347.694737 -227.514677) (xy 347.710447 -227.565607) (xy 347.71839 -227.618311)
			(xy 347.718888 -227.64496) (xy 347.71839 -227.671609) (xy 347.947224 -227.671609) (xy 347.947224 -227.618311)
			(xy 347.955167 -227.565607) (xy 347.970877 -227.514677) (xy 347.994003 -227.466656) (xy 348.024027 -227.422619)
			(xy 348.060279 -227.383548) (xy 348.10195 -227.350317) (xy 348.148108 -227.323668) (xy 348.197722 -227.304196)
			(xy 348.249684 -227.292336) (xy 348.302834 -227.288353) (xy 348.355984 -227.292336) (xy 348.407946 -227.304196)
			(xy 348.45756 -227.323668) (xy 348.503718 -227.350317) (xy 348.545389 -227.383548) (xy 348.581641 -227.422619)
			(xy 348.611665 -227.466656) (xy 348.634791 -227.514677) (xy 348.650501 -227.565607) (xy 348.658444 -227.618311)
			(xy 348.658942 -227.64496) (xy 348.658444 -227.671609) (xy 348.887024 -227.671609) (xy 348.887024 -227.618311)
			(xy 348.894967 -227.565607) (xy 348.910677 -227.514677) (xy 348.933803 -227.466656) (xy 348.963827 -227.422619)
			(xy 349.000079 -227.383548) (xy 349.04175 -227.350317) (xy 349.087908 -227.323668) (xy 349.137522 -227.304196)
			(xy 349.189484 -227.292336) (xy 349.242634 -227.288353) (xy 349.295784 -227.292336) (xy 349.347746 -227.304196)
			(xy 349.39736 -227.323668) (xy 349.443518 -227.350317) (xy 349.485189 -227.383548) (xy 349.521441 -227.422619)
			(xy 349.551465 -227.466656) (xy 349.574591 -227.514677) (xy 349.590301 -227.565607) (xy 349.598244 -227.618311)
			(xy 349.598742 -227.64496) (xy 349.598244 -227.671609) (xy 349.826824 -227.671609) (xy 349.826824 -227.618311)
			(xy 349.834767 -227.565607) (xy 349.850477 -227.514677) (xy 349.873603 -227.466656) (xy 349.903627 -227.422619)
			(xy 349.939879 -227.383548) (xy 349.98155 -227.350317) (xy 350.027708 -227.323668) (xy 350.077322 -227.304196)
			(xy 350.129284 -227.292336) (xy 350.182434 -227.288353) (xy 350.235584 -227.292336) (xy 350.287546 -227.304196)
			(xy 350.33716 -227.323668) (xy 350.383318 -227.350317) (xy 350.424989 -227.383548) (xy 350.461241 -227.422619)
			(xy 350.491265 -227.466656) (xy 350.514391 -227.514677) (xy 350.530101 -227.565607) (xy 350.538044 -227.618311)
			(xy 350.538542 -227.64496) (xy 350.538044 -227.671609) (xy 350.766624 -227.671609) (xy 350.766624 -227.618311)
			(xy 350.774567 -227.565607) (xy 350.790277 -227.514677) (xy 350.813403 -227.466656) (xy 350.843427 -227.422619)
			(xy 350.879679 -227.383548) (xy 350.92135 -227.350317) (xy 350.967508 -227.323668) (xy 351.017122 -227.304196)
			(xy 351.069084 -227.292336) (xy 351.122234 -227.288353) (xy 351.175384 -227.292336) (xy 351.227346 -227.304196)
			(xy 351.27696 -227.323668) (xy 351.323118 -227.350317) (xy 351.364789 -227.383548) (xy 351.401041 -227.422619)
			(xy 351.431065 -227.466656) (xy 351.454191 -227.514677) (xy 351.469901 -227.565607) (xy 351.477844 -227.618311)
			(xy 351.478342 -227.64496) (xy 351.477844 -227.671609) (xy 351.706424 -227.671609) (xy 351.706424 -227.618311)
			(xy 351.714367 -227.565607) (xy 351.730077 -227.514677) (xy 351.753203 -227.466656) (xy 351.783227 -227.422619)
			(xy 351.819479 -227.383548) (xy 351.86115 -227.350317) (xy 351.907308 -227.323668) (xy 351.956922 -227.304196)
			(xy 352.008884 -227.292336) (xy 352.062034 -227.288353) (xy 352.115184 -227.292336) (xy 352.167146 -227.304196)
			(xy 352.21676 -227.323668) (xy 352.262918 -227.350317) (xy 352.304589 -227.383548) (xy 352.340841 -227.422619)
			(xy 352.370865 -227.466656) (xy 352.393991 -227.514677) (xy 352.409701 -227.565607) (xy 352.417644 -227.618311)
			(xy 352.418142 -227.64496) (xy 352.417644 -227.671609) (xy 352.646224 -227.671609) (xy 352.646224 -227.618311)
			(xy 352.654167 -227.565607) (xy 352.669877 -227.514677) (xy 352.693003 -227.466656) (xy 352.723027 -227.422619)
			(xy 352.759279 -227.383548) (xy 352.80095 -227.350317) (xy 352.847108 -227.323668) (xy 352.896722 -227.304196)
			(xy 352.948684 -227.292336) (xy 353.001834 -227.288353) (xy 353.054984 -227.292336) (xy 353.106946 -227.304196)
			(xy 353.15656 -227.323668) (xy 353.202718 -227.350317) (xy 353.244389 -227.383548) (xy 353.280641 -227.422619)
			(xy 353.310665 -227.466656) (xy 353.333791 -227.514677) (xy 353.349501 -227.565607) (xy 353.357444 -227.618311)
			(xy 353.357942 -227.64496) (xy 353.357444 -227.671609) (xy 353.586024 -227.671609) (xy 353.586024 -227.618311)
			(xy 353.593967 -227.565607) (xy 353.609677 -227.514677) (xy 353.632803 -227.466656) (xy 353.662827 -227.422619)
			(xy 353.699079 -227.383548) (xy 353.74075 -227.350317) (xy 353.786908 -227.323668) (xy 353.836522 -227.304196)
			(xy 353.888484 -227.292336) (xy 353.941634 -227.288353) (xy 353.994784 -227.292336) (xy 354.046746 -227.304196)
			(xy 354.09636 -227.323668) (xy 354.142518 -227.350317) (xy 354.184189 -227.383548) (xy 354.220441 -227.422619)
			(xy 354.250465 -227.466656) (xy 354.273591 -227.514677) (xy 354.289301 -227.565607) (xy 354.297244 -227.618311)
			(xy 354.297742 -227.64496) (xy 354.297244 -227.671609) (xy 354.525824 -227.671609) (xy 354.525824 -227.618311)
			(xy 354.533767 -227.565607) (xy 354.549477 -227.514677) (xy 354.572603 -227.466656) (xy 354.602627 -227.422619)
			(xy 354.638879 -227.383548) (xy 354.68055 -227.350317) (xy 354.726708 -227.323668) (xy 354.776322 -227.304196)
			(xy 354.828284 -227.292336) (xy 354.881434 -227.288353) (xy 354.934584 -227.292336) (xy 354.986546 -227.304196)
			(xy 355.03616 -227.323668) (xy 355.082318 -227.350317) (xy 355.123989 -227.383548) (xy 355.160241 -227.422619)
			(xy 355.190265 -227.466656) (xy 355.213391 -227.514677) (xy 355.229101 -227.565607) (xy 355.237044 -227.618311)
			(xy 355.237542 -227.64496) (xy 355.237044 -227.671609) (xy 355.465624 -227.671609) (xy 355.465624 -227.618311)
			(xy 355.473567 -227.565607) (xy 355.489277 -227.514677) (xy 355.512403 -227.466656) (xy 355.542427 -227.422619)
			(xy 355.578679 -227.383548) (xy 355.62035 -227.350317) (xy 355.666508 -227.323668) (xy 355.716122 -227.304196)
			(xy 355.768084 -227.292336) (xy 355.821234 -227.288353) (xy 355.874384 -227.292336) (xy 355.926346 -227.304196)
			(xy 355.97596 -227.323668) (xy 356.022118 -227.350317) (xy 356.063789 -227.383548) (xy 356.100041 -227.422619)
			(xy 356.130065 -227.466656) (xy 356.153191 -227.514677) (xy 356.168901 -227.565607) (xy 356.176844 -227.618311)
			(xy 356.177342 -227.64496) (xy 356.176844 -227.671609) (xy 356.405424 -227.671609) (xy 356.405424 -227.618311)
			(xy 356.413367 -227.565607) (xy 356.429077 -227.514677) (xy 356.452203 -227.466656) (xy 356.482227 -227.422619)
			(xy 356.518479 -227.383548) (xy 356.56015 -227.350317) (xy 356.606308 -227.323668) (xy 356.655922 -227.304196)
			(xy 356.707884 -227.292336) (xy 356.761034 -227.288353) (xy 356.814184 -227.292336) (xy 356.866146 -227.304196)
			(xy 356.91576 -227.323668) (xy 356.961918 -227.350317) (xy 357.003589 -227.383548) (xy 357.039841 -227.422619)
			(xy 357.069865 -227.466656) (xy 357.092991 -227.514677) (xy 357.108701 -227.565607) (xy 357.116644 -227.618311)
			(xy 357.117142 -227.64496) (xy 357.116644 -227.671609) (xy 357.345224 -227.671609) (xy 357.345224 -227.618311)
			(xy 357.353167 -227.565607) (xy 357.368877 -227.514677) (xy 357.392003 -227.466656) (xy 357.422027 -227.422619)
			(xy 357.458279 -227.383548) (xy 357.49995 -227.350317) (xy 357.546108 -227.323668) (xy 357.595722 -227.304196)
			(xy 357.647684 -227.292336) (xy 357.700834 -227.288353) (xy 357.753984 -227.292336) (xy 357.805946 -227.304196)
			(xy 357.85556 -227.323668) (xy 357.901718 -227.350317) (xy 357.943389 -227.383548) (xy 357.979641 -227.422619)
			(xy 358.009665 -227.466656) (xy 358.032791 -227.514677) (xy 358.048501 -227.565607) (xy 358.056444 -227.618311)
			(xy 358.056942 -227.64496) (xy 358.056444 -227.671609) (xy 358.285024 -227.671609) (xy 358.285024 -227.618311)
			(xy 358.292967 -227.565607) (xy 358.308677 -227.514677) (xy 358.331803 -227.466656) (xy 358.361827 -227.422619)
			(xy 358.398079 -227.383548) (xy 358.43975 -227.350317) (xy 358.485908 -227.323668) (xy 358.535522 -227.304196)
			(xy 358.587484 -227.292336) (xy 358.640634 -227.288353) (xy 358.693784 -227.292336) (xy 358.745746 -227.304196)
			(xy 358.79536 -227.323668) (xy 358.841518 -227.350317) (xy 358.883189 -227.383548) (xy 358.919441 -227.422619)
			(xy 358.949465 -227.466656) (xy 358.972591 -227.514677) (xy 358.988301 -227.565607) (xy 358.996244 -227.618311)
			(xy 358.996742 -227.64496) (xy 358.996244 -227.671609) (xy 358.988301 -227.724313) (xy 358.972591 -227.775243)
			(xy 358.949465 -227.823264) (xy 358.919441 -227.867301) (xy 358.883189 -227.906372) (xy 358.841518 -227.939603)
			(xy 358.79536 -227.966252) (xy 358.745746 -227.985724) (xy 358.693784 -227.997584) (xy 358.640634 -228.001568)
			(xy 358.587484 -227.997584) (xy 358.535522 -227.985724) (xy 358.485908 -227.966252) (xy 358.43975 -227.939603)
			(xy 358.398079 -227.906372) (xy 358.361827 -227.867301) (xy 358.331803 -227.823264) (xy 358.308677 -227.775243)
			(xy 358.292967 -227.724313) (xy 358.285024 -227.671609) (xy 358.056444 -227.671609) (xy 358.048501 -227.724313)
			(xy 358.032791 -227.775243) (xy 358.009665 -227.823264) (xy 357.979641 -227.867301) (xy 357.943389 -227.906372)
			(xy 357.901718 -227.939603) (xy 357.85556 -227.966252) (xy 357.805946 -227.985724) (xy 357.753984 -227.997584)
			(xy 357.700834 -228.001568) (xy 357.647684 -227.997584) (xy 357.595722 -227.985724) (xy 357.546108 -227.966252)
			(xy 357.49995 -227.939603) (xy 357.458279 -227.906372) (xy 357.422027 -227.867301) (xy 357.392003 -227.823264)
			(xy 357.368877 -227.775243) (xy 357.353167 -227.724313) (xy 357.345224 -227.671609) (xy 357.116644 -227.671609)
			(xy 357.108701 -227.724313) (xy 357.092991 -227.775243) (xy 357.069865 -227.823264) (xy 357.039841 -227.867301)
			(xy 357.003589 -227.906372) (xy 356.961918 -227.939603) (xy 356.91576 -227.966252) (xy 356.866146 -227.985724)
			(xy 356.814184 -227.997584) (xy 356.761034 -228.001568) (xy 356.707884 -227.997584) (xy 356.655922 -227.985724)
			(xy 356.606308 -227.966252) (xy 356.56015 -227.939603) (xy 356.518479 -227.906372) (xy 356.482227 -227.867301)
			(xy 356.452203 -227.823264) (xy 356.429077 -227.775243) (xy 356.413367 -227.724313) (xy 356.405424 -227.671609)
			(xy 356.176844 -227.671609) (xy 356.168901 -227.724313) (xy 356.153191 -227.775243) (xy 356.130065 -227.823264)
			(xy 356.100041 -227.867301) (xy 356.063789 -227.906372) (xy 356.022118 -227.939603) (xy 355.97596 -227.966252)
			(xy 355.926346 -227.985724) (xy 355.874384 -227.997584) (xy 355.821234 -228.001568) (xy 355.768084 -227.997584)
			(xy 355.716122 -227.985724) (xy 355.666508 -227.966252) (xy 355.62035 -227.939603) (xy 355.578679 -227.906372)
			(xy 355.542427 -227.867301) (xy 355.512403 -227.823264) (xy 355.489277 -227.775243) (xy 355.473567 -227.724313)
			(xy 355.465624 -227.671609) (xy 355.237044 -227.671609) (xy 355.229101 -227.724313) (xy 355.213391 -227.775243)
			(xy 355.190265 -227.823264) (xy 355.160241 -227.867301) (xy 355.123989 -227.906372) (xy 355.082318 -227.939603)
			(xy 355.03616 -227.966252) (xy 354.986546 -227.985724) (xy 354.934584 -227.997584) (xy 354.881434 -228.001568)
			(xy 354.828284 -227.997584) (xy 354.776322 -227.985724) (xy 354.726708 -227.966252) (xy 354.68055 -227.939603)
			(xy 354.638879 -227.906372) (xy 354.602627 -227.867301) (xy 354.572603 -227.823264) (xy 354.549477 -227.775243)
			(xy 354.533767 -227.724313) (xy 354.525824 -227.671609) (xy 354.297244 -227.671609) (xy 354.289301 -227.724313)
			(xy 354.273591 -227.775243) (xy 354.250465 -227.823264) (xy 354.220441 -227.867301) (xy 354.184189 -227.906372)
			(xy 354.142518 -227.939603) (xy 354.09636 -227.966252) (xy 354.046746 -227.985724) (xy 353.994784 -227.997584)
			(xy 353.941634 -228.001568) (xy 353.888484 -227.997584) (xy 353.836522 -227.985724) (xy 353.786908 -227.966252)
			(xy 353.74075 -227.939603) (xy 353.699079 -227.906372) (xy 353.662827 -227.867301) (xy 353.632803 -227.823264)
			(xy 353.609677 -227.775243) (xy 353.593967 -227.724313) (xy 353.586024 -227.671609) (xy 353.357444 -227.671609)
			(xy 353.349501 -227.724313) (xy 353.333791 -227.775243) (xy 353.310665 -227.823264) (xy 353.280641 -227.867301)
			(xy 353.244389 -227.906372) (xy 353.202718 -227.939603) (xy 353.15656 -227.966252) (xy 353.106946 -227.985724)
			(xy 353.054984 -227.997584) (xy 353.001834 -228.001568) (xy 352.948684 -227.997584) (xy 352.896722 -227.985724)
			(xy 352.847108 -227.966252) (xy 352.80095 -227.939603) (xy 352.759279 -227.906372) (xy 352.723027 -227.867301)
			(xy 352.693003 -227.823264) (xy 352.669877 -227.775243) (xy 352.654167 -227.724313) (xy 352.646224 -227.671609)
			(xy 352.417644 -227.671609) (xy 352.409701 -227.724313) (xy 352.393991 -227.775243) (xy 352.370865 -227.823264)
			(xy 352.340841 -227.867301) (xy 352.304589 -227.906372) (xy 352.262918 -227.939603) (xy 352.21676 -227.966252)
			(xy 352.167146 -227.985724) (xy 352.115184 -227.997584) (xy 352.062034 -228.001568) (xy 352.008884 -227.997584)
			(xy 351.956922 -227.985724) (xy 351.907308 -227.966252) (xy 351.86115 -227.939603) (xy 351.819479 -227.906372)
			(xy 351.783227 -227.867301) (xy 351.753203 -227.823264) (xy 351.730077 -227.775243) (xy 351.714367 -227.724313)
			(xy 351.706424 -227.671609) (xy 351.477844 -227.671609) (xy 351.469901 -227.724313) (xy 351.454191 -227.775243)
			(xy 351.431065 -227.823264) (xy 351.401041 -227.867301) (xy 351.364789 -227.906372) (xy 351.323118 -227.939603)
			(xy 351.27696 -227.966252) (xy 351.227346 -227.985724) (xy 351.175384 -227.997584) (xy 351.122234 -228.001568)
			(xy 351.069084 -227.997584) (xy 351.017122 -227.985724) (xy 350.967508 -227.966252) (xy 350.92135 -227.939603)
			(xy 350.879679 -227.906372) (xy 350.843427 -227.867301) (xy 350.813403 -227.823264) (xy 350.790277 -227.775243)
			(xy 350.774567 -227.724313) (xy 350.766624 -227.671609) (xy 350.538044 -227.671609) (xy 350.530101 -227.724313)
			(xy 350.514391 -227.775243) (xy 350.491265 -227.823264) (xy 350.461241 -227.867301) (xy 350.424989 -227.906372)
			(xy 350.383318 -227.939603) (xy 350.33716 -227.966252) (xy 350.287546 -227.985724) (xy 350.235584 -227.997584)
			(xy 350.182434 -228.001568) (xy 350.129284 -227.997584) (xy 350.077322 -227.985724) (xy 350.027708 -227.966252)
			(xy 349.98155 -227.939603) (xy 349.939879 -227.906372) (xy 349.903627 -227.867301) (xy 349.873603 -227.823264)
			(xy 349.850477 -227.775243) (xy 349.834767 -227.724313) (xy 349.826824 -227.671609) (xy 349.598244 -227.671609)
			(xy 349.590301 -227.724313) (xy 349.574591 -227.775243) (xy 349.551465 -227.823264) (xy 349.521441 -227.867301)
			(xy 349.485189 -227.906372) (xy 349.443518 -227.939603) (xy 349.39736 -227.966252) (xy 349.347746 -227.985724)
			(xy 349.295784 -227.997584) (xy 349.242634 -228.001568) (xy 349.189484 -227.997584) (xy 349.137522 -227.985724)
			(xy 349.087908 -227.966252) (xy 349.04175 -227.939603) (xy 349.000079 -227.906372) (xy 348.963827 -227.867301)
			(xy 348.933803 -227.823264) (xy 348.910677 -227.775243) (xy 348.894967 -227.724313) (xy 348.887024 -227.671609)
			(xy 348.658444 -227.671609) (xy 348.650501 -227.724313) (xy 348.634791 -227.775243) (xy 348.611665 -227.823264)
			(xy 348.581641 -227.867301) (xy 348.545389 -227.906372) (xy 348.503718 -227.939603) (xy 348.45756 -227.966252)
			(xy 348.407946 -227.985724) (xy 348.355984 -227.997584) (xy 348.302834 -228.001568) (xy 348.249684 -227.997584)
			(xy 348.197722 -227.985724) (xy 348.148108 -227.966252) (xy 348.10195 -227.939603) (xy 348.060279 -227.906372)
			(xy 348.024027 -227.867301) (xy 347.994003 -227.823264) (xy 347.970877 -227.775243) (xy 347.955167 -227.724313)
			(xy 347.947224 -227.671609) (xy 347.71839 -227.671609) (xy 347.710447 -227.724313) (xy 347.694737 -227.775243)
			(xy 347.671611 -227.823264) (xy 347.641587 -227.867301) (xy 347.605335 -227.906372) (xy 347.563664 -227.939603)
			(xy 347.517506 -227.966252) (xy 347.467892 -227.985724) (xy 347.41593 -227.997584) (xy 347.36278 -228.001568)
			(xy 347.30963 -227.997584) (xy 347.257668 -227.985724) (xy 347.208054 -227.966252) (xy 347.161896 -227.939603)
			(xy 347.120225 -227.906372) (xy 347.083973 -227.867301) (xy 347.053949 -227.823264) (xy 347.030823 -227.775243)
			(xy 347.015113 -227.724313) (xy 347.00717 -227.671609) (xy 346.778844 -227.671609) (xy 346.770901 -227.724313)
			(xy 346.755191 -227.775243) (xy 346.732065 -227.823264) (xy 346.702041 -227.867301) (xy 346.665789 -227.906372)
			(xy 346.624118 -227.939603) (xy 346.57796 -227.966252) (xy 346.528346 -227.985724) (xy 346.476384 -227.997584)
			(xy 346.423234 -228.001568) (xy 346.370084 -227.997584) (xy 346.318122 -227.985724) (xy 346.268508 -227.966252)
			(xy 346.22235 -227.939603) (xy 346.180679 -227.906372) (xy 346.144427 -227.867301) (xy 346.114403 -227.823264)
			(xy 346.091277 -227.775243) (xy 346.075567 -227.724313) (xy 346.067624 -227.671609) (xy 345.839044 -227.671609)
			(xy 345.831101 -227.724313) (xy 345.815391 -227.775243) (xy 345.792265 -227.823264) (xy 345.762241 -227.867301)
			(xy 345.725989 -227.906372) (xy 345.684318 -227.939603) (xy 345.63816 -227.966252) (xy 345.588546 -227.985724)
			(xy 345.536584 -227.997584) (xy 345.483434 -228.001568) (xy 345.430284 -227.997584) (xy 345.378322 -227.985724)
			(xy 345.328708 -227.966252) (xy 345.28255 -227.939603) (xy 345.240879 -227.906372) (xy 345.204627 -227.867301)
			(xy 345.174603 -227.823264) (xy 345.151477 -227.775243) (xy 345.135767 -227.724313) (xy 345.127824 -227.671609)
			(xy 344.899244 -227.671609) (xy 344.891301 -227.724313) (xy 344.875591 -227.775243) (xy 344.852465 -227.823264)
			(xy 344.822441 -227.867301) (xy 344.786189 -227.906372) (xy 344.744518 -227.939603) (xy 344.69836 -227.966252)
			(xy 344.648746 -227.985724) (xy 344.596784 -227.997584) (xy 344.543634 -228.001568) (xy 344.490484 -227.997584)
			(xy 344.438522 -227.985724) (xy 344.388908 -227.966252) (xy 344.34275 -227.939603) (xy 344.301079 -227.906372)
			(xy 344.264827 -227.867301) (xy 344.234803 -227.823264) (xy 344.211677 -227.775243) (xy 344.195967 -227.724313)
			(xy 344.188024 -227.671609) (xy 343.959444 -227.671609) (xy 343.951501 -227.724313) (xy 343.935791 -227.775243)
			(xy 343.912665 -227.823264) (xy 343.882641 -227.867301) (xy 343.846389 -227.906372) (xy 343.804718 -227.939603)
			(xy 343.75856 -227.966252) (xy 343.708946 -227.985724) (xy 343.656984 -227.997584) (xy 343.603834 -228.001568)
			(xy 343.550684 -227.997584) (xy 343.498722 -227.985724) (xy 343.449108 -227.966252) (xy 343.40295 -227.939603)
			(xy 343.361279 -227.906372) (xy 343.325027 -227.867301) (xy 343.295003 -227.823264) (xy 343.271877 -227.775243)
			(xy 343.256167 -227.724313) (xy 343.248224 -227.671609) (xy 343.019644 -227.671609) (xy 343.011701 -227.724313)
			(xy 342.995991 -227.775243) (xy 342.972865 -227.823264) (xy 342.942841 -227.867301) (xy 342.906589 -227.906372)
			(xy 342.864918 -227.939603) (xy 342.81876 -227.966252) (xy 342.769146 -227.985724) (xy 342.717184 -227.997584)
			(xy 342.664034 -228.001568) (xy 342.610884 -227.997584) (xy 342.558922 -227.985724) (xy 342.509308 -227.966252)
			(xy 342.46315 -227.939603) (xy 342.421479 -227.906372) (xy 342.385227 -227.867301) (xy 342.355203 -227.823264)
			(xy 342.332077 -227.775243) (xy 342.316367 -227.724313) (xy 342.308424 -227.671609) (xy 342.079844 -227.671609)
			(xy 342.071901 -227.724313) (xy 342.056191 -227.775243) (xy 342.033065 -227.823264) (xy 342.003041 -227.867301)
			(xy 341.966789 -227.906372) (xy 341.925118 -227.939603) (xy 341.87896 -227.966252) (xy 341.829346 -227.985724)
			(xy 341.777384 -227.997584) (xy 341.724234 -228.001568) (xy 341.671084 -227.997584) (xy 341.619122 -227.985724)
			(xy 341.569508 -227.966252) (xy 341.52335 -227.939603) (xy 341.481679 -227.906372) (xy 341.445427 -227.867301)
			(xy 341.415403 -227.823264) (xy 341.392277 -227.775243) (xy 341.376567 -227.724313) (xy 341.368624 -227.671609)
			(xy 341.140044 -227.671609) (xy 341.132101 -227.724313) (xy 341.116391 -227.775243) (xy 341.093265 -227.823264)
			(xy 341.063241 -227.867301) (xy 341.026989 -227.906372) (xy 340.985318 -227.939603) (xy 340.93916 -227.966252)
			(xy 340.889546 -227.985724) (xy 340.837584 -227.997584) (xy 340.784434 -228.001568) (xy 340.731284 -227.997584)
			(xy 340.679322 -227.985724) (xy 340.629708 -227.966252) (xy 340.58355 -227.939603) (xy 340.541879 -227.906372)
			(xy 340.505627 -227.867301) (xy 340.475603 -227.823264) (xy 340.452477 -227.775243) (xy 340.436767 -227.724313)
			(xy 340.428824 -227.671609) (xy 340.19999 -227.671609) (xy 340.192047 -227.724313) (xy 340.176337 -227.775243)
			(xy 340.153211 -227.823264) (xy 340.123187 -227.867301) (xy 340.086935 -227.906372) (xy 340.045264 -227.939603)
			(xy 339.999106 -227.966252) (xy 339.949492 -227.985724) (xy 339.89753 -227.997584) (xy 339.84438 -228.001568)
			(xy 339.79123 -227.997584) (xy 339.739268 -227.985724) (xy 339.689654 -227.966252) (xy 339.643496 -227.939603)
			(xy 339.601825 -227.906372) (xy 339.565573 -227.867301) (xy 339.535549 -227.823264) (xy 339.512423 -227.775243)
			(xy 339.496713 -227.724313) (xy 339.48877 -227.671609) (xy 339.260444 -227.671609) (xy 339.252501 -227.724313)
			(xy 339.236791 -227.775243) (xy 339.213665 -227.823264) (xy 339.183641 -227.867301) (xy 339.147389 -227.906372)
			(xy 339.105718 -227.939603) (xy 339.05956 -227.966252) (xy 339.009946 -227.985724) (xy 338.957984 -227.997584)
			(xy 338.904834 -228.001568) (xy 338.851684 -227.997584) (xy 338.799722 -227.985724) (xy 338.750108 -227.966252)
			(xy 338.70395 -227.939603) (xy 338.662279 -227.906372) (xy 338.626027 -227.867301) (xy 338.596003 -227.823264)
			(xy 338.572877 -227.775243) (xy 338.557167 -227.724313) (xy 338.549224 -227.671609) (xy 338.320644 -227.671609)
			(xy 338.312701 -227.724313) (xy 338.296991 -227.775243) (xy 338.273865 -227.823264) (xy 338.243841 -227.867301)
			(xy 338.207589 -227.906372) (xy 338.165918 -227.939603) (xy 338.11976 -227.966252) (xy 338.070146 -227.985724)
			(xy 338.018184 -227.997584) (xy 337.965034 -228.001568) (xy 337.911884 -227.997584) (xy 337.859922 -227.985724)
			(xy 337.810308 -227.966252) (xy 337.76415 -227.939603) (xy 337.722479 -227.906372) (xy 337.686227 -227.867301)
			(xy 337.656203 -227.823264) (xy 337.633077 -227.775243) (xy 337.617367 -227.724313) (xy 337.609424 -227.671609)
			(xy 337.379854 -227.671609) (xy 337.377865 -227.698152) (xy 337.366005 -227.750117) (xy 337.346533 -227.799735)
			(xy 337.319883 -227.845896) (xy 337.286652 -227.88757) (xy 337.247581 -227.923826) (xy 337.203543 -227.953854)
			(xy 337.155522 -227.976984) (xy 337.10459 -227.992699) (xy 337.051885 -228.000648) (xy 337.025234 -228.001068)
			(xy 337.000538 -228.000669) (xy 336.951616 -227.993885) (xy 336.904102 -227.980401) (xy 336.858909 -227.960476)
			(xy 336.816906 -227.934492) (xy 336.79765 -227.919026) (xy 336.786264 -227.910248) (xy 336.759895 -227.898826)
			(xy 336.731387 -227.895204) (xy 336.702999 -227.899669) (xy 336.67698 -227.911867) (xy 336.65539 -227.930832)
			(xy 336.639939 -227.955062) (xy 336.631851 -227.982637) (xy 336.63128 -227.997004) (xy 336.63128 -228.109272)
			(xy 336.666332 -228.120702) (xy 336.691136 -228.129351) (xy 336.738084 -228.15291) (xy 336.781063 -228.183111)
			(xy 336.819139 -228.219297) (xy 336.851486 -228.260684) (xy 336.877403 -228.306373) (xy 336.896327 -228.355374)
			(xy 336.907848 -228.406624) (xy 336.911715 -228.459009) (xy 336.909745 -228.485679) (xy 337.13927 -228.485679)
			(xy 337.13927 -228.432381) (xy 337.147213 -228.379677) (xy 337.162923 -228.328747) (xy 337.186049 -228.280726)
			(xy 337.216073 -228.236689) (xy 337.252325 -228.197618) (xy 337.293996 -228.164387) (xy 337.340154 -228.137738)
			(xy 337.389768 -228.118266) (xy 337.44173 -228.106406) (xy 337.49488 -228.102423) (xy 337.54803 -228.106406)
			(xy 337.599992 -228.118266) (xy 337.649606 -228.137738) (xy 337.695764 -228.164387) (xy 337.737435 -228.197618)
			(xy 337.773687 -228.236689) (xy 337.803711 -228.280726) (xy 337.826837 -228.328747) (xy 337.842547 -228.379677)
			(xy 337.85049 -228.432381) (xy 337.850988 -228.45903) (xy 337.85049 -228.485679) (xy 338.07907 -228.485679)
			(xy 338.07907 -228.432381) (xy 338.087013 -228.379677) (xy 338.102723 -228.328747) (xy 338.125849 -228.280726)
			(xy 338.155873 -228.236689) (xy 338.192125 -228.197618) (xy 338.233796 -228.164387) (xy 338.279954 -228.137738)
			(xy 338.329568 -228.118266) (xy 338.38153 -228.106406) (xy 338.43468 -228.102423) (xy 338.48783 -228.106406)
			(xy 338.539792 -228.118266) (xy 338.589406 -228.137738) (xy 338.635564 -228.164387) (xy 338.677235 -228.197618)
			(xy 338.713487 -228.236689) (xy 338.743511 -228.280726) (xy 338.766637 -228.328747) (xy 338.782347 -228.379677)
			(xy 338.79029 -228.432381) (xy 338.790788 -228.45903) (xy 338.79029 -228.485679) (xy 339.019124 -228.485679)
			(xy 339.019124 -228.432381) (xy 339.027067 -228.379677) (xy 339.042777 -228.328747) (xy 339.065903 -228.280726)
			(xy 339.095927 -228.236689) (xy 339.132179 -228.197618) (xy 339.17385 -228.164387) (xy 339.220008 -228.137738)
			(xy 339.269622 -228.118266) (xy 339.321584 -228.106406) (xy 339.374734 -228.102423) (xy 339.427884 -228.106406)
			(xy 339.479846 -228.118266) (xy 339.52946 -228.137738) (xy 339.575618 -228.164387) (xy 339.617289 -228.197618)
			(xy 339.653541 -228.236689) (xy 339.683565 -228.280726) (xy 339.706691 -228.328747) (xy 339.722401 -228.379677)
			(xy 339.730344 -228.432381) (xy 339.730842 -228.45903) (xy 339.730344 -228.485679) (xy 339.95867 -228.485679)
			(xy 339.95867 -228.432381) (xy 339.966613 -228.379677) (xy 339.982323 -228.328747) (xy 340.005449 -228.280726)
			(xy 340.035473 -228.236689) (xy 340.071725 -228.197618) (xy 340.113396 -228.164387) (xy 340.159554 -228.137738)
			(xy 340.209168 -228.118266) (xy 340.26113 -228.106406) (xy 340.31428 -228.102423) (xy 340.36743 -228.106406)
			(xy 340.419392 -228.118266) (xy 340.469006 -228.137738) (xy 340.515164 -228.164387) (xy 340.556835 -228.197618)
			(xy 340.593087 -228.236689) (xy 340.623111 -228.280726) (xy 340.646237 -228.328747) (xy 340.661947 -228.379677)
			(xy 340.66989 -228.432381) (xy 340.670388 -228.45903) (xy 340.66989 -228.485679) (xy 340.89847 -228.485679)
			(xy 340.89847 -228.432381) (xy 340.906413 -228.379677) (xy 340.922123 -228.328747) (xy 340.945249 -228.280726)
			(xy 340.975273 -228.236689) (xy 341.011525 -228.197618) (xy 341.053196 -228.164387) (xy 341.099354 -228.137738)
			(xy 341.148968 -228.118266) (xy 341.20093 -228.106406) (xy 341.25408 -228.102423) (xy 341.30723 -228.106406)
			(xy 341.359192 -228.118266) (xy 341.408806 -228.137738) (xy 341.454964 -228.164387) (xy 341.496635 -228.197618)
			(xy 341.532887 -228.236689) (xy 341.562911 -228.280726) (xy 341.586037 -228.328747) (xy 341.601747 -228.379677)
			(xy 341.60969 -228.432381) (xy 341.610188 -228.45903) (xy 341.60969 -228.485679) (xy 341.83827 -228.485679)
			(xy 341.83827 -228.432381) (xy 341.846213 -228.379677) (xy 341.861923 -228.328747) (xy 341.885049 -228.280726)
			(xy 341.915073 -228.236689) (xy 341.951325 -228.197618) (xy 341.992996 -228.164387) (xy 342.039154 -228.137738)
			(xy 342.088768 -228.118266) (xy 342.14073 -228.106406) (xy 342.19388 -228.102423) (xy 342.24703 -228.106406)
			(xy 342.298992 -228.118266) (xy 342.348606 -228.137738) (xy 342.394764 -228.164387) (xy 342.436435 -228.197618)
			(xy 342.472687 -228.236689) (xy 342.502711 -228.280726) (xy 342.525837 -228.328747) (xy 342.541547 -228.379677)
			(xy 342.54949 -228.432381) (xy 342.549988 -228.45903) (xy 342.54949 -228.485679) (xy 342.77807 -228.485679)
			(xy 342.77807 -228.432381) (xy 342.786013 -228.379677) (xy 342.801723 -228.328747) (xy 342.824849 -228.280726)
			(xy 342.854873 -228.236689) (xy 342.891125 -228.197618) (xy 342.932796 -228.164387) (xy 342.978954 -228.137738)
			(xy 343.028568 -228.118266) (xy 343.08053 -228.106406) (xy 343.13368 -228.102423) (xy 343.18683 -228.106406)
			(xy 343.238792 -228.118266) (xy 343.288406 -228.137738) (xy 343.334564 -228.164387) (xy 343.376235 -228.197618)
			(xy 343.412487 -228.236689) (xy 343.442511 -228.280726) (xy 343.465637 -228.328747) (xy 343.481347 -228.379677)
			(xy 343.48929 -228.432381) (xy 343.489788 -228.45903) (xy 343.48929 -228.485679) (xy 343.71787 -228.485679)
			(xy 343.71787 -228.432381) (xy 343.725813 -228.379677) (xy 343.741523 -228.328747) (xy 343.764649 -228.280726)
			(xy 343.794673 -228.236689) (xy 343.830925 -228.197618) (xy 343.872596 -228.164387) (xy 343.918754 -228.137738)
			(xy 343.968368 -228.118266) (xy 344.02033 -228.106406) (xy 344.07348 -228.102423) (xy 344.12663 -228.106406)
			(xy 344.178592 -228.118266) (xy 344.228206 -228.137738) (xy 344.274364 -228.164387) (xy 344.316035 -228.197618)
			(xy 344.352287 -228.236689) (xy 344.382311 -228.280726) (xy 344.405437 -228.328747) (xy 344.421147 -228.379677)
			(xy 344.42909 -228.432381) (xy 344.429588 -228.45903) (xy 344.42909 -228.485679) (xy 344.65767 -228.485679)
			(xy 344.65767 -228.432381) (xy 344.665613 -228.379677) (xy 344.681323 -228.328747) (xy 344.704449 -228.280726)
			(xy 344.734473 -228.236689) (xy 344.770725 -228.197618) (xy 344.812396 -228.164387) (xy 344.858554 -228.137738)
			(xy 344.908168 -228.118266) (xy 344.96013 -228.106406) (xy 345.01328 -228.102423) (xy 345.06643 -228.106406)
			(xy 345.118392 -228.118266) (xy 345.168006 -228.137738) (xy 345.214164 -228.164387) (xy 345.255835 -228.197618)
			(xy 345.292087 -228.236689) (xy 345.322111 -228.280726) (xy 345.345237 -228.328747) (xy 345.360947 -228.379677)
			(xy 345.36889 -228.432381) (xy 345.369388 -228.45903) (xy 345.36889 -228.485679) (xy 345.597724 -228.485679)
			(xy 345.597724 -228.432381) (xy 345.605667 -228.379677) (xy 345.621377 -228.328747) (xy 345.644503 -228.280726)
			(xy 345.674527 -228.236689) (xy 345.710779 -228.197618) (xy 345.75245 -228.164387) (xy 345.798608 -228.137738)
			(xy 345.848222 -228.118266) (xy 345.900184 -228.106406) (xy 345.953334 -228.102423) (xy 346.006484 -228.106406)
			(xy 346.058446 -228.118266) (xy 346.10806 -228.137738) (xy 346.154218 -228.164387) (xy 346.195889 -228.197618)
			(xy 346.232141 -228.236689) (xy 346.262165 -228.280726) (xy 346.285291 -228.328747) (xy 346.301001 -228.379677)
			(xy 346.308944 -228.432381) (xy 346.309442 -228.45903) (xy 346.308944 -228.485679) (xy 346.53727 -228.485679)
			(xy 346.53727 -228.432381) (xy 346.545213 -228.379677) (xy 346.560923 -228.328747) (xy 346.584049 -228.280726)
			(xy 346.614073 -228.236689) (xy 346.650325 -228.197618) (xy 346.691996 -228.164387) (xy 346.738154 -228.137738)
			(xy 346.787768 -228.118266) (xy 346.83973 -228.106406) (xy 346.89288 -228.102423) (xy 346.94603 -228.106406)
			(xy 346.997992 -228.118266) (xy 347.047606 -228.137738) (xy 347.093764 -228.164387) (xy 347.135435 -228.197618)
			(xy 347.171687 -228.236689) (xy 347.201711 -228.280726) (xy 347.224837 -228.328747) (xy 347.240547 -228.379677)
			(xy 347.24849 -228.432381) (xy 347.248988 -228.45903) (xy 347.24849 -228.485679) (xy 347.47707 -228.485679)
			(xy 347.47707 -228.432381) (xy 347.485013 -228.379677) (xy 347.500723 -228.328747) (xy 347.523849 -228.280726)
			(xy 347.553873 -228.236689) (xy 347.590125 -228.197618) (xy 347.631796 -228.164387) (xy 347.677954 -228.137738)
			(xy 347.727568 -228.118266) (xy 347.77953 -228.106406) (xy 347.83268 -228.102423) (xy 347.88583 -228.106406)
			(xy 347.937792 -228.118266) (xy 347.987406 -228.137738) (xy 348.033564 -228.164387) (xy 348.075235 -228.197618)
			(xy 348.111487 -228.236689) (xy 348.141511 -228.280726) (xy 348.164637 -228.328747) (xy 348.180347 -228.379677)
			(xy 348.18829 -228.432381) (xy 348.188788 -228.45903) (xy 348.18829 -228.485679) (xy 348.41687 -228.485679)
			(xy 348.41687 -228.432381) (xy 348.424813 -228.379677) (xy 348.440523 -228.328747) (xy 348.463649 -228.280726)
			(xy 348.493673 -228.236689) (xy 348.529925 -228.197618) (xy 348.571596 -228.164387) (xy 348.617754 -228.137738)
			(xy 348.667368 -228.118266) (xy 348.71933 -228.106406) (xy 348.77248 -228.102423) (xy 348.82563 -228.106406)
			(xy 348.877592 -228.118266) (xy 348.927206 -228.137738) (xy 348.973364 -228.164387) (xy 349.015035 -228.197618)
			(xy 349.051287 -228.236689) (xy 349.081311 -228.280726) (xy 349.104437 -228.328747) (xy 349.120147 -228.379677)
			(xy 349.12809 -228.432381) (xy 349.128588 -228.45903) (xy 349.12809 -228.485679) (xy 349.35667 -228.485679)
			(xy 349.35667 -228.432381) (xy 349.364613 -228.379677) (xy 349.380323 -228.328747) (xy 349.403449 -228.280726)
			(xy 349.433473 -228.236689) (xy 349.469725 -228.197618) (xy 349.511396 -228.164387) (xy 349.557554 -228.137738)
			(xy 349.607168 -228.118266) (xy 349.65913 -228.106406) (xy 349.71228 -228.102423) (xy 349.76543 -228.106406)
			(xy 349.817392 -228.118266) (xy 349.867006 -228.137738) (xy 349.913164 -228.164387) (xy 349.954835 -228.197618)
			(xy 349.991087 -228.236689) (xy 350.021111 -228.280726) (xy 350.044237 -228.328747) (xy 350.059947 -228.379677)
			(xy 350.06789 -228.432381) (xy 350.068388 -228.45903) (xy 350.06789 -228.485679) (xy 350.29647 -228.485679)
			(xy 350.29647 -228.432381) (xy 350.304413 -228.379677) (xy 350.320123 -228.328747) (xy 350.343249 -228.280726)
			(xy 350.373273 -228.236689) (xy 350.409525 -228.197618) (xy 350.451196 -228.164387) (xy 350.497354 -228.137738)
			(xy 350.546968 -228.118266) (xy 350.59893 -228.106406) (xy 350.65208 -228.102423) (xy 350.70523 -228.106406)
			(xy 350.757192 -228.118266) (xy 350.806806 -228.137738) (xy 350.852964 -228.164387) (xy 350.894635 -228.197618)
			(xy 350.930887 -228.236689) (xy 350.960911 -228.280726) (xy 350.984037 -228.328747) (xy 350.999747 -228.379677)
			(xy 351.00769 -228.432381) (xy 351.008188 -228.45903) (xy 351.00769 -228.485679) (xy 351.007652 -228.485933)
			(xy 351.236524 -228.485933) (xy 351.236524 -228.432635) (xy 351.244467 -228.379931) (xy 351.260177 -228.329001)
			(xy 351.283303 -228.28098) (xy 351.313327 -228.236943) (xy 351.349579 -228.197872) (xy 351.39125 -228.164641)
			(xy 351.437408 -228.137992) (xy 351.487022 -228.11852) (xy 351.538984 -228.10666) (xy 351.592134 -228.102677)
			(xy 351.645284 -228.10666) (xy 351.697246 -228.11852) (xy 351.74686 -228.137992) (xy 351.793018 -228.164641)
			(xy 351.834689 -228.197872) (xy 351.870941 -228.236943) (xy 351.900965 -228.28098) (xy 351.924091 -228.329001)
			(xy 351.939801 -228.379931) (xy 351.947744 -228.432635) (xy 351.948242 -228.459284) (xy 351.947749 -228.485679)
			(xy 352.17607 -228.485679) (xy 352.17607 -228.432381) (xy 352.184013 -228.379677) (xy 352.199723 -228.328747)
			(xy 352.222849 -228.280726) (xy 352.252873 -228.236689) (xy 352.289125 -228.197618) (xy 352.330796 -228.164387)
			(xy 352.376954 -228.137738) (xy 352.426568 -228.118266) (xy 352.47853 -228.106406) (xy 352.53168 -228.102423)
			(xy 352.58483 -228.106406) (xy 352.636792 -228.118266) (xy 352.686406 -228.137738) (xy 352.732564 -228.164387)
			(xy 352.774235 -228.197618) (xy 352.810487 -228.236689) (xy 352.840511 -228.280726) (xy 352.863637 -228.328747)
			(xy 352.879347 -228.379677) (xy 352.88729 -228.432381) (xy 352.887788 -228.45903) (xy 352.88729 -228.485679)
			(xy 353.11587 -228.485679) (xy 353.11587 -228.432381) (xy 353.123813 -228.379677) (xy 353.139523 -228.328747)
			(xy 353.162649 -228.280726) (xy 353.192673 -228.236689) (xy 353.228925 -228.197618) (xy 353.270596 -228.164387)
			(xy 353.316754 -228.137738) (xy 353.366368 -228.118266) (xy 353.41833 -228.106406) (xy 353.47148 -228.102423)
			(xy 353.52463 -228.106406) (xy 353.576592 -228.118266) (xy 353.626206 -228.137738) (xy 353.672364 -228.164387)
			(xy 353.714035 -228.197618) (xy 353.750287 -228.236689) (xy 353.780311 -228.280726) (xy 353.803437 -228.328747)
			(xy 353.819147 -228.379677) (xy 353.82709 -228.432381) (xy 353.827588 -228.45903) (xy 353.82709 -228.485679)
			(xy 354.05567 -228.485679) (xy 354.05567 -228.432381) (xy 354.063613 -228.379677) (xy 354.079323 -228.328747)
			(xy 354.102449 -228.280726) (xy 354.132473 -228.236689) (xy 354.168725 -228.197618) (xy 354.210396 -228.164387)
			(xy 354.256554 -228.137738) (xy 354.306168 -228.118266) (xy 354.35813 -228.106406) (xy 354.41128 -228.102423)
			(xy 354.46443 -228.106406) (xy 354.516392 -228.118266) (xy 354.566006 -228.137738) (xy 354.612164 -228.164387)
			(xy 354.653835 -228.197618) (xy 354.690087 -228.236689) (xy 354.720111 -228.280726) (xy 354.743237 -228.328747)
			(xy 354.758947 -228.379677) (xy 354.76689 -228.432381) (xy 354.767388 -228.45903) (xy 354.76689 -228.485679)
			(xy 354.99547 -228.485679) (xy 354.99547 -228.432381) (xy 355.003413 -228.379677) (xy 355.019123 -228.328747)
			(xy 355.042249 -228.280726) (xy 355.072273 -228.236689) (xy 355.108525 -228.197618) (xy 355.150196 -228.164387)
			(xy 355.196354 -228.137738) (xy 355.245968 -228.118266) (xy 355.29793 -228.106406) (xy 355.35108 -228.102423)
			(xy 355.40423 -228.106406) (xy 355.456192 -228.118266) (xy 355.505806 -228.137738) (xy 355.551964 -228.164387)
			(xy 355.593635 -228.197618) (xy 355.629887 -228.236689) (xy 355.659911 -228.280726) (xy 355.683037 -228.328747)
			(xy 355.698747 -228.379677) (xy 355.70669 -228.432381) (xy 355.707188 -228.45903) (xy 355.70669 -228.485679)
			(xy 355.93527 -228.485679) (xy 355.93527 -228.432381) (xy 355.943213 -228.379677) (xy 355.958923 -228.328747)
			(xy 355.982049 -228.280726) (xy 356.012073 -228.236689) (xy 356.048325 -228.197618) (xy 356.089996 -228.164387)
			(xy 356.136154 -228.137738) (xy 356.185768 -228.118266) (xy 356.23773 -228.106406) (xy 356.29088 -228.102423)
			(xy 356.34403 -228.106406) (xy 356.395992 -228.118266) (xy 356.445606 -228.137738) (xy 356.491764 -228.164387)
			(xy 356.533435 -228.197618) (xy 356.569687 -228.236689) (xy 356.599711 -228.280726) (xy 356.622837 -228.328747)
			(xy 356.638547 -228.379677) (xy 356.64649 -228.432381) (xy 356.646988 -228.45903) (xy 356.64649 -228.485679)
			(xy 356.87507 -228.485679) (xy 356.87507 -228.432381) (xy 356.883013 -228.379677) (xy 356.898723 -228.328747)
			(xy 356.921849 -228.280726) (xy 356.951873 -228.236689) (xy 356.988125 -228.197618) (xy 357.029796 -228.164387)
			(xy 357.075954 -228.137738) (xy 357.125568 -228.118266) (xy 357.17753 -228.106406) (xy 357.23068 -228.102423)
			(xy 357.28383 -228.106406) (xy 357.335792 -228.118266) (xy 357.385406 -228.137738) (xy 357.431564 -228.164387)
			(xy 357.473235 -228.197618) (xy 357.509487 -228.236689) (xy 357.539511 -228.280726) (xy 357.562637 -228.328747)
			(xy 357.578347 -228.379677) (xy 357.58629 -228.432381) (xy 357.586788 -228.45903) (xy 357.58629 -228.485679)
			(xy 357.81487 -228.485679) (xy 357.81487 -228.432381) (xy 357.822813 -228.379677) (xy 357.838523 -228.328747)
			(xy 357.861649 -228.280726) (xy 357.891673 -228.236689) (xy 357.927925 -228.197618) (xy 357.969596 -228.164387)
			(xy 358.015754 -228.137738) (xy 358.065368 -228.118266) (xy 358.11733 -228.106406) (xy 358.17048 -228.102423)
			(xy 358.22363 -228.106406) (xy 358.275592 -228.118266) (xy 358.325206 -228.137738) (xy 358.371364 -228.164387)
			(xy 358.413035 -228.197618) (xy 358.449287 -228.236689) (xy 358.479311 -228.280726) (xy 358.502437 -228.328747)
			(xy 358.518147 -228.379677) (xy 358.52609 -228.432381) (xy 358.526588 -228.45903) (xy 358.52609 -228.485679)
			(xy 358.518147 -228.538383) (xy 358.502437 -228.589313) (xy 358.479311 -228.637334) (xy 358.449287 -228.681371)
			(xy 358.413035 -228.720442) (xy 358.371364 -228.753673) (xy 358.325206 -228.780322) (xy 358.275592 -228.799794)
			(xy 358.22363 -228.811654) (xy 358.17048 -228.815638) (xy 358.11733 -228.811654) (xy 358.065368 -228.799794)
			(xy 358.015754 -228.780322) (xy 357.969596 -228.753673) (xy 357.927925 -228.720442) (xy 357.891673 -228.681371)
			(xy 357.861649 -228.637334) (xy 357.838523 -228.589313) (xy 357.822813 -228.538383) (xy 357.81487 -228.485679)
			(xy 357.58629 -228.485679) (xy 357.578347 -228.538383) (xy 357.562637 -228.589313) (xy 357.539511 -228.637334)
			(xy 357.509487 -228.681371) (xy 357.473235 -228.720442) (xy 357.431564 -228.753673) (xy 357.385406 -228.780322)
			(xy 357.335792 -228.799794) (xy 357.28383 -228.811654) (xy 357.23068 -228.815638) (xy 357.17753 -228.811654)
			(xy 357.125568 -228.799794) (xy 357.075954 -228.780322) (xy 357.029796 -228.753673) (xy 356.988125 -228.720442)
			(xy 356.951873 -228.681371) (xy 356.921849 -228.637334) (xy 356.898723 -228.589313) (xy 356.883013 -228.538383)
			(xy 356.87507 -228.485679) (xy 356.64649 -228.485679) (xy 356.638547 -228.538383) (xy 356.622837 -228.589313)
			(xy 356.599711 -228.637334) (xy 356.569687 -228.681371) (xy 356.533435 -228.720442) (xy 356.491764 -228.753673)
			(xy 356.445606 -228.780322) (xy 356.395992 -228.799794) (xy 356.34403 -228.811654) (xy 356.29088 -228.815638)
			(xy 356.23773 -228.811654) (xy 356.185768 -228.799794) (xy 356.136154 -228.780322) (xy 356.089996 -228.753673)
			(xy 356.048325 -228.720442) (xy 356.012073 -228.681371) (xy 355.982049 -228.637334) (xy 355.958923 -228.589313)
			(xy 355.943213 -228.538383) (xy 355.93527 -228.485679) (xy 355.70669 -228.485679) (xy 355.698747 -228.538383)
			(xy 355.683037 -228.589313) (xy 355.659911 -228.637334) (xy 355.629887 -228.681371) (xy 355.593635 -228.720442)
			(xy 355.551964 -228.753673) (xy 355.505806 -228.780322) (xy 355.456192 -228.799794) (xy 355.40423 -228.811654)
			(xy 355.35108 -228.815638) (xy 355.29793 -228.811654) (xy 355.245968 -228.799794) (xy 355.196354 -228.780322)
			(xy 355.150196 -228.753673) (xy 355.108525 -228.720442) (xy 355.072273 -228.681371) (xy 355.042249 -228.637334)
			(xy 355.019123 -228.589313) (xy 355.003413 -228.538383) (xy 354.99547 -228.485679) (xy 354.76689 -228.485679)
			(xy 354.758947 -228.538383) (xy 354.743237 -228.589313) (xy 354.720111 -228.637334) (xy 354.690087 -228.681371)
			(xy 354.653835 -228.720442) (xy 354.612164 -228.753673) (xy 354.566006 -228.780322) (xy 354.516392 -228.799794)
			(xy 354.46443 -228.811654) (xy 354.41128 -228.815638) (xy 354.35813 -228.811654) (xy 354.306168 -228.799794)
			(xy 354.256554 -228.780322) (xy 354.210396 -228.753673) (xy 354.168725 -228.720442) (xy 354.132473 -228.681371)
			(xy 354.102449 -228.637334) (xy 354.079323 -228.589313) (xy 354.063613 -228.538383) (xy 354.05567 -228.485679)
			(xy 353.82709 -228.485679) (xy 353.819147 -228.538383) (xy 353.803437 -228.589313) (xy 353.780311 -228.637334)
			(xy 353.750287 -228.681371) (xy 353.714035 -228.720442) (xy 353.672364 -228.753673) (xy 353.626206 -228.780322)
			(xy 353.576592 -228.799794) (xy 353.52463 -228.811654) (xy 353.47148 -228.815638) (xy 353.41833 -228.811654)
			(xy 353.366368 -228.799794) (xy 353.316754 -228.780322) (xy 353.270596 -228.753673) (xy 353.228925 -228.720442)
			(xy 353.192673 -228.681371) (xy 353.162649 -228.637334) (xy 353.139523 -228.589313) (xy 353.123813 -228.538383)
			(xy 353.11587 -228.485679) (xy 352.88729 -228.485679) (xy 352.879347 -228.538383) (xy 352.863637 -228.589313)
			(xy 352.840511 -228.637334) (xy 352.810487 -228.681371) (xy 352.774235 -228.720442) (xy 352.732564 -228.753673)
			(xy 352.686406 -228.780322) (xy 352.636792 -228.799794) (xy 352.58483 -228.811654) (xy 352.53168 -228.815638)
			(xy 352.47853 -228.811654) (xy 352.426568 -228.799794) (xy 352.376954 -228.780322) (xy 352.330796 -228.753673)
			(xy 352.289125 -228.720442) (xy 352.252873 -228.681371) (xy 352.222849 -228.637334) (xy 352.199723 -228.589313)
			(xy 352.184013 -228.538383) (xy 352.17607 -228.485679) (xy 351.947749 -228.485679) (xy 351.947744 -228.485933)
			(xy 351.939801 -228.538637) (xy 351.924091 -228.589567) (xy 351.900965 -228.637588) (xy 351.870941 -228.681625)
			(xy 351.834689 -228.720696) (xy 351.793018 -228.753927) (xy 351.74686 -228.780576) (xy 351.697246 -228.800048)
			(xy 351.645284 -228.811908) (xy 351.592134 -228.815892) (xy 351.538984 -228.811908) (xy 351.487022 -228.800048)
			(xy 351.437408 -228.780576) (xy 351.39125 -228.753927) (xy 351.349579 -228.720696) (xy 351.313327 -228.681625)
			(xy 351.283303 -228.637588) (xy 351.260177 -228.589567) (xy 351.244467 -228.538637) (xy 351.236524 -228.485933)
			(xy 351.007652 -228.485933) (xy 350.999747 -228.538383) (xy 350.984037 -228.589313) (xy 350.960911 -228.637334)
			(xy 350.930887 -228.681371) (xy 350.894635 -228.720442) (xy 350.852964 -228.753673) (xy 350.806806 -228.780322)
			(xy 350.757192 -228.799794) (xy 350.70523 -228.811654) (xy 350.65208 -228.815638) (xy 350.59893 -228.811654)
			(xy 350.546968 -228.799794) (xy 350.497354 -228.780322) (xy 350.451196 -228.753673) (xy 350.409525 -228.720442)
			(xy 350.373273 -228.681371) (xy 350.343249 -228.637334) (xy 350.320123 -228.589313) (xy 350.304413 -228.538383)
			(xy 350.29647 -228.485679) (xy 350.06789 -228.485679) (xy 350.059947 -228.538383) (xy 350.044237 -228.589313)
			(xy 350.021111 -228.637334) (xy 349.991087 -228.681371) (xy 349.954835 -228.720442) (xy 349.913164 -228.753673)
			(xy 349.867006 -228.780322) (xy 349.817392 -228.799794) (xy 349.76543 -228.811654) (xy 349.71228 -228.815638)
			(xy 349.65913 -228.811654) (xy 349.607168 -228.799794) (xy 349.557554 -228.780322) (xy 349.511396 -228.753673)
			(xy 349.469725 -228.720442) (xy 349.433473 -228.681371) (xy 349.403449 -228.637334) (xy 349.380323 -228.589313)
			(xy 349.364613 -228.538383) (xy 349.35667 -228.485679) (xy 349.12809 -228.485679) (xy 349.120147 -228.538383)
			(xy 349.104437 -228.589313) (xy 349.081311 -228.637334) (xy 349.051287 -228.681371) (xy 349.015035 -228.720442)
			(xy 348.973364 -228.753673) (xy 348.927206 -228.780322) (xy 348.877592 -228.799794) (xy 348.82563 -228.811654)
			(xy 348.77248 -228.815638) (xy 348.71933 -228.811654) (xy 348.667368 -228.799794) (xy 348.617754 -228.780322)
			(xy 348.571596 -228.753673) (xy 348.529925 -228.720442) (xy 348.493673 -228.681371) (xy 348.463649 -228.637334)
			(xy 348.440523 -228.589313) (xy 348.424813 -228.538383) (xy 348.41687 -228.485679) (xy 348.18829 -228.485679)
			(xy 348.180347 -228.538383) (xy 348.164637 -228.589313) (xy 348.141511 -228.637334) (xy 348.111487 -228.681371)
			(xy 348.075235 -228.720442) (xy 348.033564 -228.753673) (xy 347.987406 -228.780322) (xy 347.937792 -228.799794)
			(xy 347.88583 -228.811654) (xy 347.83268 -228.815638) (xy 347.77953 -228.811654) (xy 347.727568 -228.799794)
			(xy 347.677954 -228.780322) (xy 347.631796 -228.753673) (xy 347.590125 -228.720442) (xy 347.553873 -228.681371)
			(xy 347.523849 -228.637334) (xy 347.500723 -228.589313) (xy 347.485013 -228.538383) (xy 347.47707 -228.485679)
			(xy 347.24849 -228.485679) (xy 347.240547 -228.538383) (xy 347.224837 -228.589313) (xy 347.201711 -228.637334)
			(xy 347.171687 -228.681371) (xy 347.135435 -228.720442) (xy 347.093764 -228.753673) (xy 347.047606 -228.780322)
			(xy 346.997992 -228.799794) (xy 346.94603 -228.811654) (xy 346.89288 -228.815638) (xy 346.83973 -228.811654)
			(xy 346.787768 -228.799794) (xy 346.738154 -228.780322) (xy 346.691996 -228.753673) (xy 346.650325 -228.720442)
			(xy 346.614073 -228.681371) (xy 346.584049 -228.637334) (xy 346.560923 -228.589313) (xy 346.545213 -228.538383)
			(xy 346.53727 -228.485679) (xy 346.308944 -228.485679) (xy 346.301001 -228.538383) (xy 346.285291 -228.589313)
			(xy 346.262165 -228.637334) (xy 346.232141 -228.681371) (xy 346.195889 -228.720442) (xy 346.154218 -228.753673)
			(xy 346.10806 -228.780322) (xy 346.058446 -228.799794) (xy 346.006484 -228.811654) (xy 345.953334 -228.815638)
			(xy 345.900184 -228.811654) (xy 345.848222 -228.799794) (xy 345.798608 -228.780322) (xy 345.75245 -228.753673)
			(xy 345.710779 -228.720442) (xy 345.674527 -228.681371) (xy 345.644503 -228.637334) (xy 345.621377 -228.589313)
			(xy 345.605667 -228.538383) (xy 345.597724 -228.485679) (xy 345.36889 -228.485679) (xy 345.360947 -228.538383)
			(xy 345.345237 -228.589313) (xy 345.322111 -228.637334) (xy 345.292087 -228.681371) (xy 345.255835 -228.720442)
			(xy 345.214164 -228.753673) (xy 345.168006 -228.780322) (xy 345.118392 -228.799794) (xy 345.06643 -228.811654)
			(xy 345.01328 -228.815638) (xy 344.96013 -228.811654) (xy 344.908168 -228.799794) (xy 344.858554 -228.780322)
			(xy 344.812396 -228.753673) (xy 344.770725 -228.720442) (xy 344.734473 -228.681371) (xy 344.704449 -228.637334)
			(xy 344.681323 -228.589313) (xy 344.665613 -228.538383) (xy 344.65767 -228.485679) (xy 344.42909 -228.485679)
			(xy 344.421147 -228.538383) (xy 344.405437 -228.589313) (xy 344.382311 -228.637334) (xy 344.352287 -228.681371)
			(xy 344.316035 -228.720442) (xy 344.274364 -228.753673) (xy 344.228206 -228.780322) (xy 344.178592 -228.799794)
			(xy 344.12663 -228.811654) (xy 344.07348 -228.815638) (xy 344.02033 -228.811654) (xy 343.968368 -228.799794)
			(xy 343.918754 -228.780322) (xy 343.872596 -228.753673) (xy 343.830925 -228.720442) (xy 343.794673 -228.681371)
			(xy 343.764649 -228.637334) (xy 343.741523 -228.589313) (xy 343.725813 -228.538383) (xy 343.71787 -228.485679)
			(xy 343.48929 -228.485679) (xy 343.481347 -228.538383) (xy 343.465637 -228.589313) (xy 343.442511 -228.637334)
			(xy 343.412487 -228.681371) (xy 343.376235 -228.720442) (xy 343.334564 -228.753673) (xy 343.288406 -228.780322)
			(xy 343.238792 -228.799794) (xy 343.18683 -228.811654) (xy 343.13368 -228.815638) (xy 343.08053 -228.811654)
			(xy 343.028568 -228.799794) (xy 342.978954 -228.780322) (xy 342.932796 -228.753673) (xy 342.891125 -228.720442)
			(xy 342.854873 -228.681371) (xy 342.824849 -228.637334) (xy 342.801723 -228.589313) (xy 342.786013 -228.538383)
			(xy 342.77807 -228.485679) (xy 342.54949 -228.485679) (xy 342.541547 -228.538383) (xy 342.525837 -228.589313)
			(xy 342.502711 -228.637334) (xy 342.472687 -228.681371) (xy 342.436435 -228.720442) (xy 342.394764 -228.753673)
			(xy 342.348606 -228.780322) (xy 342.298992 -228.799794) (xy 342.24703 -228.811654) (xy 342.19388 -228.815638)
			(xy 342.14073 -228.811654) (xy 342.088768 -228.799794) (xy 342.039154 -228.780322) (xy 341.992996 -228.753673)
			(xy 341.951325 -228.720442) (xy 341.915073 -228.681371) (xy 341.885049 -228.637334) (xy 341.861923 -228.589313)
			(xy 341.846213 -228.538383) (xy 341.83827 -228.485679) (xy 341.60969 -228.485679) (xy 341.601747 -228.538383)
			(xy 341.586037 -228.589313) (xy 341.562911 -228.637334) (xy 341.532887 -228.681371) (xy 341.496635 -228.720442)
			(xy 341.454964 -228.753673) (xy 341.408806 -228.780322) (xy 341.359192 -228.799794) (xy 341.30723 -228.811654)
			(xy 341.25408 -228.815638) (xy 341.20093 -228.811654) (xy 341.148968 -228.799794) (xy 341.099354 -228.780322)
			(xy 341.053196 -228.753673) (xy 341.011525 -228.720442) (xy 340.975273 -228.681371) (xy 340.945249 -228.637334)
			(xy 340.922123 -228.589313) (xy 340.906413 -228.538383) (xy 340.89847 -228.485679) (xy 340.66989 -228.485679)
			(xy 340.661947 -228.538383) (xy 340.646237 -228.589313) (xy 340.623111 -228.637334) (xy 340.593087 -228.681371)
			(xy 340.556835 -228.720442) (xy 340.515164 -228.753673) (xy 340.469006 -228.780322) (xy 340.419392 -228.799794)
			(xy 340.36743 -228.811654) (xy 340.31428 -228.815638) (xy 340.26113 -228.811654) (xy 340.209168 -228.799794)
			(xy 340.159554 -228.780322) (xy 340.113396 -228.753673) (xy 340.071725 -228.720442) (xy 340.035473 -228.681371)
			(xy 340.005449 -228.637334) (xy 339.982323 -228.589313) (xy 339.966613 -228.538383) (xy 339.95867 -228.485679)
			(xy 339.730344 -228.485679) (xy 339.722401 -228.538383) (xy 339.706691 -228.589313) (xy 339.683565 -228.637334)
			(xy 339.653541 -228.681371) (xy 339.617289 -228.720442) (xy 339.575618 -228.753673) (xy 339.52946 -228.780322)
			(xy 339.479846 -228.799794) (xy 339.427884 -228.811654) (xy 339.374734 -228.815638) (xy 339.321584 -228.811654)
			(xy 339.269622 -228.799794) (xy 339.220008 -228.780322) (xy 339.17385 -228.753673) (xy 339.132179 -228.720442)
			(xy 339.095927 -228.681371) (xy 339.065903 -228.637334) (xy 339.042777 -228.589313) (xy 339.027067 -228.538383)
			(xy 339.019124 -228.485679) (xy 338.79029 -228.485679) (xy 338.782347 -228.538383) (xy 338.766637 -228.589313)
			(xy 338.743511 -228.637334) (xy 338.713487 -228.681371) (xy 338.677235 -228.720442) (xy 338.635564 -228.753673)
			(xy 338.589406 -228.780322) (xy 338.539792 -228.799794) (xy 338.48783 -228.811654) (xy 338.43468 -228.815638)
			(xy 338.38153 -228.811654) (xy 338.329568 -228.799794) (xy 338.279954 -228.780322) (xy 338.233796 -228.753673)
			(xy 338.192125 -228.720442) (xy 338.155873 -228.681371) (xy 338.125849 -228.637334) (xy 338.102723 -228.589313)
			(xy 338.087013 -228.538383) (xy 338.07907 -228.485679) (xy 337.85049 -228.485679) (xy 337.842547 -228.538383)
			(xy 337.826837 -228.589313) (xy 337.803711 -228.637334) (xy 337.773687 -228.681371) (xy 337.737435 -228.720442)
			(xy 337.695764 -228.753673) (xy 337.649606 -228.780322) (xy 337.599992 -228.799794) (xy 337.54803 -228.811654)
			(xy 337.49488 -228.815638) (xy 337.44173 -228.811654) (xy 337.389768 -228.799794) (xy 337.340154 -228.780322)
			(xy 337.293996 -228.753673) (xy 337.252325 -228.720442) (xy 337.216073 -228.681371) (xy 337.186049 -228.637334)
			(xy 337.162923 -228.589313) (xy 337.147213 -228.538383) (xy 337.13927 -228.485679) (xy 336.909745 -228.485679)
			(xy 336.907845 -228.511395) (xy 336.896321 -228.562644) (xy 336.877395 -228.611644) (xy 336.851476 -228.657332)
			(xy 336.819126 -228.698717) (xy 336.781048 -228.734901) (xy 336.738068 -228.765099) (xy 336.691118 -228.788656)
			(xy 336.666332 -228.797358) (xy 336.63128 -228.808788) (xy 336.63128 -228.920802) (xy 336.631804 -228.935175)
			(xy 336.639877 -228.962765) (xy 336.655325 -228.987009) (xy 336.676921 -229.005983) (xy 336.702953 -229.018179)
			(xy 336.731353 -229.022632) (xy 336.759868 -229.018987) (xy 336.786235 -229.007533) (xy 336.79765 -228.99878)
			(xy 336.816927 -228.983343) (xy 336.858932 -228.957373) (xy 336.904121 -228.937453) (xy 336.951627 -228.923963)
			(xy 337.000541 -228.917162) (xy 337.025234 -228.916738) (xy 337.051878 -228.917238) (xy 337.104571 -228.925185)
			(xy 337.155491 -228.940896) (xy 337.2035 -228.96402) (xy 337.247527 -228.994042) (xy 337.286589 -229.030289)
			(xy 337.319812 -229.071953) (xy 337.346455 -229.118103) (xy 337.365922 -229.167708) (xy 337.377779 -229.219661)
			(xy 337.381761 -229.2728) (xy 337.379761 -229.299495) (xy 337.609424 -229.299495) (xy 337.609424 -229.246197)
			(xy 337.617367 -229.193493) (xy 337.633077 -229.142563) (xy 337.656203 -229.094542) (xy 337.686227 -229.050505)
			(xy 337.722479 -229.011434) (xy 337.76415 -228.978203) (xy 337.810308 -228.951554) (xy 337.859922 -228.932082)
			(xy 337.911884 -228.920222) (xy 337.965034 -228.916239) (xy 338.018184 -228.920222) (xy 338.070146 -228.932082)
			(xy 338.11976 -228.951554) (xy 338.165918 -228.978203) (xy 338.207589 -229.011434) (xy 338.243841 -229.050505)
			(xy 338.273865 -229.094542) (xy 338.296991 -229.142563) (xy 338.312701 -229.193493) (xy 338.320644 -229.246197)
			(xy 338.321142 -229.272846) (xy 338.320644 -229.299495) (xy 338.549224 -229.299495) (xy 338.549224 -229.246197)
			(xy 338.557167 -229.193493) (xy 338.572877 -229.142563) (xy 338.596003 -229.094542) (xy 338.626027 -229.050505)
			(xy 338.662279 -229.011434) (xy 338.70395 -228.978203) (xy 338.750108 -228.951554) (xy 338.799722 -228.932082)
			(xy 338.851684 -228.920222) (xy 338.904834 -228.916239) (xy 338.957984 -228.920222) (xy 339.009946 -228.932082)
			(xy 339.05956 -228.951554) (xy 339.105718 -228.978203) (xy 339.147389 -229.011434) (xy 339.183641 -229.050505)
			(xy 339.213665 -229.094542) (xy 339.236791 -229.142563) (xy 339.252501 -229.193493) (xy 339.260444 -229.246197)
			(xy 339.260942 -229.272846) (xy 339.260444 -229.299495) (xy 339.489024 -229.299495) (xy 339.489024 -229.246197)
			(xy 339.496967 -229.193493) (xy 339.512677 -229.142563) (xy 339.535803 -229.094542) (xy 339.565827 -229.050505)
			(xy 339.602079 -229.011434) (xy 339.64375 -228.978203) (xy 339.689908 -228.951554) (xy 339.739522 -228.932082)
			(xy 339.791484 -228.920222) (xy 339.844634 -228.916239) (xy 339.897784 -228.920222) (xy 339.949746 -228.932082)
			(xy 339.99936 -228.951554) (xy 340.045518 -228.978203) (xy 340.087189 -229.011434) (xy 340.123441 -229.050505)
			(xy 340.153465 -229.094542) (xy 340.176591 -229.142563) (xy 340.192301 -229.193493) (xy 340.200244 -229.246197)
			(xy 340.200742 -229.272846) (xy 340.200244 -229.299495) (xy 340.428824 -229.299495) (xy 340.428824 -229.246197)
			(xy 340.436767 -229.193493) (xy 340.452477 -229.142563) (xy 340.475603 -229.094542) (xy 340.505627 -229.050505)
			(xy 340.541879 -229.011434) (xy 340.58355 -228.978203) (xy 340.629708 -228.951554) (xy 340.679322 -228.932082)
			(xy 340.731284 -228.920222) (xy 340.784434 -228.916239) (xy 340.837584 -228.920222) (xy 340.889546 -228.932082)
			(xy 340.93916 -228.951554) (xy 340.985318 -228.978203) (xy 341.026989 -229.011434) (xy 341.063241 -229.050505)
			(xy 341.093265 -229.094542) (xy 341.116391 -229.142563) (xy 341.132101 -229.193493) (xy 341.140044 -229.246197)
			(xy 341.140542 -229.272846) (xy 341.140044 -229.299495) (xy 341.368624 -229.299495) (xy 341.368624 -229.246197)
			(xy 341.376567 -229.193493) (xy 341.392277 -229.142563) (xy 341.415403 -229.094542) (xy 341.445427 -229.050505)
			(xy 341.481679 -229.011434) (xy 341.52335 -228.978203) (xy 341.569508 -228.951554) (xy 341.619122 -228.932082)
			(xy 341.671084 -228.920222) (xy 341.724234 -228.916239) (xy 341.777384 -228.920222) (xy 341.829346 -228.932082)
			(xy 341.87896 -228.951554) (xy 341.925118 -228.978203) (xy 341.966789 -229.011434) (xy 342.003041 -229.050505)
			(xy 342.033065 -229.094542) (xy 342.056191 -229.142563) (xy 342.071901 -229.193493) (xy 342.079844 -229.246197)
			(xy 342.080342 -229.272846) (xy 342.079844 -229.299495) (xy 342.30817 -229.299495) (xy 342.30817 -229.246197)
			(xy 342.316113 -229.193493) (xy 342.331823 -229.142563) (xy 342.354949 -229.094542) (xy 342.384973 -229.050505)
			(xy 342.421225 -229.011434) (xy 342.462896 -228.978203) (xy 342.509054 -228.951554) (xy 342.558668 -228.932082)
			(xy 342.61063 -228.920222) (xy 342.66378 -228.916239) (xy 342.71693 -228.920222) (xy 342.768892 -228.932082)
			(xy 342.818506 -228.951554) (xy 342.864664 -228.978203) (xy 342.906335 -229.011434) (xy 342.942587 -229.050505)
			(xy 342.972611 -229.094542) (xy 342.995737 -229.142563) (xy 343.011447 -229.193493) (xy 343.01939 -229.246197)
			(xy 343.019888 -229.272846) (xy 343.01939 -229.299495) (xy 343.248224 -229.299495) (xy 343.248224 -229.246197)
			(xy 343.256167 -229.193493) (xy 343.271877 -229.142563) (xy 343.295003 -229.094542) (xy 343.325027 -229.050505)
			(xy 343.361279 -229.011434) (xy 343.40295 -228.978203) (xy 343.449108 -228.951554) (xy 343.498722 -228.932082)
			(xy 343.550684 -228.920222) (xy 343.603834 -228.916239) (xy 343.656984 -228.920222) (xy 343.708946 -228.932082)
			(xy 343.75856 -228.951554) (xy 343.804718 -228.978203) (xy 343.846389 -229.011434) (xy 343.882641 -229.050505)
			(xy 343.912665 -229.094542) (xy 343.935791 -229.142563) (xy 343.951501 -229.193493) (xy 343.959444 -229.246197)
			(xy 343.959942 -229.272846) (xy 343.959444 -229.299495) (xy 344.188024 -229.299495) (xy 344.188024 -229.246197)
			(xy 344.195967 -229.193493) (xy 344.211677 -229.142563) (xy 344.234803 -229.094542) (xy 344.264827 -229.050505)
			(xy 344.301079 -229.011434) (xy 344.34275 -228.978203) (xy 344.388908 -228.951554) (xy 344.438522 -228.932082)
			(xy 344.490484 -228.920222) (xy 344.543634 -228.916239) (xy 344.596784 -228.920222) (xy 344.648746 -228.932082)
			(xy 344.69836 -228.951554) (xy 344.744518 -228.978203) (xy 344.786189 -229.011434) (xy 344.822441 -229.050505)
			(xy 344.852465 -229.094542) (xy 344.875591 -229.142563) (xy 344.891301 -229.193493) (xy 344.899244 -229.246197)
			(xy 344.899742 -229.272846) (xy 344.899244 -229.299495) (xy 345.127824 -229.299495) (xy 345.127824 -229.246197)
			(xy 345.135767 -229.193493) (xy 345.151477 -229.142563) (xy 345.174603 -229.094542) (xy 345.204627 -229.050505)
			(xy 345.240879 -229.011434) (xy 345.28255 -228.978203) (xy 345.328708 -228.951554) (xy 345.378322 -228.932082)
			(xy 345.430284 -228.920222) (xy 345.483434 -228.916239) (xy 345.536584 -228.920222) (xy 345.588546 -228.932082)
			(xy 345.63816 -228.951554) (xy 345.684318 -228.978203) (xy 345.725989 -229.011434) (xy 345.762241 -229.050505)
			(xy 345.792265 -229.094542) (xy 345.815391 -229.142563) (xy 345.831101 -229.193493) (xy 345.839044 -229.246197)
			(xy 345.839542 -229.272846) (xy 345.839044 -229.299495) (xy 346.067624 -229.299495) (xy 346.067624 -229.246197)
			(xy 346.075567 -229.193493) (xy 346.091277 -229.142563) (xy 346.114403 -229.094542) (xy 346.144427 -229.050505)
			(xy 346.180679 -229.011434) (xy 346.22235 -228.978203) (xy 346.268508 -228.951554) (xy 346.318122 -228.932082)
			(xy 346.370084 -228.920222) (xy 346.423234 -228.916239) (xy 346.476384 -228.920222) (xy 346.528346 -228.932082)
			(xy 346.57796 -228.951554) (xy 346.624118 -228.978203) (xy 346.665789 -229.011434) (xy 346.702041 -229.050505)
			(xy 346.732065 -229.094542) (xy 346.755191 -229.142563) (xy 346.770901 -229.193493) (xy 346.778844 -229.246197)
			(xy 346.779342 -229.272846) (xy 346.778844 -229.299495) (xy 347.007424 -229.299495) (xy 347.007424 -229.246197)
			(xy 347.015367 -229.193493) (xy 347.031077 -229.142563) (xy 347.054203 -229.094542) (xy 347.084227 -229.050505)
			(xy 347.120479 -229.011434) (xy 347.16215 -228.978203) (xy 347.208308 -228.951554) (xy 347.257922 -228.932082)
			(xy 347.309884 -228.920222) (xy 347.363034 -228.916239) (xy 347.416184 -228.920222) (xy 347.468146 -228.932082)
			(xy 347.51776 -228.951554) (xy 347.563918 -228.978203) (xy 347.605589 -229.011434) (xy 347.641841 -229.050505)
			(xy 347.671865 -229.094542) (xy 347.694991 -229.142563) (xy 347.710701 -229.193493) (xy 347.718644 -229.246197)
			(xy 347.719142 -229.272846) (xy 347.718644 -229.299495) (xy 347.947224 -229.299495) (xy 347.947224 -229.246197)
			(xy 347.955167 -229.193493) (xy 347.970877 -229.142563) (xy 347.994003 -229.094542) (xy 348.024027 -229.050505)
			(xy 348.060279 -229.011434) (xy 348.10195 -228.978203) (xy 348.148108 -228.951554) (xy 348.197722 -228.932082)
			(xy 348.249684 -228.920222) (xy 348.302834 -228.916239) (xy 348.355984 -228.920222) (xy 348.407946 -228.932082)
			(xy 348.45756 -228.951554) (xy 348.503718 -228.978203) (xy 348.545389 -229.011434) (xy 348.581641 -229.050505)
			(xy 348.611665 -229.094542) (xy 348.634791 -229.142563) (xy 348.650501 -229.193493) (xy 348.658444 -229.246197)
			(xy 348.658942 -229.272846) (xy 348.658444 -229.299495) (xy 348.88677 -229.299495) (xy 348.88677 -229.246197)
			(xy 348.894713 -229.193493) (xy 348.910423 -229.142563) (xy 348.933549 -229.094542) (xy 348.963573 -229.050505)
			(xy 348.999825 -229.011434) (xy 349.041496 -228.978203) (xy 349.087654 -228.951554) (xy 349.137268 -228.932082)
			(xy 349.18923 -228.920222) (xy 349.24238 -228.916239) (xy 349.29553 -228.920222) (xy 349.347492 -228.932082)
			(xy 349.397106 -228.951554) (xy 349.443264 -228.978203) (xy 349.484935 -229.011434) (xy 349.521187 -229.050505)
			(xy 349.551211 -229.094542) (xy 349.574337 -229.142563) (xy 349.590047 -229.193493) (xy 349.59799 -229.246197)
			(xy 349.598488 -229.272846) (xy 349.59799 -229.299495) (xy 349.826824 -229.299495) (xy 349.826824 -229.246197)
			(xy 349.834767 -229.193493) (xy 349.850477 -229.142563) (xy 349.873603 -229.094542) (xy 349.903627 -229.050505)
			(xy 349.939879 -229.011434) (xy 349.98155 -228.978203) (xy 350.027708 -228.951554) (xy 350.077322 -228.932082)
			(xy 350.129284 -228.920222) (xy 350.182434 -228.916239) (xy 350.235584 -228.920222) (xy 350.287546 -228.932082)
			(xy 350.33716 -228.951554) (xy 350.383318 -228.978203) (xy 350.424989 -229.011434) (xy 350.461241 -229.050505)
			(xy 350.491265 -229.094542) (xy 350.514391 -229.142563) (xy 350.530101 -229.193493) (xy 350.538044 -229.246197)
			(xy 350.538542 -229.272846) (xy 350.538044 -229.299495) (xy 350.766624 -229.299495) (xy 350.766624 -229.246197)
			(xy 350.774567 -229.193493) (xy 350.790277 -229.142563) (xy 350.813403 -229.094542) (xy 350.843427 -229.050505)
			(xy 350.879679 -229.011434) (xy 350.92135 -228.978203) (xy 350.967508 -228.951554) (xy 351.017122 -228.932082)
			(xy 351.069084 -228.920222) (xy 351.122234 -228.916239) (xy 351.175384 -228.920222) (xy 351.227346 -228.932082)
			(xy 351.27696 -228.951554) (xy 351.323118 -228.978203) (xy 351.364789 -229.011434) (xy 351.401041 -229.050505)
			(xy 351.431065 -229.094542) (xy 351.454191 -229.142563) (xy 351.469901 -229.193493) (xy 351.477844 -229.246197)
			(xy 351.478342 -229.272846) (xy 351.477844 -229.299495) (xy 351.706424 -229.299495) (xy 351.706424 -229.246197)
			(xy 351.714367 -229.193493) (xy 351.730077 -229.142563) (xy 351.753203 -229.094542) (xy 351.783227 -229.050505)
			(xy 351.819479 -229.011434) (xy 351.86115 -228.978203) (xy 351.907308 -228.951554) (xy 351.956922 -228.932082)
			(xy 352.008884 -228.920222) (xy 352.062034 -228.916239) (xy 352.115184 -228.920222) (xy 352.167146 -228.932082)
			(xy 352.21676 -228.951554) (xy 352.262918 -228.978203) (xy 352.304589 -229.011434) (xy 352.340841 -229.050505)
			(xy 352.370865 -229.094542) (xy 352.393991 -229.142563) (xy 352.409701 -229.193493) (xy 352.417644 -229.246197)
			(xy 352.418142 -229.272846) (xy 352.417644 -229.299495) (xy 352.646224 -229.299495) (xy 352.646224 -229.246197)
			(xy 352.654167 -229.193493) (xy 352.669877 -229.142563) (xy 352.693003 -229.094542) (xy 352.723027 -229.050505)
			(xy 352.759279 -229.011434) (xy 352.80095 -228.978203) (xy 352.847108 -228.951554) (xy 352.896722 -228.932082)
			(xy 352.948684 -228.920222) (xy 353.001834 -228.916239) (xy 353.054984 -228.920222) (xy 353.106946 -228.932082)
			(xy 353.15656 -228.951554) (xy 353.202718 -228.978203) (xy 353.244389 -229.011434) (xy 353.280641 -229.050505)
			(xy 353.310665 -229.094542) (xy 353.333791 -229.142563) (xy 353.349501 -229.193493) (xy 353.357444 -229.246197)
			(xy 353.357942 -229.272846) (xy 353.357444 -229.299495) (xy 353.586024 -229.299495) (xy 353.586024 -229.246197)
			(xy 353.593967 -229.193493) (xy 353.609677 -229.142563) (xy 353.632803 -229.094542) (xy 353.662827 -229.050505)
			(xy 353.699079 -229.011434) (xy 353.74075 -228.978203) (xy 353.786908 -228.951554) (xy 353.836522 -228.932082)
			(xy 353.888484 -228.920222) (xy 353.941634 -228.916239) (xy 353.994784 -228.920222) (xy 354.046746 -228.932082)
			(xy 354.09636 -228.951554) (xy 354.142518 -228.978203) (xy 354.184189 -229.011434) (xy 354.220441 -229.050505)
			(xy 354.250465 -229.094542) (xy 354.273591 -229.142563) (xy 354.289301 -229.193493) (xy 354.297244 -229.246197)
			(xy 354.297742 -229.272846) (xy 354.297244 -229.299495) (xy 354.525824 -229.299495) (xy 354.525824 -229.246197)
			(xy 354.533767 -229.193493) (xy 354.549477 -229.142563) (xy 354.572603 -229.094542) (xy 354.602627 -229.050505)
			(xy 354.638879 -229.011434) (xy 354.68055 -228.978203) (xy 354.726708 -228.951554) (xy 354.776322 -228.932082)
			(xy 354.828284 -228.920222) (xy 354.881434 -228.916239) (xy 354.934584 -228.920222) (xy 354.986546 -228.932082)
			(xy 355.03616 -228.951554) (xy 355.082318 -228.978203) (xy 355.123989 -229.011434) (xy 355.160241 -229.050505)
			(xy 355.190265 -229.094542) (xy 355.213391 -229.142563) (xy 355.229101 -229.193493) (xy 355.237044 -229.246197)
			(xy 355.237542 -229.272846) (xy 355.237044 -229.299495) (xy 355.465624 -229.299495) (xy 355.465624 -229.246197)
			(xy 355.473567 -229.193493) (xy 355.489277 -229.142563) (xy 355.512403 -229.094542) (xy 355.542427 -229.050505)
			(xy 355.578679 -229.011434) (xy 355.62035 -228.978203) (xy 355.666508 -228.951554) (xy 355.716122 -228.932082)
			(xy 355.768084 -228.920222) (xy 355.821234 -228.916239) (xy 355.874384 -228.920222) (xy 355.926346 -228.932082)
			(xy 355.97596 -228.951554) (xy 356.022118 -228.978203) (xy 356.063789 -229.011434) (xy 356.100041 -229.050505)
			(xy 356.130065 -229.094542) (xy 356.153191 -229.142563) (xy 356.168901 -229.193493) (xy 356.176844 -229.246197)
			(xy 356.177342 -229.272846) (xy 356.176844 -229.299495) (xy 356.405424 -229.299495) (xy 356.405424 -229.246197)
			(xy 356.413367 -229.193493) (xy 356.429077 -229.142563) (xy 356.452203 -229.094542) (xy 356.482227 -229.050505)
			(xy 356.518479 -229.011434) (xy 356.56015 -228.978203) (xy 356.606308 -228.951554) (xy 356.655922 -228.932082)
			(xy 356.707884 -228.920222) (xy 356.761034 -228.916239) (xy 356.814184 -228.920222) (xy 356.866146 -228.932082)
			(xy 356.91576 -228.951554) (xy 356.961918 -228.978203) (xy 357.003589 -229.011434) (xy 357.039841 -229.050505)
			(xy 357.069865 -229.094542) (xy 357.092991 -229.142563) (xy 357.108701 -229.193493) (xy 357.116644 -229.246197)
			(xy 357.117142 -229.272846) (xy 357.116644 -229.299495) (xy 357.345224 -229.299495) (xy 357.345224 -229.246197)
			(xy 357.353167 -229.193493) (xy 357.368877 -229.142563) (xy 357.392003 -229.094542) (xy 357.422027 -229.050505)
			(xy 357.458279 -229.011434) (xy 357.49995 -228.978203) (xy 357.546108 -228.951554) (xy 357.595722 -228.932082)
			(xy 357.647684 -228.920222) (xy 357.700834 -228.916239) (xy 357.753984 -228.920222) (xy 357.805946 -228.932082)
			(xy 357.85556 -228.951554) (xy 357.901718 -228.978203) (xy 357.943389 -229.011434) (xy 357.979641 -229.050505)
			(xy 358.009665 -229.094542) (xy 358.032791 -229.142563) (xy 358.048501 -229.193493) (xy 358.056444 -229.246197)
			(xy 358.056942 -229.272846) (xy 358.056444 -229.299495) (xy 358.285024 -229.299495) (xy 358.285024 -229.246197)
			(xy 358.292967 -229.193493) (xy 358.308677 -229.142563) (xy 358.331803 -229.094542) (xy 358.361827 -229.050505)
			(xy 358.398079 -229.011434) (xy 358.43975 -228.978203) (xy 358.485908 -228.951554) (xy 358.535522 -228.932082)
			(xy 358.587484 -228.920222) (xy 358.640634 -228.916239) (xy 358.693784 -228.920222) (xy 358.745746 -228.932082)
			(xy 358.79536 -228.951554) (xy 358.841518 -228.978203) (xy 358.883189 -229.011434) (xy 358.919441 -229.050505)
			(xy 358.949465 -229.094542) (xy 358.972591 -229.142563) (xy 358.988301 -229.193493) (xy 358.996244 -229.246197)
			(xy 358.996742 -229.272846) (xy 358.996244 -229.299495) (xy 358.988301 -229.352199) (xy 358.972591 -229.403129)
			(xy 358.949465 -229.45115) (xy 358.919441 -229.495187) (xy 358.883189 -229.534258) (xy 358.841518 -229.567489)
			(xy 358.79536 -229.594138) (xy 358.745746 -229.61361) (xy 358.693784 -229.62547) (xy 358.640634 -229.629454)
			(xy 358.587484 -229.62547) (xy 358.535522 -229.61361) (xy 358.485908 -229.594138) (xy 358.43975 -229.567489)
			(xy 358.398079 -229.534258) (xy 358.361827 -229.495187) (xy 358.331803 -229.45115) (xy 358.308677 -229.403129)
			(xy 358.292967 -229.352199) (xy 358.285024 -229.299495) (xy 358.056444 -229.299495) (xy 358.048501 -229.352199)
			(xy 358.032791 -229.403129) (xy 358.009665 -229.45115) (xy 357.979641 -229.495187) (xy 357.943389 -229.534258)
			(xy 357.901718 -229.567489) (xy 357.85556 -229.594138) (xy 357.805946 -229.61361) (xy 357.753984 -229.62547)
			(xy 357.700834 -229.629454) (xy 357.647684 -229.62547) (xy 357.595722 -229.61361) (xy 357.546108 -229.594138)
			(xy 357.49995 -229.567489) (xy 357.458279 -229.534258) (xy 357.422027 -229.495187) (xy 357.392003 -229.45115)
			(xy 357.368877 -229.403129) (xy 357.353167 -229.352199) (xy 357.345224 -229.299495) (xy 357.116644 -229.299495)
			(xy 357.108701 -229.352199) (xy 357.092991 -229.403129) (xy 357.069865 -229.45115) (xy 357.039841 -229.495187)
			(xy 357.003589 -229.534258) (xy 356.961918 -229.567489) (xy 356.91576 -229.594138) (xy 356.866146 -229.61361)
			(xy 356.814184 -229.62547) (xy 356.761034 -229.629454) (xy 356.707884 -229.62547) (xy 356.655922 -229.61361)
			(xy 356.606308 -229.594138) (xy 356.56015 -229.567489) (xy 356.518479 -229.534258) (xy 356.482227 -229.495187)
			(xy 356.452203 -229.45115) (xy 356.429077 -229.403129) (xy 356.413367 -229.352199) (xy 356.405424 -229.299495)
			(xy 356.176844 -229.299495) (xy 356.168901 -229.352199) (xy 356.153191 -229.403129) (xy 356.130065 -229.45115)
			(xy 356.100041 -229.495187) (xy 356.063789 -229.534258) (xy 356.022118 -229.567489) (xy 355.97596 -229.594138)
			(xy 355.926346 -229.61361) (xy 355.874384 -229.62547) (xy 355.821234 -229.629454) (xy 355.768084 -229.62547)
			(xy 355.716122 -229.61361) (xy 355.666508 -229.594138) (xy 355.62035 -229.567489) (xy 355.578679 -229.534258)
			(xy 355.542427 -229.495187) (xy 355.512403 -229.45115) (xy 355.489277 -229.403129) (xy 355.473567 -229.352199)
			(xy 355.465624 -229.299495) (xy 355.237044 -229.299495) (xy 355.229101 -229.352199) (xy 355.213391 -229.403129)
			(xy 355.190265 -229.45115) (xy 355.160241 -229.495187) (xy 355.123989 -229.534258) (xy 355.082318 -229.567489)
			(xy 355.03616 -229.594138) (xy 354.986546 -229.61361) (xy 354.934584 -229.62547) (xy 354.881434 -229.629454)
			(xy 354.828284 -229.62547) (xy 354.776322 -229.61361) (xy 354.726708 -229.594138) (xy 354.68055 -229.567489)
			(xy 354.638879 -229.534258) (xy 354.602627 -229.495187) (xy 354.572603 -229.45115) (xy 354.549477 -229.403129)
			(xy 354.533767 -229.352199) (xy 354.525824 -229.299495) (xy 354.297244 -229.299495) (xy 354.289301 -229.352199)
			(xy 354.273591 -229.403129) (xy 354.250465 -229.45115) (xy 354.220441 -229.495187) (xy 354.184189 -229.534258)
			(xy 354.142518 -229.567489) (xy 354.09636 -229.594138) (xy 354.046746 -229.61361) (xy 353.994784 -229.62547)
			(xy 353.941634 -229.629454) (xy 353.888484 -229.62547) (xy 353.836522 -229.61361) (xy 353.786908 -229.594138)
			(xy 353.74075 -229.567489) (xy 353.699079 -229.534258) (xy 353.662827 -229.495187) (xy 353.632803 -229.45115)
			(xy 353.609677 -229.403129) (xy 353.593967 -229.352199) (xy 353.586024 -229.299495) (xy 353.357444 -229.299495)
			(xy 353.349501 -229.352199) (xy 353.333791 -229.403129) (xy 353.310665 -229.45115) (xy 353.280641 -229.495187)
			(xy 353.244389 -229.534258) (xy 353.202718 -229.567489) (xy 353.15656 -229.594138) (xy 353.106946 -229.61361)
			(xy 353.054984 -229.62547) (xy 353.001834 -229.629454) (xy 352.948684 -229.62547) (xy 352.896722 -229.61361)
			(xy 352.847108 -229.594138) (xy 352.80095 -229.567489) (xy 352.759279 -229.534258) (xy 352.723027 -229.495187)
			(xy 352.693003 -229.45115) (xy 352.669877 -229.403129) (xy 352.654167 -229.352199) (xy 352.646224 -229.299495)
			(xy 352.417644 -229.299495) (xy 352.409701 -229.352199) (xy 352.393991 -229.403129) (xy 352.370865 -229.45115)
			(xy 352.340841 -229.495187) (xy 352.304589 -229.534258) (xy 352.262918 -229.567489) (xy 352.21676 -229.594138)
			(xy 352.167146 -229.61361) (xy 352.115184 -229.62547) (xy 352.062034 -229.629454) (xy 352.008884 -229.62547)
			(xy 351.956922 -229.61361) (xy 351.907308 -229.594138) (xy 351.86115 -229.567489) (xy 351.819479 -229.534258)
			(xy 351.783227 -229.495187) (xy 351.753203 -229.45115) (xy 351.730077 -229.403129) (xy 351.714367 -229.352199)
			(xy 351.706424 -229.299495) (xy 351.477844 -229.299495) (xy 351.469901 -229.352199) (xy 351.454191 -229.403129)
			(xy 351.431065 -229.45115) (xy 351.401041 -229.495187) (xy 351.364789 -229.534258) (xy 351.323118 -229.567489)
			(xy 351.27696 -229.594138) (xy 351.227346 -229.61361) (xy 351.175384 -229.62547) (xy 351.122234 -229.629454)
			(xy 351.069084 -229.62547) (xy 351.017122 -229.61361) (xy 350.967508 -229.594138) (xy 350.92135 -229.567489)
			(xy 350.879679 -229.534258) (xy 350.843427 -229.495187) (xy 350.813403 -229.45115) (xy 350.790277 -229.403129)
			(xy 350.774567 -229.352199) (xy 350.766624 -229.299495) (xy 350.538044 -229.299495) (xy 350.530101 -229.352199)
			(xy 350.514391 -229.403129) (xy 350.491265 -229.45115) (xy 350.461241 -229.495187) (xy 350.424989 -229.534258)
			(xy 350.383318 -229.567489) (xy 350.33716 -229.594138) (xy 350.287546 -229.61361) (xy 350.235584 -229.62547)
			(xy 350.182434 -229.629454) (xy 350.129284 -229.62547) (xy 350.077322 -229.61361) (xy 350.027708 -229.594138)
			(xy 349.98155 -229.567489) (xy 349.939879 -229.534258) (xy 349.903627 -229.495187) (xy 349.873603 -229.45115)
			(xy 349.850477 -229.403129) (xy 349.834767 -229.352199) (xy 349.826824 -229.299495) (xy 349.59799 -229.299495)
			(xy 349.590047 -229.352199) (xy 349.574337 -229.403129) (xy 349.551211 -229.45115) (xy 349.521187 -229.495187)
			(xy 349.484935 -229.534258) (xy 349.443264 -229.567489) (xy 349.397106 -229.594138) (xy 349.347492 -229.61361)
			(xy 349.29553 -229.62547) (xy 349.24238 -229.629454) (xy 349.18923 -229.62547) (xy 349.137268 -229.61361)
			(xy 349.087654 -229.594138) (xy 349.041496 -229.567489) (xy 348.999825 -229.534258) (xy 348.963573 -229.495187)
			(xy 348.933549 -229.45115) (xy 348.910423 -229.403129) (xy 348.894713 -229.352199) (xy 348.88677 -229.299495)
			(xy 348.658444 -229.299495) (xy 348.650501 -229.352199) (xy 348.634791 -229.403129) (xy 348.611665 -229.45115)
			(xy 348.581641 -229.495187) (xy 348.545389 -229.534258) (xy 348.503718 -229.567489) (xy 348.45756 -229.594138)
			(xy 348.407946 -229.61361) (xy 348.355984 -229.62547) (xy 348.302834 -229.629454) (xy 348.249684 -229.62547)
			(xy 348.197722 -229.61361) (xy 348.148108 -229.594138) (xy 348.10195 -229.567489) (xy 348.060279 -229.534258)
			(xy 348.024027 -229.495187) (xy 347.994003 -229.45115) (xy 347.970877 -229.403129) (xy 347.955167 -229.352199)
			(xy 347.947224 -229.299495) (xy 347.718644 -229.299495) (xy 347.710701 -229.352199) (xy 347.694991 -229.403129)
			(xy 347.671865 -229.45115) (xy 347.641841 -229.495187) (xy 347.605589 -229.534258) (xy 347.563918 -229.567489)
			(xy 347.51776 -229.594138) (xy 347.468146 -229.61361) (xy 347.416184 -229.62547) (xy 347.363034 -229.629454)
			(xy 347.309884 -229.62547) (xy 347.257922 -229.61361) (xy 347.208308 -229.594138) (xy 347.16215 -229.567489)
			(xy 347.120479 -229.534258) (xy 347.084227 -229.495187) (xy 347.054203 -229.45115) (xy 347.031077 -229.403129)
			(xy 347.015367 -229.352199) (xy 347.007424 -229.299495) (xy 346.778844 -229.299495) (xy 346.770901 -229.352199)
			(xy 346.755191 -229.403129) (xy 346.732065 -229.45115) (xy 346.702041 -229.495187) (xy 346.665789 -229.534258)
			(xy 346.624118 -229.567489) (xy 346.57796 -229.594138) (xy 346.528346 -229.61361) (xy 346.476384 -229.62547)
			(xy 346.423234 -229.629454) (xy 346.370084 -229.62547) (xy 346.318122 -229.61361) (xy 346.268508 -229.594138)
			(xy 346.22235 -229.567489) (xy 346.180679 -229.534258) (xy 346.144427 -229.495187) (xy 346.114403 -229.45115)
			(xy 346.091277 -229.403129) (xy 346.075567 -229.352199) (xy 346.067624 -229.299495) (xy 345.839044 -229.299495)
			(xy 345.831101 -229.352199) (xy 345.815391 -229.403129) (xy 345.792265 -229.45115) (xy 345.762241 -229.495187)
			(xy 345.725989 -229.534258) (xy 345.684318 -229.567489) (xy 345.63816 -229.594138) (xy 345.588546 -229.61361)
			(xy 345.536584 -229.62547) (xy 345.483434 -229.629454) (xy 345.430284 -229.62547) (xy 345.378322 -229.61361)
			(xy 345.328708 -229.594138) (xy 345.28255 -229.567489) (xy 345.240879 -229.534258) (xy 345.204627 -229.495187)
			(xy 345.174603 -229.45115) (xy 345.151477 -229.403129) (xy 345.135767 -229.352199) (xy 345.127824 -229.299495)
			(xy 344.899244 -229.299495) (xy 344.891301 -229.352199) (xy 344.875591 -229.403129) (xy 344.852465 -229.45115)
			(xy 344.822441 -229.495187) (xy 344.786189 -229.534258) (xy 344.744518 -229.567489) (xy 344.69836 -229.594138)
			(xy 344.648746 -229.61361) (xy 344.596784 -229.62547) (xy 344.543634 -229.629454) (xy 344.490484 -229.62547)
			(xy 344.438522 -229.61361) (xy 344.388908 -229.594138) (xy 344.34275 -229.567489) (xy 344.301079 -229.534258)
			(xy 344.264827 -229.495187) (xy 344.234803 -229.45115) (xy 344.211677 -229.403129) (xy 344.195967 -229.352199)
			(xy 344.188024 -229.299495) (xy 343.959444 -229.299495) (xy 343.951501 -229.352199) (xy 343.935791 -229.403129)
			(xy 343.912665 -229.45115) (xy 343.882641 -229.495187) (xy 343.846389 -229.534258) (xy 343.804718 -229.567489)
			(xy 343.75856 -229.594138) (xy 343.708946 -229.61361) (xy 343.656984 -229.62547) (xy 343.603834 -229.629454)
			(xy 343.550684 -229.62547) (xy 343.498722 -229.61361) (xy 343.449108 -229.594138) (xy 343.40295 -229.567489)
			(xy 343.361279 -229.534258) (xy 343.325027 -229.495187) (xy 343.295003 -229.45115) (xy 343.271877 -229.403129)
			(xy 343.256167 -229.352199) (xy 343.248224 -229.299495) (xy 343.01939 -229.299495) (xy 343.011447 -229.352199)
			(xy 342.995737 -229.403129) (xy 342.972611 -229.45115) (xy 342.942587 -229.495187) (xy 342.906335 -229.534258)
			(xy 342.864664 -229.567489) (xy 342.818506 -229.594138) (xy 342.768892 -229.61361) (xy 342.71693 -229.62547)
			(xy 342.66378 -229.629454) (xy 342.61063 -229.62547) (xy 342.558668 -229.61361) (xy 342.509054 -229.594138)
			(xy 342.462896 -229.567489) (xy 342.421225 -229.534258) (xy 342.384973 -229.495187) (xy 342.354949 -229.45115)
			(xy 342.331823 -229.403129) (xy 342.316113 -229.352199) (xy 342.30817 -229.299495) (xy 342.079844 -229.299495)
			(xy 342.071901 -229.352199) (xy 342.056191 -229.403129) (xy 342.033065 -229.45115) (xy 342.003041 -229.495187)
			(xy 341.966789 -229.534258) (xy 341.925118 -229.567489) (xy 341.87896 -229.594138) (xy 341.829346 -229.61361)
			(xy 341.777384 -229.62547) (xy 341.724234 -229.629454) (xy 341.671084 -229.62547) (xy 341.619122 -229.61361)
			(xy 341.569508 -229.594138) (xy 341.52335 -229.567489) (xy 341.481679 -229.534258) (xy 341.445427 -229.495187)
			(xy 341.415403 -229.45115) (xy 341.392277 -229.403129) (xy 341.376567 -229.352199) (xy 341.368624 -229.299495)
			(xy 341.140044 -229.299495) (xy 341.132101 -229.352199) (xy 341.116391 -229.403129) (xy 341.093265 -229.45115)
			(xy 341.063241 -229.495187) (xy 341.026989 -229.534258) (xy 340.985318 -229.567489) (xy 340.93916 -229.594138)
			(xy 340.889546 -229.61361) (xy 340.837584 -229.62547) (xy 340.784434 -229.629454) (xy 340.731284 -229.62547)
			(xy 340.679322 -229.61361) (xy 340.629708 -229.594138) (xy 340.58355 -229.567489) (xy 340.541879 -229.534258)
			(xy 340.505627 -229.495187) (xy 340.475603 -229.45115) (xy 340.452477 -229.403129) (xy 340.436767 -229.352199)
			(xy 340.428824 -229.299495) (xy 340.200244 -229.299495) (xy 340.192301 -229.352199) (xy 340.176591 -229.403129)
			(xy 340.153465 -229.45115) (xy 340.123441 -229.495187) (xy 340.087189 -229.534258) (xy 340.045518 -229.567489)
			(xy 339.99936 -229.594138) (xy 339.949746 -229.61361) (xy 339.897784 -229.62547) (xy 339.844634 -229.629454)
			(xy 339.791484 -229.62547) (xy 339.739522 -229.61361) (xy 339.689908 -229.594138) (xy 339.64375 -229.567489)
			(xy 339.602079 -229.534258) (xy 339.565827 -229.495187) (xy 339.535803 -229.45115) (xy 339.512677 -229.403129)
			(xy 339.496967 -229.352199) (xy 339.489024 -229.299495) (xy 339.260444 -229.299495) (xy 339.252501 -229.352199)
			(xy 339.236791 -229.403129) (xy 339.213665 -229.45115) (xy 339.183641 -229.495187) (xy 339.147389 -229.534258)
			(xy 339.105718 -229.567489) (xy 339.05956 -229.594138) (xy 339.009946 -229.61361) (xy 338.957984 -229.62547)
			(xy 338.904834 -229.629454) (xy 338.851684 -229.62547) (xy 338.799722 -229.61361) (xy 338.750108 -229.594138)
			(xy 338.70395 -229.567489) (xy 338.662279 -229.534258) (xy 338.626027 -229.495187) (xy 338.596003 -229.45115)
			(xy 338.572877 -229.403129) (xy 338.557167 -229.352199) (xy 338.549224 -229.299495) (xy 338.320644 -229.299495)
			(xy 338.312701 -229.352199) (xy 338.296991 -229.403129) (xy 338.273865 -229.45115) (xy 338.243841 -229.495187)
			(xy 338.207589 -229.534258) (xy 338.165918 -229.567489) (xy 338.11976 -229.594138) (xy 338.070146 -229.61361)
			(xy 338.018184 -229.62547) (xy 337.965034 -229.629454) (xy 337.911884 -229.62547) (xy 337.859922 -229.61361)
			(xy 337.810308 -229.594138) (xy 337.76415 -229.567489) (xy 337.722479 -229.534258) (xy 337.686227 -229.495187)
			(xy 337.656203 -229.45115) (xy 337.633077 -229.403129) (xy 337.617367 -229.352199) (xy 337.609424 -229.299495)
			(xy 337.379761 -229.299495) (xy 337.377779 -229.325939) (xy 337.365922 -229.377892) (xy 337.346455 -229.427497)
			(xy 337.319812 -229.473647) (xy 337.286589 -229.515311) (xy 337.247527 -229.551558) (xy 337.2035 -229.58158)
			(xy 337.155491 -229.604704) (xy 337.104571 -229.620415) (xy 337.051878 -229.628362) (xy 337.025234 -229.628954)
			(xy 337.000539 -229.628555) (xy 336.951617 -229.621771) (xy 336.904103 -229.608286) (xy 336.85891 -229.58836)
			(xy 336.816908 -229.562376) (xy 336.79765 -229.546912) (xy 336.786263 -229.538135) (xy 336.759893 -229.526715)
			(xy 336.731385 -229.523094) (xy 336.702997 -229.527559) (xy 336.676977 -229.539756) (xy 336.655386 -229.55872)
			(xy 336.639933 -229.582949) (xy 336.631843 -229.610523) (xy 336.63128 -229.62489) (xy 336.63128 -229.736904)
			(xy 336.666332 -229.748334) (xy 336.691141 -229.756983) (xy 336.738099 -229.780544) (xy 336.781087 -229.810747)
			(xy 336.819172 -229.846938) (xy 336.851528 -229.88833) (xy 336.877452 -229.934026) (xy 336.896383 -229.983035)
			(xy 336.907908 -230.034293) (xy 336.911779 -230.086688) (xy 336.909814 -230.113311) (xy 337.13927 -230.113311)
			(xy 337.13927 -230.060013) (xy 337.147213 -230.007309) (xy 337.162923 -229.956379) (xy 337.186049 -229.908358)
			(xy 337.216073 -229.864321) (xy 337.252325 -229.82525) (xy 337.293996 -229.792019) (xy 337.340154 -229.76537)
			(xy 337.389768 -229.745898) (xy 337.44173 -229.734038) (xy 337.49488 -229.730055) (xy 337.54803 -229.734038)
			(xy 337.599992 -229.745898) (xy 337.649606 -229.76537) (xy 337.695764 -229.792019) (xy 337.737435 -229.82525)
			(xy 337.773687 -229.864321) (xy 337.803711 -229.908358) (xy 337.826837 -229.956379) (xy 337.842547 -230.007309)
			(xy 337.85049 -230.060013) (xy 337.850988 -230.086662) (xy 337.85049 -230.113311) (xy 338.07907 -230.113311)
			(xy 338.07907 -230.060013) (xy 338.087013 -230.007309) (xy 338.102723 -229.956379) (xy 338.125849 -229.908358)
			(xy 338.155873 -229.864321) (xy 338.192125 -229.82525) (xy 338.233796 -229.792019) (xy 338.279954 -229.76537)
			(xy 338.329568 -229.745898) (xy 338.38153 -229.734038) (xy 338.43468 -229.730055) (xy 338.48783 -229.734038)
			(xy 338.539792 -229.745898) (xy 338.589406 -229.76537) (xy 338.635564 -229.792019) (xy 338.677235 -229.82525)
			(xy 338.713487 -229.864321) (xy 338.743511 -229.908358) (xy 338.766637 -229.956379) (xy 338.782347 -230.007309)
			(xy 338.79029 -230.060013) (xy 338.790788 -230.086662) (xy 338.79029 -230.113311) (xy 339.01887 -230.113311)
			(xy 339.01887 -230.060013) (xy 339.026813 -230.007309) (xy 339.042523 -229.956379) (xy 339.065649 -229.908358)
			(xy 339.095673 -229.864321) (xy 339.131925 -229.82525) (xy 339.173596 -229.792019) (xy 339.219754 -229.76537)
			(xy 339.269368 -229.745898) (xy 339.32133 -229.734038) (xy 339.37448 -229.730055) (xy 339.42763 -229.734038)
			(xy 339.479592 -229.745898) (xy 339.529206 -229.76537) (xy 339.575364 -229.792019) (xy 339.617035 -229.82525)
			(xy 339.653287 -229.864321) (xy 339.683311 -229.908358) (xy 339.706437 -229.956379) (xy 339.722147 -230.007309)
			(xy 339.73009 -230.060013) (xy 339.730588 -230.086662) (xy 339.73009 -230.113311) (xy 339.95867 -230.113311)
			(xy 339.95867 -230.060013) (xy 339.966613 -230.007309) (xy 339.982323 -229.956379) (xy 340.005449 -229.908358)
			(xy 340.035473 -229.864321) (xy 340.071725 -229.82525) (xy 340.113396 -229.792019) (xy 340.159554 -229.76537)
			(xy 340.209168 -229.745898) (xy 340.26113 -229.734038) (xy 340.31428 -229.730055) (xy 340.36743 -229.734038)
			(xy 340.419392 -229.745898) (xy 340.469006 -229.76537) (xy 340.515164 -229.792019) (xy 340.556835 -229.82525)
			(xy 340.593087 -229.864321) (xy 340.623111 -229.908358) (xy 340.646237 -229.956379) (xy 340.661947 -230.007309)
			(xy 340.66989 -230.060013) (xy 340.670388 -230.086662) (xy 340.66989 -230.113311) (xy 340.89847 -230.113311)
			(xy 340.89847 -230.060013) (xy 340.906413 -230.007309) (xy 340.922123 -229.956379) (xy 340.945249 -229.908358)
			(xy 340.975273 -229.864321) (xy 341.011525 -229.82525) (xy 341.053196 -229.792019) (xy 341.099354 -229.76537)
			(xy 341.148968 -229.745898) (xy 341.20093 -229.734038) (xy 341.25408 -229.730055) (xy 341.30723 -229.734038)
			(xy 341.359192 -229.745898) (xy 341.408806 -229.76537) (xy 341.454964 -229.792019) (xy 341.496635 -229.82525)
			(xy 341.532887 -229.864321) (xy 341.562911 -229.908358) (xy 341.586037 -229.956379) (xy 341.601747 -230.007309)
			(xy 341.60969 -230.060013) (xy 341.610188 -230.086662) (xy 341.60969 -230.113311) (xy 341.83827 -230.113311)
			(xy 341.83827 -230.060013) (xy 341.846213 -230.007309) (xy 341.861923 -229.956379) (xy 341.885049 -229.908358)
			(xy 341.915073 -229.864321) (xy 341.951325 -229.82525) (xy 341.992996 -229.792019) (xy 342.039154 -229.76537)
			(xy 342.088768 -229.745898) (xy 342.14073 -229.734038) (xy 342.19388 -229.730055) (xy 342.24703 -229.734038)
			(xy 342.298992 -229.745898) (xy 342.348606 -229.76537) (xy 342.394764 -229.792019) (xy 342.436435 -229.82525)
			(xy 342.472687 -229.864321) (xy 342.502711 -229.908358) (xy 342.525837 -229.956379) (xy 342.541547 -230.007309)
			(xy 342.54949 -230.060013) (xy 342.549988 -230.086662) (xy 342.54949 -230.113311) (xy 342.77807 -230.113311)
			(xy 342.77807 -230.060013) (xy 342.786013 -230.007309) (xy 342.801723 -229.956379) (xy 342.824849 -229.908358)
			(xy 342.854873 -229.864321) (xy 342.891125 -229.82525) (xy 342.932796 -229.792019) (xy 342.978954 -229.76537)
			(xy 343.028568 -229.745898) (xy 343.08053 -229.734038) (xy 343.13368 -229.730055) (xy 343.18683 -229.734038)
			(xy 343.238792 -229.745898) (xy 343.288406 -229.76537) (xy 343.334564 -229.792019) (xy 343.376235 -229.82525)
			(xy 343.412487 -229.864321) (xy 343.442511 -229.908358) (xy 343.465637 -229.956379) (xy 343.481347 -230.007309)
			(xy 343.48929 -230.060013) (xy 343.489788 -230.086662) (xy 343.48929 -230.113311) (xy 343.71787 -230.113311)
			(xy 343.71787 -230.060013) (xy 343.725813 -230.007309) (xy 343.741523 -229.956379) (xy 343.764649 -229.908358)
			(xy 343.794673 -229.864321) (xy 343.830925 -229.82525) (xy 343.872596 -229.792019) (xy 343.918754 -229.76537)
			(xy 343.968368 -229.745898) (xy 344.02033 -229.734038) (xy 344.07348 -229.730055) (xy 344.12663 -229.734038)
			(xy 344.178592 -229.745898) (xy 344.228206 -229.76537) (xy 344.274364 -229.792019) (xy 344.316035 -229.82525)
			(xy 344.352287 -229.864321) (xy 344.382311 -229.908358) (xy 344.405437 -229.956379) (xy 344.421147 -230.007309)
			(xy 344.42909 -230.060013) (xy 344.429588 -230.086662) (xy 344.42909 -230.113311) (xy 344.657924 -230.113311)
			(xy 344.657924 -230.060013) (xy 344.665867 -230.007309) (xy 344.681577 -229.956379) (xy 344.704703 -229.908358)
			(xy 344.734727 -229.864321) (xy 344.770979 -229.82525) (xy 344.81265 -229.792019) (xy 344.858808 -229.76537)
			(xy 344.908422 -229.745898) (xy 344.960384 -229.734038) (xy 345.013534 -229.730055) (xy 345.066684 -229.734038)
			(xy 345.118646 -229.745898) (xy 345.16826 -229.76537) (xy 345.214418 -229.792019) (xy 345.256089 -229.82525)
			(xy 345.292341 -229.864321) (xy 345.322365 -229.908358) (xy 345.345491 -229.956379) (xy 345.361201 -230.007309)
			(xy 345.369144 -230.060013) (xy 345.369642 -230.086662) (xy 345.369144 -230.113311) (xy 345.59747 -230.113311)
			(xy 345.59747 -230.060013) (xy 345.605413 -230.007309) (xy 345.621123 -229.956379) (xy 345.644249 -229.908358)
			(xy 345.674273 -229.864321) (xy 345.710525 -229.82525) (xy 345.752196 -229.792019) (xy 345.798354 -229.76537)
			(xy 345.847968 -229.745898) (xy 345.89993 -229.734038) (xy 345.95308 -229.730055) (xy 346.00623 -229.734038)
			(xy 346.058192 -229.745898) (xy 346.107806 -229.76537) (xy 346.153964 -229.792019) (xy 346.195635 -229.82525)
			(xy 346.231887 -229.864321) (xy 346.261911 -229.908358) (xy 346.285037 -229.956379) (xy 346.300747 -230.007309)
			(xy 346.30869 -230.060013) (xy 346.309188 -230.086662) (xy 346.30869 -230.113311) (xy 346.53727 -230.113311)
			(xy 346.53727 -230.060013) (xy 346.545213 -230.007309) (xy 346.560923 -229.956379) (xy 346.584049 -229.908358)
			(xy 346.614073 -229.864321) (xy 346.650325 -229.82525) (xy 346.691996 -229.792019) (xy 346.738154 -229.76537)
			(xy 346.787768 -229.745898) (xy 346.83973 -229.734038) (xy 346.89288 -229.730055) (xy 346.94603 -229.734038)
			(xy 346.997992 -229.745898) (xy 347.047606 -229.76537) (xy 347.093764 -229.792019) (xy 347.135435 -229.82525)
			(xy 347.171687 -229.864321) (xy 347.201711 -229.908358) (xy 347.224837 -229.956379) (xy 347.240547 -230.007309)
			(xy 347.24849 -230.060013) (xy 347.248988 -230.086662) (xy 347.24849 -230.113311) (xy 347.47707 -230.113311)
			(xy 347.47707 -230.060013) (xy 347.485013 -230.007309) (xy 347.500723 -229.956379) (xy 347.523849 -229.908358)
			(xy 347.553873 -229.864321) (xy 347.590125 -229.82525) (xy 347.631796 -229.792019) (xy 347.677954 -229.76537)
			(xy 347.727568 -229.745898) (xy 347.77953 -229.734038) (xy 347.83268 -229.730055) (xy 347.88583 -229.734038)
			(xy 347.937792 -229.745898) (xy 347.987406 -229.76537) (xy 348.033564 -229.792019) (xy 348.075235 -229.82525)
			(xy 348.111487 -229.864321) (xy 348.141511 -229.908358) (xy 348.164637 -229.956379) (xy 348.180347 -230.007309)
			(xy 348.18829 -230.060013) (xy 348.188788 -230.086662) (xy 348.18829 -230.113311) (xy 348.41687 -230.113311)
			(xy 348.41687 -230.060013) (xy 348.424813 -230.007309) (xy 348.440523 -229.956379) (xy 348.463649 -229.908358)
			(xy 348.493673 -229.864321) (xy 348.529925 -229.82525) (xy 348.571596 -229.792019) (xy 348.617754 -229.76537)
			(xy 348.667368 -229.745898) (xy 348.71933 -229.734038) (xy 348.77248 -229.730055) (xy 348.82563 -229.734038)
			(xy 348.877592 -229.745898) (xy 348.927206 -229.76537) (xy 348.973364 -229.792019) (xy 349.015035 -229.82525)
			(xy 349.051287 -229.864321) (xy 349.081311 -229.908358) (xy 349.104437 -229.956379) (xy 349.120147 -230.007309)
			(xy 349.12809 -230.060013) (xy 349.128588 -230.086662) (xy 349.12809 -230.113311) (xy 349.35667 -230.113311)
			(xy 349.35667 -230.060013) (xy 349.364613 -230.007309) (xy 349.380323 -229.956379) (xy 349.403449 -229.908358)
			(xy 349.433473 -229.864321) (xy 349.469725 -229.82525) (xy 349.511396 -229.792019) (xy 349.557554 -229.76537)
			(xy 349.607168 -229.745898) (xy 349.65913 -229.734038) (xy 349.71228 -229.730055) (xy 349.76543 -229.734038)
			(xy 349.817392 -229.745898) (xy 349.867006 -229.76537) (xy 349.913164 -229.792019) (xy 349.954835 -229.82525)
			(xy 349.991087 -229.864321) (xy 350.021111 -229.908358) (xy 350.044237 -229.956379) (xy 350.059947 -230.007309)
			(xy 350.06789 -230.060013) (xy 350.068388 -230.086662) (xy 350.06789 -230.113311) (xy 350.29647 -230.113311)
			(xy 350.29647 -230.060013) (xy 350.304413 -230.007309) (xy 350.320123 -229.956379) (xy 350.343249 -229.908358)
			(xy 350.373273 -229.864321) (xy 350.409525 -229.82525) (xy 350.451196 -229.792019) (xy 350.497354 -229.76537)
			(xy 350.546968 -229.745898) (xy 350.59893 -229.734038) (xy 350.65208 -229.730055) (xy 350.70523 -229.734038)
			(xy 350.757192 -229.745898) (xy 350.806806 -229.76537) (xy 350.852964 -229.792019) (xy 350.894635 -229.82525)
			(xy 350.930887 -229.864321) (xy 350.960911 -229.908358) (xy 350.984037 -229.956379) (xy 350.999747 -230.007309)
			(xy 351.00769 -230.060013) (xy 351.008188 -230.086662) (xy 351.00769 -230.113311) (xy 351.23627 -230.113311)
			(xy 351.23627 -230.060013) (xy 351.244213 -230.007309) (xy 351.259923 -229.956379) (xy 351.283049 -229.908358)
			(xy 351.313073 -229.864321) (xy 351.349325 -229.82525) (xy 351.390996 -229.792019) (xy 351.437154 -229.76537)
			(xy 351.486768 -229.745898) (xy 351.53873 -229.734038) (xy 351.59188 -229.730055) (xy 351.64503 -229.734038)
			(xy 351.696992 -229.745898) (xy 351.746606 -229.76537) (xy 351.792764 -229.792019) (xy 351.834435 -229.82525)
			(xy 351.870687 -229.864321) (xy 351.900711 -229.908358) (xy 351.923837 -229.956379) (xy 351.939547 -230.007309)
			(xy 351.94749 -230.060013) (xy 351.947988 -230.086662) (xy 351.94749 -230.113311) (xy 352.17607 -230.113311)
			(xy 352.17607 -230.060013) (xy 352.184013 -230.007309) (xy 352.199723 -229.956379) (xy 352.222849 -229.908358)
			(xy 352.252873 -229.864321) (xy 352.289125 -229.82525) (xy 352.330796 -229.792019) (xy 352.376954 -229.76537)
			(xy 352.426568 -229.745898) (xy 352.47853 -229.734038) (xy 352.53168 -229.730055) (xy 352.58483 -229.734038)
			(xy 352.636792 -229.745898) (xy 352.686406 -229.76537) (xy 352.732564 -229.792019) (xy 352.774235 -229.82525)
			(xy 352.810487 -229.864321) (xy 352.840511 -229.908358) (xy 352.863637 -229.956379) (xy 352.879347 -230.007309)
			(xy 352.88729 -230.060013) (xy 352.887788 -230.086662) (xy 352.88729 -230.113311) (xy 353.11587 -230.113311)
			(xy 353.11587 -230.060013) (xy 353.123813 -230.007309) (xy 353.139523 -229.956379) (xy 353.162649 -229.908358)
			(xy 353.192673 -229.864321) (xy 353.228925 -229.82525) (xy 353.270596 -229.792019) (xy 353.316754 -229.76537)
			(xy 353.366368 -229.745898) (xy 353.41833 -229.734038) (xy 353.47148 -229.730055) (xy 353.52463 -229.734038)
			(xy 353.576592 -229.745898) (xy 353.626206 -229.76537) (xy 353.672364 -229.792019) (xy 353.714035 -229.82525)
			(xy 353.750287 -229.864321) (xy 353.780311 -229.908358) (xy 353.803437 -229.956379) (xy 353.819147 -230.007309)
			(xy 353.82709 -230.060013) (xy 353.827588 -230.086662) (xy 353.82709 -230.113311) (xy 354.055924 -230.113311)
			(xy 354.055924 -230.060013) (xy 354.063867 -230.007309) (xy 354.079577 -229.956379) (xy 354.102703 -229.908358)
			(xy 354.132727 -229.864321) (xy 354.168979 -229.82525) (xy 354.21065 -229.792019) (xy 354.256808 -229.76537)
			(xy 354.306422 -229.745898) (xy 354.358384 -229.734038) (xy 354.411534 -229.730055) (xy 354.464684 -229.734038)
			(xy 354.516646 -229.745898) (xy 354.56626 -229.76537) (xy 354.612418 -229.792019) (xy 354.654089 -229.82525)
			(xy 354.690341 -229.864321) (xy 354.720365 -229.908358) (xy 354.743491 -229.956379) (xy 354.759201 -230.007309)
			(xy 354.767144 -230.060013) (xy 354.767642 -230.086662) (xy 354.767144 -230.113311) (xy 354.99547 -230.113311)
			(xy 354.99547 -230.060013) (xy 355.003413 -230.007309) (xy 355.019123 -229.956379) (xy 355.042249 -229.908358)
			(xy 355.072273 -229.864321) (xy 355.108525 -229.82525) (xy 355.150196 -229.792019) (xy 355.196354 -229.76537)
			(xy 355.245968 -229.745898) (xy 355.29793 -229.734038) (xy 355.35108 -229.730055) (xy 355.40423 -229.734038)
			(xy 355.456192 -229.745898) (xy 355.505806 -229.76537) (xy 355.551964 -229.792019) (xy 355.593635 -229.82525)
			(xy 355.629887 -229.864321) (xy 355.659911 -229.908358) (xy 355.683037 -229.956379) (xy 355.698747 -230.007309)
			(xy 355.70669 -230.060013) (xy 355.707188 -230.086662) (xy 355.70669 -230.113311) (xy 355.93527 -230.113311)
			(xy 355.93527 -230.060013) (xy 355.943213 -230.007309) (xy 355.958923 -229.956379) (xy 355.982049 -229.908358)
			(xy 356.012073 -229.864321) (xy 356.048325 -229.82525) (xy 356.089996 -229.792019) (xy 356.136154 -229.76537)
			(xy 356.185768 -229.745898) (xy 356.23773 -229.734038) (xy 356.29088 -229.730055) (xy 356.34403 -229.734038)
			(xy 356.395992 -229.745898) (xy 356.445606 -229.76537) (xy 356.491764 -229.792019) (xy 356.533435 -229.82525)
			(xy 356.569687 -229.864321) (xy 356.599711 -229.908358) (xy 356.622837 -229.956379) (xy 356.638547 -230.007309)
			(xy 356.64649 -230.060013) (xy 356.646988 -230.086662) (xy 356.64649 -230.113311) (xy 356.87507 -230.113311)
			(xy 356.87507 -230.060013) (xy 356.883013 -230.007309) (xy 356.898723 -229.956379) (xy 356.921849 -229.908358)
			(xy 356.951873 -229.864321) (xy 356.988125 -229.82525) (xy 357.029796 -229.792019) (xy 357.075954 -229.76537)
			(xy 357.125568 -229.745898) (xy 357.17753 -229.734038) (xy 357.23068 -229.730055) (xy 357.28383 -229.734038)
			(xy 357.335792 -229.745898) (xy 357.385406 -229.76537) (xy 357.431564 -229.792019) (xy 357.473235 -229.82525)
			(xy 357.509487 -229.864321) (xy 357.539511 -229.908358) (xy 357.562637 -229.956379) (xy 357.578347 -230.007309)
			(xy 357.58629 -230.060013) (xy 357.586788 -230.086662) (xy 357.58629 -230.113311) (xy 357.81487 -230.113311)
			(xy 357.81487 -230.060013) (xy 357.822813 -230.007309) (xy 357.838523 -229.956379) (xy 357.861649 -229.908358)
			(xy 357.891673 -229.864321) (xy 357.927925 -229.82525) (xy 357.969596 -229.792019) (xy 358.015754 -229.76537)
			(xy 358.065368 -229.745898) (xy 358.11733 -229.734038) (xy 358.17048 -229.730055) (xy 358.22363 -229.734038)
			(xy 358.275592 -229.745898) (xy 358.325206 -229.76537) (xy 358.371364 -229.792019) (xy 358.413035 -229.82525)
			(xy 358.449287 -229.864321) (xy 358.479311 -229.908358) (xy 358.502437 -229.956379) (xy 358.518147 -230.007309)
			(xy 358.52609 -230.060013) (xy 358.526588 -230.086662) (xy 358.52609 -230.113311) (xy 358.518147 -230.166015)
			(xy 358.502437 -230.216945) (xy 358.479311 -230.264966) (xy 358.449287 -230.309003) (xy 358.413035 -230.348074)
			(xy 358.371364 -230.381305) (xy 358.325206 -230.407954) (xy 358.275592 -230.427426) (xy 358.22363 -230.439286)
			(xy 358.17048 -230.44327) (xy 358.11733 -230.439286) (xy 358.065368 -230.427426) (xy 358.015754 -230.407954)
			(xy 357.969596 -230.381305) (xy 357.927925 -230.348074) (xy 357.891673 -230.309003) (xy 357.861649 -230.264966)
			(xy 357.838523 -230.216945) (xy 357.822813 -230.166015) (xy 357.81487 -230.113311) (xy 357.58629 -230.113311)
			(xy 357.578347 -230.166015) (xy 357.562637 -230.216945) (xy 357.539511 -230.264966) (xy 357.509487 -230.309003)
			(xy 357.473235 -230.348074) (xy 357.431564 -230.381305) (xy 357.385406 -230.407954) (xy 357.335792 -230.427426)
			(xy 357.28383 -230.439286) (xy 357.23068 -230.44327) (xy 357.17753 -230.439286) (xy 357.125568 -230.427426)
			(xy 357.075954 -230.407954) (xy 357.029796 -230.381305) (xy 356.988125 -230.348074) (xy 356.951873 -230.309003)
			(xy 356.921849 -230.264966) (xy 356.898723 -230.216945) (xy 356.883013 -230.166015) (xy 356.87507 -230.113311)
			(xy 356.64649 -230.113311) (xy 356.638547 -230.166015) (xy 356.622837 -230.216945) (xy 356.599711 -230.264966)
			(xy 356.569687 -230.309003) (xy 356.533435 -230.348074) (xy 356.491764 -230.381305) (xy 356.445606 -230.407954)
			(xy 356.395992 -230.427426) (xy 356.34403 -230.439286) (xy 356.29088 -230.44327) (xy 356.23773 -230.439286)
			(xy 356.185768 -230.427426) (xy 356.136154 -230.407954) (xy 356.089996 -230.381305) (xy 356.048325 -230.348074)
			(xy 356.012073 -230.309003) (xy 355.982049 -230.264966) (xy 355.958923 -230.216945) (xy 355.943213 -230.166015)
			(xy 355.93527 -230.113311) (xy 355.70669 -230.113311) (xy 355.698747 -230.166015) (xy 355.683037 -230.216945)
			(xy 355.659911 -230.264966) (xy 355.629887 -230.309003) (xy 355.593635 -230.348074) (xy 355.551964 -230.381305)
			(xy 355.505806 -230.407954) (xy 355.456192 -230.427426) (xy 355.40423 -230.439286) (xy 355.35108 -230.44327)
			(xy 355.29793 -230.439286) (xy 355.245968 -230.427426) (xy 355.196354 -230.407954) (xy 355.150196 -230.381305)
			(xy 355.108525 -230.348074) (xy 355.072273 -230.309003) (xy 355.042249 -230.264966) (xy 355.019123 -230.216945)
			(xy 355.003413 -230.166015) (xy 354.99547 -230.113311) (xy 354.767144 -230.113311) (xy 354.759201 -230.166015)
			(xy 354.743491 -230.216945) (xy 354.720365 -230.264966) (xy 354.690341 -230.309003) (xy 354.654089 -230.348074)
			(xy 354.612418 -230.381305) (xy 354.56626 -230.407954) (xy 354.516646 -230.427426) (xy 354.464684 -230.439286)
			(xy 354.411534 -230.44327) (xy 354.358384 -230.439286) (xy 354.306422 -230.427426) (xy 354.256808 -230.407954)
			(xy 354.21065 -230.381305) (xy 354.168979 -230.348074) (xy 354.132727 -230.309003) (xy 354.102703 -230.264966)
			(xy 354.079577 -230.216945) (xy 354.063867 -230.166015) (xy 354.055924 -230.113311) (xy 353.82709 -230.113311)
			(xy 353.819147 -230.166015) (xy 353.803437 -230.216945) (xy 353.780311 -230.264966) (xy 353.750287 -230.309003)
			(xy 353.714035 -230.348074) (xy 353.672364 -230.381305) (xy 353.626206 -230.407954) (xy 353.576592 -230.427426)
			(xy 353.52463 -230.439286) (xy 353.47148 -230.44327) (xy 353.41833 -230.439286) (xy 353.366368 -230.427426)
			(xy 353.316754 -230.407954) (xy 353.270596 -230.381305) (xy 353.228925 -230.348074) (xy 353.192673 -230.309003)
			(xy 353.162649 -230.264966) (xy 353.139523 -230.216945) (xy 353.123813 -230.166015) (xy 353.11587 -230.113311)
			(xy 352.88729 -230.113311) (xy 352.879347 -230.166015) (xy 352.863637 -230.216945) (xy 352.840511 -230.264966)
			(xy 352.810487 -230.309003) (xy 352.774235 -230.348074) (xy 352.732564 -230.381305) (xy 352.686406 -230.407954)
			(xy 352.636792 -230.427426) (xy 352.58483 -230.439286) (xy 352.53168 -230.44327) (xy 352.47853 -230.439286)
			(xy 352.426568 -230.427426) (xy 352.376954 -230.407954) (xy 352.330796 -230.381305) (xy 352.289125 -230.348074)
			(xy 352.252873 -230.309003) (xy 352.222849 -230.264966) (xy 352.199723 -230.216945) (xy 352.184013 -230.166015)
			(xy 352.17607 -230.113311) (xy 351.94749 -230.113311) (xy 351.939547 -230.166015) (xy 351.923837 -230.216945)
			(xy 351.900711 -230.264966) (xy 351.870687 -230.309003) (xy 351.834435 -230.348074) (xy 351.792764 -230.381305)
			(xy 351.746606 -230.407954) (xy 351.696992 -230.427426) (xy 351.64503 -230.439286) (xy 351.59188 -230.44327)
			(xy 351.53873 -230.439286) (xy 351.486768 -230.427426) (xy 351.437154 -230.407954) (xy 351.390996 -230.381305)
			(xy 351.349325 -230.348074) (xy 351.313073 -230.309003) (xy 351.283049 -230.264966) (xy 351.259923 -230.216945)
			(xy 351.244213 -230.166015) (xy 351.23627 -230.113311) (xy 351.00769 -230.113311) (xy 350.999747 -230.166015)
			(xy 350.984037 -230.216945) (xy 350.960911 -230.264966) (xy 350.930887 -230.309003) (xy 350.894635 -230.348074)
			(xy 350.852964 -230.381305) (xy 350.806806 -230.407954) (xy 350.757192 -230.427426) (xy 350.70523 -230.439286)
			(xy 350.65208 -230.44327) (xy 350.59893 -230.439286) (xy 350.546968 -230.427426) (xy 350.497354 -230.407954)
			(xy 350.451196 -230.381305) (xy 350.409525 -230.348074) (xy 350.373273 -230.309003) (xy 350.343249 -230.264966)
			(xy 350.320123 -230.216945) (xy 350.304413 -230.166015) (xy 350.29647 -230.113311) (xy 350.06789 -230.113311)
			(xy 350.059947 -230.166015) (xy 350.044237 -230.216945) (xy 350.021111 -230.264966) (xy 349.991087 -230.309003)
			(xy 349.954835 -230.348074) (xy 349.913164 -230.381305) (xy 349.867006 -230.407954) (xy 349.817392 -230.427426)
			(xy 349.76543 -230.439286) (xy 349.71228 -230.44327) (xy 349.65913 -230.439286) (xy 349.607168 -230.427426)
			(xy 349.557554 -230.407954) (xy 349.511396 -230.381305) (xy 349.469725 -230.348074) (xy 349.433473 -230.309003)
			(xy 349.403449 -230.264966) (xy 349.380323 -230.216945) (xy 349.364613 -230.166015) (xy 349.35667 -230.113311)
			(xy 349.12809 -230.113311) (xy 349.120147 -230.166015) (xy 349.104437 -230.216945) (xy 349.081311 -230.264966)
			(xy 349.051287 -230.309003) (xy 349.015035 -230.348074) (xy 348.973364 -230.381305) (xy 348.927206 -230.407954)
			(xy 348.877592 -230.427426) (xy 348.82563 -230.439286) (xy 348.77248 -230.44327) (xy 348.71933 -230.439286)
			(xy 348.667368 -230.427426) (xy 348.617754 -230.407954) (xy 348.571596 -230.381305) (xy 348.529925 -230.348074)
			(xy 348.493673 -230.309003) (xy 348.463649 -230.264966) (xy 348.440523 -230.216945) (xy 348.424813 -230.166015)
			(xy 348.41687 -230.113311) (xy 348.18829 -230.113311) (xy 348.180347 -230.166015) (xy 348.164637 -230.216945)
			(xy 348.141511 -230.264966) (xy 348.111487 -230.309003) (xy 348.075235 -230.348074) (xy 348.033564 -230.381305)
			(xy 347.987406 -230.407954) (xy 347.937792 -230.427426) (xy 347.88583 -230.439286) (xy 347.83268 -230.44327)
			(xy 347.77953 -230.439286) (xy 347.727568 -230.427426) (xy 347.677954 -230.407954) (xy 347.631796 -230.381305)
			(xy 347.590125 -230.348074) (xy 347.553873 -230.309003) (xy 347.523849 -230.264966) (xy 347.500723 -230.216945)
			(xy 347.485013 -230.166015) (xy 347.47707 -230.113311) (xy 347.24849 -230.113311) (xy 347.240547 -230.166015)
			(xy 347.224837 -230.216945) (xy 347.201711 -230.264966) (xy 347.171687 -230.309003) (xy 347.135435 -230.348074)
			(xy 347.093764 -230.381305) (xy 347.047606 -230.407954) (xy 346.997992 -230.427426) (xy 346.94603 -230.439286)
			(xy 346.89288 -230.44327) (xy 346.83973 -230.439286) (xy 346.787768 -230.427426) (xy 346.738154 -230.407954)
			(xy 346.691996 -230.381305) (xy 346.650325 -230.348074) (xy 346.614073 -230.309003) (xy 346.584049 -230.264966)
			(xy 346.560923 -230.216945) (xy 346.545213 -230.166015) (xy 346.53727 -230.113311) (xy 346.30869 -230.113311)
			(xy 346.300747 -230.166015) (xy 346.285037 -230.216945) (xy 346.261911 -230.264966) (xy 346.231887 -230.309003)
			(xy 346.195635 -230.348074) (xy 346.153964 -230.381305) (xy 346.107806 -230.407954) (xy 346.058192 -230.427426)
			(xy 346.00623 -230.439286) (xy 345.95308 -230.44327) (xy 345.89993 -230.439286) (xy 345.847968 -230.427426)
			(xy 345.798354 -230.407954) (xy 345.752196 -230.381305) (xy 345.710525 -230.348074) (xy 345.674273 -230.309003)
			(xy 345.644249 -230.264966) (xy 345.621123 -230.216945) (xy 345.605413 -230.166015) (xy 345.59747 -230.113311)
			(xy 345.369144 -230.113311) (xy 345.361201 -230.166015) (xy 345.345491 -230.216945) (xy 345.322365 -230.264966)
			(xy 345.292341 -230.309003) (xy 345.256089 -230.348074) (xy 345.214418 -230.381305) (xy 345.16826 -230.407954)
			(xy 345.118646 -230.427426) (xy 345.066684 -230.439286) (xy 345.013534 -230.44327) (xy 344.960384 -230.439286)
			(xy 344.908422 -230.427426) (xy 344.858808 -230.407954) (xy 344.81265 -230.381305) (xy 344.770979 -230.348074)
			(xy 344.734727 -230.309003) (xy 344.704703 -230.264966) (xy 344.681577 -230.216945) (xy 344.665867 -230.166015)
			(xy 344.657924 -230.113311) (xy 344.42909 -230.113311) (xy 344.421147 -230.166015) (xy 344.405437 -230.216945)
			(xy 344.382311 -230.264966) (xy 344.352287 -230.309003) (xy 344.316035 -230.348074) (xy 344.274364 -230.381305)
			(xy 344.228206 -230.407954) (xy 344.178592 -230.427426) (xy 344.12663 -230.439286) (xy 344.07348 -230.44327)
			(xy 344.02033 -230.439286) (xy 343.968368 -230.427426) (xy 343.918754 -230.407954) (xy 343.872596 -230.381305)
			(xy 343.830925 -230.348074) (xy 343.794673 -230.309003) (xy 343.764649 -230.264966) (xy 343.741523 -230.216945)
			(xy 343.725813 -230.166015) (xy 343.71787 -230.113311) (xy 343.48929 -230.113311) (xy 343.481347 -230.166015)
			(xy 343.465637 -230.216945) (xy 343.442511 -230.264966) (xy 343.412487 -230.309003) (xy 343.376235 -230.348074)
			(xy 343.334564 -230.381305) (xy 343.288406 -230.407954) (xy 343.238792 -230.427426) (xy 343.18683 -230.439286)
			(xy 343.13368 -230.44327) (xy 343.08053 -230.439286) (xy 343.028568 -230.427426) (xy 342.978954 -230.407954)
			(xy 342.932796 -230.381305) (xy 342.891125 -230.348074) (xy 342.854873 -230.309003) (xy 342.824849 -230.264966)
			(xy 342.801723 -230.216945) (xy 342.786013 -230.166015) (xy 342.77807 -230.113311) (xy 342.54949 -230.113311)
			(xy 342.541547 -230.166015) (xy 342.525837 -230.216945) (xy 342.502711 -230.264966) (xy 342.472687 -230.309003)
			(xy 342.436435 -230.348074) (xy 342.394764 -230.381305) (xy 342.348606 -230.407954) (xy 342.298992 -230.427426)
			(xy 342.24703 -230.439286) (xy 342.19388 -230.44327) (xy 342.14073 -230.439286) (xy 342.088768 -230.427426)
			(xy 342.039154 -230.407954) (xy 341.992996 -230.381305) (xy 341.951325 -230.348074) (xy 341.915073 -230.309003)
			(xy 341.885049 -230.264966) (xy 341.861923 -230.216945) (xy 341.846213 -230.166015) (xy 341.83827 -230.113311)
			(xy 341.60969 -230.113311) (xy 341.601747 -230.166015) (xy 341.586037 -230.216945) (xy 341.562911 -230.264966)
			(xy 341.532887 -230.309003) (xy 341.496635 -230.348074) (xy 341.454964 -230.381305) (xy 341.408806 -230.407954)
			(xy 341.359192 -230.427426) (xy 341.30723 -230.439286) (xy 341.25408 -230.44327) (xy 341.20093 -230.439286)
			(xy 341.148968 -230.427426) (xy 341.099354 -230.407954) (xy 341.053196 -230.381305) (xy 341.011525 -230.348074)
			(xy 340.975273 -230.309003) (xy 340.945249 -230.264966) (xy 340.922123 -230.216945) (xy 340.906413 -230.166015)
			(xy 340.89847 -230.113311) (xy 340.66989 -230.113311) (xy 340.661947 -230.166015) (xy 340.646237 -230.216945)
			(xy 340.623111 -230.264966) (xy 340.593087 -230.309003) (xy 340.556835 -230.348074) (xy 340.515164 -230.381305)
			(xy 340.469006 -230.407954) (xy 340.419392 -230.427426) (xy 340.36743 -230.439286) (xy 340.31428 -230.44327)
			(xy 340.26113 -230.439286) (xy 340.209168 -230.427426) (xy 340.159554 -230.407954) (xy 340.113396 -230.381305)
			(xy 340.071725 -230.348074) (xy 340.035473 -230.309003) (xy 340.005449 -230.264966) (xy 339.982323 -230.216945)
			(xy 339.966613 -230.166015) (xy 339.95867 -230.113311) (xy 339.73009 -230.113311) (xy 339.722147 -230.166015)
			(xy 339.706437 -230.216945) (xy 339.683311 -230.264966) (xy 339.653287 -230.309003) (xy 339.617035 -230.348074)
			(xy 339.575364 -230.381305) (xy 339.529206 -230.407954) (xy 339.479592 -230.427426) (xy 339.42763 -230.439286)
			(xy 339.37448 -230.44327) (xy 339.32133 -230.439286) (xy 339.269368 -230.427426) (xy 339.219754 -230.407954)
			(xy 339.173596 -230.381305) (xy 339.131925 -230.348074) (xy 339.095673 -230.309003) (xy 339.065649 -230.264966)
			(xy 339.042523 -230.216945) (xy 339.026813 -230.166015) (xy 339.01887 -230.113311) (xy 338.79029 -230.113311)
			(xy 338.782347 -230.166015) (xy 338.766637 -230.216945) (xy 338.743511 -230.264966) (xy 338.713487 -230.309003)
			(xy 338.677235 -230.348074) (xy 338.635564 -230.381305) (xy 338.589406 -230.407954) (xy 338.539792 -230.427426)
			(xy 338.48783 -230.439286) (xy 338.43468 -230.44327) (xy 338.38153 -230.439286) (xy 338.329568 -230.427426)
			(xy 338.279954 -230.407954) (xy 338.233796 -230.381305) (xy 338.192125 -230.348074) (xy 338.155873 -230.309003)
			(xy 338.125849 -230.264966) (xy 338.102723 -230.216945) (xy 338.087013 -230.166015) (xy 338.07907 -230.113311)
			(xy 337.85049 -230.113311) (xy 337.842547 -230.166015) (xy 337.826837 -230.216945) (xy 337.803711 -230.264966)
			(xy 337.773687 -230.309003) (xy 337.737435 -230.348074) (xy 337.695764 -230.381305) (xy 337.649606 -230.407954)
			(xy 337.599992 -230.427426) (xy 337.54803 -230.439286) (xy 337.49488 -230.44327) (xy 337.44173 -230.439286)
			(xy 337.389768 -230.427426) (xy 337.340154 -230.407954) (xy 337.293996 -230.381305) (xy 337.252325 -230.348074)
			(xy 337.216073 -230.309003) (xy 337.186049 -230.264966) (xy 337.162923 -230.216945) (xy 337.147213 -230.166015)
			(xy 337.13927 -230.113311) (xy 336.909814 -230.113311) (xy 336.907912 -230.139083) (xy 336.896389 -230.190342)
			(xy 336.877462 -230.239352) (xy 336.851541 -230.28505) (xy 336.819188 -230.326445) (xy 336.781106 -230.362638)
			(xy 336.73812 -230.392844) (xy 336.691163 -230.416408) (xy 336.666332 -230.42499) (xy 336.63128 -230.43642)
			(xy 336.63128 -230.548434) (xy 336.631808 -230.562803) (xy 336.639886 -230.590385) (xy 336.655335 -230.614621)
			(xy 336.676929 -230.633588) (xy 336.702955 -230.64578) (xy 336.731349 -230.650232) (xy 336.759858 -230.646589)
			(xy 336.786221 -230.635142) (xy 336.79765 -230.626412) (xy 336.816926 -230.610974) (xy 336.858931 -230.585002)
			(xy 336.904119 -230.565079) (xy 336.951626 -230.551588) (xy 337.000541 -230.544786) (xy 337.025234 -230.54437)
			(xy 337.051883 -230.54487) (xy 337.104586 -230.552818) (xy 337.155516 -230.568532) (xy 337.203534 -230.591661)
			(xy 337.24757 -230.621688) (xy 337.286639 -230.657942) (xy 337.319868 -230.699614) (xy 337.346516 -230.745773)
			(xy 337.365987 -230.795388) (xy 337.377847 -230.84735) (xy 337.38183 -230.9005) (xy 337.379835 -230.927127)
			(xy 337.609424 -230.927127) (xy 337.609424 -230.873829) (xy 337.617367 -230.821125) (xy 337.633077 -230.770195)
			(xy 337.656203 -230.722174) (xy 337.686227 -230.678137) (xy 337.722479 -230.639066) (xy 337.76415 -230.605835)
			(xy 337.810308 -230.579186) (xy 337.859922 -230.559714) (xy 337.911884 -230.547854) (xy 337.965034 -230.543871)
			(xy 338.018184 -230.547854) (xy 338.070146 -230.559714) (xy 338.11976 -230.579186) (xy 338.165918 -230.605835)
			(xy 338.207589 -230.639066) (xy 338.243841 -230.678137) (xy 338.273865 -230.722174) (xy 338.296991 -230.770195)
			(xy 338.312701 -230.821125) (xy 338.320644 -230.873829) (xy 338.321142 -230.900478) (xy 338.320644 -230.927127)
			(xy 338.54897 -230.927127) (xy 338.54897 -230.873829) (xy 338.556913 -230.821125) (xy 338.572623 -230.770195)
			(xy 338.595749 -230.722174) (xy 338.625773 -230.678137) (xy 338.662025 -230.639066) (xy 338.703696 -230.605835)
			(xy 338.749854 -230.579186) (xy 338.799468 -230.559714) (xy 338.85143 -230.547854) (xy 338.90458 -230.543871)
			(xy 338.95773 -230.547854) (xy 339.009692 -230.559714) (xy 339.059306 -230.579186) (xy 339.105464 -230.605835)
			(xy 339.147135 -230.639066) (xy 339.183387 -230.678137) (xy 339.213411 -230.722174) (xy 339.236537 -230.770195)
			(xy 339.252247 -230.821125) (xy 339.26019 -230.873829) (xy 339.260688 -230.900478) (xy 339.26019 -230.927127)
			(xy 339.489024 -230.927127) (xy 339.489024 -230.873829) (xy 339.496967 -230.821125) (xy 339.512677 -230.770195)
			(xy 339.535803 -230.722174) (xy 339.565827 -230.678137) (xy 339.602079 -230.639066) (xy 339.64375 -230.605835)
			(xy 339.689908 -230.579186) (xy 339.739522 -230.559714) (xy 339.791484 -230.547854) (xy 339.844634 -230.543871)
			(xy 339.897784 -230.547854) (xy 339.949746 -230.559714) (xy 339.99936 -230.579186) (xy 340.045518 -230.605835)
			(xy 340.087189 -230.639066) (xy 340.123441 -230.678137) (xy 340.153465 -230.722174) (xy 340.176591 -230.770195)
			(xy 340.192301 -230.821125) (xy 340.200244 -230.873829) (xy 340.200742 -230.900478) (xy 340.200244 -230.927127)
			(xy 340.428824 -230.927127) (xy 340.428824 -230.873829) (xy 340.436767 -230.821125) (xy 340.452477 -230.770195)
			(xy 340.475603 -230.722174) (xy 340.505627 -230.678137) (xy 340.541879 -230.639066) (xy 340.58355 -230.605835)
			(xy 340.629708 -230.579186) (xy 340.679322 -230.559714) (xy 340.731284 -230.547854) (xy 340.784434 -230.543871)
			(xy 340.837584 -230.547854) (xy 340.889546 -230.559714) (xy 340.93916 -230.579186) (xy 340.985318 -230.605835)
			(xy 341.026989 -230.639066) (xy 341.063241 -230.678137) (xy 341.093265 -230.722174) (xy 341.116391 -230.770195)
			(xy 341.132101 -230.821125) (xy 341.140044 -230.873829) (xy 341.140542 -230.900478) (xy 341.140044 -230.927127)
			(xy 341.368624 -230.927127) (xy 341.368624 -230.873829) (xy 341.376567 -230.821125) (xy 341.392277 -230.770195)
			(xy 341.415403 -230.722174) (xy 341.445427 -230.678137) (xy 341.481679 -230.639066) (xy 341.52335 -230.605835)
			(xy 341.569508 -230.579186) (xy 341.619122 -230.559714) (xy 341.671084 -230.547854) (xy 341.724234 -230.543871)
			(xy 341.777384 -230.547854) (xy 341.829346 -230.559714) (xy 341.87896 -230.579186) (xy 341.925118 -230.605835)
			(xy 341.966789 -230.639066) (xy 342.003041 -230.678137) (xy 342.033065 -230.722174) (xy 342.056191 -230.770195)
			(xy 342.071901 -230.821125) (xy 342.079844 -230.873829) (xy 342.080342 -230.900478) (xy 342.079844 -230.927127)
			(xy 342.308424 -230.927127) (xy 342.308424 -230.873829) (xy 342.316367 -230.821125) (xy 342.332077 -230.770195)
			(xy 342.355203 -230.722174) (xy 342.385227 -230.678137) (xy 342.421479 -230.639066) (xy 342.46315 -230.605835)
			(xy 342.509308 -230.579186) (xy 342.558922 -230.559714) (xy 342.610884 -230.547854) (xy 342.664034 -230.543871)
			(xy 342.717184 -230.547854) (xy 342.769146 -230.559714) (xy 342.81876 -230.579186) (xy 342.864918 -230.605835)
			(xy 342.906589 -230.639066) (xy 342.942841 -230.678137) (xy 342.972865 -230.722174) (xy 342.995991 -230.770195)
			(xy 343.011701 -230.821125) (xy 343.019644 -230.873829) (xy 343.020142 -230.900478) (xy 343.019644 -230.927127)
			(xy 343.248224 -230.927127) (xy 343.248224 -230.873829) (xy 343.256167 -230.821125) (xy 343.271877 -230.770195)
			(xy 343.295003 -230.722174) (xy 343.325027 -230.678137) (xy 343.361279 -230.639066) (xy 343.40295 -230.605835)
			(xy 343.449108 -230.579186) (xy 343.498722 -230.559714) (xy 343.550684 -230.547854) (xy 343.603834 -230.543871)
			(xy 343.656984 -230.547854) (xy 343.708946 -230.559714) (xy 343.75856 -230.579186) (xy 343.804718 -230.605835)
			(xy 343.846389 -230.639066) (xy 343.882641 -230.678137) (xy 343.912665 -230.722174) (xy 343.935791 -230.770195)
			(xy 343.951501 -230.821125) (xy 343.959444 -230.873829) (xy 343.959942 -230.900478) (xy 343.959444 -230.927127)
			(xy 344.188024 -230.927127) (xy 344.188024 -230.873829) (xy 344.195967 -230.821125) (xy 344.211677 -230.770195)
			(xy 344.234803 -230.722174) (xy 344.264827 -230.678137) (xy 344.301079 -230.639066) (xy 344.34275 -230.605835)
			(xy 344.388908 -230.579186) (xy 344.438522 -230.559714) (xy 344.490484 -230.547854) (xy 344.543634 -230.543871)
			(xy 344.596784 -230.547854) (xy 344.648746 -230.559714) (xy 344.69836 -230.579186) (xy 344.744518 -230.605835)
			(xy 344.786189 -230.639066) (xy 344.822441 -230.678137) (xy 344.852465 -230.722174) (xy 344.875591 -230.770195)
			(xy 344.891301 -230.821125) (xy 344.899244 -230.873829) (xy 344.899742 -230.900478) (xy 344.899244 -230.927127)
			(xy 345.12757 -230.927127) (xy 345.12757 -230.873829) (xy 345.135513 -230.821125) (xy 345.151223 -230.770195)
			(xy 345.174349 -230.722174) (xy 345.204373 -230.678137) (xy 345.240625 -230.639066) (xy 345.282296 -230.605835)
			(xy 345.328454 -230.579186) (xy 345.378068 -230.559714) (xy 345.43003 -230.547854) (xy 345.48318 -230.543871)
			(xy 345.53633 -230.547854) (xy 345.588292 -230.559714) (xy 345.637906 -230.579186) (xy 345.684064 -230.605835)
			(xy 345.725735 -230.639066) (xy 345.761987 -230.678137) (xy 345.792011 -230.722174) (xy 345.815137 -230.770195)
			(xy 345.830847 -230.821125) (xy 345.83879 -230.873829) (xy 345.839288 -230.900478) (xy 345.83879 -230.927127)
			(xy 346.067624 -230.927127) (xy 346.067624 -230.873829) (xy 346.075567 -230.821125) (xy 346.091277 -230.770195)
			(xy 346.114403 -230.722174) (xy 346.144427 -230.678137) (xy 346.180679 -230.639066) (xy 346.22235 -230.605835)
			(xy 346.268508 -230.579186) (xy 346.318122 -230.559714) (xy 346.370084 -230.547854) (xy 346.423234 -230.543871)
			(xy 346.476384 -230.547854) (xy 346.528346 -230.559714) (xy 346.57796 -230.579186) (xy 346.624118 -230.605835)
			(xy 346.665789 -230.639066) (xy 346.702041 -230.678137) (xy 346.732065 -230.722174) (xy 346.755191 -230.770195)
			(xy 346.770901 -230.821125) (xy 346.778844 -230.873829) (xy 346.779342 -230.900478) (xy 346.778844 -230.927127)
			(xy 347.007424 -230.927127) (xy 347.007424 -230.873829) (xy 347.015367 -230.821125) (xy 347.031077 -230.770195)
			(xy 347.054203 -230.722174) (xy 347.084227 -230.678137) (xy 347.120479 -230.639066) (xy 347.16215 -230.605835)
			(xy 347.208308 -230.579186) (xy 347.257922 -230.559714) (xy 347.309884 -230.547854) (xy 347.363034 -230.543871)
			(xy 347.416184 -230.547854) (xy 347.468146 -230.559714) (xy 347.51776 -230.579186) (xy 347.563918 -230.605835)
			(xy 347.605589 -230.639066) (xy 347.641841 -230.678137) (xy 347.671865 -230.722174) (xy 347.694991 -230.770195)
			(xy 347.710701 -230.821125) (xy 347.718644 -230.873829) (xy 347.719142 -230.900478) (xy 347.718644 -230.927127)
			(xy 347.947224 -230.927127) (xy 347.947224 -230.873829) (xy 347.955167 -230.821125) (xy 347.970877 -230.770195)
			(xy 347.994003 -230.722174) (xy 348.024027 -230.678137) (xy 348.060279 -230.639066) (xy 348.10195 -230.605835)
			(xy 348.148108 -230.579186) (xy 348.197722 -230.559714) (xy 348.249684 -230.547854) (xy 348.302834 -230.543871)
			(xy 348.355984 -230.547854) (xy 348.407946 -230.559714) (xy 348.45756 -230.579186) (xy 348.503718 -230.605835)
			(xy 348.545389 -230.639066) (xy 348.581641 -230.678137) (xy 348.611665 -230.722174) (xy 348.634791 -230.770195)
			(xy 348.650501 -230.821125) (xy 348.658444 -230.873829) (xy 348.658942 -230.900478) (xy 348.658444 -230.927127)
			(xy 348.887024 -230.927127) (xy 348.887024 -230.873829) (xy 348.894967 -230.821125) (xy 348.910677 -230.770195)
			(xy 348.933803 -230.722174) (xy 348.963827 -230.678137) (xy 349.000079 -230.639066) (xy 349.04175 -230.605835)
			(xy 349.087908 -230.579186) (xy 349.137522 -230.559714) (xy 349.189484 -230.547854) (xy 349.242634 -230.543871)
			(xy 349.295784 -230.547854) (xy 349.347746 -230.559714) (xy 349.39736 -230.579186) (xy 349.443518 -230.605835)
			(xy 349.485189 -230.639066) (xy 349.521441 -230.678137) (xy 349.551465 -230.722174) (xy 349.574591 -230.770195)
			(xy 349.590301 -230.821125) (xy 349.598244 -230.873829) (xy 349.598742 -230.900478) (xy 349.598244 -230.927127)
			(xy 349.826824 -230.927127) (xy 349.826824 -230.873829) (xy 349.834767 -230.821125) (xy 349.850477 -230.770195)
			(xy 349.873603 -230.722174) (xy 349.903627 -230.678137) (xy 349.939879 -230.639066) (xy 349.98155 -230.605835)
			(xy 350.027708 -230.579186) (xy 350.077322 -230.559714) (xy 350.129284 -230.547854) (xy 350.182434 -230.543871)
			(xy 350.235584 -230.547854) (xy 350.287546 -230.559714) (xy 350.33716 -230.579186) (xy 350.383318 -230.605835)
			(xy 350.424989 -230.639066) (xy 350.461241 -230.678137) (xy 350.491265 -230.722174) (xy 350.514391 -230.770195)
			(xy 350.530101 -230.821125) (xy 350.538044 -230.873829) (xy 350.538542 -230.900478) (xy 350.538044 -230.927127)
			(xy 350.766624 -230.927127) (xy 350.766624 -230.873829) (xy 350.774567 -230.821125) (xy 350.790277 -230.770195)
			(xy 350.813403 -230.722174) (xy 350.843427 -230.678137) (xy 350.879679 -230.639066) (xy 350.92135 -230.605835)
			(xy 350.967508 -230.579186) (xy 351.017122 -230.559714) (xy 351.069084 -230.547854) (xy 351.122234 -230.543871)
			(xy 351.175384 -230.547854) (xy 351.227346 -230.559714) (xy 351.27696 -230.579186) (xy 351.323118 -230.605835)
			(xy 351.364789 -230.639066) (xy 351.401041 -230.678137) (xy 351.431065 -230.722174) (xy 351.454191 -230.770195)
			(xy 351.469901 -230.821125) (xy 351.477844 -230.873829) (xy 351.478342 -230.900478) (xy 351.477844 -230.927127)
			(xy 351.706424 -230.927127) (xy 351.706424 -230.873829) (xy 351.714367 -230.821125) (xy 351.730077 -230.770195)
			(xy 351.753203 -230.722174) (xy 351.783227 -230.678137) (xy 351.819479 -230.639066) (xy 351.86115 -230.605835)
			(xy 351.907308 -230.579186) (xy 351.956922 -230.559714) (xy 352.008884 -230.547854) (xy 352.062034 -230.543871)
			(xy 352.115184 -230.547854) (xy 352.167146 -230.559714) (xy 352.21676 -230.579186) (xy 352.262918 -230.605835)
			(xy 352.304589 -230.639066) (xy 352.340841 -230.678137) (xy 352.370865 -230.722174) (xy 352.393991 -230.770195)
			(xy 352.409701 -230.821125) (xy 352.417644 -230.873829) (xy 352.418142 -230.900478) (xy 352.417644 -230.927127)
			(xy 352.646224 -230.927127) (xy 352.646224 -230.873829) (xy 352.654167 -230.821125) (xy 352.669877 -230.770195)
			(xy 352.693003 -230.722174) (xy 352.723027 -230.678137) (xy 352.759279 -230.639066) (xy 352.80095 -230.605835)
			(xy 352.847108 -230.579186) (xy 352.896722 -230.559714) (xy 352.948684 -230.547854) (xy 353.001834 -230.543871)
			(xy 353.054984 -230.547854) (xy 353.106946 -230.559714) (xy 353.15656 -230.579186) (xy 353.202718 -230.605835)
			(xy 353.244389 -230.639066) (xy 353.280641 -230.678137) (xy 353.310665 -230.722174) (xy 353.333791 -230.770195)
			(xy 353.349501 -230.821125) (xy 353.357444 -230.873829) (xy 353.357942 -230.900478) (xy 353.357444 -230.927127)
			(xy 353.586024 -230.927127) (xy 353.586024 -230.873829) (xy 353.593967 -230.821125) (xy 353.609677 -230.770195)
			(xy 353.632803 -230.722174) (xy 353.662827 -230.678137) (xy 353.699079 -230.639066) (xy 353.74075 -230.605835)
			(xy 353.786908 -230.579186) (xy 353.836522 -230.559714) (xy 353.888484 -230.547854) (xy 353.941634 -230.543871)
			(xy 353.994784 -230.547854) (xy 354.046746 -230.559714) (xy 354.09636 -230.579186) (xy 354.142518 -230.605835)
			(xy 354.184189 -230.639066) (xy 354.220441 -230.678137) (xy 354.250465 -230.722174) (xy 354.273591 -230.770195)
			(xy 354.289301 -230.821125) (xy 354.297244 -230.873829) (xy 354.297742 -230.900478) (xy 354.297244 -230.927127)
			(xy 354.525824 -230.927127) (xy 354.525824 -230.873829) (xy 354.533767 -230.821125) (xy 354.549477 -230.770195)
			(xy 354.572603 -230.722174) (xy 354.602627 -230.678137) (xy 354.638879 -230.639066) (xy 354.68055 -230.605835)
			(xy 354.726708 -230.579186) (xy 354.776322 -230.559714) (xy 354.828284 -230.547854) (xy 354.881434 -230.543871)
			(xy 354.934584 -230.547854) (xy 354.986546 -230.559714) (xy 355.03616 -230.579186) (xy 355.082318 -230.605835)
			(xy 355.123989 -230.639066) (xy 355.160241 -230.678137) (xy 355.190265 -230.722174) (xy 355.213391 -230.770195)
			(xy 355.229101 -230.821125) (xy 355.237044 -230.873829) (xy 355.237542 -230.900478) (xy 355.237044 -230.927127)
			(xy 355.46537 -230.927127) (xy 355.46537 -230.873829) (xy 355.473313 -230.821125) (xy 355.489023 -230.770195)
			(xy 355.512149 -230.722174) (xy 355.542173 -230.678137) (xy 355.578425 -230.639066) (xy 355.620096 -230.605835)
			(xy 355.666254 -230.579186) (xy 355.715868 -230.559714) (xy 355.76783 -230.547854) (xy 355.82098 -230.543871)
			(xy 355.87413 -230.547854) (xy 355.926092 -230.559714) (xy 355.975706 -230.579186) (xy 356.021864 -230.605835)
			(xy 356.063535 -230.639066) (xy 356.099787 -230.678137) (xy 356.129811 -230.722174) (xy 356.152937 -230.770195)
			(xy 356.168647 -230.821125) (xy 356.17659 -230.873829) (xy 356.177088 -230.900478) (xy 356.17659 -230.927127)
			(xy 356.405424 -230.927127) (xy 356.405424 -230.873829) (xy 356.413367 -230.821125) (xy 356.429077 -230.770195)
			(xy 356.452203 -230.722174) (xy 356.482227 -230.678137) (xy 356.518479 -230.639066) (xy 356.56015 -230.605835)
			(xy 356.606308 -230.579186) (xy 356.655922 -230.559714) (xy 356.707884 -230.547854) (xy 356.761034 -230.543871)
			(xy 356.814184 -230.547854) (xy 356.866146 -230.559714) (xy 356.91576 -230.579186) (xy 356.961918 -230.605835)
			(xy 357.003589 -230.639066) (xy 357.039841 -230.678137) (xy 357.069865 -230.722174) (xy 357.092991 -230.770195)
			(xy 357.108701 -230.821125) (xy 357.116644 -230.873829) (xy 357.117142 -230.900478) (xy 357.116644 -230.927127)
			(xy 357.34497 -230.927127) (xy 357.34497 -230.873829) (xy 357.352913 -230.821125) (xy 357.368623 -230.770195)
			(xy 357.391749 -230.722174) (xy 357.421773 -230.678137) (xy 357.458025 -230.639066) (xy 357.499696 -230.605835)
			(xy 357.545854 -230.579186) (xy 357.595468 -230.559714) (xy 357.64743 -230.547854) (xy 357.70058 -230.543871)
			(xy 357.75373 -230.547854) (xy 357.805692 -230.559714) (xy 357.855306 -230.579186) (xy 357.901464 -230.605835)
			(xy 357.943135 -230.639066) (xy 357.979387 -230.678137) (xy 358.009411 -230.722174) (xy 358.032537 -230.770195)
			(xy 358.048247 -230.821125) (xy 358.05619 -230.873829) (xy 358.056688 -230.900478) (xy 358.05619 -230.927127)
			(xy 358.048247 -230.979831) (xy 358.032537 -231.030761) (xy 358.009411 -231.078782) (xy 357.979387 -231.122819)
			(xy 357.943135 -231.16189) (xy 357.901464 -231.195121) (xy 357.855306 -231.22177) (xy 357.805692 -231.241242)
			(xy 357.75373 -231.253102) (xy 357.70058 -231.257086) (xy 357.64743 -231.253102) (xy 357.595468 -231.241242)
			(xy 357.545854 -231.22177) (xy 357.499696 -231.195121) (xy 357.458025 -231.16189) (xy 357.421773 -231.122819)
			(xy 357.391749 -231.078782) (xy 357.368623 -231.030761) (xy 357.352913 -230.979831) (xy 357.34497 -230.927127)
			(xy 357.116644 -230.927127) (xy 357.108701 -230.979831) (xy 357.092991 -231.030761) (xy 357.069865 -231.078782)
			(xy 357.039841 -231.122819) (xy 357.003589 -231.16189) (xy 356.961918 -231.195121) (xy 356.91576 -231.22177)
			(xy 356.866146 -231.241242) (xy 356.814184 -231.253102) (xy 356.761034 -231.257086) (xy 356.707884 -231.253102)
			(xy 356.655922 -231.241242) (xy 356.606308 -231.22177) (xy 356.56015 -231.195121) (xy 356.518479 -231.16189)
			(xy 356.482227 -231.122819) (xy 356.452203 -231.078782) (xy 356.429077 -231.030761) (xy 356.413367 -230.979831)
			(xy 356.405424 -230.927127) (xy 356.17659 -230.927127) (xy 356.168647 -230.979831) (xy 356.152937 -231.030761)
			(xy 356.129811 -231.078782) (xy 356.099787 -231.122819) (xy 356.063535 -231.16189) (xy 356.021864 -231.195121)
			(xy 355.975706 -231.22177) (xy 355.926092 -231.241242) (xy 355.87413 -231.253102) (xy 355.82098 -231.257086)
			(xy 355.76783 -231.253102) (xy 355.715868 -231.241242) (xy 355.666254 -231.22177) (xy 355.620096 -231.195121)
			(xy 355.578425 -231.16189) (xy 355.542173 -231.122819) (xy 355.512149 -231.078782) (xy 355.489023 -231.030761)
			(xy 355.473313 -230.979831) (xy 355.46537 -230.927127) (xy 355.237044 -230.927127) (xy 355.229101 -230.979831)
			(xy 355.213391 -231.030761) (xy 355.190265 -231.078782) (xy 355.160241 -231.122819) (xy 355.123989 -231.16189)
			(xy 355.082318 -231.195121) (xy 355.03616 -231.22177) (xy 354.986546 -231.241242) (xy 354.934584 -231.253102)
			(xy 354.881434 -231.257086) (xy 354.828284 -231.253102) (xy 354.776322 -231.241242) (xy 354.726708 -231.22177)
			(xy 354.68055 -231.195121) (xy 354.638879 -231.16189) (xy 354.602627 -231.122819) (xy 354.572603 -231.078782)
			(xy 354.549477 -231.030761) (xy 354.533767 -230.979831) (xy 354.525824 -230.927127) (xy 354.297244 -230.927127)
			(xy 354.289301 -230.979831) (xy 354.273591 -231.030761) (xy 354.250465 -231.078782) (xy 354.220441 -231.122819)
			(xy 354.184189 -231.16189) (xy 354.142518 -231.195121) (xy 354.09636 -231.22177) (xy 354.046746 -231.241242)
			(xy 353.994784 -231.253102) (xy 353.941634 -231.257086) (xy 353.888484 -231.253102) (xy 353.836522 -231.241242)
			(xy 353.786908 -231.22177) (xy 353.74075 -231.195121) (xy 353.699079 -231.16189) (xy 353.662827 -231.122819)
			(xy 353.632803 -231.078782) (xy 353.609677 -231.030761) (xy 353.593967 -230.979831) (xy 353.586024 -230.927127)
			(xy 353.357444 -230.927127) (xy 353.349501 -230.979831) (xy 353.333791 -231.030761) (xy 353.310665 -231.078782)
			(xy 353.280641 -231.122819) (xy 353.244389 -231.16189) (xy 353.202718 -231.195121) (xy 353.15656 -231.22177)
			(xy 353.106946 -231.241242) (xy 353.054984 -231.253102) (xy 353.001834 -231.257086) (xy 352.948684 -231.253102)
			(xy 352.896722 -231.241242) (xy 352.847108 -231.22177) (xy 352.80095 -231.195121) (xy 352.759279 -231.16189)
			(xy 352.723027 -231.122819) (xy 352.693003 -231.078782) (xy 352.669877 -231.030761) (xy 352.654167 -230.979831)
			(xy 352.646224 -230.927127) (xy 352.417644 -230.927127) (xy 352.409701 -230.979831) (xy 352.393991 -231.030761)
			(xy 352.370865 -231.078782) (xy 352.340841 -231.122819) (xy 352.304589 -231.16189) (xy 352.262918 -231.195121)
			(xy 352.21676 -231.22177) (xy 352.167146 -231.241242) (xy 352.115184 -231.253102) (xy 352.062034 -231.257086)
			(xy 352.008884 -231.253102) (xy 351.956922 -231.241242) (xy 351.907308 -231.22177) (xy 351.86115 -231.195121)
			(xy 351.819479 -231.16189) (xy 351.783227 -231.122819) (xy 351.753203 -231.078782) (xy 351.730077 -231.030761)
			(xy 351.714367 -230.979831) (xy 351.706424 -230.927127) (xy 351.477844 -230.927127) (xy 351.469901 -230.979831)
			(xy 351.454191 -231.030761) (xy 351.431065 -231.078782) (xy 351.401041 -231.122819) (xy 351.364789 -231.16189)
			(xy 351.323118 -231.195121) (xy 351.27696 -231.22177) (xy 351.227346 -231.241242) (xy 351.175384 -231.253102)
			(xy 351.122234 -231.257086) (xy 351.069084 -231.253102) (xy 351.017122 -231.241242) (xy 350.967508 -231.22177)
			(xy 350.92135 -231.195121) (xy 350.879679 -231.16189) (xy 350.843427 -231.122819) (xy 350.813403 -231.078782)
			(xy 350.790277 -231.030761) (xy 350.774567 -230.979831) (xy 350.766624 -230.927127) (xy 350.538044 -230.927127)
			(xy 350.530101 -230.979831) (xy 350.514391 -231.030761) (xy 350.491265 -231.078782) (xy 350.461241 -231.122819)
			(xy 350.424989 -231.16189) (xy 350.383318 -231.195121) (xy 350.33716 -231.22177) (xy 350.287546 -231.241242)
			(xy 350.235584 -231.253102) (xy 350.182434 -231.257086) (xy 350.129284 -231.253102) (xy 350.077322 -231.241242)
			(xy 350.027708 -231.22177) (xy 349.98155 -231.195121) (xy 349.939879 -231.16189) (xy 349.903627 -231.122819)
			(xy 349.873603 -231.078782) (xy 349.850477 -231.030761) (xy 349.834767 -230.979831) (xy 349.826824 -230.927127)
			(xy 349.598244 -230.927127) (xy 349.590301 -230.979831) (xy 349.574591 -231.030761) (xy 349.551465 -231.078782)
			(xy 349.521441 -231.122819) (xy 349.485189 -231.16189) (xy 349.443518 -231.195121) (xy 349.39736 -231.22177)
			(xy 349.347746 -231.241242) (xy 349.295784 -231.253102) (xy 349.242634 -231.257086) (xy 349.189484 -231.253102)
			(xy 349.137522 -231.241242) (xy 349.087908 -231.22177) (xy 349.04175 -231.195121) (xy 349.000079 -231.16189)
			(xy 348.963827 -231.122819) (xy 348.933803 -231.078782) (xy 348.910677 -231.030761) (xy 348.894967 -230.979831)
			(xy 348.887024 -230.927127) (xy 348.658444 -230.927127) (xy 348.650501 -230.979831) (xy 348.634791 -231.030761)
			(xy 348.611665 -231.078782) (xy 348.581641 -231.122819) (xy 348.545389 -231.16189) (xy 348.503718 -231.195121)
			(xy 348.45756 -231.22177) (xy 348.407946 -231.241242) (xy 348.355984 -231.253102) (xy 348.302834 -231.257086)
			(xy 348.249684 -231.253102) (xy 348.197722 -231.241242) (xy 348.148108 -231.22177) (xy 348.10195 -231.195121)
			(xy 348.060279 -231.16189) (xy 348.024027 -231.122819) (xy 347.994003 -231.078782) (xy 347.970877 -231.030761)
			(xy 347.955167 -230.979831) (xy 347.947224 -230.927127) (xy 347.718644 -230.927127) (xy 347.710701 -230.979831)
			(xy 347.694991 -231.030761) (xy 347.671865 -231.078782) (xy 347.641841 -231.122819) (xy 347.605589 -231.16189)
			(xy 347.563918 -231.195121) (xy 347.51776 -231.22177) (xy 347.468146 -231.241242) (xy 347.416184 -231.253102)
			(xy 347.363034 -231.257086) (xy 347.309884 -231.253102) (xy 347.257922 -231.241242) (xy 347.208308 -231.22177)
			(xy 347.16215 -231.195121) (xy 347.120479 -231.16189) (xy 347.084227 -231.122819) (xy 347.054203 -231.078782)
			(xy 347.031077 -231.030761) (xy 347.015367 -230.979831) (xy 347.007424 -230.927127) (xy 346.778844 -230.927127)
			(xy 346.770901 -230.979831) (xy 346.755191 -231.030761) (xy 346.732065 -231.078782) (xy 346.702041 -231.122819)
			(xy 346.665789 -231.16189) (xy 346.624118 -231.195121) (xy 346.57796 -231.22177) (xy 346.528346 -231.241242)
			(xy 346.476384 -231.253102) (xy 346.423234 -231.257086) (xy 346.370084 -231.253102) (xy 346.318122 -231.241242)
			(xy 346.268508 -231.22177) (xy 346.22235 -231.195121) (xy 346.180679 -231.16189) (xy 346.144427 -231.122819)
			(xy 346.114403 -231.078782) (xy 346.091277 -231.030761) (xy 346.075567 -230.979831) (xy 346.067624 -230.927127)
			(xy 345.83879 -230.927127) (xy 345.830847 -230.979831) (xy 345.815137 -231.030761) (xy 345.792011 -231.078782)
			(xy 345.761987 -231.122819) (xy 345.725735 -231.16189) (xy 345.684064 -231.195121) (xy 345.637906 -231.22177)
			(xy 345.588292 -231.241242) (xy 345.53633 -231.253102) (xy 345.48318 -231.257086) (xy 345.43003 -231.253102)
			(xy 345.378068 -231.241242) (xy 345.328454 -231.22177) (xy 345.282296 -231.195121) (xy 345.240625 -231.16189)
			(xy 345.204373 -231.122819) (xy 345.174349 -231.078782) (xy 345.151223 -231.030761) (xy 345.135513 -230.979831)
			(xy 345.12757 -230.927127) (xy 344.899244 -230.927127) (xy 344.891301 -230.979831) (xy 344.875591 -231.030761)
			(xy 344.852465 -231.078782) (xy 344.822441 -231.122819) (xy 344.786189 -231.16189) (xy 344.744518 -231.195121)
			(xy 344.69836 -231.22177) (xy 344.648746 -231.241242) (xy 344.596784 -231.253102) (xy 344.543634 -231.257086)
			(xy 344.490484 -231.253102) (xy 344.438522 -231.241242) (xy 344.388908 -231.22177) (xy 344.34275 -231.195121)
			(xy 344.301079 -231.16189) (xy 344.264827 -231.122819) (xy 344.234803 -231.078782) (xy 344.211677 -231.030761)
			(xy 344.195967 -230.979831) (xy 344.188024 -230.927127) (xy 343.959444 -230.927127) (xy 343.951501 -230.979831)
			(xy 343.935791 -231.030761) (xy 343.912665 -231.078782) (xy 343.882641 -231.122819) (xy 343.846389 -231.16189)
			(xy 343.804718 -231.195121) (xy 343.75856 -231.22177) (xy 343.708946 -231.241242) (xy 343.656984 -231.253102)
			(xy 343.603834 -231.257086) (xy 343.550684 -231.253102) (xy 343.498722 -231.241242) (xy 343.449108 -231.22177)
			(xy 343.40295 -231.195121) (xy 343.361279 -231.16189) (xy 343.325027 -231.122819) (xy 343.295003 -231.078782)
			(xy 343.271877 -231.030761) (xy 343.256167 -230.979831) (xy 343.248224 -230.927127) (xy 343.019644 -230.927127)
			(xy 343.011701 -230.979831) (xy 342.995991 -231.030761) (xy 342.972865 -231.078782) (xy 342.942841 -231.122819)
			(xy 342.906589 -231.16189) (xy 342.864918 -231.195121) (xy 342.81876 -231.22177) (xy 342.769146 -231.241242)
			(xy 342.717184 -231.253102) (xy 342.664034 -231.257086) (xy 342.610884 -231.253102) (xy 342.558922 -231.241242)
			(xy 342.509308 -231.22177) (xy 342.46315 -231.195121) (xy 342.421479 -231.16189) (xy 342.385227 -231.122819)
			(xy 342.355203 -231.078782) (xy 342.332077 -231.030761) (xy 342.316367 -230.979831) (xy 342.308424 -230.927127)
			(xy 342.079844 -230.927127) (xy 342.071901 -230.979831) (xy 342.056191 -231.030761) (xy 342.033065 -231.078782)
			(xy 342.003041 -231.122819) (xy 341.966789 -231.16189) (xy 341.925118 -231.195121) (xy 341.87896 -231.22177)
			(xy 341.829346 -231.241242) (xy 341.777384 -231.253102) (xy 341.724234 -231.257086) (xy 341.671084 -231.253102)
			(xy 341.619122 -231.241242) (xy 341.569508 -231.22177) (xy 341.52335 -231.195121) (xy 341.481679 -231.16189)
			(xy 341.445427 -231.122819) (xy 341.415403 -231.078782) (xy 341.392277 -231.030761) (xy 341.376567 -230.979831)
			(xy 341.368624 -230.927127) (xy 341.140044 -230.927127) (xy 341.132101 -230.979831) (xy 341.116391 -231.030761)
			(xy 341.093265 -231.078782) (xy 341.063241 -231.122819) (xy 341.026989 -231.16189) (xy 340.985318 -231.195121)
			(xy 340.93916 -231.22177) (xy 340.889546 -231.241242) (xy 340.837584 -231.253102) (xy 340.784434 -231.257086)
			(xy 340.731284 -231.253102) (xy 340.679322 -231.241242) (xy 340.629708 -231.22177) (xy 340.58355 -231.195121)
			(xy 340.541879 -231.16189) (xy 340.505627 -231.122819) (xy 340.475603 -231.078782) (xy 340.452477 -231.030761)
			(xy 340.436767 -230.979831) (xy 340.428824 -230.927127) (xy 340.200244 -230.927127) (xy 340.192301 -230.979831)
			(xy 340.176591 -231.030761) (xy 340.153465 -231.078782) (xy 340.123441 -231.122819) (xy 340.087189 -231.16189)
			(xy 340.045518 -231.195121) (xy 339.99936 -231.22177) (xy 339.949746 -231.241242) (xy 339.897784 -231.253102)
			(xy 339.844634 -231.257086) (xy 339.791484 -231.253102) (xy 339.739522 -231.241242) (xy 339.689908 -231.22177)
			(xy 339.64375 -231.195121) (xy 339.602079 -231.16189) (xy 339.565827 -231.122819) (xy 339.535803 -231.078782)
			(xy 339.512677 -231.030761) (xy 339.496967 -230.979831) (xy 339.489024 -230.927127) (xy 339.26019 -230.927127)
			(xy 339.252247 -230.979831) (xy 339.236537 -231.030761) (xy 339.213411 -231.078782) (xy 339.183387 -231.122819)
			(xy 339.147135 -231.16189) (xy 339.105464 -231.195121) (xy 339.059306 -231.22177) (xy 339.009692 -231.241242)
			(xy 338.95773 -231.253102) (xy 338.90458 -231.257086) (xy 338.85143 -231.253102) (xy 338.799468 -231.241242)
			(xy 338.749854 -231.22177) (xy 338.703696 -231.195121) (xy 338.662025 -231.16189) (xy 338.625773 -231.122819)
			(xy 338.595749 -231.078782) (xy 338.572623 -231.030761) (xy 338.556913 -230.979831) (xy 338.54897 -230.927127)
			(xy 338.320644 -230.927127) (xy 338.312701 -230.979831) (xy 338.296991 -231.030761) (xy 338.273865 -231.078782)
			(xy 338.243841 -231.122819) (xy 338.207589 -231.16189) (xy 338.165918 -231.195121) (xy 338.11976 -231.22177)
			(xy 338.070146 -231.241242) (xy 338.018184 -231.253102) (xy 337.965034 -231.257086) (xy 337.911884 -231.253102)
			(xy 337.859922 -231.241242) (xy 337.810308 -231.22177) (xy 337.76415 -231.195121) (xy 337.722479 -231.16189)
			(xy 337.686227 -231.122819) (xy 337.656203 -231.078782) (xy 337.633077 -231.030761) (xy 337.617367 -230.979831)
			(xy 337.609424 -230.927127) (xy 337.379835 -230.927127) (xy 337.377847 -230.95365) (xy 337.365987 -231.005612)
			(xy 337.346516 -231.055227) (xy 337.319868 -231.101386) (xy 337.286639 -231.143058) (xy 337.24757 -231.179312)
			(xy 337.203534 -231.209339) (xy 337.155516 -231.232468) (xy 337.104586 -231.248182) (xy 337.051883 -231.25613)
			(xy 337.025234 -231.256586) (xy 337.000538 -231.256187) (xy 336.951616 -231.249403) (xy 336.904102 -231.23592)
			(xy 336.858908 -231.215995) (xy 336.816904 -231.190013) (xy 336.79765 -231.174544) (xy 336.786265 -231.165765)
			(xy 336.759897 -231.154342) (xy 336.73139 -231.150719) (xy 336.703002 -231.155183) (xy 336.676983 -231.167382)
			(xy 336.655395 -231.186348) (xy 336.639947 -231.210579) (xy 336.631863 -231.238155) (xy 336.63128 -231.252522)
			(xy 336.63128 -231.36479) (xy 336.666332 -231.37622) (xy 336.691134 -231.384869) (xy 336.73808 -231.408428)
			(xy 336.781056 -231.438628) (xy 336.81913 -231.474813) (xy 336.851475 -231.516198) (xy 336.87739 -231.561886)
			(xy 336.896312 -231.610885) (xy 336.907831 -231.662132) (xy 336.911698 -231.714515) (xy 336.909726 -231.741197)
			(xy 337.13927 -231.741197) (xy 337.13927 -231.687899) (xy 337.147213 -231.635195) (xy 337.162923 -231.584265)
			(xy 337.186049 -231.536244) (xy 337.216073 -231.492207) (xy 337.252325 -231.453136) (xy 337.293996 -231.419905)
			(xy 337.340154 -231.393256) (xy 337.389768 -231.373784) (xy 337.44173 -231.361924) (xy 337.49488 -231.357941)
			(xy 337.54803 -231.361924) (xy 337.599992 -231.373784) (xy 337.649606 -231.393256) (xy 337.695764 -231.419905)
			(xy 337.737435 -231.453136) (xy 337.773687 -231.492207) (xy 337.803711 -231.536244) (xy 337.826837 -231.584265)
			(xy 337.842547 -231.635195) (xy 337.85049 -231.687899) (xy 337.850988 -231.714548) (xy 337.85049 -231.741197)
			(xy 338.07907 -231.741197) (xy 338.07907 -231.687899) (xy 338.087013 -231.635195) (xy 338.102723 -231.584265)
			(xy 338.125849 -231.536244) (xy 338.155873 -231.492207) (xy 338.192125 -231.453136) (xy 338.233796 -231.419905)
			(xy 338.279954 -231.393256) (xy 338.329568 -231.373784) (xy 338.38153 -231.361924) (xy 338.43468 -231.357941)
			(xy 338.48783 -231.361924) (xy 338.539792 -231.373784) (xy 338.589406 -231.393256) (xy 338.635564 -231.419905)
			(xy 338.677235 -231.453136) (xy 338.713487 -231.492207) (xy 338.743511 -231.536244) (xy 338.766637 -231.584265)
			(xy 338.782347 -231.635195) (xy 338.79029 -231.687899) (xy 338.790788 -231.714548) (xy 338.79029 -231.741197)
			(xy 339.01887 -231.741197) (xy 339.01887 -231.687899) (xy 339.026813 -231.635195) (xy 339.042523 -231.584265)
			(xy 339.065649 -231.536244) (xy 339.095673 -231.492207) (xy 339.131925 -231.453136) (xy 339.173596 -231.419905)
			(xy 339.219754 -231.393256) (xy 339.269368 -231.373784) (xy 339.32133 -231.361924) (xy 339.37448 -231.357941)
			(xy 339.42763 -231.361924) (xy 339.479592 -231.373784) (xy 339.529206 -231.393256) (xy 339.575364 -231.419905)
			(xy 339.617035 -231.453136) (xy 339.653287 -231.492207) (xy 339.683311 -231.536244) (xy 339.706437 -231.584265)
			(xy 339.722147 -231.635195) (xy 339.73009 -231.687899) (xy 339.730588 -231.714548) (xy 339.73009 -231.741197)
			(xy 339.95867 -231.741197) (xy 339.95867 -231.687899) (xy 339.966613 -231.635195) (xy 339.982323 -231.584265)
			(xy 340.005449 -231.536244) (xy 340.035473 -231.492207) (xy 340.071725 -231.453136) (xy 340.113396 -231.419905)
			(xy 340.159554 -231.393256) (xy 340.209168 -231.373784) (xy 340.26113 -231.361924) (xy 340.31428 -231.357941)
			(xy 340.36743 -231.361924) (xy 340.419392 -231.373784) (xy 340.469006 -231.393256) (xy 340.515164 -231.419905)
			(xy 340.556835 -231.453136) (xy 340.593087 -231.492207) (xy 340.623111 -231.536244) (xy 340.646237 -231.584265)
			(xy 340.661947 -231.635195) (xy 340.66989 -231.687899) (xy 340.670388 -231.714548) (xy 340.66989 -231.741197)
			(xy 340.89847 -231.741197) (xy 340.89847 -231.687899) (xy 340.906413 -231.635195) (xy 340.922123 -231.584265)
			(xy 340.945249 -231.536244) (xy 340.975273 -231.492207) (xy 341.011525 -231.453136) (xy 341.053196 -231.419905)
			(xy 341.099354 -231.393256) (xy 341.148968 -231.373784) (xy 341.20093 -231.361924) (xy 341.25408 -231.357941)
			(xy 341.30723 -231.361924) (xy 341.359192 -231.373784) (xy 341.408806 -231.393256) (xy 341.454964 -231.419905)
			(xy 341.496635 -231.453136) (xy 341.532887 -231.492207) (xy 341.562911 -231.536244) (xy 341.586037 -231.584265)
			(xy 341.601747 -231.635195) (xy 341.60969 -231.687899) (xy 341.610188 -231.714548) (xy 341.60969 -231.741197)
			(xy 341.838524 -231.741197) (xy 341.838524 -231.687899) (xy 341.846467 -231.635195) (xy 341.862177 -231.584265)
			(xy 341.885303 -231.536244) (xy 341.915327 -231.492207) (xy 341.951579 -231.453136) (xy 341.99325 -231.419905)
			(xy 342.039408 -231.393256) (xy 342.089022 -231.373784) (xy 342.140984 -231.361924) (xy 342.194134 -231.357941)
			(xy 342.247284 -231.361924) (xy 342.299246 -231.373784) (xy 342.34886 -231.393256) (xy 342.395018 -231.419905)
			(xy 342.436689 -231.453136) (xy 342.472941 -231.492207) (xy 342.502965 -231.536244) (xy 342.526091 -231.584265)
			(xy 342.541801 -231.635195) (xy 342.549744 -231.687899) (xy 342.550242 -231.714548) (xy 342.549744 -231.741197)
			(xy 342.77807 -231.741197) (xy 342.77807 -231.687899) (xy 342.786013 -231.635195) (xy 342.801723 -231.584265)
			(xy 342.824849 -231.536244) (xy 342.854873 -231.492207) (xy 342.891125 -231.453136) (xy 342.932796 -231.419905)
			(xy 342.978954 -231.393256) (xy 343.028568 -231.373784) (xy 343.08053 -231.361924) (xy 343.13368 -231.357941)
			(xy 343.18683 -231.361924) (xy 343.238792 -231.373784) (xy 343.288406 -231.393256) (xy 343.334564 -231.419905)
			(xy 343.376235 -231.453136) (xy 343.412487 -231.492207) (xy 343.442511 -231.536244) (xy 343.465637 -231.584265)
			(xy 343.481347 -231.635195) (xy 343.48929 -231.687899) (xy 343.489788 -231.714548) (xy 343.48929 -231.741197)
			(xy 343.71787 -231.741197) (xy 343.71787 -231.687899) (xy 343.725813 -231.635195) (xy 343.741523 -231.584265)
			(xy 343.764649 -231.536244) (xy 343.794673 -231.492207) (xy 343.830925 -231.453136) (xy 343.872596 -231.419905)
			(xy 343.918754 -231.393256) (xy 343.968368 -231.373784) (xy 344.02033 -231.361924) (xy 344.07348 -231.357941)
			(xy 344.12663 -231.361924) (xy 344.178592 -231.373784) (xy 344.228206 -231.393256) (xy 344.274364 -231.419905)
			(xy 344.316035 -231.453136) (xy 344.352287 -231.492207) (xy 344.382311 -231.536244) (xy 344.405437 -231.584265)
			(xy 344.421147 -231.635195) (xy 344.42909 -231.687899) (xy 344.429588 -231.714548) (xy 344.42909 -231.741197)
			(xy 344.65767 -231.741197) (xy 344.65767 -231.687899) (xy 344.665613 -231.635195) (xy 344.681323 -231.584265)
			(xy 344.704449 -231.536244) (xy 344.734473 -231.492207) (xy 344.770725 -231.453136) (xy 344.812396 -231.419905)
			(xy 344.858554 -231.393256) (xy 344.908168 -231.373784) (xy 344.96013 -231.361924) (xy 345.01328 -231.357941)
			(xy 345.06643 -231.361924) (xy 345.118392 -231.373784) (xy 345.168006 -231.393256) (xy 345.214164 -231.419905)
			(xy 345.255835 -231.453136) (xy 345.292087 -231.492207) (xy 345.322111 -231.536244) (xy 345.345237 -231.584265)
			(xy 345.360947 -231.635195) (xy 345.36889 -231.687899) (xy 345.369388 -231.714548) (xy 345.36889 -231.741197)
			(xy 345.59747 -231.741197) (xy 345.59747 -231.687899) (xy 345.605413 -231.635195) (xy 345.621123 -231.584265)
			(xy 345.644249 -231.536244) (xy 345.674273 -231.492207) (xy 345.710525 -231.453136) (xy 345.752196 -231.419905)
			(xy 345.798354 -231.393256) (xy 345.847968 -231.373784) (xy 345.89993 -231.361924) (xy 345.95308 -231.357941)
			(xy 346.00623 -231.361924) (xy 346.058192 -231.373784) (xy 346.107806 -231.393256) (xy 346.153964 -231.419905)
			(xy 346.195635 -231.453136) (xy 346.231887 -231.492207) (xy 346.261911 -231.536244) (xy 346.285037 -231.584265)
			(xy 346.300747 -231.635195) (xy 346.30869 -231.687899) (xy 346.309188 -231.714548) (xy 346.30869 -231.741197)
			(xy 346.53727 -231.741197) (xy 346.53727 -231.687899) (xy 346.545213 -231.635195) (xy 346.560923 -231.584265)
			(xy 346.584049 -231.536244) (xy 346.614073 -231.492207) (xy 346.650325 -231.453136) (xy 346.691996 -231.419905)
			(xy 346.738154 -231.393256) (xy 346.787768 -231.373784) (xy 346.83973 -231.361924) (xy 346.89288 -231.357941)
			(xy 346.94603 -231.361924) (xy 346.997992 -231.373784) (xy 347.047606 -231.393256) (xy 347.093764 -231.419905)
			(xy 347.135435 -231.453136) (xy 347.171687 -231.492207) (xy 347.201711 -231.536244) (xy 347.224837 -231.584265)
			(xy 347.240547 -231.635195) (xy 347.24849 -231.687899) (xy 347.248988 -231.714548) (xy 347.24849 -231.741197)
			(xy 347.47707 -231.741197) (xy 347.47707 -231.687899) (xy 347.485013 -231.635195) (xy 347.500723 -231.584265)
			(xy 347.523849 -231.536244) (xy 347.553873 -231.492207) (xy 347.590125 -231.453136) (xy 347.631796 -231.419905)
			(xy 347.677954 -231.393256) (xy 347.727568 -231.373784) (xy 347.77953 -231.361924) (xy 347.83268 -231.357941)
			(xy 347.88583 -231.361924) (xy 347.937792 -231.373784) (xy 347.987406 -231.393256) (xy 348.033564 -231.419905)
			(xy 348.075235 -231.453136) (xy 348.111487 -231.492207) (xy 348.141511 -231.536244) (xy 348.164637 -231.584265)
			(xy 348.180347 -231.635195) (xy 348.18829 -231.687899) (xy 348.188788 -231.714548) (xy 348.18829 -231.741197)
			(xy 348.417124 -231.741197) (xy 348.417124 -231.687899) (xy 348.425067 -231.635195) (xy 348.440777 -231.584265)
			(xy 348.463903 -231.536244) (xy 348.493927 -231.492207) (xy 348.530179 -231.453136) (xy 348.57185 -231.419905)
			(xy 348.618008 -231.393256) (xy 348.667622 -231.373784) (xy 348.719584 -231.361924) (xy 348.772734 -231.357941)
			(xy 348.825884 -231.361924) (xy 348.877846 -231.373784) (xy 348.92746 -231.393256) (xy 348.973618 -231.419905)
			(xy 349.015289 -231.453136) (xy 349.051541 -231.492207) (xy 349.081565 -231.536244) (xy 349.104691 -231.584265)
			(xy 349.120401 -231.635195) (xy 349.128344 -231.687899) (xy 349.128842 -231.714548) (xy 349.128344 -231.741197)
			(xy 349.35667 -231.741197) (xy 349.35667 -231.687899) (xy 349.364613 -231.635195) (xy 349.380323 -231.584265)
			(xy 349.403449 -231.536244) (xy 349.433473 -231.492207) (xy 349.469725 -231.453136) (xy 349.511396 -231.419905)
			(xy 349.557554 -231.393256) (xy 349.607168 -231.373784) (xy 349.65913 -231.361924) (xy 349.71228 -231.357941)
			(xy 349.76543 -231.361924) (xy 349.817392 -231.373784) (xy 349.867006 -231.393256) (xy 349.913164 -231.419905)
			(xy 349.954835 -231.453136) (xy 349.991087 -231.492207) (xy 350.021111 -231.536244) (xy 350.044237 -231.584265)
			(xy 350.059947 -231.635195) (xy 350.06789 -231.687899) (xy 350.068388 -231.714548) (xy 350.06789 -231.741197)
			(xy 350.29647 -231.741197) (xy 350.29647 -231.687899) (xy 350.304413 -231.635195) (xy 350.320123 -231.584265)
			(xy 350.343249 -231.536244) (xy 350.373273 -231.492207) (xy 350.409525 -231.453136) (xy 350.451196 -231.419905)
			(xy 350.497354 -231.393256) (xy 350.546968 -231.373784) (xy 350.59893 -231.361924) (xy 350.65208 -231.357941)
			(xy 350.70523 -231.361924) (xy 350.757192 -231.373784) (xy 350.806806 -231.393256) (xy 350.852964 -231.419905)
			(xy 350.894635 -231.453136) (xy 350.930887 -231.492207) (xy 350.960911 -231.536244) (xy 350.984037 -231.584265)
			(xy 350.999747 -231.635195) (xy 351.00769 -231.687899) (xy 351.008188 -231.714548) (xy 351.00769 -231.741197)
			(xy 351.23627 -231.741197) (xy 351.23627 -231.687899) (xy 351.244213 -231.635195) (xy 351.259923 -231.584265)
			(xy 351.283049 -231.536244) (xy 351.313073 -231.492207) (xy 351.349325 -231.453136) (xy 351.390996 -231.419905)
			(xy 351.437154 -231.393256) (xy 351.486768 -231.373784) (xy 351.53873 -231.361924) (xy 351.59188 -231.357941)
			(xy 351.64503 -231.361924) (xy 351.696992 -231.373784) (xy 351.746606 -231.393256) (xy 351.792764 -231.419905)
			(xy 351.834435 -231.453136) (xy 351.870687 -231.492207) (xy 351.900711 -231.536244) (xy 351.923837 -231.584265)
			(xy 351.939547 -231.635195) (xy 351.94749 -231.687899) (xy 351.947988 -231.714548) (xy 351.94749 -231.741197)
			(xy 352.17607 -231.741197) (xy 352.17607 -231.687899) (xy 352.184013 -231.635195) (xy 352.199723 -231.584265)
			(xy 352.222849 -231.536244) (xy 352.252873 -231.492207) (xy 352.289125 -231.453136) (xy 352.330796 -231.419905)
			(xy 352.376954 -231.393256) (xy 352.426568 -231.373784) (xy 352.47853 -231.361924) (xy 352.53168 -231.357941)
			(xy 352.58483 -231.361924) (xy 352.636792 -231.373784) (xy 352.686406 -231.393256) (xy 352.732564 -231.419905)
			(xy 352.774235 -231.453136) (xy 352.810487 -231.492207) (xy 352.840511 -231.536244) (xy 352.863637 -231.584265)
			(xy 352.879347 -231.635195) (xy 352.88729 -231.687899) (xy 352.887788 -231.714548) (xy 352.88729 -231.741197)
			(xy 353.11587 -231.741197) (xy 353.11587 -231.687899) (xy 353.123813 -231.635195) (xy 353.139523 -231.584265)
			(xy 353.162649 -231.536244) (xy 353.192673 -231.492207) (xy 353.228925 -231.453136) (xy 353.270596 -231.419905)
			(xy 353.316754 -231.393256) (xy 353.366368 -231.373784) (xy 353.41833 -231.361924) (xy 353.47148 -231.357941)
			(xy 353.52463 -231.361924) (xy 353.576592 -231.373784) (xy 353.626206 -231.393256) (xy 353.672364 -231.419905)
			(xy 353.714035 -231.453136) (xy 353.750287 -231.492207) (xy 353.780311 -231.536244) (xy 353.803437 -231.584265)
			(xy 353.819147 -231.635195) (xy 353.82709 -231.687899) (xy 353.827588 -231.714548) (xy 353.82709 -231.741197)
			(xy 354.05567 -231.741197) (xy 354.05567 -231.687899) (xy 354.063613 -231.635195) (xy 354.079323 -231.584265)
			(xy 354.102449 -231.536244) (xy 354.132473 -231.492207) (xy 354.168725 -231.453136) (xy 354.210396 -231.419905)
			(xy 354.256554 -231.393256) (xy 354.306168 -231.373784) (xy 354.35813 -231.361924) (xy 354.41128 -231.357941)
			(xy 354.46443 -231.361924) (xy 354.516392 -231.373784) (xy 354.566006 -231.393256) (xy 354.612164 -231.419905)
			(xy 354.653835 -231.453136) (xy 354.690087 -231.492207) (xy 354.720111 -231.536244) (xy 354.743237 -231.584265)
			(xy 354.758947 -231.635195) (xy 354.76689 -231.687899) (xy 354.767388 -231.714548) (xy 354.76689 -231.741197)
			(xy 354.99547 -231.741197) (xy 354.99547 -231.687899) (xy 355.003413 -231.635195) (xy 355.019123 -231.584265)
			(xy 355.042249 -231.536244) (xy 355.072273 -231.492207) (xy 355.108525 -231.453136) (xy 355.150196 -231.419905)
			(xy 355.196354 -231.393256) (xy 355.245968 -231.373784) (xy 355.29793 -231.361924) (xy 355.35108 -231.357941)
			(xy 355.40423 -231.361924) (xy 355.456192 -231.373784) (xy 355.505806 -231.393256) (xy 355.551964 -231.419905)
			(xy 355.593635 -231.453136) (xy 355.629887 -231.492207) (xy 355.659911 -231.536244) (xy 355.683037 -231.584265)
			(xy 355.698747 -231.635195) (xy 355.70669 -231.687899) (xy 355.707188 -231.714548) (xy 355.70669 -231.741197)
			(xy 355.93527 -231.741197) (xy 355.93527 -231.687899) (xy 355.943213 -231.635195) (xy 355.958923 -231.584265)
			(xy 355.982049 -231.536244) (xy 356.012073 -231.492207) (xy 356.048325 -231.453136) (xy 356.089996 -231.419905)
			(xy 356.136154 -231.393256) (xy 356.185768 -231.373784) (xy 356.23773 -231.361924) (xy 356.29088 -231.357941)
			(xy 356.34403 -231.361924) (xy 356.395992 -231.373784) (xy 356.445606 -231.393256) (xy 356.491764 -231.419905)
			(xy 356.533435 -231.453136) (xy 356.569687 -231.492207) (xy 356.599711 -231.536244) (xy 356.622837 -231.584265)
			(xy 356.638547 -231.635195) (xy 356.64649 -231.687899) (xy 356.646988 -231.714548) (xy 356.64649 -231.741197)
			(xy 356.87507 -231.741197) (xy 356.87507 -231.687899) (xy 356.883013 -231.635195) (xy 356.898723 -231.584265)
			(xy 356.921849 -231.536244) (xy 356.951873 -231.492207) (xy 356.988125 -231.453136) (xy 357.029796 -231.419905)
			(xy 357.075954 -231.393256) (xy 357.125568 -231.373784) (xy 357.17753 -231.361924) (xy 357.23068 -231.357941)
			(xy 357.28383 -231.361924) (xy 357.335792 -231.373784) (xy 357.385406 -231.393256) (xy 357.431564 -231.419905)
			(xy 357.473235 -231.453136) (xy 357.509487 -231.492207) (xy 357.539511 -231.536244) (xy 357.562637 -231.584265)
			(xy 357.578347 -231.635195) (xy 357.58629 -231.687899) (xy 357.586788 -231.714548) (xy 357.58629 -231.741197)
			(xy 357.578347 -231.793901) (xy 357.562637 -231.844831) (xy 357.539511 -231.892852) (xy 357.509487 -231.936889)
			(xy 357.473235 -231.97596) (xy 357.431564 -232.009191) (xy 357.385406 -232.03584) (xy 357.335792 -232.055312)
			(xy 357.28383 -232.067172) (xy 357.23068 -232.071156) (xy 357.17753 -232.067172) (xy 357.125568 -232.055312)
			(xy 357.075954 -232.03584) (xy 357.029796 -232.009191) (xy 356.988125 -231.97596) (xy 356.951873 -231.936889)
			(xy 356.921849 -231.892852) (xy 356.898723 -231.844831) (xy 356.883013 -231.793901) (xy 356.87507 -231.741197)
			(xy 356.64649 -231.741197) (xy 356.638547 -231.793901) (xy 356.622837 -231.844831) (xy 356.599711 -231.892852)
			(xy 356.569687 -231.936889) (xy 356.533435 -231.97596) (xy 356.491764 -232.009191) (xy 356.445606 -232.03584)
			(xy 356.395992 -232.055312) (xy 356.34403 -232.067172) (xy 356.29088 -232.071156) (xy 356.23773 -232.067172)
			(xy 356.185768 -232.055312) (xy 356.136154 -232.03584) (xy 356.089996 -232.009191) (xy 356.048325 -231.97596)
			(xy 356.012073 -231.936889) (xy 355.982049 -231.892852) (xy 355.958923 -231.844831) (xy 355.943213 -231.793901)
			(xy 355.93527 -231.741197) (xy 355.70669 -231.741197) (xy 355.698747 -231.793901) (xy 355.683037 -231.844831)
			(xy 355.659911 -231.892852) (xy 355.629887 -231.936889) (xy 355.593635 -231.97596) (xy 355.551964 -232.009191)
			(xy 355.505806 -232.03584) (xy 355.456192 -232.055312) (xy 355.40423 -232.067172) (xy 355.35108 -232.071156)
			(xy 355.29793 -232.067172) (xy 355.245968 -232.055312) (xy 355.196354 -232.03584) (xy 355.150196 -232.009191)
			(xy 355.108525 -231.97596) (xy 355.072273 -231.936889) (xy 355.042249 -231.892852) (xy 355.019123 -231.844831)
			(xy 355.003413 -231.793901) (xy 354.99547 -231.741197) (xy 354.76689 -231.741197) (xy 354.758947 -231.793901)
			(xy 354.743237 -231.844831) (xy 354.720111 -231.892852) (xy 354.690087 -231.936889) (xy 354.653835 -231.97596)
			(xy 354.612164 -232.009191) (xy 354.566006 -232.03584) (xy 354.516392 -232.055312) (xy 354.46443 -232.067172)
			(xy 354.41128 -232.071156) (xy 354.35813 -232.067172) (xy 354.306168 -232.055312) (xy 354.256554 -232.03584)
			(xy 354.210396 -232.009191) (xy 354.168725 -231.97596) (xy 354.132473 -231.936889) (xy 354.102449 -231.892852)
			(xy 354.079323 -231.844831) (xy 354.063613 -231.793901) (xy 354.05567 -231.741197) (xy 353.82709 -231.741197)
			(xy 353.819147 -231.793901) (xy 353.803437 -231.844831) (xy 353.780311 -231.892852) (xy 353.750287 -231.936889)
			(xy 353.714035 -231.97596) (xy 353.672364 -232.009191) (xy 353.626206 -232.03584) (xy 353.576592 -232.055312)
			(xy 353.52463 -232.067172) (xy 353.47148 -232.071156) (xy 353.41833 -232.067172) (xy 353.366368 -232.055312)
			(xy 353.316754 -232.03584) (xy 353.270596 -232.009191) (xy 353.228925 -231.97596) (xy 353.192673 -231.936889)
			(xy 353.162649 -231.892852) (xy 353.139523 -231.844831) (xy 353.123813 -231.793901) (xy 353.11587 -231.741197)
			(xy 352.88729 -231.741197) (xy 352.879347 -231.793901) (xy 352.863637 -231.844831) (xy 352.840511 -231.892852)
			(xy 352.810487 -231.936889) (xy 352.774235 -231.97596) (xy 352.732564 -232.009191) (xy 352.686406 -232.03584)
			(xy 352.636792 -232.055312) (xy 352.58483 -232.067172) (xy 352.53168 -232.071156) (xy 352.47853 -232.067172)
			(xy 352.426568 -232.055312) (xy 352.376954 -232.03584) (xy 352.330796 -232.009191) (xy 352.289125 -231.97596)
			(xy 352.252873 -231.936889) (xy 352.222849 -231.892852) (xy 352.199723 -231.844831) (xy 352.184013 -231.793901)
			(xy 352.17607 -231.741197) (xy 351.94749 -231.741197) (xy 351.939547 -231.793901) (xy 351.923837 -231.844831)
			(xy 351.900711 -231.892852) (xy 351.870687 -231.936889) (xy 351.834435 -231.97596) (xy 351.792764 -232.009191)
			(xy 351.746606 -232.03584) (xy 351.696992 -232.055312) (xy 351.64503 -232.067172) (xy 351.59188 -232.071156)
			(xy 351.53873 -232.067172) (xy 351.486768 -232.055312) (xy 351.437154 -232.03584) (xy 351.390996 -232.009191)
			(xy 351.349325 -231.97596) (xy 351.313073 -231.936889) (xy 351.283049 -231.892852) (xy 351.259923 -231.844831)
			(xy 351.244213 -231.793901) (xy 351.23627 -231.741197) (xy 351.00769 -231.741197) (xy 350.999747 -231.793901)
			(xy 350.984037 -231.844831) (xy 350.960911 -231.892852) (xy 350.930887 -231.936889) (xy 350.894635 -231.97596)
			(xy 350.852964 -232.009191) (xy 350.806806 -232.03584) (xy 350.757192 -232.055312) (xy 350.70523 -232.067172)
			(xy 350.65208 -232.071156) (xy 350.59893 -232.067172) (xy 350.546968 -232.055312) (xy 350.497354 -232.03584)
			(xy 350.451196 -232.009191) (xy 350.409525 -231.97596) (xy 350.373273 -231.936889) (xy 350.343249 -231.892852)
			(xy 350.320123 -231.844831) (xy 350.304413 -231.793901) (xy 350.29647 -231.741197) (xy 350.06789 -231.741197)
			(xy 350.059947 -231.793901) (xy 350.044237 -231.844831) (xy 350.021111 -231.892852) (xy 349.991087 -231.936889)
			(xy 349.954835 -231.97596) (xy 349.913164 -232.009191) (xy 349.867006 -232.03584) (xy 349.817392 -232.055312)
			(xy 349.76543 -232.067172) (xy 349.71228 -232.071156) (xy 349.65913 -232.067172) (xy 349.607168 -232.055312)
			(xy 349.557554 -232.03584) (xy 349.511396 -232.009191) (xy 349.469725 -231.97596) (xy 349.433473 -231.936889)
			(xy 349.403449 -231.892852) (xy 349.380323 -231.844831) (xy 349.364613 -231.793901) (xy 349.35667 -231.741197)
			(xy 349.128344 -231.741197) (xy 349.120401 -231.793901) (xy 349.104691 -231.844831) (xy 349.081565 -231.892852)
			(xy 349.051541 -231.936889) (xy 349.015289 -231.97596) (xy 348.973618 -232.009191) (xy 348.92746 -232.03584)
			(xy 348.877846 -232.055312) (xy 348.825884 -232.067172) (xy 348.772734 -232.071156) (xy 348.719584 -232.067172)
			(xy 348.667622 -232.055312) (xy 348.618008 -232.03584) (xy 348.57185 -232.009191) (xy 348.530179 -231.97596)
			(xy 348.493927 -231.936889) (xy 348.463903 -231.892852) (xy 348.440777 -231.844831) (xy 348.425067 -231.793901)
			(xy 348.417124 -231.741197) (xy 348.18829 -231.741197) (xy 348.180347 -231.793901) (xy 348.164637 -231.844831)
			(xy 348.141511 -231.892852) (xy 348.111487 -231.936889) (xy 348.075235 -231.97596) (xy 348.033564 -232.009191)
			(xy 347.987406 -232.03584) (xy 347.937792 -232.055312) (xy 347.88583 -232.067172) (xy 347.83268 -232.071156)
			(xy 347.77953 -232.067172) (xy 347.727568 -232.055312) (xy 347.677954 -232.03584) (xy 347.631796 -232.009191)
			(xy 347.590125 -231.97596) (xy 347.553873 -231.936889) (xy 347.523849 -231.892852) (xy 347.500723 -231.844831)
			(xy 347.485013 -231.793901) (xy 347.47707 -231.741197) (xy 347.24849 -231.741197) (xy 347.240547 -231.793901)
			(xy 347.224837 -231.844831) (xy 347.201711 -231.892852) (xy 347.171687 -231.936889) (xy 347.135435 -231.97596)
			(xy 347.093764 -232.009191) (xy 347.047606 -232.03584) (xy 346.997992 -232.055312) (xy 346.94603 -232.067172)
			(xy 346.89288 -232.071156) (xy 346.83973 -232.067172) (xy 346.787768 -232.055312) (xy 346.738154 -232.03584)
			(xy 346.691996 -232.009191) (xy 346.650325 -231.97596) (xy 346.614073 -231.936889) (xy 346.584049 -231.892852)
			(xy 346.560923 -231.844831) (xy 346.545213 -231.793901) (xy 346.53727 -231.741197) (xy 346.30869 -231.741197)
			(xy 346.300747 -231.793901) (xy 346.285037 -231.844831) (xy 346.261911 -231.892852) (xy 346.231887 -231.936889)
			(xy 346.195635 -231.97596) (xy 346.153964 -232.009191) (xy 346.107806 -232.03584) (xy 346.058192 -232.055312)
			(xy 346.00623 -232.067172) (xy 345.95308 -232.071156) (xy 345.89993 -232.067172) (xy 345.847968 -232.055312)
			(xy 345.798354 -232.03584) (xy 345.752196 -232.009191) (xy 345.710525 -231.97596) (xy 345.674273 -231.936889)
			(xy 345.644249 -231.892852) (xy 345.621123 -231.844831) (xy 345.605413 -231.793901) (xy 345.59747 -231.741197)
			(xy 345.36889 -231.741197) (xy 345.360947 -231.793901) (xy 345.345237 -231.844831) (xy 345.322111 -231.892852)
			(xy 345.292087 -231.936889) (xy 345.255835 -231.97596) (xy 345.214164 -232.009191) (xy 345.168006 -232.03584)
			(xy 345.118392 -232.055312) (xy 345.06643 -232.067172) (xy 345.01328 -232.071156) (xy 344.96013 -232.067172)
			(xy 344.908168 -232.055312) (xy 344.858554 -232.03584) (xy 344.812396 -232.009191) (xy 344.770725 -231.97596)
			(xy 344.734473 -231.936889) (xy 344.704449 -231.892852) (xy 344.681323 -231.844831) (xy 344.665613 -231.793901)
			(xy 344.65767 -231.741197) (xy 344.42909 -231.741197) (xy 344.421147 -231.793901) (xy 344.405437 -231.844831)
			(xy 344.382311 -231.892852) (xy 344.352287 -231.936889) (xy 344.316035 -231.97596) (xy 344.274364 -232.009191)
			(xy 344.228206 -232.03584) (xy 344.178592 -232.055312) (xy 344.12663 -232.067172) (xy 344.07348 -232.071156)
			(xy 344.02033 -232.067172) (xy 343.968368 -232.055312) (xy 343.918754 -232.03584) (xy 343.872596 -232.009191)
			(xy 343.830925 -231.97596) (xy 343.794673 -231.936889) (xy 343.764649 -231.892852) (xy 343.741523 -231.844831)
			(xy 343.725813 -231.793901) (xy 343.71787 -231.741197) (xy 343.48929 -231.741197) (xy 343.481347 -231.793901)
			(xy 343.465637 -231.844831) (xy 343.442511 -231.892852) (xy 343.412487 -231.936889) (xy 343.376235 -231.97596)
			(xy 343.334564 -232.009191) (xy 343.288406 -232.03584) (xy 343.238792 -232.055312) (xy 343.18683 -232.067172)
			(xy 343.13368 -232.071156) (xy 343.08053 -232.067172) (xy 343.028568 -232.055312) (xy 342.978954 -232.03584)
			(xy 342.932796 -232.009191) (xy 342.891125 -231.97596) (xy 342.854873 -231.936889) (xy 342.824849 -231.892852)
			(xy 342.801723 -231.844831) (xy 342.786013 -231.793901) (xy 342.77807 -231.741197) (xy 342.549744 -231.741197)
			(xy 342.541801 -231.793901) (xy 342.526091 -231.844831) (xy 342.502965 -231.892852) (xy 342.472941 -231.936889)
			(xy 342.436689 -231.97596) (xy 342.395018 -232.009191) (xy 342.34886 -232.03584) (xy 342.299246 -232.055312)
			(xy 342.247284 -232.067172) (xy 342.194134 -232.071156) (xy 342.140984 -232.067172) (xy 342.089022 -232.055312)
			(xy 342.039408 -232.03584) (xy 341.99325 -232.009191) (xy 341.951579 -231.97596) (xy 341.915327 -231.936889)
			(xy 341.885303 -231.892852) (xy 341.862177 -231.844831) (xy 341.846467 -231.793901) (xy 341.838524 -231.741197)
			(xy 341.60969 -231.741197) (xy 341.601747 -231.793901) (xy 341.586037 -231.844831) (xy 341.562911 -231.892852)
			(xy 341.532887 -231.936889) (xy 341.496635 -231.97596) (xy 341.454964 -232.009191) (xy 341.408806 -232.03584)
			(xy 341.359192 -232.055312) (xy 341.30723 -232.067172) (xy 341.25408 -232.071156) (xy 341.20093 -232.067172)
			(xy 341.148968 -232.055312) (xy 341.099354 -232.03584) (xy 341.053196 -232.009191) (xy 341.011525 -231.97596)
			(xy 340.975273 -231.936889) (xy 340.945249 -231.892852) (xy 340.922123 -231.844831) (xy 340.906413 -231.793901)
			(xy 340.89847 -231.741197) (xy 340.66989 -231.741197) (xy 340.661947 -231.793901) (xy 340.646237 -231.844831)
			(xy 340.623111 -231.892852) (xy 340.593087 -231.936889) (xy 340.556835 -231.97596) (xy 340.515164 -232.009191)
			(xy 340.469006 -232.03584) (xy 340.419392 -232.055312) (xy 340.36743 -232.067172) (xy 340.31428 -232.071156)
			(xy 340.26113 -232.067172) (xy 340.209168 -232.055312) (xy 340.159554 -232.03584) (xy 340.113396 -232.009191)
			(xy 340.071725 -231.97596) (xy 340.035473 -231.936889) (xy 340.005449 -231.892852) (xy 339.982323 -231.844831)
			(xy 339.966613 -231.793901) (xy 339.95867 -231.741197) (xy 339.73009 -231.741197) (xy 339.722147 -231.793901)
			(xy 339.706437 -231.844831) (xy 339.683311 -231.892852) (xy 339.653287 -231.936889) (xy 339.617035 -231.97596)
			(xy 339.575364 -232.009191) (xy 339.529206 -232.03584) (xy 339.479592 -232.055312) (xy 339.42763 -232.067172)
			(xy 339.37448 -232.071156) (xy 339.32133 -232.067172) (xy 339.269368 -232.055312) (xy 339.219754 -232.03584)
			(xy 339.173596 -232.009191) (xy 339.131925 -231.97596) (xy 339.095673 -231.936889) (xy 339.065649 -231.892852)
			(xy 339.042523 -231.844831) (xy 339.026813 -231.793901) (xy 339.01887 -231.741197) (xy 338.79029 -231.741197)
			(xy 338.782347 -231.793901) (xy 338.766637 -231.844831) (xy 338.743511 -231.892852) (xy 338.713487 -231.936889)
			(xy 338.677235 -231.97596) (xy 338.635564 -232.009191) (xy 338.589406 -232.03584) (xy 338.539792 -232.055312)
			(xy 338.48783 -232.067172) (xy 338.43468 -232.071156) (xy 338.38153 -232.067172) (xy 338.329568 -232.055312)
			(xy 338.279954 -232.03584) (xy 338.233796 -232.009191) (xy 338.192125 -231.97596) (xy 338.155873 -231.936889)
			(xy 338.125849 -231.892852) (xy 338.102723 -231.844831) (xy 338.087013 -231.793901) (xy 338.07907 -231.741197)
			(xy 337.85049 -231.741197) (xy 337.842547 -231.793901) (xy 337.826837 -231.844831) (xy 337.803711 -231.892852)
			(xy 337.773687 -231.936889) (xy 337.737435 -231.97596) (xy 337.695764 -232.009191) (xy 337.649606 -232.03584)
			(xy 337.599992 -232.055312) (xy 337.54803 -232.067172) (xy 337.49488 -232.071156) (xy 337.44173 -232.067172)
			(xy 337.389768 -232.055312) (xy 337.340154 -232.03584) (xy 337.293996 -232.009191) (xy 337.252325 -231.97596)
			(xy 337.216073 -231.936889) (xy 337.186049 -231.892852) (xy 337.162923 -231.844831) (xy 337.147213 -231.793901)
			(xy 337.13927 -231.741197) (xy 336.909726 -231.741197) (xy 336.907827 -231.766898) (xy 336.896303 -231.818144)
			(xy 336.877377 -231.867141) (xy 336.851458 -231.912827) (xy 336.81911 -231.95421) (xy 336.781033 -231.990392)
			(xy 336.738055 -232.020587) (xy 336.691107 -232.044142) (xy 336.666332 -232.052876) (xy 336.63128 -232.064306)
			(xy 336.63128 -232.17632) (xy 336.631806 -232.190691) (xy 336.639882 -232.218277) (xy 336.65533 -232.242516)
			(xy 336.676926 -232.261485) (xy 336.702954 -232.27368) (xy 336.731351 -232.278132) (xy 336.759863 -232.274488)
			(xy 336.786227 -232.263038) (xy 336.79765 -232.254298) (xy 336.816926 -232.23886) (xy 336.858931 -232.212889)
			(xy 336.90412 -232.192968) (xy 336.951627 -232.179477) (xy 337.000541 -232.172676) (xy 337.025234 -232.172256)
			(xy 337.051884 -232.172756) (xy 337.104589 -232.180705) (xy 337.155521 -232.196419) (xy 337.203541 -232.219549)
			(xy 337.247579 -232.249577) (xy 337.286649 -232.285833) (xy 337.31988 -232.327506) (xy 337.346529 -232.373667)
			(xy 337.366001 -232.423284) (xy 337.377861 -232.475248) (xy 337.381844 -232.5284) (xy 337.37985 -232.555013)
			(xy 337.609424 -232.555013) (xy 337.609424 -232.501715) (xy 337.617367 -232.449011) (xy 337.633077 -232.398081)
			(xy 337.656203 -232.35006) (xy 337.686227 -232.306023) (xy 337.722479 -232.266952) (xy 337.76415 -232.233721)
			(xy 337.810308 -232.207072) (xy 337.859922 -232.1876) (xy 337.911884 -232.17574) (xy 337.965034 -232.171757)
			(xy 338.018184 -232.17574) (xy 338.070146 -232.1876) (xy 338.11976 -232.207072) (xy 338.165918 -232.233721)
			(xy 338.207589 -232.266952) (xy 338.243841 -232.306023) (xy 338.273865 -232.35006) (xy 338.296991 -232.398081)
			(xy 338.312701 -232.449011) (xy 338.320644 -232.501715) (xy 338.321142 -232.528364) (xy 338.320644 -232.555013)
			(xy 338.549224 -232.555013) (xy 338.549224 -232.501715) (xy 338.557167 -232.449011) (xy 338.572877 -232.398081)
			(xy 338.596003 -232.35006) (xy 338.626027 -232.306023) (xy 338.662279 -232.266952) (xy 338.70395 -232.233721)
			(xy 338.750108 -232.207072) (xy 338.799722 -232.1876) (xy 338.851684 -232.17574) (xy 338.904834 -232.171757)
			(xy 338.957984 -232.17574) (xy 339.009946 -232.1876) (xy 339.05956 -232.207072) (xy 339.105718 -232.233721)
			(xy 339.147389 -232.266952) (xy 339.183641 -232.306023) (xy 339.213665 -232.35006) (xy 339.236791 -232.398081)
			(xy 339.252501 -232.449011) (xy 339.260444 -232.501715) (xy 339.260942 -232.528364) (xy 339.260444 -232.555013)
			(xy 339.48877 -232.555013) (xy 339.48877 -232.501715) (xy 339.496713 -232.449011) (xy 339.512423 -232.398081)
			(xy 339.535549 -232.35006) (xy 339.565573 -232.306023) (xy 339.601825 -232.266952) (xy 339.643496 -232.233721)
			(xy 339.689654 -232.207072) (xy 339.739268 -232.1876) (xy 339.79123 -232.17574) (xy 339.84438 -232.171757)
			(xy 339.89753 -232.17574) (xy 339.949492 -232.1876) (xy 339.999106 -232.207072) (xy 340.045264 -232.233721)
			(xy 340.086935 -232.266952) (xy 340.123187 -232.306023) (xy 340.153211 -232.35006) (xy 340.176337 -232.398081)
			(xy 340.192047 -232.449011) (xy 340.19999 -232.501715) (xy 340.200488 -232.528364) (xy 340.19999 -232.555013)
			(xy 340.428824 -232.555013) (xy 340.428824 -232.501715) (xy 340.436767 -232.449011) (xy 340.452477 -232.398081)
			(xy 340.475603 -232.35006) (xy 340.505627 -232.306023) (xy 340.541879 -232.266952) (xy 340.58355 -232.233721)
			(xy 340.629708 -232.207072) (xy 340.679322 -232.1876) (xy 340.731284 -232.17574) (xy 340.784434 -232.171757)
			(xy 340.837584 -232.17574) (xy 340.889546 -232.1876) (xy 340.93916 -232.207072) (xy 340.985318 -232.233721)
			(xy 341.026989 -232.266952) (xy 341.063241 -232.306023) (xy 341.093265 -232.35006) (xy 341.116391 -232.398081)
			(xy 341.132101 -232.449011) (xy 341.140044 -232.501715) (xy 341.140542 -232.528364) (xy 341.140044 -232.555013)
			(xy 341.368624 -232.555013) (xy 341.368624 -232.501715) (xy 341.376567 -232.449011) (xy 341.392277 -232.398081)
			(xy 341.415403 -232.35006) (xy 341.445427 -232.306023) (xy 341.481679 -232.266952) (xy 341.52335 -232.233721)
			(xy 341.569508 -232.207072) (xy 341.619122 -232.1876) (xy 341.671084 -232.17574) (xy 341.724234 -232.171757)
			(xy 341.777384 -232.17574) (xy 341.829346 -232.1876) (xy 341.87896 -232.207072) (xy 341.925118 -232.233721)
			(xy 341.966789 -232.266952) (xy 342.003041 -232.306023) (xy 342.033065 -232.35006) (xy 342.056191 -232.398081)
			(xy 342.071901 -232.449011) (xy 342.079844 -232.501715) (xy 342.080342 -232.528364) (xy 342.079844 -232.555013)
			(xy 342.308424 -232.555013) (xy 342.308424 -232.501715) (xy 342.316367 -232.449011) (xy 342.332077 -232.398081)
			(xy 342.355203 -232.35006) (xy 342.385227 -232.306023) (xy 342.421479 -232.266952) (xy 342.46315 -232.233721)
			(xy 342.509308 -232.207072) (xy 342.558922 -232.1876) (xy 342.610884 -232.17574) (xy 342.664034 -232.171757)
			(xy 342.717184 -232.17574) (xy 342.769146 -232.1876) (xy 342.81876 -232.207072) (xy 342.864918 -232.233721)
			(xy 342.906589 -232.266952) (xy 342.942841 -232.306023) (xy 342.972865 -232.35006) (xy 342.995991 -232.398081)
			(xy 343.011701 -232.449011) (xy 343.019644 -232.501715) (xy 343.020142 -232.528364) (xy 343.019644 -232.555013)
			(xy 343.248224 -232.555013) (xy 343.248224 -232.501715) (xy 343.256167 -232.449011) (xy 343.271877 -232.398081)
			(xy 343.295003 -232.35006) (xy 343.325027 -232.306023) (xy 343.361279 -232.266952) (xy 343.40295 -232.233721)
			(xy 343.449108 -232.207072) (xy 343.498722 -232.1876) (xy 343.550684 -232.17574) (xy 343.603834 -232.171757)
			(xy 343.656984 -232.17574) (xy 343.708946 -232.1876) (xy 343.75856 -232.207072) (xy 343.804718 -232.233721)
			(xy 343.846389 -232.266952) (xy 343.882641 -232.306023) (xy 343.912665 -232.35006) (xy 343.935791 -232.398081)
			(xy 343.951501 -232.449011) (xy 343.959444 -232.501715) (xy 343.959942 -232.528364) (xy 343.959444 -232.555013)
			(xy 344.188024 -232.555013) (xy 344.188024 -232.501715) (xy 344.195967 -232.449011) (xy 344.211677 -232.398081)
			(xy 344.234803 -232.35006) (xy 344.264827 -232.306023) (xy 344.301079 -232.266952) (xy 344.34275 -232.233721)
			(xy 344.388908 -232.207072) (xy 344.438522 -232.1876) (xy 344.490484 -232.17574) (xy 344.543634 -232.171757)
			(xy 344.596784 -232.17574) (xy 344.648746 -232.1876) (xy 344.69836 -232.207072) (xy 344.744518 -232.233721)
			(xy 344.786189 -232.266952) (xy 344.822441 -232.306023) (xy 344.852465 -232.35006) (xy 344.875591 -232.398081)
			(xy 344.891301 -232.449011) (xy 344.899244 -232.501715) (xy 344.899742 -232.528364) (xy 344.899244 -232.555013)
			(xy 345.127824 -232.555013) (xy 345.127824 -232.501715) (xy 345.135767 -232.449011) (xy 345.151477 -232.398081)
			(xy 345.174603 -232.35006) (xy 345.204627 -232.306023) (xy 345.240879 -232.266952) (xy 345.28255 -232.233721)
			(xy 345.328708 -232.207072) (xy 345.378322 -232.1876) (xy 345.430284 -232.17574) (xy 345.483434 -232.171757)
			(xy 345.536584 -232.17574) (xy 345.588546 -232.1876) (xy 345.63816 -232.207072) (xy 345.684318 -232.233721)
			(xy 345.725989 -232.266952) (xy 345.762241 -232.306023) (xy 345.792265 -232.35006) (xy 345.815391 -232.398081)
			(xy 345.831101 -232.449011) (xy 345.839044 -232.501715) (xy 345.839542 -232.528364) (xy 345.839044 -232.555013)
			(xy 346.06737 -232.555013) (xy 346.06737 -232.501715) (xy 346.075313 -232.449011) (xy 346.091023 -232.398081)
			(xy 346.114149 -232.35006) (xy 346.144173 -232.306023) (xy 346.180425 -232.266952) (xy 346.222096 -232.233721)
			(xy 346.268254 -232.207072) (xy 346.317868 -232.1876) (xy 346.36983 -232.17574) (xy 346.42298 -232.171757)
			(xy 346.47613 -232.17574) (xy 346.528092 -232.1876) (xy 346.577706 -232.207072) (xy 346.623864 -232.233721)
			(xy 346.665535 -232.266952) (xy 346.701787 -232.306023) (xy 346.731811 -232.35006) (xy 346.754937 -232.398081)
			(xy 346.770647 -232.449011) (xy 346.77859 -232.501715) (xy 346.779088 -232.528364) (xy 346.77859 -232.555013)
			(xy 347.007424 -232.555013) (xy 347.007424 -232.501715) (xy 347.015367 -232.449011) (xy 347.031077 -232.398081)
			(xy 347.054203 -232.35006) (xy 347.084227 -232.306023) (xy 347.120479 -232.266952) (xy 347.16215 -232.233721)
			(xy 347.208308 -232.207072) (xy 347.257922 -232.1876) (xy 347.309884 -232.17574) (xy 347.363034 -232.171757)
			(xy 347.416184 -232.17574) (xy 347.468146 -232.1876) (xy 347.51776 -232.207072) (xy 347.563918 -232.233721)
			(xy 347.605589 -232.266952) (xy 347.641841 -232.306023) (xy 347.671865 -232.35006) (xy 347.694991 -232.398081)
			(xy 347.710701 -232.449011) (xy 347.718644 -232.501715) (xy 347.719142 -232.528364) (xy 347.718644 -232.555013)
			(xy 347.947224 -232.555013) (xy 347.947224 -232.501715) (xy 347.955167 -232.449011) (xy 347.970877 -232.398081)
			(xy 347.994003 -232.35006) (xy 348.024027 -232.306023) (xy 348.060279 -232.266952) (xy 348.10195 -232.233721)
			(xy 348.148108 -232.207072) (xy 348.197722 -232.1876) (xy 348.249684 -232.17574) (xy 348.302834 -232.171757)
			(xy 348.355984 -232.17574) (xy 348.407946 -232.1876) (xy 348.45756 -232.207072) (xy 348.503718 -232.233721)
			(xy 348.545389 -232.266952) (xy 348.581641 -232.306023) (xy 348.611665 -232.35006) (xy 348.634791 -232.398081)
			(xy 348.650501 -232.449011) (xy 348.658444 -232.501715) (xy 348.658942 -232.528364) (xy 348.658444 -232.555013)
			(xy 349.826824 -232.555013) (xy 349.826824 -232.501715) (xy 349.834767 -232.449011) (xy 349.850477 -232.398081)
			(xy 349.873603 -232.35006) (xy 349.903627 -232.306023) (xy 349.939879 -232.266952) (xy 349.98155 -232.233721)
			(xy 350.027708 -232.207072) (xy 350.077322 -232.1876) (xy 350.129284 -232.17574) (xy 350.182434 -232.171757)
			(xy 350.235584 -232.17574) (xy 350.287546 -232.1876) (xy 350.33716 -232.207072) (xy 350.383318 -232.233721)
			(xy 350.424989 -232.266952) (xy 350.461241 -232.306023) (xy 350.491265 -232.35006) (xy 350.514391 -232.398081)
			(xy 350.530101 -232.449011) (xy 350.538044 -232.501715) (xy 350.538542 -232.528364) (xy 350.538044 -232.555013)
			(xy 350.766624 -232.555013) (xy 350.766624 -232.501715) (xy 350.774567 -232.449011) (xy 350.790277 -232.398081)
			(xy 350.813403 -232.35006) (xy 350.843427 -232.306023) (xy 350.879679 -232.266952) (xy 350.92135 -232.233721)
			(xy 350.967508 -232.207072) (xy 351.017122 -232.1876) (xy 351.069084 -232.17574) (xy 351.122234 -232.171757)
			(xy 351.175384 -232.17574) (xy 351.227346 -232.1876) (xy 351.27696 -232.207072) (xy 351.323118 -232.233721)
			(xy 351.364789 -232.266952) (xy 351.401041 -232.306023) (xy 351.431065 -232.35006) (xy 351.454191 -232.398081)
			(xy 351.469901 -232.449011) (xy 351.477844 -232.501715) (xy 351.478342 -232.528364) (xy 351.477844 -232.555013)
			(xy 351.706424 -232.555013) (xy 351.706424 -232.501715) (xy 351.714367 -232.449011) (xy 351.730077 -232.398081)
			(xy 351.753203 -232.35006) (xy 351.783227 -232.306023) (xy 351.819479 -232.266952) (xy 351.86115 -232.233721)
			(xy 351.907308 -232.207072) (xy 351.956922 -232.1876) (xy 352.008884 -232.17574) (xy 352.062034 -232.171757)
			(xy 352.115184 -232.17574) (xy 352.167146 -232.1876) (xy 352.21676 -232.207072) (xy 352.262918 -232.233721)
			(xy 352.304589 -232.266952) (xy 352.340841 -232.306023) (xy 352.370865 -232.35006) (xy 352.393991 -232.398081)
			(xy 352.409701 -232.449011) (xy 352.417644 -232.501715) (xy 352.418142 -232.528364) (xy 352.417644 -232.555013)
			(xy 352.646224 -232.555013) (xy 352.646224 -232.501715) (xy 352.654167 -232.449011) (xy 352.669877 -232.398081)
			(xy 352.693003 -232.35006) (xy 352.723027 -232.306023) (xy 352.759279 -232.266952) (xy 352.80095 -232.233721)
			(xy 352.847108 -232.207072) (xy 352.896722 -232.1876) (xy 352.948684 -232.17574) (xy 353.001834 -232.171757)
			(xy 353.054984 -232.17574) (xy 353.106946 -232.1876) (xy 353.15656 -232.207072) (xy 353.202718 -232.233721)
			(xy 353.244389 -232.266952) (xy 353.280641 -232.306023) (xy 353.310665 -232.35006) (xy 353.333791 -232.398081)
			(xy 353.349501 -232.449011) (xy 353.357444 -232.501715) (xy 353.357942 -232.528364) (xy 353.357444 -232.555013)
			(xy 353.586024 -232.555013) (xy 353.586024 -232.501715) (xy 353.593967 -232.449011) (xy 353.609677 -232.398081)
			(xy 353.632803 -232.35006) (xy 353.662827 -232.306023) (xy 353.699079 -232.266952) (xy 353.74075 -232.233721)
			(xy 353.786908 -232.207072) (xy 353.836522 -232.1876) (xy 353.888484 -232.17574) (xy 353.941634 -232.171757)
			(xy 353.994784 -232.17574) (xy 354.046746 -232.1876) (xy 354.09636 -232.207072) (xy 354.142518 -232.233721)
			(xy 354.184189 -232.266952) (xy 354.220441 -232.306023) (xy 354.250465 -232.35006) (xy 354.273591 -232.398081)
			(xy 354.289301 -232.449011) (xy 354.297244 -232.501715) (xy 354.297742 -232.528364) (xy 354.297244 -232.555013)
			(xy 354.525824 -232.555013) (xy 354.525824 -232.501715) (xy 354.533767 -232.449011) (xy 354.549477 -232.398081)
			(xy 354.572603 -232.35006) (xy 354.602627 -232.306023) (xy 354.638879 -232.266952) (xy 354.68055 -232.233721)
			(xy 354.726708 -232.207072) (xy 354.776322 -232.1876) (xy 354.828284 -232.17574) (xy 354.881434 -232.171757)
			(xy 354.934584 -232.17574) (xy 354.986546 -232.1876) (xy 355.03616 -232.207072) (xy 355.082318 -232.233721)
			(xy 355.123989 -232.266952) (xy 355.160241 -232.306023) (xy 355.190265 -232.35006) (xy 355.213391 -232.398081)
			(xy 355.229101 -232.449011) (xy 355.237044 -232.501715) (xy 355.237542 -232.528364) (xy 355.237044 -232.555013)
			(xy 355.465624 -232.555013) (xy 355.465624 -232.501715) (xy 355.473567 -232.449011) (xy 355.489277 -232.398081)
			(xy 355.512403 -232.35006) (xy 355.542427 -232.306023) (xy 355.578679 -232.266952) (xy 355.62035 -232.233721)
			(xy 355.666508 -232.207072) (xy 355.716122 -232.1876) (xy 355.768084 -232.17574) (xy 355.821234 -232.171757)
			(xy 355.874384 -232.17574) (xy 355.926346 -232.1876) (xy 355.97596 -232.207072) (xy 356.022118 -232.233721)
			(xy 356.063789 -232.266952) (xy 356.100041 -232.306023) (xy 356.130065 -232.35006) (xy 356.153191 -232.398081)
			(xy 356.168901 -232.449011) (xy 356.176844 -232.501715) (xy 356.177342 -232.528364) (xy 356.176844 -232.555013)
			(xy 356.168901 -232.607717) (xy 356.153191 -232.658647) (xy 356.130065 -232.706668) (xy 356.100041 -232.750705)
			(xy 356.063789 -232.789776) (xy 356.022118 -232.823007) (xy 355.97596 -232.849656) (xy 355.926346 -232.869128)
			(xy 355.874384 -232.880988) (xy 355.821234 -232.884972) (xy 355.768084 -232.880988) (xy 355.716122 -232.869128)
			(xy 355.666508 -232.849656) (xy 355.62035 -232.823007) (xy 355.578679 -232.789776) (xy 355.542427 -232.750705)
			(xy 355.512403 -232.706668) (xy 355.489277 -232.658647) (xy 355.473567 -232.607717) (xy 355.465624 -232.555013)
			(xy 355.237044 -232.555013) (xy 355.229101 -232.607717) (xy 355.213391 -232.658647) (xy 355.190265 -232.706668)
			(xy 355.160241 -232.750705) (xy 355.123989 -232.789776) (xy 355.082318 -232.823007) (xy 355.03616 -232.849656)
			(xy 354.986546 -232.869128) (xy 354.934584 -232.880988) (xy 354.881434 -232.884972) (xy 354.828284 -232.880988)
			(xy 354.776322 -232.869128) (xy 354.726708 -232.849656) (xy 354.68055 -232.823007) (xy 354.638879 -232.789776)
			(xy 354.602627 -232.750705) (xy 354.572603 -232.706668) (xy 354.549477 -232.658647) (xy 354.533767 -232.607717)
			(xy 354.525824 -232.555013) (xy 354.297244 -232.555013) (xy 354.289301 -232.607717) (xy 354.273591 -232.658647)
			(xy 354.250465 -232.706668) (xy 354.220441 -232.750705) (xy 354.184189 -232.789776) (xy 354.142518 -232.823007)
			(xy 354.09636 -232.849656) (xy 354.046746 -232.869128) (xy 353.994784 -232.880988) (xy 353.941634 -232.884972)
			(xy 353.888484 -232.880988) (xy 353.836522 -232.869128) (xy 353.786908 -232.849656) (xy 353.74075 -232.823007)
			(xy 353.699079 -232.789776) (xy 353.662827 -232.750705) (xy 353.632803 -232.706668) (xy 353.609677 -232.658647)
			(xy 353.593967 -232.607717) (xy 353.586024 -232.555013) (xy 353.357444 -232.555013) (xy 353.349501 -232.607717)
			(xy 353.333791 -232.658647) (xy 353.310665 -232.706668) (xy 353.280641 -232.750705) (xy 353.244389 -232.789776)
			(xy 353.202718 -232.823007) (xy 353.15656 -232.849656) (xy 353.106946 -232.869128) (xy 353.054984 -232.880988)
			(xy 353.001834 -232.884972) (xy 352.948684 -232.880988) (xy 352.896722 -232.869128) (xy 352.847108 -232.849656)
			(xy 352.80095 -232.823007) (xy 352.759279 -232.789776) (xy 352.723027 -232.750705) (xy 352.693003 -232.706668)
			(xy 352.669877 -232.658647) (xy 352.654167 -232.607717) (xy 352.646224 -232.555013) (xy 352.417644 -232.555013)
			(xy 352.409701 -232.607717) (xy 352.393991 -232.658647) (xy 352.370865 -232.706668) (xy 352.340841 -232.750705)
			(xy 352.304589 -232.789776) (xy 352.262918 -232.823007) (xy 352.21676 -232.849656) (xy 352.167146 -232.869128)
			(xy 352.115184 -232.880988) (xy 352.062034 -232.884972) (xy 352.008884 -232.880988) (xy 351.956922 -232.869128)
			(xy 351.907308 -232.849656) (xy 351.86115 -232.823007) (xy 351.819479 -232.789776) (xy 351.783227 -232.750705)
			(xy 351.753203 -232.706668) (xy 351.730077 -232.658647) (xy 351.714367 -232.607717) (xy 351.706424 -232.555013)
			(xy 351.477844 -232.555013) (xy 351.469901 -232.607717) (xy 351.454191 -232.658647) (xy 351.431065 -232.706668)
			(xy 351.401041 -232.750705) (xy 351.364789 -232.789776) (xy 351.323118 -232.823007) (xy 351.27696 -232.849656)
			(xy 351.227346 -232.869128) (xy 351.175384 -232.880988) (xy 351.122234 -232.884972) (xy 351.069084 -232.880988)
			(xy 351.017122 -232.869128) (xy 350.967508 -232.849656) (xy 350.92135 -232.823007) (xy 350.879679 -232.789776)
			(xy 350.843427 -232.750705) (xy 350.813403 -232.706668) (xy 350.790277 -232.658647) (xy 350.774567 -232.607717)
			(xy 350.766624 -232.555013) (xy 350.538044 -232.555013) (xy 350.530101 -232.607717) (xy 350.514391 -232.658647)
			(xy 350.491265 -232.706668) (xy 350.461241 -232.750705) (xy 350.424989 -232.789776) (xy 350.383318 -232.823007)
			(xy 350.33716 -232.849656) (xy 350.287546 -232.869128) (xy 350.235584 -232.880988) (xy 350.182434 -232.884972)
			(xy 350.129284 -232.880988) (xy 350.077322 -232.869128) (xy 350.027708 -232.849656) (xy 349.98155 -232.823007)
			(xy 349.939879 -232.789776) (xy 349.903627 -232.750705) (xy 349.873603 -232.706668) (xy 349.850477 -232.658647)
			(xy 349.834767 -232.607717) (xy 349.826824 -232.555013) (xy 348.658444 -232.555013) (xy 348.650501 -232.607717)
			(xy 348.634791 -232.658647) (xy 348.611665 -232.706668) (xy 348.581641 -232.750705) (xy 348.545389 -232.789776)
			(xy 348.503718 -232.823007) (xy 348.45756 -232.849656) (xy 348.407946 -232.869128) (xy 348.355984 -232.880988)
			(xy 348.302834 -232.884972) (xy 348.249684 -232.880988) (xy 348.197722 -232.869128) (xy 348.148108 -232.849656)
			(xy 348.10195 -232.823007) (xy 348.060279 -232.789776) (xy 348.024027 -232.750705) (xy 347.994003 -232.706668)
			(xy 347.970877 -232.658647) (xy 347.955167 -232.607717) (xy 347.947224 -232.555013) (xy 347.718644 -232.555013)
			(xy 347.710701 -232.607717) (xy 347.694991 -232.658647) (xy 347.671865 -232.706668) (xy 347.641841 -232.750705)
			(xy 347.605589 -232.789776) (xy 347.563918 -232.823007) (xy 347.51776 -232.849656) (xy 347.468146 -232.869128)
			(xy 347.416184 -232.880988) (xy 347.363034 -232.884972) (xy 347.309884 -232.880988) (xy 347.257922 -232.869128)
			(xy 347.208308 -232.849656) (xy 347.16215 -232.823007) (xy 347.120479 -232.789776) (xy 347.084227 -232.750705)
			(xy 347.054203 -232.706668) (xy 347.031077 -232.658647) (xy 347.015367 -232.607717) (xy 347.007424 -232.555013)
			(xy 346.77859 -232.555013) (xy 346.770647 -232.607717) (xy 346.754937 -232.658647) (xy 346.731811 -232.706668)
			(xy 346.701787 -232.750705) (xy 346.665535 -232.789776) (xy 346.623864 -232.823007) (xy 346.577706 -232.849656)
			(xy 346.528092 -232.869128) (xy 346.47613 -232.880988) (xy 346.42298 -232.884972) (xy 346.36983 -232.880988)
			(xy 346.317868 -232.869128) (xy 346.268254 -232.849656) (xy 346.222096 -232.823007) (xy 346.180425 -232.789776)
			(xy 346.144173 -232.750705) (xy 346.114149 -232.706668) (xy 346.091023 -232.658647) (xy 346.075313 -232.607717)
			(xy 346.06737 -232.555013) (xy 345.839044 -232.555013) (xy 345.831101 -232.607717) (xy 345.815391 -232.658647)
			(xy 345.792265 -232.706668) (xy 345.762241 -232.750705) (xy 345.725989 -232.789776) (xy 345.684318 -232.823007)
			(xy 345.63816 -232.849656) (xy 345.588546 -232.869128) (xy 345.536584 -232.880988) (xy 345.483434 -232.884972)
			(xy 345.430284 -232.880988) (xy 345.378322 -232.869128) (xy 345.328708 -232.849656) (xy 345.28255 -232.823007)
			(xy 345.240879 -232.789776) (xy 345.204627 -232.750705) (xy 345.174603 -232.706668) (xy 345.151477 -232.658647)
			(xy 345.135767 -232.607717) (xy 345.127824 -232.555013) (xy 344.899244 -232.555013) (xy 344.891301 -232.607717)
			(xy 344.875591 -232.658647) (xy 344.852465 -232.706668) (xy 344.822441 -232.750705) (xy 344.786189 -232.789776)
			(xy 344.744518 -232.823007) (xy 344.69836 -232.849656) (xy 344.648746 -232.869128) (xy 344.596784 -232.880988)
			(xy 344.543634 -232.884972) (xy 344.490484 -232.880988) (xy 344.438522 -232.869128) (xy 344.388908 -232.849656)
			(xy 344.34275 -232.823007) (xy 344.301079 -232.789776) (xy 344.264827 -232.750705) (xy 344.234803 -232.706668)
			(xy 344.211677 -232.658647) (xy 344.195967 -232.607717) (xy 344.188024 -232.555013) (xy 343.959444 -232.555013)
			(xy 343.951501 -232.607717) (xy 343.935791 -232.658647) (xy 343.912665 -232.706668) (xy 343.882641 -232.750705)
			(xy 343.846389 -232.789776) (xy 343.804718 -232.823007) (xy 343.75856 -232.849656) (xy 343.708946 -232.869128)
			(xy 343.656984 -232.880988) (xy 343.603834 -232.884972) (xy 343.550684 -232.880988) (xy 343.498722 -232.869128)
			(xy 343.449108 -232.849656) (xy 343.40295 -232.823007) (xy 343.361279 -232.789776) (xy 343.325027 -232.750705)
			(xy 343.295003 -232.706668) (xy 343.271877 -232.658647) (xy 343.256167 -232.607717) (xy 343.248224 -232.555013)
			(xy 343.019644 -232.555013) (xy 343.011701 -232.607717) (xy 342.995991 -232.658647) (xy 342.972865 -232.706668)
			(xy 342.942841 -232.750705) (xy 342.906589 -232.789776) (xy 342.864918 -232.823007) (xy 342.81876 -232.849656)
			(xy 342.769146 -232.869128) (xy 342.717184 -232.880988) (xy 342.664034 -232.884972) (xy 342.610884 -232.880988)
			(xy 342.558922 -232.869128) (xy 342.509308 -232.849656) (xy 342.46315 -232.823007) (xy 342.421479 -232.789776)
			(xy 342.385227 -232.750705) (xy 342.355203 -232.706668) (xy 342.332077 -232.658647) (xy 342.316367 -232.607717)
			(xy 342.308424 -232.555013) (xy 342.079844 -232.555013) (xy 342.071901 -232.607717) (xy 342.056191 -232.658647)
			(xy 342.033065 -232.706668) (xy 342.003041 -232.750705) (xy 341.966789 -232.789776) (xy 341.925118 -232.823007)
			(xy 341.87896 -232.849656) (xy 341.829346 -232.869128) (xy 341.777384 -232.880988) (xy 341.724234 -232.884972)
			(xy 341.671084 -232.880988) (xy 341.619122 -232.869128) (xy 341.569508 -232.849656) (xy 341.52335 -232.823007)
			(xy 341.481679 -232.789776) (xy 341.445427 -232.750705) (xy 341.415403 -232.706668) (xy 341.392277 -232.658647)
			(xy 341.376567 -232.607717) (xy 341.368624 -232.555013) (xy 341.140044 -232.555013) (xy 341.132101 -232.607717)
			(xy 341.116391 -232.658647) (xy 341.093265 -232.706668) (xy 341.063241 -232.750705) (xy 341.026989 -232.789776)
			(xy 340.985318 -232.823007) (xy 340.93916 -232.849656) (xy 340.889546 -232.869128) (xy 340.837584 -232.880988)
			(xy 340.784434 -232.884972) (xy 340.731284 -232.880988) (xy 340.679322 -232.869128) (xy 340.629708 -232.849656)
			(xy 340.58355 -232.823007) (xy 340.541879 -232.789776) (xy 340.505627 -232.750705) (xy 340.475603 -232.706668)
			(xy 340.452477 -232.658647) (xy 340.436767 -232.607717) (xy 340.428824 -232.555013) (xy 340.19999 -232.555013)
			(xy 340.192047 -232.607717) (xy 340.176337 -232.658647) (xy 340.153211 -232.706668) (xy 340.123187 -232.750705)
			(xy 340.086935 -232.789776) (xy 340.045264 -232.823007) (xy 339.999106 -232.849656) (xy 339.949492 -232.869128)
			(xy 339.89753 -232.880988) (xy 339.84438 -232.884972) (xy 339.79123 -232.880988) (xy 339.739268 -232.869128)
			(xy 339.689654 -232.849656) (xy 339.643496 -232.823007) (xy 339.601825 -232.789776) (xy 339.565573 -232.750705)
			(xy 339.535549 -232.706668) (xy 339.512423 -232.658647) (xy 339.496713 -232.607717) (xy 339.48877 -232.555013)
			(xy 339.260444 -232.555013) (xy 339.252501 -232.607717) (xy 339.236791 -232.658647) (xy 339.213665 -232.706668)
			(xy 339.183641 -232.750705) (xy 339.147389 -232.789776) (xy 339.105718 -232.823007) (xy 339.05956 -232.849656)
			(xy 339.009946 -232.869128) (xy 338.957984 -232.880988) (xy 338.904834 -232.884972) (xy 338.851684 -232.880988)
			(xy 338.799722 -232.869128) (xy 338.750108 -232.849656) (xy 338.70395 -232.823007) (xy 338.662279 -232.789776)
			(xy 338.626027 -232.750705) (xy 338.596003 -232.706668) (xy 338.572877 -232.658647) (xy 338.557167 -232.607717)
			(xy 338.549224 -232.555013) (xy 338.320644 -232.555013) (xy 338.312701 -232.607717) (xy 338.296991 -232.658647)
			(xy 338.273865 -232.706668) (xy 338.243841 -232.750705) (xy 338.207589 -232.789776) (xy 338.165918 -232.823007)
			(xy 338.11976 -232.849656) (xy 338.070146 -232.869128) (xy 338.018184 -232.880988) (xy 337.965034 -232.884972)
			(xy 337.911884 -232.880988) (xy 337.859922 -232.869128) (xy 337.810308 -232.849656) (xy 337.76415 -232.823007)
			(xy 337.722479 -232.789776) (xy 337.686227 -232.750705) (xy 337.656203 -232.706668) (xy 337.633077 -232.658647)
			(xy 337.617367 -232.607717) (xy 337.609424 -232.555013) (xy 337.37985 -232.555013) (xy 337.377861 -232.581552)
			(xy 337.366001 -232.633516) (xy 337.346529 -232.683133) (xy 337.31988 -232.729294) (xy 337.286649 -232.770967)
			(xy 337.247579 -232.807223) (xy 337.203541 -232.837251) (xy 337.155521 -232.860381) (xy 337.104589 -232.876095)
			(xy 337.051884 -232.884044) (xy 337.025234 -232.884472) (xy 337.000538 -232.884073) (xy 336.951616 -232.877289)
			(xy 336.904102 -232.863805) (xy 336.858909 -232.84388) (xy 336.816906 -232.817897) (xy 336.79765 -232.80243)
			(xy 336.786264 -232.793652) (xy 336.759895 -232.782229) (xy 336.731388 -232.778607) (xy 336.703 -232.783072)
			(xy 336.676981 -232.795271) (xy 336.655391 -232.814236) (xy 336.639941 -232.838466) (xy 336.631854 -232.866041)
			(xy 336.63128 -232.880408) (xy 336.63128 -232.992422) (xy 336.666332 -233.003852) (xy 336.691139 -233.012501)
			(xy 336.738095 -233.036062) (xy 336.781081 -233.066264) (xy 336.819163 -233.102453) (xy 336.851517 -233.143844)
			(xy 336.877439 -233.189539) (xy 336.896368 -233.238546) (xy 336.907892 -233.289801) (xy 336.911762 -233.342194)
			(xy 336.909796 -233.368829) (xy 337.13927 -233.368829) (xy 337.13927 -233.315531) (xy 337.147213 -233.262827)
			(xy 337.162923 -233.211897) (xy 337.186049 -233.163876) (xy 337.216073 -233.119839) (xy 337.252325 -233.080768)
			(xy 337.293996 -233.047537) (xy 337.340154 -233.020888) (xy 337.389768 -233.001416) (xy 337.44173 -232.989556)
			(xy 337.49488 -232.985573) (xy 337.54803 -232.989556) (xy 337.599992 -233.001416) (xy 337.649606 -233.020888)
			(xy 337.695764 -233.047537) (xy 337.737435 -233.080768) (xy 337.773687 -233.119839) (xy 337.803711 -233.163876)
			(xy 337.826837 -233.211897) (xy 337.842547 -233.262827) (xy 337.85049 -233.315531) (xy 337.850988 -233.34218)
			(xy 337.85049 -233.368829) (xy 338.07907 -233.368829) (xy 338.07907 -233.315531) (xy 338.087013 -233.262827)
			(xy 338.102723 -233.211897) (xy 338.125849 -233.163876) (xy 338.155873 -233.119839) (xy 338.192125 -233.080768)
			(xy 338.233796 -233.047537) (xy 338.279954 -233.020888) (xy 338.329568 -233.001416) (xy 338.38153 -232.989556)
			(xy 338.43468 -232.985573) (xy 338.48783 -232.989556) (xy 338.539792 -233.001416) (xy 338.589406 -233.020888)
			(xy 338.635564 -233.047537) (xy 338.677235 -233.080768) (xy 338.713487 -233.119839) (xy 338.743511 -233.163876)
			(xy 338.766637 -233.211897) (xy 338.782347 -233.262827) (xy 338.79029 -233.315531) (xy 338.790788 -233.34218)
			(xy 338.79029 -233.368829) (xy 339.019124 -233.368829) (xy 339.019124 -233.315531) (xy 339.027067 -233.262827)
			(xy 339.042777 -233.211897) (xy 339.065903 -233.163876) (xy 339.095927 -233.119839) (xy 339.132179 -233.080768)
			(xy 339.17385 -233.047537) (xy 339.220008 -233.020888) (xy 339.269622 -233.001416) (xy 339.321584 -232.989556)
			(xy 339.374734 -232.985573) (xy 339.427884 -232.989556) (xy 339.479846 -233.001416) (xy 339.52946 -233.020888)
			(xy 339.575618 -233.047537) (xy 339.617289 -233.080768) (xy 339.653541 -233.119839) (xy 339.683565 -233.163876)
			(xy 339.706691 -233.211897) (xy 339.722401 -233.262827) (xy 339.730344 -233.315531) (xy 339.730842 -233.34218)
			(xy 339.730344 -233.368829) (xy 339.95867 -233.368829) (xy 339.95867 -233.315531) (xy 339.966613 -233.262827)
			(xy 339.982323 -233.211897) (xy 340.005449 -233.163876) (xy 340.035473 -233.119839) (xy 340.071725 -233.080768)
			(xy 340.113396 -233.047537) (xy 340.159554 -233.020888) (xy 340.209168 -233.001416) (xy 340.26113 -232.989556)
			(xy 340.31428 -232.985573) (xy 340.36743 -232.989556) (xy 340.419392 -233.001416) (xy 340.469006 -233.020888)
			(xy 340.515164 -233.047537) (xy 340.556835 -233.080768) (xy 340.593087 -233.119839) (xy 340.623111 -233.163876)
			(xy 340.646237 -233.211897) (xy 340.661947 -233.262827) (xy 340.66989 -233.315531) (xy 340.670388 -233.34218)
			(xy 340.66989 -233.368829) (xy 340.89847 -233.368829) (xy 340.89847 -233.315531) (xy 340.906413 -233.262827)
			(xy 340.922123 -233.211897) (xy 340.945249 -233.163876) (xy 340.975273 -233.119839) (xy 341.011525 -233.080768)
			(xy 341.053196 -233.047537) (xy 341.099354 -233.020888) (xy 341.148968 -233.001416) (xy 341.20093 -232.989556)
			(xy 341.25408 -232.985573) (xy 341.30723 -232.989556) (xy 341.359192 -233.001416) (xy 341.408806 -233.020888)
			(xy 341.454964 -233.047537) (xy 341.496635 -233.080768) (xy 341.532887 -233.119839) (xy 341.562911 -233.163876)
			(xy 341.586037 -233.211897) (xy 341.601747 -233.262827) (xy 341.60969 -233.315531) (xy 341.610188 -233.34218)
			(xy 341.60969 -233.368829) (xy 341.83827 -233.368829) (xy 341.83827 -233.315531) (xy 341.846213 -233.262827)
			(xy 341.861923 -233.211897) (xy 341.885049 -233.163876) (xy 341.915073 -233.119839) (xy 341.951325 -233.080768)
			(xy 341.992996 -233.047537) (xy 342.039154 -233.020888) (xy 342.088768 -233.001416) (xy 342.14073 -232.989556)
			(xy 342.19388 -232.985573) (xy 342.24703 -232.989556) (xy 342.298992 -233.001416) (xy 342.348606 -233.020888)
			(xy 342.394764 -233.047537) (xy 342.436435 -233.080768) (xy 342.472687 -233.119839) (xy 342.502711 -233.163876)
			(xy 342.525837 -233.211897) (xy 342.541547 -233.262827) (xy 342.54949 -233.315531) (xy 342.549988 -233.34218)
			(xy 342.54949 -233.368829) (xy 342.77807 -233.368829) (xy 342.77807 -233.315531) (xy 342.786013 -233.262827)
			(xy 342.801723 -233.211897) (xy 342.824849 -233.163876) (xy 342.854873 -233.119839) (xy 342.891125 -233.080768)
			(xy 342.932796 -233.047537) (xy 342.978954 -233.020888) (xy 343.028568 -233.001416) (xy 343.08053 -232.989556)
			(xy 343.13368 -232.985573) (xy 343.18683 -232.989556) (xy 343.238792 -233.001416) (xy 343.288406 -233.020888)
			(xy 343.334564 -233.047537) (xy 343.376235 -233.080768) (xy 343.412487 -233.119839) (xy 343.442511 -233.163876)
			(xy 343.465637 -233.211897) (xy 343.481347 -233.262827) (xy 343.48929 -233.315531) (xy 343.489788 -233.34218)
			(xy 343.48929 -233.368829) (xy 343.71787 -233.368829) (xy 343.71787 -233.315531) (xy 343.725813 -233.262827)
			(xy 343.741523 -233.211897) (xy 343.764649 -233.163876) (xy 343.794673 -233.119839) (xy 343.830925 -233.080768)
			(xy 343.872596 -233.047537) (xy 343.918754 -233.020888) (xy 343.968368 -233.001416) (xy 344.02033 -232.989556)
			(xy 344.07348 -232.985573) (xy 344.12663 -232.989556) (xy 344.178592 -233.001416) (xy 344.228206 -233.020888)
			(xy 344.274364 -233.047537) (xy 344.316035 -233.080768) (xy 344.352287 -233.119839) (xy 344.382311 -233.163876)
			(xy 344.405437 -233.211897) (xy 344.421147 -233.262827) (xy 344.42909 -233.315531) (xy 344.429588 -233.34218)
			(xy 344.42909 -233.368829) (xy 344.65767 -233.368829) (xy 344.65767 -233.315531) (xy 344.665613 -233.262827)
			(xy 344.681323 -233.211897) (xy 344.704449 -233.163876) (xy 344.734473 -233.119839) (xy 344.770725 -233.080768)
			(xy 344.812396 -233.047537) (xy 344.858554 -233.020888) (xy 344.908168 -233.001416) (xy 344.96013 -232.989556)
			(xy 345.01328 -232.985573) (xy 345.06643 -232.989556) (xy 345.118392 -233.001416) (xy 345.168006 -233.020888)
			(xy 345.214164 -233.047537) (xy 345.255835 -233.080768) (xy 345.292087 -233.119839) (xy 345.322111 -233.163876)
			(xy 345.345237 -233.211897) (xy 345.360947 -233.262827) (xy 345.36889 -233.315531) (xy 345.369388 -233.34218)
			(xy 345.36889 -233.368829) (xy 345.597724 -233.368829) (xy 345.597724 -233.315531) (xy 345.605667 -233.262827)
			(xy 345.621377 -233.211897) (xy 345.644503 -233.163876) (xy 345.674527 -233.119839) (xy 345.710779 -233.080768)
			(xy 345.75245 -233.047537) (xy 345.798608 -233.020888) (xy 345.848222 -233.001416) (xy 345.900184 -232.989556)
			(xy 345.953334 -232.985573) (xy 346.006484 -232.989556) (xy 346.058446 -233.001416) (xy 346.10806 -233.020888)
			(xy 346.154218 -233.047537) (xy 346.195889 -233.080768) (xy 346.232141 -233.119839) (xy 346.262165 -233.163876)
			(xy 346.285291 -233.211897) (xy 346.301001 -233.262827) (xy 346.308944 -233.315531) (xy 346.309442 -233.34218)
			(xy 346.308944 -233.368829) (xy 346.53727 -233.368829) (xy 346.53727 -233.315531) (xy 346.545213 -233.262827)
			(xy 346.560923 -233.211897) (xy 346.584049 -233.163876) (xy 346.614073 -233.119839) (xy 346.650325 -233.080768)
			(xy 346.691996 -233.047537) (xy 346.738154 -233.020888) (xy 346.787768 -233.001416) (xy 346.83973 -232.989556)
			(xy 346.89288 -232.985573) (xy 346.94603 -232.989556) (xy 346.997992 -233.001416) (xy 347.047606 -233.020888)
			(xy 347.093764 -233.047537) (xy 347.135435 -233.080768) (xy 347.171687 -233.119839) (xy 347.201711 -233.163876)
			(xy 347.224837 -233.211897) (xy 347.240547 -233.262827) (xy 347.24849 -233.315531) (xy 347.248988 -233.34218)
			(xy 347.24849 -233.368829) (xy 347.47707 -233.368829) (xy 347.47707 -233.315531) (xy 347.485013 -233.262827)
			(xy 347.500723 -233.211897) (xy 347.523849 -233.163876) (xy 347.553873 -233.119839) (xy 347.590125 -233.080768)
			(xy 347.631796 -233.047537) (xy 347.677954 -233.020888) (xy 347.727568 -233.001416) (xy 347.77953 -232.989556)
			(xy 347.83268 -232.985573) (xy 347.88583 -232.989556) (xy 347.937792 -233.001416) (xy 347.987406 -233.020888)
			(xy 348.033564 -233.047537) (xy 348.075235 -233.080768) (xy 348.111487 -233.119839) (xy 348.141511 -233.163876)
			(xy 348.164637 -233.211897) (xy 348.180347 -233.262827) (xy 348.18829 -233.315531) (xy 348.188788 -233.34218)
			(xy 348.18829 -233.368829) (xy 348.41687 -233.368829) (xy 348.41687 -233.315531) (xy 348.424813 -233.262827)
			(xy 348.440523 -233.211897) (xy 348.463649 -233.163876) (xy 348.493673 -233.119839) (xy 348.529925 -233.080768)
			(xy 348.571596 -233.047537) (xy 348.617754 -233.020888) (xy 348.667368 -233.001416) (xy 348.71933 -232.989556)
			(xy 348.77248 -232.985573) (xy 348.82563 -232.989556) (xy 348.877592 -233.001416) (xy 348.927206 -233.020888)
			(xy 348.973364 -233.047537) (xy 349.015035 -233.080768) (xy 349.051287 -233.119839) (xy 349.081311 -233.163876)
			(xy 349.104437 -233.211897) (xy 349.120147 -233.262827) (xy 349.12809 -233.315531) (xy 349.128588 -233.34218)
			(xy 349.12809 -233.368829) (xy 349.120147 -233.421533) (xy 349.104437 -233.472463) (xy 349.081311 -233.520484)
			(xy 349.051287 -233.564521) (xy 349.015035 -233.603592) (xy 348.973364 -233.636823) (xy 348.927206 -233.663472)
			(xy 348.877592 -233.682944) (xy 348.82563 -233.694804) (xy 348.77248 -233.698788) (xy 348.71933 -233.694804)
			(xy 348.667368 -233.682944) (xy 348.617754 -233.663472) (xy 348.571596 -233.636823) (xy 348.529925 -233.603592)
			(xy 348.493673 -233.564521) (xy 348.463649 -233.520484) (xy 348.440523 -233.472463) (xy 348.424813 -233.421533)
			(xy 348.41687 -233.368829) (xy 348.18829 -233.368829) (xy 348.180347 -233.421533) (xy 348.164637 -233.472463)
			(xy 348.141511 -233.520484) (xy 348.111487 -233.564521) (xy 348.075235 -233.603592) (xy 348.033564 -233.636823)
			(xy 347.987406 -233.663472) (xy 347.937792 -233.682944) (xy 347.88583 -233.694804) (xy 347.83268 -233.698788)
			(xy 347.77953 -233.694804) (xy 347.727568 -233.682944) (xy 347.677954 -233.663472) (xy 347.631796 -233.636823)
			(xy 347.590125 -233.603592) (xy 347.553873 -233.564521) (xy 347.523849 -233.520484) (xy 347.500723 -233.472463)
			(xy 347.485013 -233.421533) (xy 347.47707 -233.368829) (xy 347.24849 -233.368829) (xy 347.240547 -233.421533)
			(xy 347.224837 -233.472463) (xy 347.201711 -233.520484) (xy 347.171687 -233.564521) (xy 347.135435 -233.603592)
			(xy 347.093764 -233.636823) (xy 347.047606 -233.663472) (xy 346.997992 -233.682944) (xy 346.94603 -233.694804)
			(xy 346.89288 -233.698788) (xy 346.83973 -233.694804) (xy 346.787768 -233.682944) (xy 346.738154 -233.663472)
			(xy 346.691996 -233.636823) (xy 346.650325 -233.603592) (xy 346.614073 -233.564521) (xy 346.584049 -233.520484)
			(xy 346.560923 -233.472463) (xy 346.545213 -233.421533) (xy 346.53727 -233.368829) (xy 346.308944 -233.368829)
			(xy 346.301001 -233.421533) (xy 346.285291 -233.472463) (xy 346.262165 -233.520484) (xy 346.232141 -233.564521)
			(xy 346.195889 -233.603592) (xy 346.154218 -233.636823) (xy 346.10806 -233.663472) (xy 346.058446 -233.682944)
			(xy 346.006484 -233.694804) (xy 345.953334 -233.698788) (xy 345.900184 -233.694804) (xy 345.848222 -233.682944)
			(xy 345.798608 -233.663472) (xy 345.75245 -233.636823) (xy 345.710779 -233.603592) (xy 345.674527 -233.564521)
			(xy 345.644503 -233.520484) (xy 345.621377 -233.472463) (xy 345.605667 -233.421533) (xy 345.597724 -233.368829)
			(xy 345.36889 -233.368829) (xy 345.360947 -233.421533) (xy 345.345237 -233.472463) (xy 345.322111 -233.520484)
			(xy 345.292087 -233.564521) (xy 345.255835 -233.603592) (xy 345.214164 -233.636823) (xy 345.168006 -233.663472)
			(xy 345.118392 -233.682944) (xy 345.06643 -233.694804) (xy 345.01328 -233.698788) (xy 344.96013 -233.694804)
			(xy 344.908168 -233.682944) (xy 344.858554 -233.663472) (xy 344.812396 -233.636823) (xy 344.770725 -233.603592)
			(xy 344.734473 -233.564521) (xy 344.704449 -233.520484) (xy 344.681323 -233.472463) (xy 344.665613 -233.421533)
			(xy 344.65767 -233.368829) (xy 344.42909 -233.368829) (xy 344.421147 -233.421533) (xy 344.405437 -233.472463)
			(xy 344.382311 -233.520484) (xy 344.352287 -233.564521) (xy 344.316035 -233.603592) (xy 344.274364 -233.636823)
			(xy 344.228206 -233.663472) (xy 344.178592 -233.682944) (xy 344.12663 -233.694804) (xy 344.07348 -233.698788)
			(xy 344.02033 -233.694804) (xy 343.968368 -233.682944) (xy 343.918754 -233.663472) (xy 343.872596 -233.636823)
			(xy 343.830925 -233.603592) (xy 343.794673 -233.564521) (xy 343.764649 -233.520484) (xy 343.741523 -233.472463)
			(xy 343.725813 -233.421533) (xy 343.71787 -233.368829) (xy 343.48929 -233.368829) (xy 343.481347 -233.421533)
			(xy 343.465637 -233.472463) (xy 343.442511 -233.520484) (xy 343.412487 -233.564521) (xy 343.376235 -233.603592)
			(xy 343.334564 -233.636823) (xy 343.288406 -233.663472) (xy 343.238792 -233.682944) (xy 343.18683 -233.694804)
			(xy 343.13368 -233.698788) (xy 343.08053 -233.694804) (xy 343.028568 -233.682944) (xy 342.978954 -233.663472)
			(xy 342.932796 -233.636823) (xy 342.891125 -233.603592) (xy 342.854873 -233.564521) (xy 342.824849 -233.520484)
			(xy 342.801723 -233.472463) (xy 342.786013 -233.421533) (xy 342.77807 -233.368829) (xy 342.54949 -233.368829)
			(xy 342.541547 -233.421533) (xy 342.525837 -233.472463) (xy 342.502711 -233.520484) (xy 342.472687 -233.564521)
			(xy 342.436435 -233.603592) (xy 342.394764 -233.636823) (xy 342.348606 -233.663472) (xy 342.298992 -233.682944)
			(xy 342.24703 -233.694804) (xy 342.19388 -233.698788) (xy 342.14073 -233.694804) (xy 342.088768 -233.682944)
			(xy 342.039154 -233.663472) (xy 341.992996 -233.636823) (xy 341.951325 -233.603592) (xy 341.915073 -233.564521)
			(xy 341.885049 -233.520484) (xy 341.861923 -233.472463) (xy 341.846213 -233.421533) (xy 341.83827 -233.368829)
			(xy 341.60969 -233.368829) (xy 341.601747 -233.421533) (xy 341.586037 -233.472463) (xy 341.562911 -233.520484)
			(xy 341.532887 -233.564521) (xy 341.496635 -233.603592) (xy 341.454964 -233.636823) (xy 341.408806 -233.663472)
			(xy 341.359192 -233.682944) (xy 341.30723 -233.694804) (xy 341.25408 -233.698788) (xy 341.20093 -233.694804)
			(xy 341.148968 -233.682944) (xy 341.099354 -233.663472) (xy 341.053196 -233.636823) (xy 341.011525 -233.603592)
			(xy 340.975273 -233.564521) (xy 340.945249 -233.520484) (xy 340.922123 -233.472463) (xy 340.906413 -233.421533)
			(xy 340.89847 -233.368829) (xy 340.66989 -233.368829) (xy 340.661947 -233.421533) (xy 340.646237 -233.472463)
			(xy 340.623111 -233.520484) (xy 340.593087 -233.564521) (xy 340.556835 -233.603592) (xy 340.515164 -233.636823)
			(xy 340.469006 -233.663472) (xy 340.419392 -233.682944) (xy 340.36743 -233.694804) (xy 340.31428 -233.698788)
			(xy 340.26113 -233.694804) (xy 340.209168 -233.682944) (xy 340.159554 -233.663472) (xy 340.113396 -233.636823)
			(xy 340.071725 -233.603592) (xy 340.035473 -233.564521) (xy 340.005449 -233.520484) (xy 339.982323 -233.472463)
			(xy 339.966613 -233.421533) (xy 339.95867 -233.368829) (xy 339.730344 -233.368829) (xy 339.722401 -233.421533)
			(xy 339.706691 -233.472463) (xy 339.683565 -233.520484) (xy 339.653541 -233.564521) (xy 339.617289 -233.603592)
			(xy 339.575618 -233.636823) (xy 339.52946 -233.663472) (xy 339.479846 -233.682944) (xy 339.427884 -233.694804)
			(xy 339.374734 -233.698788) (xy 339.321584 -233.694804) (xy 339.269622 -233.682944) (xy 339.220008 -233.663472)
			(xy 339.17385 -233.636823) (xy 339.132179 -233.603592) (xy 339.095927 -233.564521) (xy 339.065903 -233.520484)
			(xy 339.042777 -233.472463) (xy 339.027067 -233.421533) (xy 339.019124 -233.368829) (xy 338.79029 -233.368829)
			(xy 338.782347 -233.421533) (xy 338.766637 -233.472463) (xy 338.743511 -233.520484) (xy 338.713487 -233.564521)
			(xy 338.677235 -233.603592) (xy 338.635564 -233.636823) (xy 338.589406 -233.663472) (xy 338.539792 -233.682944)
			(xy 338.48783 -233.694804) (xy 338.43468 -233.698788) (xy 338.38153 -233.694804) (xy 338.329568 -233.682944)
			(xy 338.279954 -233.663472) (xy 338.233796 -233.636823) (xy 338.192125 -233.603592) (xy 338.155873 -233.564521)
			(xy 338.125849 -233.520484) (xy 338.102723 -233.472463) (xy 338.087013 -233.421533) (xy 338.07907 -233.368829)
			(xy 337.85049 -233.368829) (xy 337.842547 -233.421533) (xy 337.826837 -233.472463) (xy 337.803711 -233.520484)
			(xy 337.773687 -233.564521) (xy 337.737435 -233.603592) (xy 337.695764 -233.636823) (xy 337.649606 -233.663472)
			(xy 337.599992 -233.682944) (xy 337.54803 -233.694804) (xy 337.49488 -233.698788) (xy 337.44173 -233.694804)
			(xy 337.389768 -233.682944) (xy 337.340154 -233.663472) (xy 337.293996 -233.636823) (xy 337.252325 -233.603592)
			(xy 337.216073 -233.564521) (xy 337.186049 -233.520484) (xy 337.162923 -233.472463) (xy 337.147213 -233.421533)
			(xy 337.13927 -233.368829) (xy 336.909796 -233.368829) (xy 336.907894 -233.394586) (xy 336.896371 -233.445842)
			(xy 336.877445 -233.49485) (xy 336.851524 -233.540545) (xy 336.819172 -233.581937) (xy 336.781091 -233.618128)
			(xy 336.738106 -233.648332) (xy 336.691151 -233.671894) (xy 336.666332 -233.680508) (xy 336.63128 -233.691938)
			(xy 336.63128 -233.804206) (xy 336.631805 -233.818578) (xy 336.639878 -233.846168) (xy 336.655326 -233.870411)
			(xy 336.676922 -233.889383) (xy 336.702953 -233.90158) (xy 336.731353 -233.906032) (xy 336.759867 -233.902387)
			(xy 336.786233 -233.890934) (xy 336.79765 -233.882184) (xy 336.816927 -233.866747) (xy 336.858932 -233.840777)
			(xy 336.90412 -233.820856) (xy 336.951627 -233.807366) (xy 337.000541 -233.800565) (xy 337.025234 -233.800142)
			(xy 337.051878 -233.800642) (xy 337.10457 -233.808589) (xy 337.155489 -233.8243) (xy 337.203498 -233.847424)
			(xy 337.247525 -233.877445) (xy 337.286586 -233.913692) (xy 337.319809 -233.955355) (xy 337.346451 -234.001504)
			(xy 337.365918 -234.051109) (xy 337.377775 -234.103061) (xy 337.381757 -234.1562) (xy 337.379756 -234.182899)
			(xy 337.609424 -234.182899) (xy 337.609424 -234.129601) (xy 337.617367 -234.076897) (xy 337.633077 -234.025967)
			(xy 337.656203 -233.977946) (xy 337.686227 -233.933909) (xy 337.722479 -233.894838) (xy 337.76415 -233.861607)
			(xy 337.810308 -233.834958) (xy 337.859922 -233.815486) (xy 337.911884 -233.803626) (xy 337.965034 -233.799643)
			(xy 338.018184 -233.803626) (xy 338.070146 -233.815486) (xy 338.11976 -233.834958) (xy 338.165918 -233.861607)
			(xy 338.207589 -233.894838) (xy 338.243841 -233.933909) (xy 338.273865 -233.977946) (xy 338.296991 -234.025967)
			(xy 338.312701 -234.076897) (xy 338.320644 -234.129601) (xy 338.321142 -234.15625) (xy 338.320644 -234.182899)
			(xy 338.549224 -234.182899) (xy 338.549224 -234.129601) (xy 338.557167 -234.076897) (xy 338.572877 -234.025967)
			(xy 338.596003 -233.977946) (xy 338.626027 -233.933909) (xy 338.662279 -233.894838) (xy 338.70395 -233.861607)
			(xy 338.750108 -233.834958) (xy 338.799722 -233.815486) (xy 338.851684 -233.803626) (xy 338.904834 -233.799643)
			(xy 338.957984 -233.803626) (xy 339.009946 -233.815486) (xy 339.05956 -233.834958) (xy 339.105718 -233.861607)
			(xy 339.147389 -233.894838) (xy 339.183641 -233.933909) (xy 339.213665 -233.977946) (xy 339.236791 -234.025967)
			(xy 339.252501 -234.076897) (xy 339.260444 -234.129601) (xy 339.260942 -234.15625) (xy 339.260444 -234.182899)
			(xy 339.489024 -234.182899) (xy 339.489024 -234.129601) (xy 339.496967 -234.076897) (xy 339.512677 -234.025967)
			(xy 339.535803 -233.977946) (xy 339.565827 -233.933909) (xy 339.602079 -233.894838) (xy 339.64375 -233.861607)
			(xy 339.689908 -233.834958) (xy 339.739522 -233.815486) (xy 339.791484 -233.803626) (xy 339.844634 -233.799643)
			(xy 339.897784 -233.803626) (xy 339.949746 -233.815486) (xy 339.99936 -233.834958) (xy 340.045518 -233.861607)
			(xy 340.087189 -233.894838) (xy 340.123441 -233.933909) (xy 340.153465 -233.977946) (xy 340.176591 -234.025967)
			(xy 340.192301 -234.076897) (xy 340.200244 -234.129601) (xy 340.200742 -234.15625) (xy 340.200244 -234.182899)
			(xy 340.428824 -234.182899) (xy 340.428824 -234.129601) (xy 340.436767 -234.076897) (xy 340.452477 -234.025967)
			(xy 340.475603 -233.977946) (xy 340.505627 -233.933909) (xy 340.541879 -233.894838) (xy 340.58355 -233.861607)
			(xy 340.629708 -233.834958) (xy 340.679322 -233.815486) (xy 340.731284 -233.803626) (xy 340.784434 -233.799643)
			(xy 340.837584 -233.803626) (xy 340.889546 -233.815486) (xy 340.93916 -233.834958) (xy 340.985318 -233.861607)
			(xy 341.026989 -233.894838) (xy 341.063241 -233.933909) (xy 341.093265 -233.977946) (xy 341.116391 -234.025967)
			(xy 341.132101 -234.076897) (xy 341.140044 -234.129601) (xy 341.140542 -234.15625) (xy 341.140044 -234.182899)
			(xy 341.368624 -234.182899) (xy 341.368624 -234.129601) (xy 341.376567 -234.076897) (xy 341.392277 -234.025967)
			(xy 341.415403 -233.977946) (xy 341.445427 -233.933909) (xy 341.481679 -233.894838) (xy 341.52335 -233.861607)
			(xy 341.569508 -233.834958) (xy 341.619122 -233.815486) (xy 341.671084 -233.803626) (xy 341.724234 -233.799643)
			(xy 341.777384 -233.803626) (xy 341.829346 -233.815486) (xy 341.87896 -233.834958) (xy 341.925118 -233.861607)
			(xy 341.966789 -233.894838) (xy 342.003041 -233.933909) (xy 342.033065 -233.977946) (xy 342.056191 -234.025967)
			(xy 342.071901 -234.076897) (xy 342.079844 -234.129601) (xy 342.080342 -234.15625) (xy 342.079844 -234.182899)
			(xy 342.30817 -234.182899) (xy 342.30817 -234.129601) (xy 342.316113 -234.076897) (xy 342.331823 -234.025967)
			(xy 342.354949 -233.977946) (xy 342.384973 -233.933909) (xy 342.421225 -233.894838) (xy 342.462896 -233.861607)
			(xy 342.509054 -233.834958) (xy 342.558668 -233.815486) (xy 342.61063 -233.803626) (xy 342.66378 -233.799643)
			(xy 342.71693 -233.803626) (xy 342.768892 -233.815486) (xy 342.818506 -233.834958) (xy 342.864664 -233.861607)
			(xy 342.906335 -233.894838) (xy 342.942587 -233.933909) (xy 342.972611 -233.977946) (xy 342.995737 -234.025967)
			(xy 343.011447 -234.076897) (xy 343.01939 -234.129601) (xy 343.019888 -234.15625) (xy 343.01939 -234.182899)
			(xy 343.248224 -234.182899) (xy 343.248224 -234.129601) (xy 343.256167 -234.076897) (xy 343.271877 -234.025967)
			(xy 343.295003 -233.977946) (xy 343.325027 -233.933909) (xy 343.361279 -233.894838) (xy 343.40295 -233.861607)
			(xy 343.449108 -233.834958) (xy 343.498722 -233.815486) (xy 343.550684 -233.803626) (xy 343.603834 -233.799643)
			(xy 343.656984 -233.803626) (xy 343.708946 -233.815486) (xy 343.75856 -233.834958) (xy 343.804718 -233.861607)
			(xy 343.846389 -233.894838) (xy 343.882641 -233.933909) (xy 343.912665 -233.977946) (xy 343.935791 -234.025967)
			(xy 343.951501 -234.076897) (xy 343.959444 -234.129601) (xy 343.959942 -234.15625) (xy 343.959444 -234.182899)
			(xy 344.188024 -234.182899) (xy 344.188024 -234.129601) (xy 344.195967 -234.076897) (xy 344.211677 -234.025967)
			(xy 344.234803 -233.977946) (xy 344.264827 -233.933909) (xy 344.301079 -233.894838) (xy 344.34275 -233.861607)
			(xy 344.388908 -233.834958) (xy 344.438522 -233.815486) (xy 344.490484 -233.803626) (xy 344.543634 -233.799643)
			(xy 344.596784 -233.803626) (xy 344.648746 -233.815486) (xy 344.69836 -233.834958) (xy 344.744518 -233.861607)
			(xy 344.786189 -233.894838) (xy 344.822441 -233.933909) (xy 344.852465 -233.977946) (xy 344.875591 -234.025967)
			(xy 344.891301 -234.076897) (xy 344.899244 -234.129601) (xy 344.899742 -234.15625) (xy 344.899244 -234.182899)
			(xy 345.127824 -234.182899) (xy 345.127824 -234.129601) (xy 345.135767 -234.076897) (xy 345.151477 -234.025967)
			(xy 345.174603 -233.977946) (xy 345.204627 -233.933909) (xy 345.240879 -233.894838) (xy 345.28255 -233.861607)
			(xy 345.328708 -233.834958) (xy 345.378322 -233.815486) (xy 345.430284 -233.803626) (xy 345.483434 -233.799643)
			(xy 345.536584 -233.803626) (xy 345.588546 -233.815486) (xy 345.63816 -233.834958) (xy 345.684318 -233.861607)
			(xy 345.725989 -233.894838) (xy 345.762241 -233.933909) (xy 345.792265 -233.977946) (xy 345.815391 -234.025967)
			(xy 345.831101 -234.076897) (xy 345.839044 -234.129601) (xy 345.839542 -234.15625) (xy 345.839044 -234.182899)
			(xy 346.067624 -234.182899) (xy 346.067624 -234.129601) (xy 346.075567 -234.076897) (xy 346.091277 -234.025967)
			(xy 346.114403 -233.977946) (xy 346.144427 -233.933909) (xy 346.180679 -233.894838) (xy 346.22235 -233.861607)
			(xy 346.268508 -233.834958) (xy 346.318122 -233.815486) (xy 346.370084 -233.803626) (xy 346.423234 -233.799643)
			(xy 346.476384 -233.803626) (xy 346.528346 -233.815486) (xy 346.57796 -233.834958) (xy 346.624118 -233.861607)
			(xy 346.665789 -233.894838) (xy 346.702041 -233.933909) (xy 346.732065 -233.977946) (xy 346.755191 -234.025967)
			(xy 346.770901 -234.076897) (xy 346.778844 -234.129601) (xy 346.779342 -234.15625) (xy 346.778844 -234.182899)
			(xy 347.007424 -234.182899) (xy 347.007424 -234.129601) (xy 347.015367 -234.076897) (xy 347.031077 -234.025967)
			(xy 347.054203 -233.977946) (xy 347.084227 -233.933909) (xy 347.120479 -233.894838) (xy 347.16215 -233.861607)
			(xy 347.208308 -233.834958) (xy 347.257922 -233.815486) (xy 347.309884 -233.803626) (xy 347.363034 -233.799643)
			(xy 347.416184 -233.803626) (xy 347.468146 -233.815486) (xy 347.51776 -233.834958) (xy 347.563918 -233.861607)
			(xy 347.605589 -233.894838) (xy 347.641841 -233.933909) (xy 347.671865 -233.977946) (xy 347.694991 -234.025967)
			(xy 347.710701 -234.076897) (xy 347.718644 -234.129601) (xy 347.719142 -234.15625) (xy 347.718644 -234.182899)
			(xy 347.947224 -234.182899) (xy 347.947224 -234.129601) (xy 347.955167 -234.076897) (xy 347.970877 -234.025967)
			(xy 347.994003 -233.977946) (xy 348.024027 -233.933909) (xy 348.060279 -233.894838) (xy 348.10195 -233.861607)
			(xy 348.148108 -233.834958) (xy 348.197722 -233.815486) (xy 348.249684 -233.803626) (xy 348.302834 -233.799643)
			(xy 348.355984 -233.803626) (xy 348.407946 -233.815486) (xy 348.45756 -233.834958) (xy 348.503718 -233.861607)
			(xy 348.545389 -233.894838) (xy 348.581641 -233.933909) (xy 348.611665 -233.977946) (xy 348.634791 -234.025967)
			(xy 348.650501 -234.076897) (xy 348.658444 -234.129601) (xy 348.658942 -234.15625) (xy 348.658444 -234.182899)
			(xy 348.88677 -234.182899) (xy 348.88677 -234.129601) (xy 348.894713 -234.076897) (xy 348.910423 -234.025967)
			(xy 348.933549 -233.977946) (xy 348.963573 -233.933909) (xy 348.999825 -233.894838) (xy 349.041496 -233.861607)
			(xy 349.087654 -233.834958) (xy 349.137268 -233.815486) (xy 349.18923 -233.803626) (xy 349.24238 -233.799643)
			(xy 349.29553 -233.803626) (xy 349.347492 -233.815486) (xy 349.397106 -233.834958) (xy 349.443264 -233.861607)
			(xy 349.484935 -233.894838) (xy 349.521187 -233.933909) (xy 349.551211 -233.977946) (xy 349.574337 -234.025967)
			(xy 349.590047 -234.076897) (xy 349.59799 -234.129601) (xy 349.598488 -234.15625) (xy 349.59799 -234.182899)
			(xy 349.590047 -234.235603) (xy 349.574337 -234.286533) (xy 349.551211 -234.334554) (xy 349.521187 -234.378591)
			(xy 349.484935 -234.417662) (xy 349.443264 -234.450893) (xy 349.397106 -234.477542) (xy 349.347492 -234.497014)
			(xy 349.29553 -234.508874) (xy 349.24238 -234.512858) (xy 349.18923 -234.508874) (xy 349.137268 -234.497014)
			(xy 349.087654 -234.477542) (xy 349.041496 -234.450893) (xy 348.999825 -234.417662) (xy 348.963573 -234.378591)
			(xy 348.933549 -234.334554) (xy 348.910423 -234.286533) (xy 348.894713 -234.235603) (xy 348.88677 -234.182899)
			(xy 348.658444 -234.182899) (xy 348.650501 -234.235603) (xy 348.634791 -234.286533) (xy 348.611665 -234.334554)
			(xy 348.581641 -234.378591) (xy 348.545389 -234.417662) (xy 348.503718 -234.450893) (xy 348.45756 -234.477542)
			(xy 348.407946 -234.497014) (xy 348.355984 -234.508874) (xy 348.302834 -234.512858) (xy 348.249684 -234.508874)
			(xy 348.197722 -234.497014) (xy 348.148108 -234.477542) (xy 348.10195 -234.450893) (xy 348.060279 -234.417662)
			(xy 348.024027 -234.378591) (xy 347.994003 -234.334554) (xy 347.970877 -234.286533) (xy 347.955167 -234.235603)
			(xy 347.947224 -234.182899) (xy 347.718644 -234.182899) (xy 347.710701 -234.235603) (xy 347.694991 -234.286533)
			(xy 347.671865 -234.334554) (xy 347.641841 -234.378591) (xy 347.605589 -234.417662) (xy 347.563918 -234.450893)
			(xy 347.51776 -234.477542) (xy 347.468146 -234.497014) (xy 347.416184 -234.508874) (xy 347.363034 -234.512858)
			(xy 347.309884 -234.508874) (xy 347.257922 -234.497014) (xy 347.208308 -234.477542) (xy 347.16215 -234.450893)
			(xy 347.120479 -234.417662) (xy 347.084227 -234.378591) (xy 347.054203 -234.334554) (xy 347.031077 -234.286533)
			(xy 347.015367 -234.235603) (xy 347.007424 -234.182899) (xy 346.778844 -234.182899) (xy 346.770901 -234.235603)
			(xy 346.755191 -234.286533) (xy 346.732065 -234.334554) (xy 346.702041 -234.378591) (xy 346.665789 -234.417662)
			(xy 346.624118 -234.450893) (xy 346.57796 -234.477542) (xy 346.528346 -234.497014) (xy 346.476384 -234.508874)
			(xy 346.423234 -234.512858) (xy 346.370084 -234.508874) (xy 346.318122 -234.497014) (xy 346.268508 -234.477542)
			(xy 346.22235 -234.450893) (xy 346.180679 -234.417662) (xy 346.144427 -234.378591) (xy 346.114403 -234.334554)
			(xy 346.091277 -234.286533) (xy 346.075567 -234.235603) (xy 346.067624 -234.182899) (xy 345.839044 -234.182899)
			(xy 345.831101 -234.235603) (xy 345.815391 -234.286533) (xy 345.792265 -234.334554) (xy 345.762241 -234.378591)
			(xy 345.725989 -234.417662) (xy 345.684318 -234.450893) (xy 345.63816 -234.477542) (xy 345.588546 -234.497014)
			(xy 345.536584 -234.508874) (xy 345.483434 -234.512858) (xy 345.430284 -234.508874) (xy 345.378322 -234.497014)
			(xy 345.328708 -234.477542) (xy 345.28255 -234.450893) (xy 345.240879 -234.417662) (xy 345.204627 -234.378591)
			(xy 345.174603 -234.334554) (xy 345.151477 -234.286533) (xy 345.135767 -234.235603) (xy 345.127824 -234.182899)
			(xy 344.899244 -234.182899) (xy 344.891301 -234.235603) (xy 344.875591 -234.286533) (xy 344.852465 -234.334554)
			(xy 344.822441 -234.378591) (xy 344.786189 -234.417662) (xy 344.744518 -234.450893) (xy 344.69836 -234.477542)
			(xy 344.648746 -234.497014) (xy 344.596784 -234.508874) (xy 344.543634 -234.512858) (xy 344.490484 -234.508874)
			(xy 344.438522 -234.497014) (xy 344.388908 -234.477542) (xy 344.34275 -234.450893) (xy 344.301079 -234.417662)
			(xy 344.264827 -234.378591) (xy 344.234803 -234.334554) (xy 344.211677 -234.286533) (xy 344.195967 -234.235603)
			(xy 344.188024 -234.182899) (xy 343.959444 -234.182899) (xy 343.951501 -234.235603) (xy 343.935791 -234.286533)
			(xy 343.912665 -234.334554) (xy 343.882641 -234.378591) (xy 343.846389 -234.417662) (xy 343.804718 -234.450893)
			(xy 343.75856 -234.477542) (xy 343.708946 -234.497014) (xy 343.656984 -234.508874) (xy 343.603834 -234.512858)
			(xy 343.550684 -234.508874) (xy 343.498722 -234.497014) (xy 343.449108 -234.477542) (xy 343.40295 -234.450893)
			(xy 343.361279 -234.417662) (xy 343.325027 -234.378591) (xy 343.295003 -234.334554) (xy 343.271877 -234.286533)
			(xy 343.256167 -234.235603) (xy 343.248224 -234.182899) (xy 343.01939 -234.182899) (xy 343.011447 -234.235603)
			(xy 342.995737 -234.286533) (xy 342.972611 -234.334554) (xy 342.942587 -234.378591) (xy 342.906335 -234.417662)
			(xy 342.864664 -234.450893) (xy 342.818506 -234.477542) (xy 342.768892 -234.497014) (xy 342.71693 -234.508874)
			(xy 342.66378 -234.512858) (xy 342.61063 -234.508874) (xy 342.558668 -234.497014) (xy 342.509054 -234.477542)
			(xy 342.462896 -234.450893) (xy 342.421225 -234.417662) (xy 342.384973 -234.378591) (xy 342.354949 -234.334554)
			(xy 342.331823 -234.286533) (xy 342.316113 -234.235603) (xy 342.30817 -234.182899) (xy 342.079844 -234.182899)
			(xy 342.071901 -234.235603) (xy 342.056191 -234.286533) (xy 342.033065 -234.334554) (xy 342.003041 -234.378591)
			(xy 341.966789 -234.417662) (xy 341.925118 -234.450893) (xy 341.87896 -234.477542) (xy 341.829346 -234.497014)
			(xy 341.777384 -234.508874) (xy 341.724234 -234.512858) (xy 341.671084 -234.508874) (xy 341.619122 -234.497014)
			(xy 341.569508 -234.477542) (xy 341.52335 -234.450893) (xy 341.481679 -234.417662) (xy 341.445427 -234.378591)
			(xy 341.415403 -234.334554) (xy 341.392277 -234.286533) (xy 341.376567 -234.235603) (xy 341.368624 -234.182899)
			(xy 341.140044 -234.182899) (xy 341.132101 -234.235603) (xy 341.116391 -234.286533) (xy 341.093265 -234.334554)
			(xy 341.063241 -234.378591) (xy 341.026989 -234.417662) (xy 340.985318 -234.450893) (xy 340.93916 -234.477542)
			(xy 340.889546 -234.497014) (xy 340.837584 -234.508874) (xy 340.784434 -234.512858) (xy 340.731284 -234.508874)
			(xy 340.679322 -234.497014) (xy 340.629708 -234.477542) (xy 340.58355 -234.450893) (xy 340.541879 -234.417662)
			(xy 340.505627 -234.378591) (xy 340.475603 -234.334554) (xy 340.452477 -234.286533) (xy 340.436767 -234.235603)
			(xy 340.428824 -234.182899) (xy 340.200244 -234.182899) (xy 340.192301 -234.235603) (xy 340.176591 -234.286533)
			(xy 340.153465 -234.334554) (xy 340.123441 -234.378591) (xy 340.087189 -234.417662) (xy 340.045518 -234.450893)
			(xy 339.99936 -234.477542) (xy 339.949746 -234.497014) (xy 339.897784 -234.508874) (xy 339.844634 -234.512858)
			(xy 339.791484 -234.508874) (xy 339.739522 -234.497014) (xy 339.689908 -234.477542) (xy 339.64375 -234.450893)
			(xy 339.602079 -234.417662) (xy 339.565827 -234.378591) (xy 339.535803 -234.334554) (xy 339.512677 -234.286533)
			(xy 339.496967 -234.235603) (xy 339.489024 -234.182899) (xy 339.260444 -234.182899) (xy 339.252501 -234.235603)
			(xy 339.236791 -234.286533) (xy 339.213665 -234.334554) (xy 339.183641 -234.378591) (xy 339.147389 -234.417662)
			(xy 339.105718 -234.450893) (xy 339.05956 -234.477542) (xy 339.009946 -234.497014) (xy 338.957984 -234.508874)
			(xy 338.904834 -234.512858) (xy 338.851684 -234.508874) (xy 338.799722 -234.497014) (xy 338.750108 -234.477542)
			(xy 338.70395 -234.450893) (xy 338.662279 -234.417662) (xy 338.626027 -234.378591) (xy 338.596003 -234.334554)
			(xy 338.572877 -234.286533) (xy 338.557167 -234.235603) (xy 338.549224 -234.182899) (xy 338.320644 -234.182899)
			(xy 338.312701 -234.235603) (xy 338.296991 -234.286533) (xy 338.273865 -234.334554) (xy 338.243841 -234.378591)
			(xy 338.207589 -234.417662) (xy 338.165918 -234.450893) (xy 338.11976 -234.477542) (xy 338.070146 -234.497014)
			(xy 338.018184 -234.508874) (xy 337.965034 -234.512858) (xy 337.911884 -234.508874) (xy 337.859922 -234.497014)
			(xy 337.810308 -234.477542) (xy 337.76415 -234.450893) (xy 337.722479 -234.417662) (xy 337.686227 -234.378591)
			(xy 337.656203 -234.334554) (xy 337.633077 -234.286533) (xy 337.617367 -234.235603) (xy 337.609424 -234.182899)
			(xy 337.379756 -234.182899) (xy 337.377775 -234.209339) (xy 337.365918 -234.261291) (xy 337.346451 -234.310896)
			(xy 337.319809 -234.357045) (xy 337.286586 -234.398708) (xy 337.247525 -234.434955) (xy 337.203498 -234.464976)
			(xy 337.155489 -234.4881) (xy 337.10457 -234.503811) (xy 337.051878 -234.511758) (xy 337.025234 -234.512358)
			(xy 337.000539 -234.511959) (xy 336.951616 -234.505175) (xy 336.904103 -234.49169) (xy 336.85891 -234.471765)
			(xy 336.816907 -234.445781) (xy 336.79765 -234.430316) (xy 336.786264 -234.421538) (xy 336.759894 -234.410118)
			(xy 336.731386 -234.406497) (xy 336.702998 -234.410962) (xy 336.676978 -234.423159) (xy 336.655387 -234.442124)
			(xy 336.639935 -234.466352) (xy 336.631845 -234.493927) (xy 336.63128 -234.508294) (xy 336.63128 -234.620308)
			(xy 336.666332 -234.631738) (xy 336.69114 -234.640387) (xy 336.738098 -234.663948) (xy 336.781086 -234.694151)
			(xy 336.81917 -234.730341) (xy 336.851526 -234.771733) (xy 336.877449 -234.817429) (xy 336.896379 -234.866438)
			(xy 336.907905 -234.917695) (xy 336.911776 -234.970089) (xy 336.90981 -234.996715) (xy 337.13927 -234.996715)
			(xy 337.13927 -234.943417) (xy 337.147213 -234.890713) (xy 337.162923 -234.839783) (xy 337.186049 -234.791762)
			(xy 337.216073 -234.747725) (xy 337.252325 -234.708654) (xy 337.293996 -234.675423) (xy 337.340154 -234.648774)
			(xy 337.389768 -234.629302) (xy 337.44173 -234.617442) (xy 337.49488 -234.613459) (xy 337.54803 -234.617442)
			(xy 337.599992 -234.629302) (xy 337.649606 -234.648774) (xy 337.695764 -234.675423) (xy 337.737435 -234.708654)
			(xy 337.773687 -234.747725) (xy 337.803711 -234.791762) (xy 337.826837 -234.839783) (xy 337.842547 -234.890713)
			(xy 337.85049 -234.943417) (xy 337.850988 -234.970066) (xy 337.85049 -234.996715) (xy 338.079324 -234.996715)
			(xy 338.079324 -234.943417) (xy 338.087267 -234.890713) (xy 338.102977 -234.839783) (xy 338.126103 -234.791762)
			(xy 338.156127 -234.747725) (xy 338.192379 -234.708654) (xy 338.23405 -234.675423) (xy 338.280208 -234.648774)
			(xy 338.329822 -234.629302) (xy 338.381784 -234.617442) (xy 338.434934 -234.613459) (xy 338.488084 -234.617442)
			(xy 338.540046 -234.629302) (xy 338.58966 -234.648774) (xy 338.635818 -234.675423) (xy 338.677489 -234.708654)
			(xy 338.713741 -234.747725) (xy 338.743765 -234.791762) (xy 338.766891 -234.839783) (xy 338.782601 -234.890713)
			(xy 338.790544 -234.943417) (xy 338.791042 -234.970066) (xy 338.790544 -234.996715) (xy 339.01887 -234.996715)
			(xy 339.01887 -234.943417) (xy 339.026813 -234.890713) (xy 339.042523 -234.839783) (xy 339.065649 -234.791762)
			(xy 339.095673 -234.747725) (xy 339.131925 -234.708654) (xy 339.173596 -234.675423) (xy 339.219754 -234.648774)
			(xy 339.269368 -234.629302) (xy 339.32133 -234.617442) (xy 339.37448 -234.613459) (xy 339.42763 -234.617442)
			(xy 339.479592 -234.629302) (xy 339.529206 -234.648774) (xy 339.575364 -234.675423) (xy 339.617035 -234.708654)
			(xy 339.653287 -234.747725) (xy 339.683311 -234.791762) (xy 339.706437 -234.839783) (xy 339.722147 -234.890713)
			(xy 339.73009 -234.943417) (xy 339.730588 -234.970066) (xy 339.73009 -234.996715) (xy 339.95867 -234.996715)
			(xy 339.95867 -234.943417) (xy 339.966613 -234.890713) (xy 339.982323 -234.839783) (xy 340.005449 -234.791762)
			(xy 340.035473 -234.747725) (xy 340.071725 -234.708654) (xy 340.113396 -234.675423) (xy 340.159554 -234.648774)
			(xy 340.209168 -234.629302) (xy 340.26113 -234.617442) (xy 340.31428 -234.613459) (xy 340.36743 -234.617442)
			(xy 340.419392 -234.629302) (xy 340.469006 -234.648774) (xy 340.515164 -234.675423) (xy 340.556835 -234.708654)
			(xy 340.593087 -234.747725) (xy 340.623111 -234.791762) (xy 340.646237 -234.839783) (xy 340.661947 -234.890713)
			(xy 340.66989 -234.943417) (xy 340.670388 -234.970066) (xy 340.66989 -234.996715) (xy 340.89847 -234.996715)
			(xy 340.89847 -234.943417) (xy 340.906413 -234.890713) (xy 340.922123 -234.839783) (xy 340.945249 -234.791762)
			(xy 340.975273 -234.747725) (xy 341.011525 -234.708654) (xy 341.053196 -234.675423) (xy 341.099354 -234.648774)
			(xy 341.148968 -234.629302) (xy 341.20093 -234.617442) (xy 341.25408 -234.613459) (xy 341.30723 -234.617442)
			(xy 341.359192 -234.629302) (xy 341.408806 -234.648774) (xy 341.454964 -234.675423) (xy 341.496635 -234.708654)
			(xy 341.532887 -234.747725) (xy 341.562911 -234.791762) (xy 341.586037 -234.839783) (xy 341.601747 -234.890713)
			(xy 341.60969 -234.943417) (xy 341.610188 -234.970066) (xy 341.60969 -234.996715) (xy 341.83827 -234.996715)
			(xy 341.83827 -234.943417) (xy 341.846213 -234.890713) (xy 341.861923 -234.839783) (xy 341.885049 -234.791762)
			(xy 341.915073 -234.747725) (xy 341.951325 -234.708654) (xy 341.992996 -234.675423) (xy 342.039154 -234.648774)
			(xy 342.088768 -234.629302) (xy 342.14073 -234.617442) (xy 342.19388 -234.613459) (xy 342.24703 -234.617442)
			(xy 342.298992 -234.629302) (xy 342.348606 -234.648774) (xy 342.394764 -234.675423) (xy 342.436435 -234.708654)
			(xy 342.472687 -234.747725) (xy 342.502711 -234.791762) (xy 342.525837 -234.839783) (xy 342.541547 -234.890713)
			(xy 342.54949 -234.943417) (xy 342.549988 -234.970066) (xy 342.54949 -234.996715) (xy 342.77807 -234.996715)
			(xy 342.77807 -234.943417) (xy 342.786013 -234.890713) (xy 342.801723 -234.839783) (xy 342.824849 -234.791762)
			(xy 342.854873 -234.747725) (xy 342.891125 -234.708654) (xy 342.932796 -234.675423) (xy 342.978954 -234.648774)
			(xy 343.028568 -234.629302) (xy 343.08053 -234.617442) (xy 343.13368 -234.613459) (xy 343.18683 -234.617442)
			(xy 343.238792 -234.629302) (xy 343.288406 -234.648774) (xy 343.334564 -234.675423) (xy 343.376235 -234.708654)
			(xy 343.412487 -234.747725) (xy 343.442511 -234.791762) (xy 343.465637 -234.839783) (xy 343.481347 -234.890713)
			(xy 343.48929 -234.943417) (xy 343.489788 -234.970066) (xy 343.48929 -234.996715) (xy 343.71787 -234.996715)
			(xy 343.71787 -234.943417) (xy 343.725813 -234.890713) (xy 343.741523 -234.839783) (xy 343.764649 -234.791762)
			(xy 343.794673 -234.747725) (xy 343.830925 -234.708654) (xy 343.872596 -234.675423) (xy 343.918754 -234.648774)
			(xy 343.968368 -234.629302) (xy 344.02033 -234.617442) (xy 344.07348 -234.613459) (xy 344.12663 -234.617442)
			(xy 344.178592 -234.629302) (xy 344.228206 -234.648774) (xy 344.274364 -234.675423) (xy 344.316035 -234.708654)
			(xy 344.352287 -234.747725) (xy 344.382311 -234.791762) (xy 344.405437 -234.839783) (xy 344.421147 -234.890713)
			(xy 344.42909 -234.943417) (xy 344.429588 -234.970066) (xy 344.42909 -234.996715) (xy 344.657924 -234.996715)
			(xy 344.657924 -234.943417) (xy 344.665867 -234.890713) (xy 344.681577 -234.839783) (xy 344.704703 -234.791762)
			(xy 344.734727 -234.747725) (xy 344.770979 -234.708654) (xy 344.81265 -234.675423) (xy 344.858808 -234.648774)
			(xy 344.908422 -234.629302) (xy 344.960384 -234.617442) (xy 345.013534 -234.613459) (xy 345.066684 -234.617442)
			(xy 345.118646 -234.629302) (xy 345.16826 -234.648774) (xy 345.214418 -234.675423) (xy 345.256089 -234.708654)
			(xy 345.292341 -234.747725) (xy 345.322365 -234.791762) (xy 345.345491 -234.839783) (xy 345.361201 -234.890713)
			(xy 345.369144 -234.943417) (xy 345.369642 -234.970066) (xy 345.369144 -234.996715) (xy 345.59747 -234.996715)
			(xy 345.59747 -234.943417) (xy 345.605413 -234.890713) (xy 345.621123 -234.839783) (xy 345.644249 -234.791762)
			(xy 345.674273 -234.747725) (xy 345.710525 -234.708654) (xy 345.752196 -234.675423) (xy 345.798354 -234.648774)
			(xy 345.847968 -234.629302) (xy 345.89993 -234.617442) (xy 345.95308 -234.613459) (xy 346.00623 -234.617442)
			(xy 346.058192 -234.629302) (xy 346.107806 -234.648774) (xy 346.153964 -234.675423) (xy 346.195635 -234.708654)
			(xy 346.231887 -234.747725) (xy 346.261911 -234.791762) (xy 346.285037 -234.839783) (xy 346.300747 -234.890713)
			(xy 346.30869 -234.943417) (xy 346.309188 -234.970066) (xy 346.30869 -234.996715) (xy 346.53727 -234.996715)
			(xy 346.53727 -234.943417) (xy 346.545213 -234.890713) (xy 346.560923 -234.839783) (xy 346.584049 -234.791762)
			(xy 346.614073 -234.747725) (xy 346.650325 -234.708654) (xy 346.691996 -234.675423) (xy 346.738154 -234.648774)
			(xy 346.787768 -234.629302) (xy 346.83973 -234.617442) (xy 346.89288 -234.613459) (xy 346.94603 -234.617442)
			(xy 346.997992 -234.629302) (xy 347.047606 -234.648774) (xy 347.093764 -234.675423) (xy 347.135435 -234.708654)
			(xy 347.171687 -234.747725) (xy 347.201711 -234.791762) (xy 347.224837 -234.839783) (xy 347.240547 -234.890713)
			(xy 347.24849 -234.943417) (xy 347.248988 -234.970066) (xy 347.24849 -234.996715) (xy 347.47707 -234.996715)
			(xy 347.47707 -234.943417) (xy 347.485013 -234.890713) (xy 347.500723 -234.839783) (xy 347.523849 -234.791762)
			(xy 347.553873 -234.747725) (xy 347.590125 -234.708654) (xy 347.631796 -234.675423) (xy 347.677954 -234.648774)
			(xy 347.727568 -234.629302) (xy 347.77953 -234.617442) (xy 347.83268 -234.613459) (xy 347.88583 -234.617442)
			(xy 347.937792 -234.629302) (xy 347.987406 -234.648774) (xy 348.033564 -234.675423) (xy 348.075235 -234.708654)
			(xy 348.111487 -234.747725) (xy 348.141511 -234.791762) (xy 348.164637 -234.839783) (xy 348.180347 -234.890713)
			(xy 348.18829 -234.943417) (xy 348.188788 -234.970066) (xy 348.18829 -234.996715) (xy 348.180347 -235.049419)
			(xy 348.164637 -235.100349) (xy 348.141511 -235.14837) (xy 348.111487 -235.192407) (xy 348.075235 -235.231478)
			(xy 348.033564 -235.264709) (xy 347.987406 -235.291358) (xy 347.937792 -235.31083) (xy 347.88583 -235.32269)
			(xy 347.83268 -235.326674) (xy 347.77953 -235.32269) (xy 347.727568 -235.31083) (xy 347.677954 -235.291358)
			(xy 347.631796 -235.264709) (xy 347.590125 -235.231478) (xy 347.553873 -235.192407) (xy 347.523849 -235.14837)
			(xy 347.500723 -235.100349) (xy 347.485013 -235.049419) (xy 347.47707 -234.996715) (xy 347.24849 -234.996715)
			(xy 347.240547 -235.049419) (xy 347.224837 -235.100349) (xy 347.201711 -235.14837) (xy 347.171687 -235.192407)
			(xy 347.135435 -235.231478) (xy 347.093764 -235.264709) (xy 347.047606 -235.291358) (xy 346.997992 -235.31083)
			(xy 346.94603 -235.32269) (xy 346.89288 -235.326674) (xy 346.83973 -235.32269) (xy 346.787768 -235.31083)
			(xy 346.738154 -235.291358) (xy 346.691996 -235.264709) (xy 346.650325 -235.231478) (xy 346.614073 -235.192407)
			(xy 346.584049 -235.14837) (xy 346.560923 -235.100349) (xy 346.545213 -235.049419) (xy 346.53727 -234.996715)
			(xy 346.30869 -234.996715) (xy 346.300747 -235.049419) (xy 346.285037 -235.100349) (xy 346.261911 -235.14837)
			(xy 346.231887 -235.192407) (xy 346.195635 -235.231478) (xy 346.153964 -235.264709) (xy 346.107806 -235.291358)
			(xy 346.058192 -235.31083) (xy 346.00623 -235.32269) (xy 345.95308 -235.326674) (xy 345.89993 -235.32269)
			(xy 345.847968 -235.31083) (xy 345.798354 -235.291358) (xy 345.752196 -235.264709) (xy 345.710525 -235.231478)
			(xy 345.674273 -235.192407) (xy 345.644249 -235.14837) (xy 345.621123 -235.100349) (xy 345.605413 -235.049419)
			(xy 345.59747 -234.996715) (xy 345.369144 -234.996715) (xy 345.361201 -235.049419) (xy 345.345491 -235.100349)
			(xy 345.322365 -235.14837) (xy 345.292341 -235.192407) (xy 345.256089 -235.231478) (xy 345.214418 -235.264709)
			(xy 345.16826 -235.291358) (xy 345.118646 -235.31083) (xy 345.066684 -235.32269) (xy 345.013534 -235.326674)
			(xy 344.960384 -235.32269) (xy 344.908422 -235.31083) (xy 344.858808 -235.291358) (xy 344.81265 -235.264709)
			(xy 344.770979 -235.231478) (xy 344.734727 -235.192407) (xy 344.704703 -235.14837) (xy 344.681577 -235.100349)
			(xy 344.665867 -235.049419) (xy 344.657924 -234.996715) (xy 344.42909 -234.996715) (xy 344.421147 -235.049419)
			(xy 344.405437 -235.100349) (xy 344.382311 -235.14837) (xy 344.352287 -235.192407) (xy 344.316035 -235.231478)
			(xy 344.274364 -235.264709) (xy 344.228206 -235.291358) (xy 344.178592 -235.31083) (xy 344.12663 -235.32269)
			(xy 344.07348 -235.326674) (xy 344.02033 -235.32269) (xy 343.968368 -235.31083) (xy 343.918754 -235.291358)
			(xy 343.872596 -235.264709) (xy 343.830925 -235.231478) (xy 343.794673 -235.192407) (xy 343.764649 -235.14837)
			(xy 343.741523 -235.100349) (xy 343.725813 -235.049419) (xy 343.71787 -234.996715) (xy 343.48929 -234.996715)
			(xy 343.481347 -235.049419) (xy 343.465637 -235.100349) (xy 343.442511 -235.14837) (xy 343.412487 -235.192407)
			(xy 343.376235 -235.231478) (xy 343.334564 -235.264709) (xy 343.288406 -235.291358) (xy 343.238792 -235.31083)
			(xy 343.18683 -235.32269) (xy 343.13368 -235.326674) (xy 343.08053 -235.32269) (xy 343.028568 -235.31083)
			(xy 342.978954 -235.291358) (xy 342.932796 -235.264709) (xy 342.891125 -235.231478) (xy 342.854873 -235.192407)
			(xy 342.824849 -235.14837) (xy 342.801723 -235.100349) (xy 342.786013 -235.049419) (xy 342.77807 -234.996715)
			(xy 342.54949 -234.996715) (xy 342.541547 -235.049419) (xy 342.525837 -235.100349) (xy 342.502711 -235.14837)
			(xy 342.472687 -235.192407) (xy 342.436435 -235.231478) (xy 342.394764 -235.264709) (xy 342.348606 -235.291358)
			(xy 342.298992 -235.31083) (xy 342.24703 -235.32269) (xy 342.19388 -235.326674) (xy 342.14073 -235.32269)
			(xy 342.088768 -235.31083) (xy 342.039154 -235.291358) (xy 341.992996 -235.264709) (xy 341.951325 -235.231478)
			(xy 341.915073 -235.192407) (xy 341.885049 -235.14837) (xy 341.861923 -235.100349) (xy 341.846213 -235.049419)
			(xy 341.83827 -234.996715) (xy 341.60969 -234.996715) (xy 341.601747 -235.049419) (xy 341.586037 -235.100349)
			(xy 341.562911 -235.14837) (xy 341.532887 -235.192407) (xy 341.496635 -235.231478) (xy 341.454964 -235.264709)
			(xy 341.408806 -235.291358) (xy 341.359192 -235.31083) (xy 341.30723 -235.32269) (xy 341.25408 -235.326674)
			(xy 341.20093 -235.32269) (xy 341.148968 -235.31083) (xy 341.099354 -235.291358) (xy 341.053196 -235.264709)
			(xy 341.011525 -235.231478) (xy 340.975273 -235.192407) (xy 340.945249 -235.14837) (xy 340.922123 -235.100349)
			(xy 340.906413 -235.049419) (xy 340.89847 -234.996715) (xy 340.66989 -234.996715) (xy 340.661947 -235.049419)
			(xy 340.646237 -235.100349) (xy 340.623111 -235.14837) (xy 340.593087 -235.192407) (xy 340.556835 -235.231478)
			(xy 340.515164 -235.264709) (xy 340.469006 -235.291358) (xy 340.419392 -235.31083) (xy 340.36743 -235.32269)
			(xy 340.31428 -235.326674) (xy 340.26113 -235.32269) (xy 340.209168 -235.31083) (xy 340.159554 -235.291358)
			(xy 340.113396 -235.264709) (xy 340.071725 -235.231478) (xy 340.035473 -235.192407) (xy 340.005449 -235.14837)
			(xy 339.982323 -235.100349) (xy 339.966613 -235.049419) (xy 339.95867 -234.996715) (xy 339.73009 -234.996715)
			(xy 339.722147 -235.049419) (xy 339.706437 -235.100349) (xy 339.683311 -235.14837) (xy 339.653287 -235.192407)
			(xy 339.617035 -235.231478) (xy 339.575364 -235.264709) (xy 339.529206 -235.291358) (xy 339.479592 -235.31083)
			(xy 339.42763 -235.32269) (xy 339.37448 -235.326674) (xy 339.32133 -235.32269) (xy 339.269368 -235.31083)
			(xy 339.219754 -235.291358) (xy 339.173596 -235.264709) (xy 339.131925 -235.231478) (xy 339.095673 -235.192407)
			(xy 339.065649 -235.14837) (xy 339.042523 -235.100349) (xy 339.026813 -235.049419) (xy 339.01887 -234.996715)
			(xy 338.790544 -234.996715) (xy 338.782601 -235.049419) (xy 338.766891 -235.100349) (xy 338.743765 -235.14837)
			(xy 338.713741 -235.192407) (xy 338.677489 -235.231478) (xy 338.635818 -235.264709) (xy 338.58966 -235.291358)
			(xy 338.540046 -235.31083) (xy 338.488084 -235.32269) (xy 338.434934 -235.326674) (xy 338.381784 -235.32269)
			(xy 338.329822 -235.31083) (xy 338.280208 -235.291358) (xy 338.23405 -235.264709) (xy 338.192379 -235.231478)
			(xy 338.156127 -235.192407) (xy 338.126103 -235.14837) (xy 338.102977 -235.100349) (xy 338.087267 -235.049419)
			(xy 338.079324 -234.996715) (xy 337.85049 -234.996715) (xy 337.842547 -235.049419) (xy 337.826837 -235.100349)
			(xy 337.803711 -235.14837) (xy 337.773687 -235.192407) (xy 337.737435 -235.231478) (xy 337.695764 -235.264709)
			(xy 337.649606 -235.291358) (xy 337.599992 -235.31083) (xy 337.54803 -235.32269) (xy 337.49488 -235.326674)
			(xy 337.44173 -235.32269) (xy 337.389768 -235.31083) (xy 337.340154 -235.291358) (xy 337.293996 -235.264709)
			(xy 337.252325 -235.231478) (xy 337.216073 -235.192407) (xy 337.186049 -235.14837) (xy 337.162923 -235.100349)
			(xy 337.147213 -235.049419) (xy 337.13927 -234.996715) (xy 336.90981 -234.996715) (xy 336.907908 -235.022484)
			(xy 336.896385 -235.073742) (xy 336.877458 -235.122752) (xy 336.851537 -235.168449) (xy 336.819185 -235.209843)
			(xy 336.781102 -235.246036) (xy 336.738117 -235.276241) (xy 336.69116 -235.299805) (xy 336.666332 -235.308394)
			(xy 336.63128 -235.319824) (xy 336.63128 -235.431838) (xy 336.631809 -235.446207) (xy 336.639887 -235.473788)
			(xy 336.655336 -235.498023) (xy 336.67693 -235.516988) (xy 336.702955 -235.52918) (xy 336.731349 -235.533632)
			(xy 336.759857 -235.52999) (xy 336.786219 -235.518543) (xy 336.79765 -235.509816) (xy 336.816926 -235.494378)
			(xy 336.858931 -235.468405) (xy 336.904119 -235.448483) (xy 336.951626 -235.434991) (xy 337.000541 -235.42819)
			(xy 337.025234 -235.427774) (xy 337.051883 -235.428274) (xy 337.104585 -235.436222) (xy 337.155514 -235.451936)
			(xy 337.203532 -235.475065) (xy 337.247568 -235.505091) (xy 337.286636 -235.541345) (xy 337.319865 -235.583016)
			(xy 337.346513 -235.629175) (xy 337.365984 -235.678789) (xy 337.377843 -235.730751) (xy 337.381826 -235.7839)
			(xy 337.37983 -235.810531) (xy 337.609424 -235.810531) (xy 337.609424 -235.757233) (xy 337.617367 -235.704529)
			(xy 337.633077 -235.653599) (xy 337.656203 -235.605578) (xy 337.686227 -235.561541) (xy 337.722479 -235.52247)
			(xy 337.76415 -235.489239) (xy 337.810308 -235.46259) (xy 337.859922 -235.443118) (xy 337.911884 -235.431258)
			(xy 337.965034 -235.427275) (xy 338.018184 -235.431258) (xy 338.070146 -235.443118) (xy 338.11976 -235.46259)
			(xy 338.165918 -235.489239) (xy 338.207589 -235.52247) (xy 338.243841 -235.561541) (xy 338.273865 -235.605578)
			(xy 338.296991 -235.653599) (xy 338.312701 -235.704529) (xy 338.320644 -235.757233) (xy 338.321142 -235.783882)
			(xy 338.320644 -235.810531) (xy 338.54897 -235.810531) (xy 338.54897 -235.757233) (xy 338.556913 -235.704529)
			(xy 338.572623 -235.653599) (xy 338.595749 -235.605578) (xy 338.625773 -235.561541) (xy 338.662025 -235.52247)
			(xy 338.703696 -235.489239) (xy 338.749854 -235.46259) (xy 338.799468 -235.443118) (xy 338.85143 -235.431258)
			(xy 338.90458 -235.427275) (xy 338.95773 -235.431258) (xy 339.009692 -235.443118) (xy 339.059306 -235.46259)
			(xy 339.105464 -235.489239) (xy 339.147135 -235.52247) (xy 339.183387 -235.561541) (xy 339.213411 -235.605578)
			(xy 339.236537 -235.653599) (xy 339.252247 -235.704529) (xy 339.26019 -235.757233) (xy 339.260688 -235.783882)
			(xy 339.26019 -235.810531) (xy 339.489024 -235.810531) (xy 339.489024 -235.757233) (xy 339.496967 -235.704529)
			(xy 339.512677 -235.653599) (xy 339.535803 -235.605578) (xy 339.565827 -235.561541) (xy 339.602079 -235.52247)
			(xy 339.64375 -235.489239) (xy 339.689908 -235.46259) (xy 339.739522 -235.443118) (xy 339.791484 -235.431258)
			(xy 339.844634 -235.427275) (xy 339.897784 -235.431258) (xy 339.949746 -235.443118) (xy 339.99936 -235.46259)
			(xy 340.045518 -235.489239) (xy 340.087189 -235.52247) (xy 340.123441 -235.561541) (xy 340.153465 -235.605578)
			(xy 340.176591 -235.653599) (xy 340.192301 -235.704529) (xy 340.200244 -235.757233) (xy 340.200742 -235.783882)
			(xy 340.200244 -235.810531) (xy 340.428824 -235.810531) (xy 340.428824 -235.757233) (xy 340.436767 -235.704529)
			(xy 340.452477 -235.653599) (xy 340.475603 -235.605578) (xy 340.505627 -235.561541) (xy 340.541879 -235.52247)
			(xy 340.58355 -235.489239) (xy 340.629708 -235.46259) (xy 340.679322 -235.443118) (xy 340.731284 -235.431258)
			(xy 340.784434 -235.427275) (xy 340.837584 -235.431258) (xy 340.889546 -235.443118) (xy 340.93916 -235.46259)
			(xy 340.985318 -235.489239) (xy 341.026989 -235.52247) (xy 341.063241 -235.561541) (xy 341.093265 -235.605578)
			(xy 341.116391 -235.653599) (xy 341.132101 -235.704529) (xy 341.140044 -235.757233) (xy 341.140542 -235.783882)
			(xy 341.140044 -235.810531) (xy 341.368624 -235.810531) (xy 341.368624 -235.757233) (xy 341.376567 -235.704529)
			(xy 341.392277 -235.653599) (xy 341.415403 -235.605578) (xy 341.445427 -235.561541) (xy 341.481679 -235.52247)
			(xy 341.52335 -235.489239) (xy 341.569508 -235.46259) (xy 341.619122 -235.443118) (xy 341.671084 -235.431258)
			(xy 341.724234 -235.427275) (xy 341.777384 -235.431258) (xy 341.829346 -235.443118) (xy 341.87896 -235.46259)
			(xy 341.925118 -235.489239) (xy 341.966789 -235.52247) (xy 342.003041 -235.561541) (xy 342.033065 -235.605578)
			(xy 342.056191 -235.653599) (xy 342.071901 -235.704529) (xy 342.079844 -235.757233) (xy 342.080342 -235.783882)
			(xy 342.079844 -235.810531) (xy 342.308424 -235.810531) (xy 342.308424 -235.757233) (xy 342.316367 -235.704529)
			(xy 342.332077 -235.653599) (xy 342.355203 -235.605578) (xy 342.385227 -235.561541) (xy 342.421479 -235.52247)
			(xy 342.46315 -235.489239) (xy 342.509308 -235.46259) (xy 342.558922 -235.443118) (xy 342.610884 -235.431258)
			(xy 342.664034 -235.427275) (xy 342.717184 -235.431258) (xy 342.769146 -235.443118) (xy 342.81876 -235.46259)
			(xy 342.864918 -235.489239) (xy 342.906589 -235.52247) (xy 342.942841 -235.561541) (xy 342.972865 -235.605578)
			(xy 342.995991 -235.653599) (xy 343.011701 -235.704529) (xy 343.019644 -235.757233) (xy 343.020142 -235.783882)
			(xy 343.019644 -235.810531) (xy 343.248224 -235.810531) (xy 343.248224 -235.757233) (xy 343.256167 -235.704529)
			(xy 343.271877 -235.653599) (xy 343.295003 -235.605578) (xy 343.325027 -235.561541) (xy 343.361279 -235.52247)
			(xy 343.40295 -235.489239) (xy 343.449108 -235.46259) (xy 343.498722 -235.443118) (xy 343.550684 -235.431258)
			(xy 343.603834 -235.427275) (xy 343.656984 -235.431258) (xy 343.708946 -235.443118) (xy 343.75856 -235.46259)
			(xy 343.804718 -235.489239) (xy 343.846389 -235.52247) (xy 343.882641 -235.561541) (xy 343.912665 -235.605578)
			(xy 343.935791 -235.653599) (xy 343.951501 -235.704529) (xy 343.959444 -235.757233) (xy 343.959942 -235.783882)
			(xy 343.959444 -235.810531) (xy 344.188024 -235.810531) (xy 344.188024 -235.757233) (xy 344.195967 -235.704529)
			(xy 344.211677 -235.653599) (xy 344.234803 -235.605578) (xy 344.264827 -235.561541) (xy 344.301079 -235.52247)
			(xy 344.34275 -235.489239) (xy 344.388908 -235.46259) (xy 344.438522 -235.443118) (xy 344.490484 -235.431258)
			(xy 344.543634 -235.427275) (xy 344.596784 -235.431258) (xy 344.648746 -235.443118) (xy 344.69836 -235.46259)
			(xy 344.744518 -235.489239) (xy 344.786189 -235.52247) (xy 344.822441 -235.561541) (xy 344.852465 -235.605578)
			(xy 344.875591 -235.653599) (xy 344.891301 -235.704529) (xy 344.899244 -235.757233) (xy 344.899742 -235.783882)
			(xy 344.899244 -235.810531) (xy 345.12757 -235.810531) (xy 345.12757 -235.757233) (xy 345.135513 -235.704529)
			(xy 345.151223 -235.653599) (xy 345.174349 -235.605578) (xy 345.204373 -235.561541) (xy 345.240625 -235.52247)
			(xy 345.282296 -235.489239) (xy 345.328454 -235.46259) (xy 345.378068 -235.443118) (xy 345.43003 -235.431258)
			(xy 345.48318 -235.427275) (xy 345.53633 -235.431258) (xy 345.588292 -235.443118) (xy 345.637906 -235.46259)
			(xy 345.684064 -235.489239) (xy 345.725735 -235.52247) (xy 345.761987 -235.561541) (xy 345.792011 -235.605578)
			(xy 345.815137 -235.653599) (xy 345.830847 -235.704529) (xy 345.83879 -235.757233) (xy 345.839288 -235.783882)
			(xy 345.83879 -235.810531) (xy 346.067624 -235.810531) (xy 346.067624 -235.757233) (xy 346.075567 -235.704529)
			(xy 346.091277 -235.653599) (xy 346.114403 -235.605578) (xy 346.144427 -235.561541) (xy 346.180679 -235.52247)
			(xy 346.22235 -235.489239) (xy 346.268508 -235.46259) (xy 346.318122 -235.443118) (xy 346.370084 -235.431258)
			(xy 346.423234 -235.427275) (xy 346.476384 -235.431258) (xy 346.528346 -235.443118) (xy 346.57796 -235.46259)
			(xy 346.624118 -235.489239) (xy 346.665789 -235.52247) (xy 346.702041 -235.561541) (xy 346.732065 -235.605578)
			(xy 346.755191 -235.653599) (xy 346.770901 -235.704529) (xy 346.778844 -235.757233) (xy 346.779342 -235.783882)
			(xy 346.778844 -235.810531) (xy 347.007424 -235.810531) (xy 347.007424 -235.757233) (xy 347.015367 -235.704529)
			(xy 347.031077 -235.653599) (xy 347.054203 -235.605578) (xy 347.084227 -235.561541) (xy 347.120479 -235.52247)
			(xy 347.16215 -235.489239) (xy 347.208308 -235.46259) (xy 347.257922 -235.443118) (xy 347.309884 -235.431258)
			(xy 347.363034 -235.427275) (xy 347.416184 -235.431258) (xy 347.468146 -235.443118) (xy 347.51776 -235.46259)
			(xy 347.563918 -235.489239) (xy 347.605589 -235.52247) (xy 347.641841 -235.561541) (xy 347.671865 -235.605578)
			(xy 347.694991 -235.653599) (xy 347.710701 -235.704529) (xy 347.718644 -235.757233) (xy 347.719142 -235.783882)
			(xy 347.718644 -235.810531) (xy 347.710701 -235.863235) (xy 347.694991 -235.914165) (xy 347.671865 -235.962186)
			(xy 347.641841 -236.006223) (xy 347.605589 -236.045294) (xy 347.563918 -236.078525) (xy 347.51776 -236.105174)
			(xy 347.468146 -236.124646) (xy 347.416184 -236.136506) (xy 347.363034 -236.14049) (xy 347.309884 -236.136506)
			(xy 347.257922 -236.124646) (xy 347.208308 -236.105174) (xy 347.16215 -236.078525) (xy 347.120479 -236.045294)
			(xy 347.084227 -236.006223) (xy 347.054203 -235.962186) (xy 347.031077 -235.914165) (xy 347.015367 -235.863235)
			(xy 347.007424 -235.810531) (xy 346.778844 -235.810531) (xy 346.770901 -235.863235) (xy 346.755191 -235.914165)
			(xy 346.732065 -235.962186) (xy 346.702041 -236.006223) (xy 346.665789 -236.045294) (xy 346.624118 -236.078525)
			(xy 346.57796 -236.105174) (xy 346.528346 -236.124646) (xy 346.476384 -236.136506) (xy 346.423234 -236.14049)
			(xy 346.370084 -236.136506) (xy 346.318122 -236.124646) (xy 346.268508 -236.105174) (xy 346.22235 -236.078525)
			(xy 346.180679 -236.045294) (xy 346.144427 -236.006223) (xy 346.114403 -235.962186) (xy 346.091277 -235.914165)
			(xy 346.075567 -235.863235) (xy 346.067624 -235.810531) (xy 345.83879 -235.810531) (xy 345.830847 -235.863235)
			(xy 345.815137 -235.914165) (xy 345.792011 -235.962186) (xy 345.761987 -236.006223) (xy 345.725735 -236.045294)
			(xy 345.684064 -236.078525) (xy 345.637906 -236.105174) (xy 345.588292 -236.124646) (xy 345.53633 -236.136506)
			(xy 345.48318 -236.14049) (xy 345.43003 -236.136506) (xy 345.378068 -236.124646) (xy 345.328454 -236.105174)
			(xy 345.282296 -236.078525) (xy 345.240625 -236.045294) (xy 345.204373 -236.006223) (xy 345.174349 -235.962186)
			(xy 345.151223 -235.914165) (xy 345.135513 -235.863235) (xy 345.12757 -235.810531) (xy 344.899244 -235.810531)
			(xy 344.891301 -235.863235) (xy 344.875591 -235.914165) (xy 344.852465 -235.962186) (xy 344.822441 -236.006223)
			(xy 344.786189 -236.045294) (xy 344.744518 -236.078525) (xy 344.69836 -236.105174) (xy 344.648746 -236.124646)
			(xy 344.596784 -236.136506) (xy 344.543634 -236.14049) (xy 344.490484 -236.136506) (xy 344.438522 -236.124646)
			(xy 344.388908 -236.105174) (xy 344.34275 -236.078525) (xy 344.301079 -236.045294) (xy 344.264827 -236.006223)
			(xy 344.234803 -235.962186) (xy 344.211677 -235.914165) (xy 344.195967 -235.863235) (xy 344.188024 -235.810531)
			(xy 343.959444 -235.810531) (xy 343.951501 -235.863235) (xy 343.935791 -235.914165) (xy 343.912665 -235.962186)
			(xy 343.882641 -236.006223) (xy 343.846389 -236.045294) (xy 343.804718 -236.078525) (xy 343.75856 -236.105174)
			(xy 343.708946 -236.124646) (xy 343.656984 -236.136506) (xy 343.603834 -236.14049) (xy 343.550684 -236.136506)
			(xy 343.498722 -236.124646) (xy 343.449108 -236.105174) (xy 343.40295 -236.078525) (xy 343.361279 -236.045294)
			(xy 343.325027 -236.006223) (xy 343.295003 -235.962186) (xy 343.271877 -235.914165) (xy 343.256167 -235.863235)
			(xy 343.248224 -235.810531) (xy 343.019644 -235.810531) (xy 343.011701 -235.863235) (xy 342.995991 -235.914165)
			(xy 342.972865 -235.962186) (xy 342.942841 -236.006223) (xy 342.906589 -236.045294) (xy 342.864918 -236.078525)
			(xy 342.81876 -236.105174) (xy 342.769146 -236.124646) (xy 342.717184 -236.136506) (xy 342.664034 -236.14049)
			(xy 342.610884 -236.136506) (xy 342.558922 -236.124646) (xy 342.509308 -236.105174) (xy 342.46315 -236.078525)
			(xy 342.421479 -236.045294) (xy 342.385227 -236.006223) (xy 342.355203 -235.962186) (xy 342.332077 -235.914165)
			(xy 342.316367 -235.863235) (xy 342.308424 -235.810531) (xy 342.079844 -235.810531) (xy 342.071901 -235.863235)
			(xy 342.056191 -235.914165) (xy 342.033065 -235.962186) (xy 342.003041 -236.006223) (xy 341.966789 -236.045294)
			(xy 341.925118 -236.078525) (xy 341.87896 -236.105174) (xy 341.829346 -236.124646) (xy 341.777384 -236.136506)
			(xy 341.724234 -236.14049) (xy 341.671084 -236.136506) (xy 341.619122 -236.124646) (xy 341.569508 -236.105174)
			(xy 341.52335 -236.078525) (xy 341.481679 -236.045294) (xy 341.445427 -236.006223) (xy 341.415403 -235.962186)
			(xy 341.392277 -235.914165) (xy 341.376567 -235.863235) (xy 341.368624 -235.810531) (xy 341.140044 -235.810531)
			(xy 341.132101 -235.863235) (xy 341.116391 -235.914165) (xy 341.093265 -235.962186) (xy 341.063241 -236.006223)
			(xy 341.026989 -236.045294) (xy 340.985318 -236.078525) (xy 340.93916 -236.105174) (xy 340.889546 -236.124646)
			(xy 340.837584 -236.136506) (xy 340.784434 -236.14049) (xy 340.731284 -236.136506) (xy 340.679322 -236.124646)
			(xy 340.629708 -236.105174) (xy 340.58355 -236.078525) (xy 340.541879 -236.045294) (xy 340.505627 -236.006223)
			(xy 340.475603 -235.962186) (xy 340.452477 -235.914165) (xy 340.436767 -235.863235) (xy 340.428824 -235.810531)
			(xy 340.200244 -235.810531) (xy 340.192301 -235.863235) (xy 340.176591 -235.914165) (xy 340.153465 -235.962186)
			(xy 340.123441 -236.006223) (xy 340.087189 -236.045294) (xy 340.045518 -236.078525) (xy 339.99936 -236.105174)
			(xy 339.949746 -236.124646) (xy 339.897784 -236.136506) (xy 339.844634 -236.14049) (xy 339.791484 -236.136506)
			(xy 339.739522 -236.124646) (xy 339.689908 -236.105174) (xy 339.64375 -236.078525) (xy 339.602079 -236.045294)
			(xy 339.565827 -236.006223) (xy 339.535803 -235.962186) (xy 339.512677 -235.914165) (xy 339.496967 -235.863235)
			(xy 339.489024 -235.810531) (xy 339.26019 -235.810531) (xy 339.252247 -235.863235) (xy 339.236537 -235.914165)
			(xy 339.213411 -235.962186) (xy 339.183387 -236.006223) (xy 339.147135 -236.045294) (xy 339.105464 -236.078525)
			(xy 339.059306 -236.105174) (xy 339.009692 -236.124646) (xy 338.95773 -236.136506) (xy 338.90458 -236.14049)
			(xy 338.85143 -236.136506) (xy 338.799468 -236.124646) (xy 338.749854 -236.105174) (xy 338.703696 -236.078525)
			(xy 338.662025 -236.045294) (xy 338.625773 -236.006223) (xy 338.595749 -235.962186) (xy 338.572623 -235.914165)
			(xy 338.556913 -235.863235) (xy 338.54897 -235.810531) (xy 338.320644 -235.810531) (xy 338.312701 -235.863235)
			(xy 338.296991 -235.914165) (xy 338.273865 -235.962186) (xy 338.243841 -236.006223) (xy 338.207589 -236.045294)
			(xy 338.165918 -236.078525) (xy 338.11976 -236.105174) (xy 338.070146 -236.124646) (xy 338.018184 -236.136506)
			(xy 337.965034 -236.14049) (xy 337.911884 -236.136506) (xy 337.859922 -236.124646) (xy 337.810308 -236.105174)
			(xy 337.76415 -236.078525) (xy 337.722479 -236.045294) (xy 337.686227 -236.006223) (xy 337.656203 -235.962186)
			(xy 337.633077 -235.914165) (xy 337.617367 -235.863235) (xy 337.609424 -235.810531) (xy 337.37983 -235.810531)
			(xy 337.377843 -235.837049) (xy 337.365984 -235.889011) (xy 337.346513 -235.938625) (xy 337.319865 -235.984784)
			(xy 337.286636 -236.026455) (xy 337.247568 -236.062709) (xy 337.203532 -236.092735) (xy 337.155514 -236.115864)
			(xy 337.104585 -236.131578) (xy 337.051883 -236.139526) (xy 337.025234 -236.13999) (xy 337.000538 -236.139591)
			(xy 336.951616 -236.132807) (xy 336.904101 -236.119324) (xy 336.858908 -236.0994) (xy 336.816904 -236.073418)
			(xy 336.79765 -236.057948) (xy 336.786265 -236.049169) (xy 336.759897 -236.037745) (xy 336.73139 -236.034122)
			(xy 336.703003 -236.038586) (xy 336.676984 -236.050785) (xy 336.655396 -236.069752) (xy 336.639948 -236.093983)
			(xy 336.631866 -236.121559) (xy 336.63128 -236.135926) (xy 336.63128 -236.248194) (xy 336.666332 -236.259624)
			(xy 336.691152 -236.268263) (xy 336.738135 -236.291807) (xy 336.781147 -236.322001) (xy 336.819256 -236.358188)
			(xy 336.851633 -236.399583) (xy 336.877574 -236.445286) (xy 336.896518 -236.494305) (xy 336.908052 -236.545576)
			(xy 336.911926 -236.597985) (xy 336.909961 -236.624601) (xy 337.13927 -236.624601) (xy 337.13927 -236.571303)
			(xy 337.147213 -236.518599) (xy 337.162923 -236.467669) (xy 337.186049 -236.419648) (xy 337.216073 -236.375611)
			(xy 337.252325 -236.33654) (xy 337.293996 -236.303309) (xy 337.340154 -236.27666) (xy 337.389768 -236.257188)
			(xy 337.44173 -236.245328) (xy 337.49488 -236.241345) (xy 337.54803 -236.245328) (xy 337.599992 -236.257188)
			(xy 337.649606 -236.27666) (xy 337.695764 -236.303309) (xy 337.737435 -236.33654) (xy 337.773687 -236.375611)
			(xy 337.803711 -236.419648) (xy 337.826837 -236.467669) (xy 337.842547 -236.518599) (xy 337.85049 -236.571303)
			(xy 337.850988 -236.597952) (xy 337.85049 -236.624601) (xy 338.07907 -236.624601) (xy 338.07907 -236.571303)
			(xy 338.087013 -236.518599) (xy 338.102723 -236.467669) (xy 338.125849 -236.419648) (xy 338.155873 -236.375611)
			(xy 338.192125 -236.33654) (xy 338.233796 -236.303309) (xy 338.279954 -236.27666) (xy 338.329568 -236.257188)
			(xy 338.38153 -236.245328) (xy 338.43468 -236.241345) (xy 338.48783 -236.245328) (xy 338.539792 -236.257188)
			(xy 338.589406 -236.27666) (xy 338.635564 -236.303309) (xy 338.677235 -236.33654) (xy 338.713487 -236.375611)
			(xy 338.743511 -236.419648) (xy 338.766637 -236.467669) (xy 338.782347 -236.518599) (xy 338.79029 -236.571303)
			(xy 338.790788 -236.597952) (xy 338.79029 -236.624601) (xy 339.01887 -236.624601) (xy 339.01887 -236.571303)
			(xy 339.026813 -236.518599) (xy 339.042523 -236.467669) (xy 339.065649 -236.419648) (xy 339.095673 -236.375611)
			(xy 339.131925 -236.33654) (xy 339.173596 -236.303309) (xy 339.219754 -236.27666) (xy 339.269368 -236.257188)
			(xy 339.32133 -236.245328) (xy 339.37448 -236.241345) (xy 339.42763 -236.245328) (xy 339.479592 -236.257188)
			(xy 339.529206 -236.27666) (xy 339.575364 -236.303309) (xy 339.617035 -236.33654) (xy 339.653287 -236.375611)
			(xy 339.683311 -236.419648) (xy 339.706437 -236.467669) (xy 339.722147 -236.518599) (xy 339.73009 -236.571303)
			(xy 339.730588 -236.597952) (xy 339.73009 -236.624601) (xy 339.95867 -236.624601) (xy 339.95867 -236.571303)
			(xy 339.966613 -236.518599) (xy 339.982323 -236.467669) (xy 340.005449 -236.419648) (xy 340.035473 -236.375611)
			(xy 340.071725 -236.33654) (xy 340.113396 -236.303309) (xy 340.159554 -236.27666) (xy 340.209168 -236.257188)
			(xy 340.26113 -236.245328) (xy 340.31428 -236.241345) (xy 340.36743 -236.245328) (xy 340.419392 -236.257188)
			(xy 340.469006 -236.27666) (xy 340.515164 -236.303309) (xy 340.556835 -236.33654) (xy 340.593087 -236.375611)
			(xy 340.623111 -236.419648) (xy 340.646237 -236.467669) (xy 340.661947 -236.518599) (xy 340.66989 -236.571303)
			(xy 340.670388 -236.597952) (xy 340.66989 -236.624601) (xy 340.89847 -236.624601) (xy 340.89847 -236.571303)
			(xy 340.906413 -236.518599) (xy 340.922123 -236.467669) (xy 340.945249 -236.419648) (xy 340.975273 -236.375611)
			(xy 341.011525 -236.33654) (xy 341.053196 -236.303309) (xy 341.099354 -236.27666) (xy 341.148968 -236.257188)
			(xy 341.20093 -236.245328) (xy 341.25408 -236.241345) (xy 341.30723 -236.245328) (xy 341.359192 -236.257188)
			(xy 341.408806 -236.27666) (xy 341.454964 -236.303309) (xy 341.496635 -236.33654) (xy 341.532887 -236.375611)
			(xy 341.562911 -236.419648) (xy 341.586037 -236.467669) (xy 341.601747 -236.518599) (xy 341.60969 -236.571303)
			(xy 341.610188 -236.597952) (xy 341.60969 -236.624601) (xy 341.838524 -236.624601) (xy 341.838524 -236.571303)
			(xy 341.846467 -236.518599) (xy 341.862177 -236.467669) (xy 341.885303 -236.419648) (xy 341.915327 -236.375611)
			(xy 341.951579 -236.33654) (xy 341.99325 -236.303309) (xy 342.039408 -236.27666) (xy 342.089022 -236.257188)
			(xy 342.140984 -236.245328) (xy 342.194134 -236.241345) (xy 342.247284 -236.245328) (xy 342.299246 -236.257188)
			(xy 342.34886 -236.27666) (xy 342.395018 -236.303309) (xy 342.436689 -236.33654) (xy 342.472941 -236.375611)
			(xy 342.502965 -236.419648) (xy 342.526091 -236.467669) (xy 342.541801 -236.518599) (xy 342.549744 -236.571303)
			(xy 342.550242 -236.597952) (xy 342.549744 -236.624601) (xy 342.77807 -236.624601) (xy 342.77807 -236.571303)
			(xy 342.786013 -236.518599) (xy 342.801723 -236.467669) (xy 342.824849 -236.419648) (xy 342.854873 -236.375611)
			(xy 342.891125 -236.33654) (xy 342.932796 -236.303309) (xy 342.978954 -236.27666) (xy 343.028568 -236.257188)
			(xy 343.08053 -236.245328) (xy 343.13368 -236.241345) (xy 343.18683 -236.245328) (xy 343.238792 -236.257188)
			(xy 343.288406 -236.27666) (xy 343.334564 -236.303309) (xy 343.376235 -236.33654) (xy 343.412487 -236.375611)
			(xy 343.442511 -236.419648) (xy 343.465637 -236.467669) (xy 343.481347 -236.518599) (xy 343.48929 -236.571303)
			(xy 343.489788 -236.597952) (xy 343.48929 -236.624601) (xy 343.71787 -236.624601) (xy 343.71787 -236.571303)
			(xy 343.725813 -236.518599) (xy 343.741523 -236.467669) (xy 343.764649 -236.419648) (xy 343.794673 -236.375611)
			(xy 343.830925 -236.33654) (xy 343.872596 -236.303309) (xy 343.918754 -236.27666) (xy 343.968368 -236.257188)
			(xy 344.02033 -236.245328) (xy 344.07348 -236.241345) (xy 344.12663 -236.245328) (xy 344.178592 -236.257188)
			(xy 344.228206 -236.27666) (xy 344.274364 -236.303309) (xy 344.316035 -236.33654) (xy 344.352287 -236.375611)
			(xy 344.382311 -236.419648) (xy 344.405437 -236.467669) (xy 344.421147 -236.518599) (xy 344.42909 -236.571303)
			(xy 344.429588 -236.597952) (xy 344.42909 -236.624601) (xy 344.65767 -236.624601) (xy 344.65767 -236.571303)
			(xy 344.665613 -236.518599) (xy 344.681323 -236.467669) (xy 344.704449 -236.419648) (xy 344.734473 -236.375611)
			(xy 344.770725 -236.33654) (xy 344.812396 -236.303309) (xy 344.858554 -236.27666) (xy 344.908168 -236.257188)
			(xy 344.96013 -236.245328) (xy 345.01328 -236.241345) (xy 345.06643 -236.245328) (xy 345.118392 -236.257188)
			(xy 345.168006 -236.27666) (xy 345.214164 -236.303309) (xy 345.255835 -236.33654) (xy 345.292087 -236.375611)
			(xy 345.322111 -236.419648) (xy 345.345237 -236.467669) (xy 345.360947 -236.518599) (xy 345.36889 -236.571303)
			(xy 345.369388 -236.597952) (xy 345.36889 -236.624601) (xy 345.59747 -236.624601) (xy 345.59747 -236.571303)
			(xy 345.605413 -236.518599) (xy 345.621123 -236.467669) (xy 345.644249 -236.419648) (xy 345.674273 -236.375611)
			(xy 345.710525 -236.33654) (xy 345.752196 -236.303309) (xy 345.798354 -236.27666) (xy 345.847968 -236.257188)
			(xy 345.89993 -236.245328) (xy 345.95308 -236.241345) (xy 346.00623 -236.245328) (xy 346.058192 -236.257188)
			(xy 346.107806 -236.27666) (xy 346.153964 -236.303309) (xy 346.195635 -236.33654) (xy 346.231887 -236.375611)
			(xy 346.261911 -236.419648) (xy 346.285037 -236.467669) (xy 346.300747 -236.518599) (xy 346.30869 -236.571303)
			(xy 346.309188 -236.597952) (xy 346.30869 -236.624601) (xy 346.53727 -236.624601) (xy 346.53727 -236.571303)
			(xy 346.545213 -236.518599) (xy 346.560923 -236.467669) (xy 346.584049 -236.419648) (xy 346.614073 -236.375611)
			(xy 346.650325 -236.33654) (xy 346.691996 -236.303309) (xy 346.738154 -236.27666) (xy 346.787768 -236.257188)
			(xy 346.83973 -236.245328) (xy 346.89288 -236.241345) (xy 346.94603 -236.245328) (xy 346.997992 -236.257188)
			(xy 347.047606 -236.27666) (xy 347.093764 -236.303309) (xy 347.135435 -236.33654) (xy 347.171687 -236.375611)
			(xy 347.201711 -236.419648) (xy 347.224837 -236.467669) (xy 347.240547 -236.518599) (xy 347.24849 -236.571303)
			(xy 347.248988 -236.597952) (xy 347.24849 -236.624601) (xy 347.240547 -236.677305) (xy 347.224837 -236.728235)
			(xy 347.201711 -236.776256) (xy 347.171687 -236.820293) (xy 347.135435 -236.859364) (xy 347.093764 -236.892595)
			(xy 347.047606 -236.919244) (xy 346.997992 -236.938716) (xy 346.94603 -236.950576) (xy 346.89288 -236.95456)
			(xy 346.83973 -236.950576) (xy 346.787768 -236.938716) (xy 346.738154 -236.919244) (xy 346.691996 -236.892595)
			(xy 346.650325 -236.859364) (xy 346.614073 -236.820293) (xy 346.584049 -236.776256) (xy 346.560923 -236.728235)
			(xy 346.545213 -236.677305) (xy 346.53727 -236.624601) (xy 346.30869 -236.624601) (xy 346.300747 -236.677305)
			(xy 346.285037 -236.728235) (xy 346.261911 -236.776256) (xy 346.231887 -236.820293) (xy 346.195635 -236.859364)
			(xy 346.153964 -236.892595) (xy 346.107806 -236.919244) (xy 346.058192 -236.938716) (xy 346.00623 -236.950576)
			(xy 345.95308 -236.95456) (xy 345.89993 -236.950576) (xy 345.847968 -236.938716) (xy 345.798354 -236.919244)
			(xy 345.752196 -236.892595) (xy 345.710525 -236.859364) (xy 345.674273 -236.820293) (xy 345.644249 -236.776256)
			(xy 345.621123 -236.728235) (xy 345.605413 -236.677305) (xy 345.59747 -236.624601) (xy 345.36889 -236.624601)
			(xy 345.360947 -236.677305) (xy 345.345237 -236.728235) (xy 345.322111 -236.776256) (xy 345.292087 -236.820293)
			(xy 345.255835 -236.859364) (xy 345.214164 -236.892595) (xy 345.168006 -236.919244) (xy 345.118392 -236.938716)
			(xy 345.06643 -236.950576) (xy 345.01328 -236.95456) (xy 344.96013 -236.950576) (xy 344.908168 -236.938716)
			(xy 344.858554 -236.919244) (xy 344.812396 -236.892595) (xy 344.770725 -236.859364) (xy 344.734473 -236.820293)
			(xy 344.704449 -236.776256) (xy 344.681323 -236.728235) (xy 344.665613 -236.677305) (xy 344.65767 -236.624601)
			(xy 344.42909 -236.624601) (xy 344.421147 -236.677305) (xy 344.405437 -236.728235) (xy 344.382311 -236.776256)
			(xy 344.352287 -236.820293) (xy 344.316035 -236.859364) (xy 344.274364 -236.892595) (xy 344.228206 -236.919244)
			(xy 344.178592 -236.938716) (xy 344.12663 -236.950576) (xy 344.07348 -236.95456) (xy 344.02033 -236.950576)
			(xy 343.968368 -236.938716) (xy 343.918754 -236.919244) (xy 343.872596 -236.892595) (xy 343.830925 -236.859364)
			(xy 343.794673 -236.820293) (xy 343.764649 -236.776256) (xy 343.741523 -236.728235) (xy 343.725813 -236.677305)
			(xy 343.71787 -236.624601) (xy 343.48929 -236.624601) (xy 343.481347 -236.677305) (xy 343.465637 -236.728235)
			(xy 343.442511 -236.776256) (xy 343.412487 -236.820293) (xy 343.376235 -236.859364) (xy 343.334564 -236.892595)
			(xy 343.288406 -236.919244) (xy 343.238792 -236.938716) (xy 343.18683 -236.950576) (xy 343.13368 -236.95456)
			(xy 343.08053 -236.950576) (xy 343.028568 -236.938716) (xy 342.978954 -236.919244) (xy 342.932796 -236.892595)
			(xy 342.891125 -236.859364) (xy 342.854873 -236.820293) (xy 342.824849 -236.776256) (xy 342.801723 -236.728235)
			(xy 342.786013 -236.677305) (xy 342.77807 -236.624601) (xy 342.549744 -236.624601) (xy 342.541801 -236.677305)
			(xy 342.526091 -236.728235) (xy 342.502965 -236.776256) (xy 342.472941 -236.820293) (xy 342.436689 -236.859364)
			(xy 342.395018 -236.892595) (xy 342.34886 -236.919244) (xy 342.299246 -236.938716) (xy 342.247284 -236.950576)
			(xy 342.194134 -236.95456) (xy 342.140984 -236.950576) (xy 342.089022 -236.938716) (xy 342.039408 -236.919244)
			(xy 341.99325 -236.892595) (xy 341.951579 -236.859364) (xy 341.915327 -236.820293) (xy 341.885303 -236.776256)
			(xy 341.862177 -236.728235) (xy 341.846467 -236.677305) (xy 341.838524 -236.624601) (xy 341.60969 -236.624601)
			(xy 341.601747 -236.677305) (xy 341.586037 -236.728235) (xy 341.562911 -236.776256) (xy 341.532887 -236.820293)
			(xy 341.496635 -236.859364) (xy 341.454964 -236.892595) (xy 341.408806 -236.919244) (xy 341.359192 -236.938716)
			(xy 341.30723 -236.950576) (xy 341.25408 -236.95456) (xy 341.20093 -236.950576) (xy 341.148968 -236.938716)
			(xy 341.099354 -236.919244) (xy 341.053196 -236.892595) (xy 341.011525 -236.859364) (xy 340.975273 -236.820293)
			(xy 340.945249 -236.776256) (xy 340.922123 -236.728235) (xy 340.906413 -236.677305) (xy 340.89847 -236.624601)
			(xy 340.66989 -236.624601) (xy 340.661947 -236.677305) (xy 340.646237 -236.728235) (xy 340.623111 -236.776256)
			(xy 340.593087 -236.820293) (xy 340.556835 -236.859364) (xy 340.515164 -236.892595) (xy 340.469006 -236.919244)
			(xy 340.419392 -236.938716) (xy 340.36743 -236.950576) (xy 340.31428 -236.95456) (xy 340.26113 -236.950576)
			(xy 340.209168 -236.938716) (xy 340.159554 -236.919244) (xy 340.113396 -236.892595) (xy 340.071725 -236.859364)
			(xy 340.035473 -236.820293) (xy 340.005449 -236.776256) (xy 339.982323 -236.728235) (xy 339.966613 -236.677305)
			(xy 339.95867 -236.624601) (xy 339.73009 -236.624601) (xy 339.722147 -236.677305) (xy 339.706437 -236.728235)
			(xy 339.683311 -236.776256) (xy 339.653287 -236.820293) (xy 339.617035 -236.859364) (xy 339.575364 -236.892595)
			(xy 339.529206 -236.919244) (xy 339.479592 -236.938716) (xy 339.42763 -236.950576) (xy 339.37448 -236.95456)
			(xy 339.32133 -236.950576) (xy 339.269368 -236.938716) (xy 339.219754 -236.919244) (xy 339.173596 -236.892595)
			(xy 339.131925 -236.859364) (xy 339.095673 -236.820293) (xy 339.065649 -236.776256) (xy 339.042523 -236.728235)
			(xy 339.026813 -236.677305) (xy 339.01887 -236.624601) (xy 338.79029 -236.624601) (xy 338.782347 -236.677305)
			(xy 338.766637 -236.728235) (xy 338.743511 -236.776256) (xy 338.713487 -236.820293) (xy 338.677235 -236.859364)
			(xy 338.635564 -236.892595) (xy 338.589406 -236.919244) (xy 338.539792 -236.938716) (xy 338.48783 -236.950576)
			(xy 338.43468 -236.95456) (xy 338.38153 -236.950576) (xy 338.329568 -236.938716) (xy 338.279954 -236.919244)
			(xy 338.233796 -236.892595) (xy 338.192125 -236.859364) (xy 338.155873 -236.820293) (xy 338.125849 -236.776256)
			(xy 338.102723 -236.728235) (xy 338.087013 -236.677305) (xy 338.07907 -236.624601) (xy 337.85049 -236.624601)
			(xy 337.842547 -236.677305) (xy 337.826837 -236.728235) (xy 337.803711 -236.776256) (xy 337.773687 -236.820293)
			(xy 337.737435 -236.859364) (xy 337.695764 -236.892595) (xy 337.649606 -236.919244) (xy 337.599992 -236.938716)
			(xy 337.54803 -236.950576) (xy 337.49488 -236.95456) (xy 337.44173 -236.950576) (xy 337.389768 -236.938716)
			(xy 337.340154 -236.919244) (xy 337.293996 -236.892595) (xy 337.252325 -236.859364) (xy 337.216073 -236.820293)
			(xy 337.186049 -236.776256) (xy 337.162923 -236.728235) (xy 337.147213 -236.677305) (xy 337.13927 -236.624601)
			(xy 336.909961 -236.624601) (xy 336.908057 -236.650395) (xy 336.896527 -236.701667) (xy 336.877587 -236.750687)
			(xy 336.851649 -236.796393) (xy 336.819276 -236.83779) (xy 336.781171 -236.87398) (xy 336.738161 -236.904177)
			(xy 336.69118 -236.927726) (xy 336.666332 -236.93628) (xy 336.63128 -236.94771) (xy 336.63128 -237.05947)
			(xy 336.631813 -237.073835) (xy 336.639896 -237.101408) (xy 336.655346 -237.125635) (xy 336.676937 -237.144593)
			(xy 336.702958 -237.156781) (xy 336.731345 -237.161232) (xy 336.759847 -237.157593) (xy 336.786204 -237.146152)
			(xy 336.79765 -237.137448) (xy 336.816926 -237.122008) (xy 336.858929 -237.096034) (xy 336.904118 -237.076109)
			(xy 336.951625 -237.062617) (xy 337.000541 -237.055814) (xy 337.025234 -237.055406) (xy 337.051881 -237.055906)
			(xy 337.104578 -237.063854) (xy 337.155502 -237.079566) (xy 337.203516 -237.102692) (xy 337.247548 -237.132716)
			(xy 337.286613 -237.168967) (xy 337.319839 -237.210634) (xy 337.346484 -237.256789) (xy 337.365953 -237.306398)
			(xy 337.377811 -237.358356) (xy 337.381794 -237.4115) (xy 337.379796 -237.438163) (xy 337.609424 -237.438163)
			(xy 337.609424 -237.384865) (xy 337.617367 -237.332161) (xy 337.633077 -237.281231) (xy 337.656203 -237.23321)
			(xy 337.686227 -237.189173) (xy 337.722479 -237.150102) (xy 337.76415 -237.116871) (xy 337.810308 -237.090222)
			(xy 337.859922 -237.07075) (xy 337.911884 -237.05889) (xy 337.965034 -237.054907) (xy 338.018184 -237.05889)
			(xy 338.070146 -237.07075) (xy 338.11976 -237.090222) (xy 338.165918 -237.116871) (xy 338.207589 -237.150102)
			(xy 338.243841 -237.189173) (xy 338.273865 -237.23321) (xy 338.296991 -237.281231) (xy 338.312701 -237.332161)
			(xy 338.320644 -237.384865) (xy 338.321142 -237.411514) (xy 338.320644 -237.438163) (xy 338.549224 -237.438163)
			(xy 338.549224 -237.384865) (xy 338.557167 -237.332161) (xy 338.572877 -237.281231) (xy 338.596003 -237.23321)
			(xy 338.626027 -237.189173) (xy 338.662279 -237.150102) (xy 338.70395 -237.116871) (xy 338.750108 -237.090222)
			(xy 338.799722 -237.07075) (xy 338.851684 -237.05889) (xy 338.904834 -237.054907) (xy 338.957984 -237.05889)
			(xy 339.009946 -237.07075) (xy 339.05956 -237.090222) (xy 339.105718 -237.116871) (xy 339.147389 -237.150102)
			(xy 339.183641 -237.189173) (xy 339.213665 -237.23321) (xy 339.236791 -237.281231) (xy 339.252501 -237.332161)
			(xy 339.260444 -237.384865) (xy 339.260942 -237.411514) (xy 339.260444 -237.438163) (xy 339.48877 -237.438163)
			(xy 339.48877 -237.384865) (xy 339.496713 -237.332161) (xy 339.512423 -237.281231) (xy 339.535549 -237.23321)
			(xy 339.565573 -237.189173) (xy 339.601825 -237.150102) (xy 339.643496 -237.116871) (xy 339.689654 -237.090222)
			(xy 339.739268 -237.07075) (xy 339.79123 -237.05889) (xy 339.84438 -237.054907) (xy 339.89753 -237.05889)
			(xy 339.949492 -237.07075) (xy 339.999106 -237.090222) (xy 340.045264 -237.116871) (xy 340.086935 -237.150102)
			(xy 340.123187 -237.189173) (xy 340.153211 -237.23321) (xy 340.176337 -237.281231) (xy 340.192047 -237.332161)
			(xy 340.19999 -237.384865) (xy 340.200488 -237.411514) (xy 340.19999 -237.438163) (xy 340.428824 -237.438163)
			(xy 340.428824 -237.384865) (xy 340.436767 -237.332161) (xy 340.452477 -237.281231) (xy 340.475603 -237.23321)
			(xy 340.505627 -237.189173) (xy 340.541879 -237.150102) (xy 340.58355 -237.116871) (xy 340.629708 -237.090222)
			(xy 340.679322 -237.07075) (xy 340.731284 -237.05889) (xy 340.784434 -237.054907) (xy 340.837584 -237.05889)
			(xy 340.889546 -237.07075) (xy 340.93916 -237.090222) (xy 340.985318 -237.116871) (xy 341.026989 -237.150102)
			(xy 341.063241 -237.189173) (xy 341.093265 -237.23321) (xy 341.116391 -237.281231) (xy 341.132101 -237.332161)
			(xy 341.140044 -237.384865) (xy 341.140542 -237.411514) (xy 341.140044 -237.438163) (xy 341.368624 -237.438163)
			(xy 341.368624 -237.384865) (xy 341.376567 -237.332161) (xy 341.392277 -237.281231) (xy 341.415403 -237.23321)
			(xy 341.445427 -237.189173) (xy 341.481679 -237.150102) (xy 341.52335 -237.116871) (xy 341.569508 -237.090222)
			(xy 341.619122 -237.07075) (xy 341.671084 -237.05889) (xy 341.724234 -237.054907) (xy 341.777384 -237.05889)
			(xy 341.829346 -237.07075) (xy 341.87896 -237.090222) (xy 341.925118 -237.116871) (xy 341.966789 -237.150102)
			(xy 342.003041 -237.189173) (xy 342.033065 -237.23321) (xy 342.056191 -237.281231) (xy 342.071901 -237.332161)
			(xy 342.079844 -237.384865) (xy 342.080342 -237.411514) (xy 342.079844 -237.438163) (xy 342.308424 -237.438163)
			(xy 342.308424 -237.384865) (xy 342.316367 -237.332161) (xy 342.332077 -237.281231) (xy 342.355203 -237.23321)
			(xy 342.385227 -237.189173) (xy 342.421479 -237.150102) (xy 342.46315 -237.116871) (xy 342.509308 -237.090222)
			(xy 342.558922 -237.07075) (xy 342.610884 -237.05889) (xy 342.664034 -237.054907) (xy 342.717184 -237.05889)
			(xy 342.769146 -237.07075) (xy 342.81876 -237.090222) (xy 342.864918 -237.116871) (xy 342.906589 -237.150102)
			(xy 342.942841 -237.189173) (xy 342.972865 -237.23321) (xy 342.995991 -237.281231) (xy 343.011701 -237.332161)
			(xy 343.019644 -237.384865) (xy 343.020142 -237.411514) (xy 343.019644 -237.438163) (xy 343.248224 -237.438163)
			(xy 343.248224 -237.384865) (xy 343.256167 -237.332161) (xy 343.271877 -237.281231) (xy 343.295003 -237.23321)
			(xy 343.325027 -237.189173) (xy 343.361279 -237.150102) (xy 343.40295 -237.116871) (xy 343.449108 -237.090222)
			(xy 343.498722 -237.07075) (xy 343.550684 -237.05889) (xy 343.603834 -237.054907) (xy 343.656984 -237.05889)
			(xy 343.708946 -237.07075) (xy 343.75856 -237.090222) (xy 343.804718 -237.116871) (xy 343.846389 -237.150102)
			(xy 343.882641 -237.189173) (xy 343.912665 -237.23321) (xy 343.935791 -237.281231) (xy 343.951501 -237.332161)
			(xy 343.959444 -237.384865) (xy 343.959942 -237.411514) (xy 343.959444 -237.438163) (xy 344.188024 -237.438163)
			(xy 344.188024 -237.384865) (xy 344.195967 -237.332161) (xy 344.211677 -237.281231) (xy 344.234803 -237.23321)
			(xy 344.264827 -237.189173) (xy 344.301079 -237.150102) (xy 344.34275 -237.116871) (xy 344.388908 -237.090222)
			(xy 344.438522 -237.07075) (xy 344.490484 -237.05889) (xy 344.543634 -237.054907) (xy 344.596784 -237.05889)
			(xy 344.648746 -237.07075) (xy 344.69836 -237.090222) (xy 344.744518 -237.116871) (xy 344.786189 -237.150102)
			(xy 344.822441 -237.189173) (xy 344.852465 -237.23321) (xy 344.875591 -237.281231) (xy 344.891301 -237.332161)
			(xy 344.899244 -237.384865) (xy 344.899742 -237.411514) (xy 344.899244 -237.438163) (xy 345.127824 -237.438163)
			(xy 345.127824 -237.384865) (xy 345.135767 -237.332161) (xy 345.151477 -237.281231) (xy 345.174603 -237.23321)
			(xy 345.204627 -237.189173) (xy 345.240879 -237.150102) (xy 345.28255 -237.116871) (xy 345.328708 -237.090222)
			(xy 345.378322 -237.07075) (xy 345.430284 -237.05889) (xy 345.483434 -237.054907) (xy 345.536584 -237.05889)
			(xy 345.588546 -237.07075) (xy 345.63816 -237.090222) (xy 345.684318 -237.116871) (xy 345.725989 -237.150102)
			(xy 345.762241 -237.189173) (xy 345.792265 -237.23321) (xy 345.815391 -237.281231) (xy 345.831101 -237.332161)
			(xy 345.839044 -237.384865) (xy 345.839542 -237.411514) (xy 345.839044 -237.438163) (xy 346.06737 -237.438163)
			(xy 346.06737 -237.384865) (xy 346.075313 -237.332161) (xy 346.091023 -237.281231) (xy 346.114149 -237.23321)
			(xy 346.144173 -237.189173) (xy 346.180425 -237.150102) (xy 346.222096 -237.116871) (xy 346.268254 -237.090222)
			(xy 346.317868 -237.07075) (xy 346.36983 -237.05889) (xy 346.42298 -237.054907) (xy 346.47613 -237.05889)
			(xy 346.528092 -237.07075) (xy 346.577706 -237.090222) (xy 346.623864 -237.116871) (xy 346.665535 -237.150102)
			(xy 346.701787 -237.189173) (xy 346.731811 -237.23321) (xy 346.754937 -237.281231) (xy 346.770647 -237.332161)
			(xy 346.77859 -237.384865) (xy 346.779088 -237.411514) (xy 346.77859 -237.438163) (xy 346.770647 -237.490867)
			(xy 346.754937 -237.541797) (xy 346.731811 -237.589818) (xy 346.701787 -237.633855) (xy 346.665535 -237.672926)
			(xy 346.623864 -237.706157) (xy 346.577706 -237.732806) (xy 346.528092 -237.752278) (xy 346.47613 -237.764138)
			(xy 346.42298 -237.768122) (xy 346.36983 -237.764138) (xy 346.317868 -237.752278) (xy 346.268254 -237.732806)
			(xy 346.222096 -237.706157) (xy 346.180425 -237.672926) (xy 346.144173 -237.633855) (xy 346.114149 -237.589818)
			(xy 346.091023 -237.541797) (xy 346.075313 -237.490867) (xy 346.06737 -237.438163) (xy 345.839044 -237.438163)
			(xy 345.831101 -237.490867) (xy 345.815391 -237.541797) (xy 345.792265 -237.589818) (xy 345.762241 -237.633855)
			(xy 345.725989 -237.672926) (xy 345.684318 -237.706157) (xy 345.63816 -237.732806) (xy 345.588546 -237.752278)
			(xy 345.536584 -237.764138) (xy 345.483434 -237.768122) (xy 345.430284 -237.764138) (xy 345.378322 -237.752278)
			(xy 345.328708 -237.732806) (xy 345.28255 -237.706157) (xy 345.240879 -237.672926) (xy 345.204627 -237.633855)
			(xy 345.174603 -237.589818) (xy 345.151477 -237.541797) (xy 345.135767 -237.490867) (xy 345.127824 -237.438163)
			(xy 344.899244 -237.438163) (xy 344.891301 -237.490867) (xy 344.875591 -237.541797) (xy 344.852465 -237.589818)
			(xy 344.822441 -237.633855) (xy 344.786189 -237.672926) (xy 344.744518 -237.706157) (xy 344.69836 -237.732806)
			(xy 344.648746 -237.752278) (xy 344.596784 -237.764138) (xy 344.543634 -237.768122) (xy 344.490484 -237.764138)
			(xy 344.438522 -237.752278) (xy 344.388908 -237.732806) (xy 344.34275 -237.706157) (xy 344.301079 -237.672926)
			(xy 344.264827 -237.633855) (xy 344.234803 -237.589818) (xy 344.211677 -237.541797) (xy 344.195967 -237.490867)
			(xy 344.188024 -237.438163) (xy 343.959444 -237.438163) (xy 343.951501 -237.490867) (xy 343.935791 -237.541797)
			(xy 343.912665 -237.589818) (xy 343.882641 -237.633855) (xy 343.846389 -237.672926) (xy 343.804718 -237.706157)
			(xy 343.75856 -237.732806) (xy 343.708946 -237.752278) (xy 343.656984 -237.764138) (xy 343.603834 -237.768122)
			(xy 343.550684 -237.764138) (xy 343.498722 -237.752278) (xy 343.449108 -237.732806) (xy 343.40295 -237.706157)
			(xy 343.361279 -237.672926) (xy 343.325027 -237.633855) (xy 343.295003 -237.589818) (xy 343.271877 -237.541797)
			(xy 343.256167 -237.490867) (xy 343.248224 -237.438163) (xy 343.019644 -237.438163) (xy 343.011701 -237.490867)
			(xy 342.995991 -237.541797) (xy 342.972865 -237.589818) (xy 342.942841 -237.633855) (xy 342.906589 -237.672926)
			(xy 342.864918 -237.706157) (xy 342.81876 -237.732806) (xy 342.769146 -237.752278) (xy 342.717184 -237.764138)
			(xy 342.664034 -237.768122) (xy 342.610884 -237.764138) (xy 342.558922 -237.752278) (xy 342.509308 -237.732806)
			(xy 342.46315 -237.706157) (xy 342.421479 -237.672926) (xy 342.385227 -237.633855) (xy 342.355203 -237.589818)
			(xy 342.332077 -237.541797) (xy 342.316367 -237.490867) (xy 342.308424 -237.438163) (xy 342.079844 -237.438163)
			(xy 342.071901 -237.490867) (xy 342.056191 -237.541797) (xy 342.033065 -237.589818) (xy 342.003041 -237.633855)
			(xy 341.966789 -237.672926) (xy 341.925118 -237.706157) (xy 341.87896 -237.732806) (xy 341.829346 -237.752278)
			(xy 341.777384 -237.764138) (xy 341.724234 -237.768122) (xy 341.671084 -237.764138) (xy 341.619122 -237.752278)
			(xy 341.569508 -237.732806) (xy 341.52335 -237.706157) (xy 341.481679 -237.672926) (xy 341.445427 -237.633855)
			(xy 341.415403 -237.589818) (xy 341.392277 -237.541797) (xy 341.376567 -237.490867) (xy 341.368624 -237.438163)
			(xy 341.140044 -237.438163) (xy 341.132101 -237.490867) (xy 341.116391 -237.541797) (xy 341.093265 -237.589818)
			(xy 341.063241 -237.633855) (xy 341.026989 -237.672926) (xy 340.985318 -237.706157) (xy 340.93916 -237.732806)
			(xy 340.889546 -237.752278) (xy 340.837584 -237.764138) (xy 340.784434 -237.768122) (xy 340.731284 -237.764138)
			(xy 340.679322 -237.752278) (xy 340.629708 -237.732806) (xy 340.58355 -237.706157) (xy 340.541879 -237.672926)
			(xy 340.505627 -237.633855) (xy 340.475603 -237.589818) (xy 340.452477 -237.541797) (xy 340.436767 -237.490867)
			(xy 340.428824 -237.438163) (xy 340.19999 -237.438163) (xy 340.192047 -237.490867) (xy 340.176337 -237.541797)
			(xy 340.153211 -237.589818) (xy 340.123187 -237.633855) (xy 340.086935 -237.672926) (xy 340.045264 -237.706157)
			(xy 339.999106 -237.732806) (xy 339.949492 -237.752278) (xy 339.89753 -237.764138) (xy 339.84438 -237.768122)
			(xy 339.79123 -237.764138) (xy 339.739268 -237.752278) (xy 339.689654 -237.732806) (xy 339.643496 -237.706157)
			(xy 339.601825 -237.672926) (xy 339.565573 -237.633855) (xy 339.535549 -237.589818) (xy 339.512423 -237.541797)
			(xy 339.496713 -237.490867) (xy 339.48877 -237.438163) (xy 339.260444 -237.438163) (xy 339.252501 -237.490867)
			(xy 339.236791 -237.541797) (xy 339.213665 -237.589818) (xy 339.183641 -237.633855) (xy 339.147389 -237.672926)
			(xy 339.105718 -237.706157) (xy 339.05956 -237.732806) (xy 339.009946 -237.752278) (xy 338.957984 -237.764138)
			(xy 338.904834 -237.768122) (xy 338.851684 -237.764138) (xy 338.799722 -237.752278) (xy 338.750108 -237.732806)
			(xy 338.70395 -237.706157) (xy 338.662279 -237.672926) (xy 338.626027 -237.633855) (xy 338.596003 -237.589818)
			(xy 338.572877 -237.541797) (xy 338.557167 -237.490867) (xy 338.549224 -237.438163) (xy 338.320644 -237.438163)
			(xy 338.312701 -237.490867) (xy 338.296991 -237.541797) (xy 338.273865 -237.589818) (xy 338.243841 -237.633855)
			(xy 338.207589 -237.672926) (xy 338.165918 -237.706157) (xy 338.11976 -237.732806) (xy 338.070146 -237.752278)
			(xy 338.018184 -237.764138) (xy 337.965034 -237.768122) (xy 337.911884 -237.764138) (xy 337.859922 -237.752278)
			(xy 337.810308 -237.732806) (xy 337.76415 -237.706157) (xy 337.722479 -237.672926) (xy 337.686227 -237.633855)
			(xy 337.656203 -237.589818) (xy 337.633077 -237.541797) (xy 337.617367 -237.490867) (xy 337.609424 -237.438163)
			(xy 337.379796 -237.438163) (xy 337.377811 -237.464644) (xy 337.365953 -237.516602) (xy 337.346484 -237.566211)
			(xy 337.319839 -237.612366) (xy 337.286613 -237.654033) (xy 337.247548 -237.690284) (xy 337.203516 -237.720308)
			(xy 337.155502 -237.743434) (xy 337.104578 -237.759146) (xy 337.051881 -237.767094) (xy 337.025234 -237.767622)
			(xy 337.000539 -237.767223) (xy 336.951617 -237.760438) (xy 336.904104 -237.746952) (xy 336.858913 -237.727025)
			(xy 336.816911 -237.70104) (xy 336.79765 -237.68558) (xy 336.786267 -237.676799) (xy 336.759901 -237.665372)
			(xy 336.731394 -237.661746) (xy 336.703007 -237.666211) (xy 336.67699 -237.678411) (xy 336.655404 -237.69738)
			(xy 336.639962 -237.721614) (xy 336.631886 -237.749191) (xy 336.63128 -237.763558) (xy 336.63128 -237.875826)
			(xy 336.666332 -237.887256) (xy 336.691139 -237.895905) (xy 336.738094 -237.919465) (xy 336.781079 -237.949668)
			(xy 336.819162 -237.985857) (xy 336.851514 -238.027247) (xy 336.877436 -238.072942) (xy 336.896365 -238.121948)
			(xy 336.907889 -238.173203) (xy 336.911758 -238.225595) (xy 336.909791 -238.252233) (xy 337.13927 -238.252233)
			(xy 337.13927 -238.198935) (xy 337.147213 -238.146231) (xy 337.162923 -238.095301) (xy 337.186049 -238.04728)
			(xy 337.216073 -238.003243) (xy 337.252325 -237.964172) (xy 337.293996 -237.930941) (xy 337.340154 -237.904292)
			(xy 337.389768 -237.88482) (xy 337.44173 -237.87296) (xy 337.49488 -237.868977) (xy 337.54803 -237.87296)
			(xy 337.599992 -237.88482) (xy 337.649606 -237.904292) (xy 337.695764 -237.930941) (xy 337.737435 -237.964172)
			(xy 337.773687 -238.003243) (xy 337.803711 -238.04728) (xy 337.826837 -238.095301) (xy 337.842547 -238.146231)
			(xy 337.85049 -238.198935) (xy 337.850988 -238.225584) (xy 337.85049 -238.252233) (xy 338.07907 -238.252233)
			(xy 338.07907 -238.198935) (xy 338.087013 -238.146231) (xy 338.102723 -238.095301) (xy 338.125849 -238.04728)
			(xy 338.155873 -238.003243) (xy 338.192125 -237.964172) (xy 338.233796 -237.930941) (xy 338.279954 -237.904292)
			(xy 338.329568 -237.88482) (xy 338.38153 -237.87296) (xy 338.43468 -237.868977) (xy 338.48783 -237.87296)
			(xy 338.539792 -237.88482) (xy 338.589406 -237.904292) (xy 338.635564 -237.930941) (xy 338.677235 -237.964172)
			(xy 338.713487 -238.003243) (xy 338.743511 -238.04728) (xy 338.766637 -238.095301) (xy 338.782347 -238.146231)
			(xy 338.79029 -238.198935) (xy 338.790788 -238.225584) (xy 338.79029 -238.252233) (xy 339.019124 -238.252233)
			(xy 339.019124 -238.198935) (xy 339.027067 -238.146231) (xy 339.042777 -238.095301) (xy 339.065903 -238.04728)
			(xy 339.095927 -238.003243) (xy 339.132179 -237.964172) (xy 339.17385 -237.930941) (xy 339.220008 -237.904292)
			(xy 339.269622 -237.88482) (xy 339.321584 -237.87296) (xy 339.374734 -237.868977) (xy 339.427884 -237.87296)
			(xy 339.479846 -237.88482) (xy 339.52946 -237.904292) (xy 339.575618 -237.930941) (xy 339.617289 -237.964172)
			(xy 339.653541 -238.003243) (xy 339.683565 -238.04728) (xy 339.706691 -238.095301) (xy 339.722401 -238.146231)
			(xy 339.730344 -238.198935) (xy 339.730842 -238.225584) (xy 339.730344 -238.252233) (xy 339.95867 -238.252233)
			(xy 339.95867 -238.198935) (xy 339.966613 -238.146231) (xy 339.982323 -238.095301) (xy 340.005449 -238.04728)
			(xy 340.035473 -238.003243) (xy 340.071725 -237.964172) (xy 340.113396 -237.930941) (xy 340.159554 -237.904292)
			(xy 340.209168 -237.88482) (xy 340.26113 -237.87296) (xy 340.31428 -237.868977) (xy 340.36743 -237.87296)
			(xy 340.419392 -237.88482) (xy 340.469006 -237.904292) (xy 340.515164 -237.930941) (xy 340.556835 -237.964172)
			(xy 340.593087 -238.003243) (xy 340.623111 -238.04728) (xy 340.646237 -238.095301) (xy 340.661947 -238.146231)
			(xy 340.66989 -238.198935) (xy 340.670388 -238.225584) (xy 340.66989 -238.252233) (xy 340.89847 -238.252233)
			(xy 340.89847 -238.198935) (xy 340.906413 -238.146231) (xy 340.922123 -238.095301) (xy 340.945249 -238.04728)
			(xy 340.975273 -238.003243) (xy 341.011525 -237.964172) (xy 341.053196 -237.930941) (xy 341.099354 -237.904292)
			(xy 341.148968 -237.88482) (xy 341.20093 -237.87296) (xy 341.25408 -237.868977) (xy 341.30723 -237.87296)
			(xy 341.359192 -237.88482) (xy 341.408806 -237.904292) (xy 341.454964 -237.930941) (xy 341.496635 -237.964172)
			(xy 341.532887 -238.003243) (xy 341.562911 -238.04728) (xy 341.586037 -238.095301) (xy 341.601747 -238.146231)
			(xy 341.60969 -238.198935) (xy 341.610188 -238.225584) (xy 341.60969 -238.252233) (xy 341.83827 -238.252233)
			(xy 341.83827 -238.198935) (xy 341.846213 -238.146231) (xy 341.861923 -238.095301) (xy 341.885049 -238.04728)
			(xy 341.915073 -238.003243) (xy 341.951325 -237.964172) (xy 341.992996 -237.930941) (xy 342.039154 -237.904292)
			(xy 342.088768 -237.88482) (xy 342.14073 -237.87296) (xy 342.19388 -237.868977) (xy 342.24703 -237.87296)
			(xy 342.298992 -237.88482) (xy 342.348606 -237.904292) (xy 342.394764 -237.930941) (xy 342.436435 -237.964172)
			(xy 342.472687 -238.003243) (xy 342.502711 -238.04728) (xy 342.525837 -238.095301) (xy 342.541547 -238.146231)
			(xy 342.54949 -238.198935) (xy 342.549988 -238.225584) (xy 342.54949 -238.252233) (xy 342.77807 -238.252233)
			(xy 342.77807 -238.198935) (xy 342.786013 -238.146231) (xy 342.801723 -238.095301) (xy 342.824849 -238.04728)
			(xy 342.854873 -238.003243) (xy 342.891125 -237.964172) (xy 342.932796 -237.930941) (xy 342.978954 -237.904292)
			(xy 343.028568 -237.88482) (xy 343.08053 -237.87296) (xy 343.13368 -237.868977) (xy 343.18683 -237.87296)
			(xy 343.238792 -237.88482) (xy 343.288406 -237.904292) (xy 343.334564 -237.930941) (xy 343.376235 -237.964172)
			(xy 343.412487 -238.003243) (xy 343.442511 -238.04728) (xy 343.465637 -238.095301) (xy 343.481347 -238.146231)
			(xy 343.48929 -238.198935) (xy 343.489788 -238.225584) (xy 343.48929 -238.252233) (xy 343.71787 -238.252233)
			(xy 343.71787 -238.198935) (xy 343.725813 -238.146231) (xy 343.741523 -238.095301) (xy 343.764649 -238.04728)
			(xy 343.794673 -238.003243) (xy 343.830925 -237.964172) (xy 343.872596 -237.930941) (xy 343.918754 -237.904292)
			(xy 343.968368 -237.88482) (xy 344.02033 -237.87296) (xy 344.07348 -237.868977) (xy 344.12663 -237.87296)
			(xy 344.178592 -237.88482) (xy 344.228206 -237.904292) (xy 344.274364 -237.930941) (xy 344.316035 -237.964172)
			(xy 344.352287 -238.003243) (xy 344.382311 -238.04728) (xy 344.405437 -238.095301) (xy 344.421147 -238.146231)
			(xy 344.42909 -238.198935) (xy 344.429588 -238.225584) (xy 344.42909 -238.252233) (xy 344.65767 -238.252233)
			(xy 344.65767 -238.198935) (xy 344.665613 -238.146231) (xy 344.681323 -238.095301) (xy 344.704449 -238.04728)
			(xy 344.734473 -238.003243) (xy 344.770725 -237.964172) (xy 344.812396 -237.930941) (xy 344.858554 -237.904292)
			(xy 344.908168 -237.88482) (xy 344.96013 -237.87296) (xy 345.01328 -237.868977) (xy 345.06643 -237.87296)
			(xy 345.118392 -237.88482) (xy 345.168006 -237.904292) (xy 345.214164 -237.930941) (xy 345.255835 -237.964172)
			(xy 345.292087 -238.003243) (xy 345.322111 -238.04728) (xy 345.345237 -238.095301) (xy 345.360947 -238.146231)
			(xy 345.36889 -238.198935) (xy 345.369388 -238.225584) (xy 345.36889 -238.252233) (xy 345.597724 -238.252233)
			(xy 345.597724 -238.198935) (xy 345.605667 -238.146231) (xy 345.621377 -238.095301) (xy 345.644503 -238.04728)
			(xy 345.674527 -238.003243) (xy 345.710779 -237.964172) (xy 345.75245 -237.930941) (xy 345.798608 -237.904292)
			(xy 345.848222 -237.88482) (xy 345.900184 -237.87296) (xy 345.953334 -237.868977) (xy 346.006484 -237.87296)
			(xy 346.058446 -237.88482) (xy 346.10806 -237.904292) (xy 346.154218 -237.930941) (xy 346.195889 -237.964172)
			(xy 346.232141 -238.003243) (xy 346.262165 -238.04728) (xy 346.285291 -238.095301) (xy 346.301001 -238.146231)
			(xy 346.308944 -238.198935) (xy 346.309442 -238.225584) (xy 346.308944 -238.252233) (xy 346.301001 -238.304937)
			(xy 346.285291 -238.355867) (xy 346.262165 -238.403888) (xy 346.232141 -238.447925) (xy 346.195889 -238.486996)
			(xy 346.154218 -238.520227) (xy 346.10806 -238.546876) (xy 346.058446 -238.566348) (xy 346.006484 -238.578208)
			(xy 345.953334 -238.582192) (xy 345.900184 -238.578208) (xy 345.848222 -238.566348) (xy 345.798608 -238.546876)
			(xy 345.75245 -238.520227) (xy 345.710779 -238.486996) (xy 345.674527 -238.447925) (xy 345.644503 -238.403888)
			(xy 345.621377 -238.355867) (xy 345.605667 -238.304937) (xy 345.597724 -238.252233) (xy 345.36889 -238.252233)
			(xy 345.360947 -238.304937) (xy 345.345237 -238.355867) (xy 345.322111 -238.403888) (xy 345.292087 -238.447925)
			(xy 345.255835 -238.486996) (xy 345.214164 -238.520227) (xy 345.168006 -238.546876) (xy 345.118392 -238.566348)
			(xy 345.06643 -238.578208) (xy 345.01328 -238.582192) (xy 344.96013 -238.578208) (xy 344.908168 -238.566348)
			(xy 344.858554 -238.546876) (xy 344.812396 -238.520227) (xy 344.770725 -238.486996) (xy 344.734473 -238.447925)
			(xy 344.704449 -238.403888) (xy 344.681323 -238.355867) (xy 344.665613 -238.304937) (xy 344.65767 -238.252233)
			(xy 344.42909 -238.252233) (xy 344.421147 -238.304937) (xy 344.405437 -238.355867) (xy 344.382311 -238.403888)
			(xy 344.352287 -238.447925) (xy 344.316035 -238.486996) (xy 344.274364 -238.520227) (xy 344.228206 -238.546876)
			(xy 344.178592 -238.566348) (xy 344.12663 -238.578208) (xy 344.07348 -238.582192) (xy 344.02033 -238.578208)
			(xy 343.968368 -238.566348) (xy 343.918754 -238.546876) (xy 343.872596 -238.520227) (xy 343.830925 -238.486996)
			(xy 343.794673 -238.447925) (xy 343.764649 -238.403888) (xy 343.741523 -238.355867) (xy 343.725813 -238.304937)
			(xy 343.71787 -238.252233) (xy 343.48929 -238.252233) (xy 343.481347 -238.304937) (xy 343.465637 -238.355867)
			(xy 343.442511 -238.403888) (xy 343.412487 -238.447925) (xy 343.376235 -238.486996) (xy 343.334564 -238.520227)
			(xy 343.288406 -238.546876) (xy 343.238792 -238.566348) (xy 343.18683 -238.578208) (xy 343.13368 -238.582192)
			(xy 343.08053 -238.578208) (xy 343.028568 -238.566348) (xy 342.978954 -238.546876) (xy 342.932796 -238.520227)
			(xy 342.891125 -238.486996) (xy 342.854873 -238.447925) (xy 342.824849 -238.403888) (xy 342.801723 -238.355867)
			(xy 342.786013 -238.304937) (xy 342.77807 -238.252233) (xy 342.54949 -238.252233) (xy 342.541547 -238.304937)
			(xy 342.525837 -238.355867) (xy 342.502711 -238.403888) (xy 342.472687 -238.447925) (xy 342.436435 -238.486996)
			(xy 342.394764 -238.520227) (xy 342.348606 -238.546876) (xy 342.298992 -238.566348) (xy 342.24703 -238.578208)
			(xy 342.19388 -238.582192) (xy 342.14073 -238.578208) (xy 342.088768 -238.566348) (xy 342.039154 -238.546876)
			(xy 341.992996 -238.520227) (xy 341.951325 -238.486996) (xy 341.915073 -238.447925) (xy 341.885049 -238.403888)
			(xy 341.861923 -238.355867) (xy 341.846213 -238.304937) (xy 341.83827 -238.252233) (xy 341.60969 -238.252233)
			(xy 341.601747 -238.304937) (xy 341.586037 -238.355867) (xy 341.562911 -238.403888) (xy 341.532887 -238.447925)
			(xy 341.496635 -238.486996) (xy 341.454964 -238.520227) (xy 341.408806 -238.546876) (xy 341.359192 -238.566348)
			(xy 341.30723 -238.578208) (xy 341.25408 -238.582192) (xy 341.20093 -238.578208) (xy 341.148968 -238.566348)
			(xy 341.099354 -238.546876) (xy 341.053196 -238.520227) (xy 341.011525 -238.486996) (xy 340.975273 -238.447925)
			(xy 340.945249 -238.403888) (xy 340.922123 -238.355867) (xy 340.906413 -238.304937) (xy 340.89847 -238.252233)
			(xy 340.66989 -238.252233) (xy 340.661947 -238.304937) (xy 340.646237 -238.355867) (xy 340.623111 -238.403888)
			(xy 340.593087 -238.447925) (xy 340.556835 -238.486996) (xy 340.515164 -238.520227) (xy 340.469006 -238.546876)
			(xy 340.419392 -238.566348) (xy 340.36743 -238.578208) (xy 340.31428 -238.582192) (xy 340.26113 -238.578208)
			(xy 340.209168 -238.566348) (xy 340.159554 -238.546876) (xy 340.113396 -238.520227) (xy 340.071725 -238.486996)
			(xy 340.035473 -238.447925) (xy 340.005449 -238.403888) (xy 339.982323 -238.355867) (xy 339.966613 -238.304937)
			(xy 339.95867 -238.252233) (xy 339.730344 -238.252233) (xy 339.722401 -238.304937) (xy 339.706691 -238.355867)
			(xy 339.683565 -238.403888) (xy 339.653541 -238.447925) (xy 339.617289 -238.486996) (xy 339.575618 -238.520227)
			(xy 339.52946 -238.546876) (xy 339.479846 -238.566348) (xy 339.427884 -238.578208) (xy 339.374734 -238.582192)
			(xy 339.321584 -238.578208) (xy 339.269622 -238.566348) (xy 339.220008 -238.546876) (xy 339.17385 -238.520227)
			(xy 339.132179 -238.486996) (xy 339.095927 -238.447925) (xy 339.065903 -238.403888) (xy 339.042777 -238.355867)
			(xy 339.027067 -238.304937) (xy 339.019124 -238.252233) (xy 338.79029 -238.252233) (xy 338.782347 -238.304937)
			(xy 338.766637 -238.355867) (xy 338.743511 -238.403888) (xy 338.713487 -238.447925) (xy 338.677235 -238.486996)
			(xy 338.635564 -238.520227) (xy 338.589406 -238.546876) (xy 338.539792 -238.566348) (xy 338.48783 -238.578208)
			(xy 338.43468 -238.582192) (xy 338.38153 -238.578208) (xy 338.329568 -238.566348) (xy 338.279954 -238.546876)
			(xy 338.233796 -238.520227) (xy 338.192125 -238.486996) (xy 338.155873 -238.447925) (xy 338.125849 -238.403888)
			(xy 338.102723 -238.355867) (xy 338.087013 -238.304937) (xy 338.07907 -238.252233) (xy 337.85049 -238.252233)
			(xy 337.842547 -238.304937) (xy 337.826837 -238.355867) (xy 337.803711 -238.403888) (xy 337.773687 -238.447925)
			(xy 337.737435 -238.486996) (xy 337.695764 -238.520227) (xy 337.649606 -238.546876) (xy 337.599992 -238.566348)
			(xy 337.54803 -238.578208) (xy 337.49488 -238.582192) (xy 337.44173 -238.578208) (xy 337.389768 -238.566348)
			(xy 337.340154 -238.546876) (xy 337.293996 -238.520227) (xy 337.252325 -238.486996) (xy 337.216073 -238.447925)
			(xy 337.186049 -238.403888) (xy 337.162923 -238.355867) (xy 337.147213 -238.304937) (xy 337.13927 -238.252233)
			(xy 336.909791 -238.252233) (xy 336.90789 -238.277987) (xy 336.896367 -238.329243) (xy 336.877441 -238.378249)
			(xy 336.85152 -238.423944) (xy 336.819168 -238.465336) (xy 336.781087 -238.501526) (xy 336.738103 -238.531729)
			(xy 336.691148 -238.555291) (xy 336.666332 -238.563912) (xy 336.63128 -238.575342) (xy 336.63128 -238.687356)
			(xy 336.631811 -238.701723) (xy 336.639892 -238.729299) (xy 336.655342 -238.753529) (xy 336.676934 -238.772491)
			(xy 336.702957 -238.784681) (xy 336.731346 -238.789132) (xy 336.759851 -238.785491) (xy 336.786211 -238.774048)
			(xy 336.79765 -238.765334) (xy 336.816926 -238.749895) (xy 336.85893 -238.723921) (xy 336.904118 -238.703998)
			(xy 336.951626 -238.690505) (xy 337.000541 -238.683703) (xy 337.025234 -238.683292) (xy 337.051882 -238.683792)
			(xy 337.104581 -238.69174) (xy 337.155507 -238.707453) (xy 337.203523 -238.73058) (xy 337.247556 -238.760605)
			(xy 337.286623 -238.796857) (xy 337.31985 -238.838527) (xy 337.346496 -238.884683) (xy 337.365966 -238.934294)
			(xy 337.377825 -238.986254) (xy 337.381808 -239.0394) (xy 337.379811 -239.066049) (xy 337.609424 -239.066049)
			(xy 337.609424 -239.012751) (xy 337.617367 -238.960047) (xy 337.633077 -238.909117) (xy 337.656203 -238.861096)
			(xy 337.686227 -238.817059) (xy 337.722479 -238.777988) (xy 337.76415 -238.744757) (xy 337.810308 -238.718108)
			(xy 337.859922 -238.698636) (xy 337.911884 -238.686776) (xy 337.965034 -238.682793) (xy 338.018184 -238.686776)
			(xy 338.070146 -238.698636) (xy 338.11976 -238.718108) (xy 338.165918 -238.744757) (xy 338.207589 -238.777988)
			(xy 338.243841 -238.817059) (xy 338.273865 -238.861096) (xy 338.296991 -238.909117) (xy 338.312701 -238.960047)
			(xy 338.320644 -239.012751) (xy 338.321142 -239.0394) (xy 338.320644 -239.066049) (xy 338.549224 -239.066049)
			(xy 338.549224 -239.012751) (xy 338.557167 -238.960047) (xy 338.572877 -238.909117) (xy 338.596003 -238.861096)
			(xy 338.626027 -238.817059) (xy 338.662279 -238.777988) (xy 338.70395 -238.744757) (xy 338.750108 -238.718108)
			(xy 338.799722 -238.698636) (xy 338.851684 -238.686776) (xy 338.904834 -238.682793) (xy 338.957984 -238.686776)
			(xy 339.009946 -238.698636) (xy 339.05956 -238.718108) (xy 339.105718 -238.744757) (xy 339.147389 -238.777988)
			(xy 339.183641 -238.817059) (xy 339.213665 -238.861096) (xy 339.236791 -238.909117) (xy 339.252501 -238.960047)
			(xy 339.260444 -239.012751) (xy 339.260942 -239.0394) (xy 339.260444 -239.066049) (xy 339.489024 -239.066049)
			(xy 339.489024 -239.012751) (xy 339.496967 -238.960047) (xy 339.512677 -238.909117) (xy 339.535803 -238.861096)
			(xy 339.565827 -238.817059) (xy 339.602079 -238.777988) (xy 339.64375 -238.744757) (xy 339.689908 -238.718108)
			(xy 339.739522 -238.698636) (xy 339.791484 -238.686776) (xy 339.844634 -238.682793) (xy 339.897784 -238.686776)
			(xy 339.949746 -238.698636) (xy 339.99936 -238.718108) (xy 340.045518 -238.744757) (xy 340.087189 -238.777988)
			(xy 340.123441 -238.817059) (xy 340.153465 -238.861096) (xy 340.176591 -238.909117) (xy 340.192301 -238.960047)
			(xy 340.200244 -239.012751) (xy 340.200742 -239.0394) (xy 340.200244 -239.066049) (xy 340.428824 -239.066049)
			(xy 340.428824 -239.012751) (xy 340.436767 -238.960047) (xy 340.452477 -238.909117) (xy 340.475603 -238.861096)
			(xy 340.505627 -238.817059) (xy 340.541879 -238.777988) (xy 340.58355 -238.744757) (xy 340.629708 -238.718108)
			(xy 340.679322 -238.698636) (xy 340.731284 -238.686776) (xy 340.784434 -238.682793) (xy 340.837584 -238.686776)
			(xy 340.889546 -238.698636) (xy 340.93916 -238.718108) (xy 340.985318 -238.744757) (xy 341.026989 -238.777988)
			(xy 341.063241 -238.817059) (xy 341.093265 -238.861096) (xy 341.116391 -238.909117) (xy 341.132101 -238.960047)
			(xy 341.140044 -239.012751) (xy 341.140542 -239.0394) (xy 341.140044 -239.066049) (xy 341.368624 -239.066049)
			(xy 341.368624 -239.012751) (xy 341.376567 -238.960047) (xy 341.392277 -238.909117) (xy 341.415403 -238.861096)
			(xy 341.445427 -238.817059) (xy 341.481679 -238.777988) (xy 341.52335 -238.744757) (xy 341.569508 -238.718108)
			(xy 341.619122 -238.698636) (xy 341.671084 -238.686776) (xy 341.724234 -238.682793) (xy 341.777384 -238.686776)
			(xy 341.829346 -238.698636) (xy 341.87896 -238.718108) (xy 341.925118 -238.744757) (xy 341.966789 -238.777988)
			(xy 342.003041 -238.817059) (xy 342.033065 -238.861096) (xy 342.056191 -238.909117) (xy 342.071901 -238.960047)
			(xy 342.079844 -239.012751) (xy 342.080342 -239.0394) (xy 342.079844 -239.066049) (xy 342.30817 -239.066049)
			(xy 342.30817 -239.012751) (xy 342.316113 -238.960047) (xy 342.331823 -238.909117) (xy 342.354949 -238.861096)
			(xy 342.384973 -238.817059) (xy 342.421225 -238.777988) (xy 342.462896 -238.744757) (xy 342.509054 -238.718108)
			(xy 342.558668 -238.698636) (xy 342.61063 -238.686776) (xy 342.66378 -238.682793) (xy 342.71693 -238.686776)
			(xy 342.768892 -238.698636) (xy 342.818506 -238.718108) (xy 342.864664 -238.744757) (xy 342.906335 -238.777988)
			(xy 342.942587 -238.817059) (xy 342.972611 -238.861096) (xy 342.995737 -238.909117) (xy 343.011447 -238.960047)
			(xy 343.01939 -239.012751) (xy 343.019888 -239.0394) (xy 343.01939 -239.066049) (xy 343.248224 -239.066049)
			(xy 343.248224 -239.012751) (xy 343.256167 -238.960047) (xy 343.271877 -238.909117) (xy 343.295003 -238.861096)
			(xy 343.325027 -238.817059) (xy 343.361279 -238.777988) (xy 343.40295 -238.744757) (xy 343.449108 -238.718108)
			(xy 343.498722 -238.698636) (xy 343.550684 -238.686776) (xy 343.603834 -238.682793) (xy 343.656984 -238.686776)
			(xy 343.708946 -238.698636) (xy 343.75856 -238.718108) (xy 343.804718 -238.744757) (xy 343.846389 -238.777988)
			(xy 343.882641 -238.817059) (xy 343.912665 -238.861096) (xy 343.935791 -238.909117) (xy 343.951501 -238.960047)
			(xy 343.959444 -239.012751) (xy 343.959942 -239.0394) (xy 343.959444 -239.066049) (xy 344.188024 -239.066049)
			(xy 344.188024 -239.012751) (xy 344.195967 -238.960047) (xy 344.211677 -238.909117) (xy 344.234803 -238.861096)
			(xy 344.264827 -238.817059) (xy 344.301079 -238.777988) (xy 344.34275 -238.744757) (xy 344.388908 -238.718108)
			(xy 344.438522 -238.698636) (xy 344.490484 -238.686776) (xy 344.543634 -238.682793) (xy 344.596784 -238.686776)
			(xy 344.648746 -238.698636) (xy 344.69836 -238.718108) (xy 344.744518 -238.744757) (xy 344.786189 -238.777988)
			(xy 344.822441 -238.817059) (xy 344.852465 -238.861096) (xy 344.875591 -238.909117) (xy 344.891301 -238.960047)
			(xy 344.899244 -239.012751) (xy 344.899742 -239.0394) (xy 344.899244 -239.066049) (xy 345.127824 -239.066049)
			(xy 345.127824 -239.012751) (xy 345.135767 -238.960047) (xy 345.151477 -238.909117) (xy 345.174603 -238.861096)
			(xy 345.204627 -238.817059) (xy 345.240879 -238.777988) (xy 345.28255 -238.744757) (xy 345.328708 -238.718108)
			(xy 345.378322 -238.698636) (xy 345.430284 -238.686776) (xy 345.483434 -238.682793) (xy 345.536584 -238.686776)
			(xy 345.588546 -238.698636) (xy 345.63816 -238.718108) (xy 345.684318 -238.744757) (xy 345.725989 -238.777988)
			(xy 345.762241 -238.817059) (xy 345.792265 -238.861096) (xy 345.815391 -238.909117) (xy 345.831101 -238.960047)
			(xy 345.839044 -239.012751) (xy 345.839542 -239.0394) (xy 345.839044 -239.066049) (xy 346.067624 -239.066049)
			(xy 346.067624 -239.012751) (xy 346.075567 -238.960047) (xy 346.091277 -238.909117) (xy 346.114403 -238.861096)
			(xy 346.144427 -238.817059) (xy 346.180679 -238.777988) (xy 346.22235 -238.744757) (xy 346.268508 -238.718108)
			(xy 346.318122 -238.698636) (xy 346.370084 -238.686776) (xy 346.423234 -238.682793) (xy 346.476384 -238.686776)
			(xy 346.528346 -238.698636) (xy 346.57796 -238.718108) (xy 346.624118 -238.744757) (xy 346.665789 -238.777988)
			(xy 346.702041 -238.817059) (xy 346.732065 -238.861096) (xy 346.755191 -238.909117) (xy 346.770901 -238.960047)
			(xy 346.778844 -239.012751) (xy 346.779342 -239.0394) (xy 346.778844 -239.066049) (xy 346.770901 -239.118753)
			(xy 346.755191 -239.169683) (xy 346.732065 -239.217704) (xy 346.702041 -239.261741) (xy 346.665789 -239.300812)
			(xy 346.624118 -239.334043) (xy 346.57796 -239.360692) (xy 346.528346 -239.380164) (xy 346.476384 -239.392024)
			(xy 346.423234 -239.396008) (xy 346.370084 -239.392024) (xy 346.318122 -239.380164) (xy 346.268508 -239.360692)
			(xy 346.22235 -239.334043) (xy 346.180679 -239.300812) (xy 346.144427 -239.261741) (xy 346.114403 -239.217704)
			(xy 346.091277 -239.169683) (xy 346.075567 -239.118753) (xy 346.067624 -239.066049) (xy 345.839044 -239.066049)
			(xy 345.831101 -239.118753) (xy 345.815391 -239.169683) (xy 345.792265 -239.217704) (xy 345.762241 -239.261741)
			(xy 345.725989 -239.300812) (xy 345.684318 -239.334043) (xy 345.63816 -239.360692) (xy 345.588546 -239.380164)
			(xy 345.536584 -239.392024) (xy 345.483434 -239.396008) (xy 345.430284 -239.392024) (xy 345.378322 -239.380164)
			(xy 345.328708 -239.360692) (xy 345.28255 -239.334043) (xy 345.240879 -239.300812) (xy 345.204627 -239.261741)
			(xy 345.174603 -239.217704) (xy 345.151477 -239.169683) (xy 345.135767 -239.118753) (xy 345.127824 -239.066049)
			(xy 344.899244 -239.066049) (xy 344.891301 -239.118753) (xy 344.875591 -239.169683) (xy 344.852465 -239.217704)
			(xy 344.822441 -239.261741) (xy 344.786189 -239.300812) (xy 344.744518 -239.334043) (xy 344.69836 -239.360692)
			(xy 344.648746 -239.380164) (xy 344.596784 -239.392024) (xy 344.543634 -239.396008) (xy 344.490484 -239.392024)
			(xy 344.438522 -239.380164) (xy 344.388908 -239.360692) (xy 344.34275 -239.334043) (xy 344.301079 -239.300812)
			(xy 344.264827 -239.261741) (xy 344.234803 -239.217704) (xy 344.211677 -239.169683) (xy 344.195967 -239.118753)
			(xy 344.188024 -239.066049) (xy 343.959444 -239.066049) (xy 343.951501 -239.118753) (xy 343.935791 -239.169683)
			(xy 343.912665 -239.217704) (xy 343.882641 -239.261741) (xy 343.846389 -239.300812) (xy 343.804718 -239.334043)
			(xy 343.75856 -239.360692) (xy 343.708946 -239.380164) (xy 343.656984 -239.392024) (xy 343.603834 -239.396008)
			(xy 343.550684 -239.392024) (xy 343.498722 -239.380164) (xy 343.449108 -239.360692) (xy 343.40295 -239.334043)
			(xy 343.361279 -239.300812) (xy 343.325027 -239.261741) (xy 343.295003 -239.217704) (xy 343.271877 -239.169683)
			(xy 343.256167 -239.118753) (xy 343.248224 -239.066049) (xy 343.01939 -239.066049) (xy 343.011447 -239.118753)
			(xy 342.995737 -239.169683) (xy 342.972611 -239.217704) (xy 342.942587 -239.261741) (xy 342.906335 -239.300812)
			(xy 342.864664 -239.334043) (xy 342.818506 -239.360692) (xy 342.768892 -239.380164) (xy 342.71693 -239.392024)
			(xy 342.66378 -239.396008) (xy 342.61063 -239.392024) (xy 342.558668 -239.380164) (xy 342.509054 -239.360692)
			(xy 342.462896 -239.334043) (xy 342.421225 -239.300812) (xy 342.384973 -239.261741) (xy 342.354949 -239.217704)
			(xy 342.331823 -239.169683) (xy 342.316113 -239.118753) (xy 342.30817 -239.066049) (xy 342.079844 -239.066049)
			(xy 342.071901 -239.118753) (xy 342.056191 -239.169683) (xy 342.033065 -239.217704) (xy 342.003041 -239.261741)
			(xy 341.966789 -239.300812) (xy 341.925118 -239.334043) (xy 341.87896 -239.360692) (xy 341.829346 -239.380164)
			(xy 341.777384 -239.392024) (xy 341.724234 -239.396008) (xy 341.671084 -239.392024) (xy 341.619122 -239.380164)
			(xy 341.569508 -239.360692) (xy 341.52335 -239.334043) (xy 341.481679 -239.300812) (xy 341.445427 -239.261741)
			(xy 341.415403 -239.217704) (xy 341.392277 -239.169683) (xy 341.376567 -239.118753) (xy 341.368624 -239.066049)
			(xy 341.140044 -239.066049) (xy 341.132101 -239.118753) (xy 341.116391 -239.169683) (xy 341.093265 -239.217704)
			(xy 341.063241 -239.261741) (xy 341.026989 -239.300812) (xy 340.985318 -239.334043) (xy 340.93916 -239.360692)
			(xy 340.889546 -239.380164) (xy 340.837584 -239.392024) (xy 340.784434 -239.396008) (xy 340.731284 -239.392024)
			(xy 340.679322 -239.380164) (xy 340.629708 -239.360692) (xy 340.58355 -239.334043) (xy 340.541879 -239.300812)
			(xy 340.505627 -239.261741) (xy 340.475603 -239.217704) (xy 340.452477 -239.169683) (xy 340.436767 -239.118753)
			(xy 340.428824 -239.066049) (xy 340.200244 -239.066049) (xy 340.192301 -239.118753) (xy 340.176591 -239.169683)
			(xy 340.153465 -239.217704) (xy 340.123441 -239.261741) (xy 340.087189 -239.300812) (xy 340.045518 -239.334043)
			(xy 339.99936 -239.360692) (xy 339.949746 -239.380164) (xy 339.897784 -239.392024) (xy 339.844634 -239.396008)
			(xy 339.791484 -239.392024) (xy 339.739522 -239.380164) (xy 339.689908 -239.360692) (xy 339.64375 -239.334043)
			(xy 339.602079 -239.300812) (xy 339.565827 -239.261741) (xy 339.535803 -239.217704) (xy 339.512677 -239.169683)
			(xy 339.496967 -239.118753) (xy 339.489024 -239.066049) (xy 339.260444 -239.066049) (xy 339.252501 -239.118753)
			(xy 339.236791 -239.169683) (xy 339.213665 -239.217704) (xy 339.183641 -239.261741) (xy 339.147389 -239.300812)
			(xy 339.105718 -239.334043) (xy 339.05956 -239.360692) (xy 339.009946 -239.380164) (xy 338.957984 -239.392024)
			(xy 338.904834 -239.396008) (xy 338.851684 -239.392024) (xy 338.799722 -239.380164) (xy 338.750108 -239.360692)
			(xy 338.70395 -239.334043) (xy 338.662279 -239.300812) (xy 338.626027 -239.261741) (xy 338.596003 -239.217704)
			(xy 338.572877 -239.169683) (xy 338.557167 -239.118753) (xy 338.549224 -239.066049) (xy 338.320644 -239.066049)
			(xy 338.312701 -239.118753) (xy 338.296991 -239.169683) (xy 338.273865 -239.217704) (xy 338.243841 -239.261741)
			(xy 338.207589 -239.300812) (xy 338.165918 -239.334043) (xy 338.11976 -239.360692) (xy 338.070146 -239.380164)
			(xy 338.018184 -239.392024) (xy 337.965034 -239.396008) (xy 337.911884 -239.392024) (xy 337.859922 -239.380164)
			(xy 337.810308 -239.360692) (xy 337.76415 -239.334043) (xy 337.722479 -239.300812) (xy 337.686227 -239.261741)
			(xy 337.656203 -239.217704) (xy 337.633077 -239.169683) (xy 337.617367 -239.118753) (xy 337.609424 -239.066049)
			(xy 337.379811 -239.066049) (xy 337.377825 -239.092546) (xy 337.365966 -239.144506) (xy 337.346496 -239.194117)
			(xy 337.31985 -239.240273) (xy 337.286623 -239.281943) (xy 337.247556 -239.318195) (xy 337.203523 -239.34822)
			(xy 337.155507 -239.371347) (xy 337.104581 -239.38706) (xy 337.051882 -239.395008) (xy 337.025234 -239.395508)
			(xy 337.000539 -239.395109) (xy 336.951617 -239.388324) (xy 336.904105 -239.374838) (xy 336.858914 -239.35491)
			(xy 336.816913 -239.328924) (xy 336.79765 -239.313466) (xy 336.786266 -239.304686) (xy 336.759899 -239.29326)
			(xy 336.731393 -239.289636) (xy 336.703005 -239.2941) (xy 336.676987 -239.3063) (xy 336.655401 -239.325268)
			(xy 336.639956 -239.3495) (xy 336.631877 -239.377077) (xy 336.63128 -239.391444) (xy 336.63128 -239.503458)
			(xy 336.666332 -239.514888) (xy 336.691137 -239.523537) (xy 336.738087 -239.547097) (xy 336.781068 -239.577298)
			(xy 336.819146 -239.613485) (xy 336.851495 -239.654873) (xy 336.877413 -239.700564) (xy 336.896338 -239.749566)
			(xy 336.90786 -239.800817) (xy 336.911728 -239.853205) (xy 336.909759 -239.879865) (xy 337.13927 -239.879865)
			(xy 337.13927 -239.826567) (xy 337.147213 -239.773863) (xy 337.162923 -239.722933) (xy 337.186049 -239.674912)
			(xy 337.216073 -239.630875) (xy 337.252325 -239.591804) (xy 337.293996 -239.558573) (xy 337.340154 -239.531924)
			(xy 337.389768 -239.512452) (xy 337.44173 -239.500592) (xy 337.49488 -239.496609) (xy 337.54803 -239.500592)
			(xy 337.599992 -239.512452) (xy 337.649606 -239.531924) (xy 337.695764 -239.558573) (xy 337.737435 -239.591804)
			(xy 337.773687 -239.630875) (xy 337.803711 -239.674912) (xy 337.826837 -239.722933) (xy 337.842547 -239.773863)
			(xy 337.85049 -239.826567) (xy 337.850988 -239.853216) (xy 337.85049 -239.879865) (xy 338.079324 -239.879865)
			(xy 338.079324 -239.826567) (xy 338.087267 -239.773863) (xy 338.102977 -239.722933) (xy 338.126103 -239.674912)
			(xy 338.156127 -239.630875) (xy 338.192379 -239.591804) (xy 338.23405 -239.558573) (xy 338.280208 -239.531924)
			(xy 338.329822 -239.512452) (xy 338.381784 -239.500592) (xy 338.434934 -239.496609) (xy 338.488084 -239.500592)
			(xy 338.540046 -239.512452) (xy 338.58966 -239.531924) (xy 338.635818 -239.558573) (xy 338.677489 -239.591804)
			(xy 338.713741 -239.630875) (xy 338.743765 -239.674912) (xy 338.766891 -239.722933) (xy 338.782601 -239.773863)
			(xy 338.790544 -239.826567) (xy 338.791042 -239.853216) (xy 338.790544 -239.879865) (xy 339.01887 -239.879865)
			(xy 339.01887 -239.826567) (xy 339.026813 -239.773863) (xy 339.042523 -239.722933) (xy 339.065649 -239.674912)
			(xy 339.095673 -239.630875) (xy 339.131925 -239.591804) (xy 339.173596 -239.558573) (xy 339.219754 -239.531924)
			(xy 339.269368 -239.512452) (xy 339.32133 -239.500592) (xy 339.37448 -239.496609) (xy 339.42763 -239.500592)
			(xy 339.479592 -239.512452) (xy 339.529206 -239.531924) (xy 339.575364 -239.558573) (xy 339.617035 -239.591804)
			(xy 339.653287 -239.630875) (xy 339.683311 -239.674912) (xy 339.706437 -239.722933) (xy 339.722147 -239.773863)
			(xy 339.73009 -239.826567) (xy 339.730588 -239.853216) (xy 339.73009 -239.879865) (xy 339.95867 -239.879865)
			(xy 339.95867 -239.826567) (xy 339.966613 -239.773863) (xy 339.982323 -239.722933) (xy 340.005449 -239.674912)
			(xy 340.035473 -239.630875) (xy 340.071725 -239.591804) (xy 340.113396 -239.558573) (xy 340.159554 -239.531924)
			(xy 340.209168 -239.512452) (xy 340.26113 -239.500592) (xy 340.31428 -239.496609) (xy 340.36743 -239.500592)
			(xy 340.419392 -239.512452) (xy 340.469006 -239.531924) (xy 340.515164 -239.558573) (xy 340.556835 -239.591804)
			(xy 340.593087 -239.630875) (xy 340.623111 -239.674912) (xy 340.646237 -239.722933) (xy 340.661947 -239.773863)
			(xy 340.66989 -239.826567) (xy 340.670388 -239.853216) (xy 340.66989 -239.879865) (xy 340.89847 -239.879865)
			(xy 340.89847 -239.826567) (xy 340.906413 -239.773863) (xy 340.922123 -239.722933) (xy 340.945249 -239.674912)
			(xy 340.975273 -239.630875) (xy 341.011525 -239.591804) (xy 341.053196 -239.558573) (xy 341.099354 -239.531924)
			(xy 341.148968 -239.512452) (xy 341.20093 -239.500592) (xy 341.25408 -239.496609) (xy 341.30723 -239.500592)
			(xy 341.359192 -239.512452) (xy 341.408806 -239.531924) (xy 341.454964 -239.558573) (xy 341.496635 -239.591804)
			(xy 341.532887 -239.630875) (xy 341.562911 -239.674912) (xy 341.586037 -239.722933) (xy 341.601747 -239.773863)
			(xy 341.60969 -239.826567) (xy 341.610188 -239.853216) (xy 341.60969 -239.879865) (xy 341.83827 -239.879865)
			(xy 341.83827 -239.826567) (xy 341.846213 -239.773863) (xy 341.861923 -239.722933) (xy 341.885049 -239.674912)
			(xy 341.915073 -239.630875) (xy 341.951325 -239.591804) (xy 341.992996 -239.558573) (xy 342.039154 -239.531924)
			(xy 342.088768 -239.512452) (xy 342.14073 -239.500592) (xy 342.19388 -239.496609) (xy 342.24703 -239.500592)
			(xy 342.298992 -239.512452) (xy 342.348606 -239.531924) (xy 342.394764 -239.558573) (xy 342.436435 -239.591804)
			(xy 342.472687 -239.630875) (xy 342.502711 -239.674912) (xy 342.525837 -239.722933) (xy 342.541547 -239.773863)
			(xy 342.54949 -239.826567) (xy 342.549988 -239.853216) (xy 342.54949 -239.879865) (xy 342.77807 -239.879865)
			(xy 342.77807 -239.826567) (xy 342.786013 -239.773863) (xy 342.801723 -239.722933) (xy 342.824849 -239.674912)
			(xy 342.854873 -239.630875) (xy 342.891125 -239.591804) (xy 342.932796 -239.558573) (xy 342.978954 -239.531924)
			(xy 343.028568 -239.512452) (xy 343.08053 -239.500592) (xy 343.13368 -239.496609) (xy 343.18683 -239.500592)
			(xy 343.238792 -239.512452) (xy 343.288406 -239.531924) (xy 343.334564 -239.558573) (xy 343.376235 -239.591804)
			(xy 343.412487 -239.630875) (xy 343.442511 -239.674912) (xy 343.465637 -239.722933) (xy 343.481347 -239.773863)
			(xy 343.48929 -239.826567) (xy 343.489788 -239.853216) (xy 343.48929 -239.879865) (xy 343.71787 -239.879865)
			(xy 343.71787 -239.826567) (xy 343.725813 -239.773863) (xy 343.741523 -239.722933) (xy 343.764649 -239.674912)
			(xy 343.794673 -239.630875) (xy 343.830925 -239.591804) (xy 343.872596 -239.558573) (xy 343.918754 -239.531924)
			(xy 343.968368 -239.512452) (xy 344.02033 -239.500592) (xy 344.07348 -239.496609) (xy 344.12663 -239.500592)
			(xy 344.178592 -239.512452) (xy 344.228206 -239.531924) (xy 344.274364 -239.558573) (xy 344.316035 -239.591804)
			(xy 344.352287 -239.630875) (xy 344.382311 -239.674912) (xy 344.405437 -239.722933) (xy 344.421147 -239.773863)
			(xy 344.42909 -239.826567) (xy 344.429588 -239.853216) (xy 344.42909 -239.879865) (xy 344.657924 -239.879865)
			(xy 344.657924 -239.826567) (xy 344.665867 -239.773863) (xy 344.681577 -239.722933) (xy 344.704703 -239.674912)
			(xy 344.734727 -239.630875) (xy 344.770979 -239.591804) (xy 344.81265 -239.558573) (xy 344.858808 -239.531924)
			(xy 344.908422 -239.512452) (xy 344.960384 -239.500592) (xy 345.013534 -239.496609) (xy 345.066684 -239.500592)
			(xy 345.118646 -239.512452) (xy 345.16826 -239.531924) (xy 345.214418 -239.558573) (xy 345.256089 -239.591804)
			(xy 345.292341 -239.630875) (xy 345.322365 -239.674912) (xy 345.345491 -239.722933) (xy 345.361201 -239.773863)
			(xy 345.369144 -239.826567) (xy 345.369642 -239.853216) (xy 345.369144 -239.879865) (xy 345.59747 -239.879865)
			(xy 345.59747 -239.826567) (xy 345.605413 -239.773863) (xy 345.621123 -239.722933) (xy 345.644249 -239.674912)
			(xy 345.674273 -239.630875) (xy 345.710525 -239.591804) (xy 345.752196 -239.558573) (xy 345.798354 -239.531924)
			(xy 345.847968 -239.512452) (xy 345.89993 -239.500592) (xy 345.95308 -239.496609) (xy 346.00623 -239.500592)
			(xy 346.058192 -239.512452) (xy 346.107806 -239.531924) (xy 346.153964 -239.558573) (xy 346.195635 -239.591804)
			(xy 346.231887 -239.630875) (xy 346.261911 -239.674912) (xy 346.285037 -239.722933) (xy 346.300747 -239.773863)
			(xy 346.30869 -239.826567) (xy 346.309188 -239.853216) (xy 346.30869 -239.879865) (xy 346.300747 -239.932569)
			(xy 346.285037 -239.983499) (xy 346.261911 -240.03152) (xy 346.231887 -240.075557) (xy 346.195635 -240.114628)
			(xy 346.153964 -240.147859) (xy 346.107806 -240.174508) (xy 346.058192 -240.19398) (xy 346.00623 -240.20584)
			(xy 345.95308 -240.209824) (xy 345.89993 -240.20584) (xy 345.847968 -240.19398) (xy 345.798354 -240.174508)
			(xy 345.752196 -240.147859) (xy 345.710525 -240.114628) (xy 345.674273 -240.075557) (xy 345.644249 -240.03152)
			(xy 345.621123 -239.983499) (xy 345.605413 -239.932569) (xy 345.59747 -239.879865) (xy 345.369144 -239.879865)
			(xy 345.361201 -239.932569) (xy 345.345491 -239.983499) (xy 345.322365 -240.03152) (xy 345.292341 -240.075557)
			(xy 345.256089 -240.114628) (xy 345.214418 -240.147859) (xy 345.16826 -240.174508) (xy 345.118646 -240.19398)
			(xy 345.066684 -240.20584) (xy 345.013534 -240.209824) (xy 344.960384 -240.20584) (xy 344.908422 -240.19398)
			(xy 344.858808 -240.174508) (xy 344.81265 -240.147859) (xy 344.770979 -240.114628) (xy 344.734727 -240.075557)
			(xy 344.704703 -240.03152) (xy 344.681577 -239.983499) (xy 344.665867 -239.932569) (xy 344.657924 -239.879865)
			(xy 344.42909 -239.879865) (xy 344.421147 -239.932569) (xy 344.405437 -239.983499) (xy 344.382311 -240.03152)
			(xy 344.352287 -240.075557) (xy 344.316035 -240.114628) (xy 344.274364 -240.147859) (xy 344.228206 -240.174508)
			(xy 344.178592 -240.19398) (xy 344.12663 -240.20584) (xy 344.07348 -240.209824) (xy 344.02033 -240.20584)
			(xy 343.968368 -240.19398) (xy 343.918754 -240.174508) (xy 343.872596 -240.147859) (xy 343.830925 -240.114628)
			(xy 343.794673 -240.075557) (xy 343.764649 -240.03152) (xy 343.741523 -239.983499) (xy 343.725813 -239.932569)
			(xy 343.71787 -239.879865) (xy 343.48929 -239.879865) (xy 343.481347 -239.932569) (xy 343.465637 -239.983499)
			(xy 343.442511 -240.03152) (xy 343.412487 -240.075557) (xy 343.376235 -240.114628) (xy 343.334564 -240.147859)
			(xy 343.288406 -240.174508) (xy 343.238792 -240.19398) (xy 343.18683 -240.20584) (xy 343.13368 -240.209824)
			(xy 343.08053 -240.20584) (xy 343.028568 -240.19398) (xy 342.978954 -240.174508) (xy 342.932796 -240.147859)
			(xy 342.891125 -240.114628) (xy 342.854873 -240.075557) (xy 342.824849 -240.03152) (xy 342.801723 -239.983499)
			(xy 342.786013 -239.932569) (xy 342.77807 -239.879865) (xy 342.54949 -239.879865) (xy 342.541547 -239.932569)
			(xy 342.525837 -239.983499) (xy 342.502711 -240.03152) (xy 342.472687 -240.075557) (xy 342.436435 -240.114628)
			(xy 342.394764 -240.147859) (xy 342.348606 -240.174508) (xy 342.298992 -240.19398) (xy 342.24703 -240.20584)
			(xy 342.19388 -240.209824) (xy 342.14073 -240.20584) (xy 342.088768 -240.19398) (xy 342.039154 -240.174508)
			(xy 341.992996 -240.147859) (xy 341.951325 -240.114628) (xy 341.915073 -240.075557) (xy 341.885049 -240.03152)
			(xy 341.861923 -239.983499) (xy 341.846213 -239.932569) (xy 341.83827 -239.879865) (xy 341.60969 -239.879865)
			(xy 341.601747 -239.932569) (xy 341.586037 -239.983499) (xy 341.562911 -240.03152) (xy 341.532887 -240.075557)
			(xy 341.496635 -240.114628) (xy 341.454964 -240.147859) (xy 341.408806 -240.174508) (xy 341.359192 -240.19398)
			(xy 341.30723 -240.20584) (xy 341.25408 -240.209824) (xy 341.20093 -240.20584) (xy 341.148968 -240.19398)
			(xy 341.099354 -240.174508) (xy 341.053196 -240.147859) (xy 341.011525 -240.114628) (xy 340.975273 -240.075557)
			(xy 340.945249 -240.03152) (xy 340.922123 -239.983499) (xy 340.906413 -239.932569) (xy 340.89847 -239.879865)
			(xy 340.66989 -239.879865) (xy 340.661947 -239.932569) (xy 340.646237 -239.983499) (xy 340.623111 -240.03152)
			(xy 340.593087 -240.075557) (xy 340.556835 -240.114628) (xy 340.515164 -240.147859) (xy 340.469006 -240.174508)
			(xy 340.419392 -240.19398) (xy 340.36743 -240.20584) (xy 340.31428 -240.209824) (xy 340.26113 -240.20584)
			(xy 340.209168 -240.19398) (xy 340.159554 -240.174508) (xy 340.113396 -240.147859) (xy 340.071725 -240.114628)
			(xy 340.035473 -240.075557) (xy 340.005449 -240.03152) (xy 339.982323 -239.983499) (xy 339.966613 -239.932569)
			(xy 339.95867 -239.879865) (xy 339.73009 -239.879865) (xy 339.722147 -239.932569) (xy 339.706437 -239.983499)
			(xy 339.683311 -240.03152) (xy 339.653287 -240.075557) (xy 339.617035 -240.114628) (xy 339.575364 -240.147859)
			(xy 339.529206 -240.174508) (xy 339.479592 -240.19398) (xy 339.42763 -240.20584) (xy 339.37448 -240.209824)
			(xy 339.32133 -240.20584) (xy 339.269368 -240.19398) (xy 339.219754 -240.174508) (xy 339.173596 -240.147859)
			(xy 339.131925 -240.114628) (xy 339.095673 -240.075557) (xy 339.065649 -240.03152) (xy 339.042523 -239.983499)
			(xy 339.026813 -239.932569) (xy 339.01887 -239.879865) (xy 338.790544 -239.879865) (xy 338.782601 -239.932569)
			(xy 338.766891 -239.983499) (xy 338.743765 -240.03152) (xy 338.713741 -240.075557) (xy 338.677489 -240.114628)
			(xy 338.635818 -240.147859) (xy 338.58966 -240.174508) (xy 338.540046 -240.19398) (xy 338.488084 -240.20584)
			(xy 338.434934 -240.209824) (xy 338.381784 -240.20584) (xy 338.329822 -240.19398) (xy 338.280208 -240.174508)
			(xy 338.23405 -240.147859) (xy 338.192379 -240.114628) (xy 338.156127 -240.075557) (xy 338.126103 -240.03152)
			(xy 338.102977 -239.983499) (xy 338.087267 -239.932569) (xy 338.079324 -239.879865) (xy 337.85049 -239.879865)
			(xy 337.842547 -239.932569) (xy 337.826837 -239.983499) (xy 337.803711 -240.03152) (xy 337.773687 -240.075557)
			(xy 337.737435 -240.114628) (xy 337.695764 -240.147859) (xy 337.649606 -240.174508) (xy 337.599992 -240.19398)
			(xy 337.54803 -240.20584) (xy 337.49488 -240.209824) (xy 337.44173 -240.20584) (xy 337.389768 -240.19398)
			(xy 337.340154 -240.174508) (xy 337.293996 -240.147859) (xy 337.252325 -240.114628) (xy 337.216073 -240.075557)
			(xy 337.186049 -240.03152) (xy 337.162923 -239.983499) (xy 337.147213 -239.932569) (xy 337.13927 -239.879865)
			(xy 336.909759 -239.879865) (xy 336.907859 -239.905593) (xy 336.896335 -239.956843) (xy 336.877409 -240.005845)
			(xy 336.851489 -240.051536) (xy 336.819139 -240.092923) (xy 336.78106 -240.129109) (xy 336.738079 -240.159308)
			(xy 336.691127 -240.182867) (xy 336.666332 -240.191544) (xy 336.63128 -240.202974) (xy 336.63128 -240.315242)
			(xy 336.631809 -240.32961) (xy 336.639888 -240.357191) (xy 336.655337 -240.381424) (xy 336.676931 -240.400389)
			(xy 336.702956 -240.41258) (xy 336.731348 -240.417032) (xy 336.759856 -240.41339) (xy 336.786217 -240.401944)
			(xy 336.79765 -240.39322) (xy 336.816926 -240.377782) (xy 336.85893 -240.351809) (xy 336.904119 -240.331886)
			(xy 336.951626 -240.318394) (xy 337.000541 -240.311593) (xy 337.025234 -240.311178) (xy 337.051883 -240.311678)
			(xy 337.104584 -240.319626) (xy 337.155513 -240.33534) (xy 337.20353 -240.358468) (xy 337.247565 -240.388494)
			(xy 337.286633 -240.424748) (xy 337.319862 -240.466419) (xy 337.346509 -240.512576) (xy 337.36598 -240.56219)
			(xy 337.377839 -240.614152) (xy 337.381822 -240.6673) (xy 337.379826 -240.693935) (xy 337.609424 -240.693935)
			(xy 337.609424 -240.640637) (xy 337.617367 -240.587933) (xy 337.633077 -240.537003) (xy 337.656203 -240.488982)
			(xy 337.686227 -240.444945) (xy 337.722479 -240.405874) (xy 337.76415 -240.372643) (xy 337.810308 -240.345994)
			(xy 337.859922 -240.326522) (xy 337.911884 -240.314662) (xy 337.965034 -240.310679) (xy 338.018184 -240.314662)
			(xy 338.070146 -240.326522) (xy 338.11976 -240.345994) (xy 338.165918 -240.372643) (xy 338.207589 -240.405874)
			(xy 338.243841 -240.444945) (xy 338.273865 -240.488982) (xy 338.296991 -240.537003) (xy 338.312701 -240.587933)
			(xy 338.320644 -240.640637) (xy 338.321142 -240.667286) (xy 338.320644 -240.693935) (xy 338.54897 -240.693935)
			(xy 338.54897 -240.640637) (xy 338.556913 -240.587933) (xy 338.572623 -240.537003) (xy 338.595749 -240.488982)
			(xy 338.625773 -240.444945) (xy 338.662025 -240.405874) (xy 338.703696 -240.372643) (xy 338.749854 -240.345994)
			(xy 338.799468 -240.326522) (xy 338.85143 -240.314662) (xy 338.90458 -240.310679) (xy 338.95773 -240.314662)
			(xy 339.009692 -240.326522) (xy 339.059306 -240.345994) (xy 339.105464 -240.372643) (xy 339.147135 -240.405874)
			(xy 339.183387 -240.444945) (xy 339.213411 -240.488982) (xy 339.236537 -240.537003) (xy 339.252247 -240.587933)
			(xy 339.26019 -240.640637) (xy 339.260688 -240.667286) (xy 339.26019 -240.693935) (xy 339.489024 -240.693935)
			(xy 339.489024 -240.640637) (xy 339.496967 -240.587933) (xy 339.512677 -240.537003) (xy 339.535803 -240.488982)
			(xy 339.565827 -240.444945) (xy 339.602079 -240.405874) (xy 339.64375 -240.372643) (xy 339.689908 -240.345994)
			(xy 339.739522 -240.326522) (xy 339.791484 -240.314662) (xy 339.844634 -240.310679) (xy 339.897784 -240.314662)
			(xy 339.949746 -240.326522) (xy 339.99936 -240.345994) (xy 340.045518 -240.372643) (xy 340.087189 -240.405874)
			(xy 340.123441 -240.444945) (xy 340.153465 -240.488982) (xy 340.176591 -240.537003) (xy 340.192301 -240.587933)
			(xy 340.200244 -240.640637) (xy 340.200742 -240.667286) (xy 340.200244 -240.693935) (xy 340.428824 -240.693935)
			(xy 340.428824 -240.640637) (xy 340.436767 -240.587933) (xy 340.452477 -240.537003) (xy 340.475603 -240.488982)
			(xy 340.505627 -240.444945) (xy 340.541879 -240.405874) (xy 340.58355 -240.372643) (xy 340.629708 -240.345994)
			(xy 340.679322 -240.326522) (xy 340.731284 -240.314662) (xy 340.784434 -240.310679) (xy 340.837584 -240.314662)
			(xy 340.889546 -240.326522) (xy 340.93916 -240.345994) (xy 340.985318 -240.372643) (xy 341.026989 -240.405874)
			(xy 341.063241 -240.444945) (xy 341.093265 -240.488982) (xy 341.116391 -240.537003) (xy 341.132101 -240.587933)
			(xy 341.140044 -240.640637) (xy 341.140542 -240.667286) (xy 341.140044 -240.693935) (xy 341.368624 -240.693935)
			(xy 341.368624 -240.640637) (xy 341.376567 -240.587933) (xy 341.392277 -240.537003) (xy 341.415403 -240.488982)
			(xy 341.445427 -240.444945) (xy 341.481679 -240.405874) (xy 341.52335 -240.372643) (xy 341.569508 -240.345994)
			(xy 341.619122 -240.326522) (xy 341.671084 -240.314662) (xy 341.724234 -240.310679) (xy 341.777384 -240.314662)
			(xy 341.829346 -240.326522) (xy 341.87896 -240.345994) (xy 341.925118 -240.372643) (xy 341.966789 -240.405874)
			(xy 342.003041 -240.444945) (xy 342.033065 -240.488982) (xy 342.056191 -240.537003) (xy 342.071901 -240.587933)
			(xy 342.079844 -240.640637) (xy 342.080342 -240.667286) (xy 342.079844 -240.693935) (xy 342.308424 -240.693935)
			(xy 342.308424 -240.640637) (xy 342.316367 -240.587933) (xy 342.332077 -240.537003) (xy 342.355203 -240.488982)
			(xy 342.385227 -240.444945) (xy 342.421479 -240.405874) (xy 342.46315 -240.372643) (xy 342.509308 -240.345994)
			(xy 342.558922 -240.326522) (xy 342.610884 -240.314662) (xy 342.664034 -240.310679) (xy 342.717184 -240.314662)
			(xy 342.769146 -240.326522) (xy 342.81876 -240.345994) (xy 342.864918 -240.372643) (xy 342.906589 -240.405874)
			(xy 342.942841 -240.444945) (xy 342.972865 -240.488982) (xy 342.995991 -240.537003) (xy 343.011701 -240.587933)
			(xy 343.019644 -240.640637) (xy 343.020142 -240.667286) (xy 343.019644 -240.693935) (xy 343.248224 -240.693935)
			(xy 343.248224 -240.640637) (xy 343.256167 -240.587933) (xy 343.271877 -240.537003) (xy 343.295003 -240.488982)
			(xy 343.325027 -240.444945) (xy 343.361279 -240.405874) (xy 343.40295 -240.372643) (xy 343.449108 -240.345994)
			(xy 343.498722 -240.326522) (xy 343.550684 -240.314662) (xy 343.603834 -240.310679) (xy 343.656984 -240.314662)
			(xy 343.708946 -240.326522) (xy 343.75856 -240.345994) (xy 343.804718 -240.372643) (xy 343.846389 -240.405874)
			(xy 343.882641 -240.444945) (xy 343.912665 -240.488982) (xy 343.935791 -240.537003) (xy 343.951501 -240.587933)
			(xy 343.959444 -240.640637) (xy 343.959942 -240.667286) (xy 343.959444 -240.693935) (xy 344.188024 -240.693935)
			(xy 344.188024 -240.640637) (xy 344.195967 -240.587933) (xy 344.211677 -240.537003) (xy 344.234803 -240.488982)
			(xy 344.264827 -240.444945) (xy 344.301079 -240.405874) (xy 344.34275 -240.372643) (xy 344.388908 -240.345994)
			(xy 344.438522 -240.326522) (xy 344.490484 -240.314662) (xy 344.543634 -240.310679) (xy 344.596784 -240.314662)
			(xy 344.648746 -240.326522) (xy 344.69836 -240.345994) (xy 344.744518 -240.372643) (xy 344.786189 -240.405874)
			(xy 344.822441 -240.444945) (xy 344.852465 -240.488982) (xy 344.875591 -240.537003) (xy 344.891301 -240.587933)
			(xy 344.899244 -240.640637) (xy 344.899742 -240.667286) (xy 344.899244 -240.693935) (xy 345.12757 -240.693935)
			(xy 345.12757 -240.640637) (xy 345.135513 -240.587933) (xy 345.151223 -240.537003) (xy 345.174349 -240.488982)
			(xy 345.204373 -240.444945) (xy 345.240625 -240.405874) (xy 345.282296 -240.372643) (xy 345.328454 -240.345994)
			(xy 345.378068 -240.326522) (xy 345.43003 -240.314662) (xy 345.48318 -240.310679) (xy 345.53633 -240.314662)
			(xy 345.588292 -240.326522) (xy 345.637906 -240.345994) (xy 345.684064 -240.372643) (xy 345.725735 -240.405874)
			(xy 345.761987 -240.444945) (xy 345.792011 -240.488982) (xy 345.815137 -240.537003) (xy 345.830847 -240.587933)
			(xy 345.83879 -240.640637) (xy 345.839288 -240.667286) (xy 345.83879 -240.693935) (xy 346.067624 -240.693935)
			(xy 346.067624 -240.640637) (xy 346.075567 -240.587933) (xy 346.091277 -240.537003) (xy 346.114403 -240.488982)
			(xy 346.144427 -240.444945) (xy 346.180679 -240.405874) (xy 346.22235 -240.372643) (xy 346.268508 -240.345994)
			(xy 346.318122 -240.326522) (xy 346.370084 -240.314662) (xy 346.423234 -240.310679) (xy 346.476384 -240.314662)
			(xy 346.528346 -240.326522) (xy 346.57796 -240.345994) (xy 346.624118 -240.372643) (xy 346.665789 -240.405874)
			(xy 346.702041 -240.444945) (xy 346.732065 -240.488982) (xy 346.755191 -240.537003) (xy 346.770901 -240.587933)
			(xy 346.778844 -240.640637) (xy 346.779342 -240.667286) (xy 346.778844 -240.693935) (xy 346.770901 -240.746639)
			(xy 346.755191 -240.797569) (xy 346.732065 -240.84559) (xy 346.702041 -240.889627) (xy 346.665789 -240.928698)
			(xy 346.624118 -240.961929) (xy 346.57796 -240.988578) (xy 346.528346 -241.00805) (xy 346.476384 -241.01991)
			(xy 346.423234 -241.023894) (xy 346.370084 -241.01991) (xy 346.318122 -241.00805) (xy 346.268508 -240.988578)
			(xy 346.22235 -240.961929) (xy 346.180679 -240.928698) (xy 346.144427 -240.889627) (xy 346.114403 -240.84559)
			(xy 346.091277 -240.797569) (xy 346.075567 -240.746639) (xy 346.067624 -240.693935) (xy 345.83879 -240.693935)
			(xy 345.830847 -240.746639) (xy 345.815137 -240.797569) (xy 345.792011 -240.84559) (xy 345.761987 -240.889627)
			(xy 345.725735 -240.928698) (xy 345.684064 -240.961929) (xy 345.637906 -240.988578) (xy 345.588292 -241.00805)
			(xy 345.53633 -241.01991) (xy 345.48318 -241.023894) (xy 345.43003 -241.01991) (xy 345.378068 -241.00805)
			(xy 345.328454 -240.988578) (xy 345.282296 -240.961929) (xy 345.240625 -240.928698) (xy 345.204373 -240.889627)
			(xy 345.174349 -240.84559) (xy 345.151223 -240.797569) (xy 345.135513 -240.746639) (xy 345.12757 -240.693935)
			(xy 344.899244 -240.693935) (xy 344.891301 -240.746639) (xy 344.875591 -240.797569) (xy 344.852465 -240.84559)
			(xy 344.822441 -240.889627) (xy 344.786189 -240.928698) (xy 344.744518 -240.961929) (xy 344.69836 -240.988578)
			(xy 344.648746 -241.00805) (xy 344.596784 -241.01991) (xy 344.543634 -241.023894) (xy 344.490484 -241.01991)
			(xy 344.438522 -241.00805) (xy 344.388908 -240.988578) (xy 344.34275 -240.961929) (xy 344.301079 -240.928698)
			(xy 344.264827 -240.889627) (xy 344.234803 -240.84559) (xy 344.211677 -240.797569) (xy 344.195967 -240.746639)
			(xy 344.188024 -240.693935) (xy 343.959444 -240.693935) (xy 343.951501 -240.746639) (xy 343.935791 -240.797569)
			(xy 343.912665 -240.84559) (xy 343.882641 -240.889627) (xy 343.846389 -240.928698) (xy 343.804718 -240.961929)
			(xy 343.75856 -240.988578) (xy 343.708946 -241.00805) (xy 343.656984 -241.01991) (xy 343.603834 -241.023894)
			(xy 343.550684 -241.01991) (xy 343.498722 -241.00805) (xy 343.449108 -240.988578) (xy 343.40295 -240.961929)
			(xy 343.361279 -240.928698) (xy 343.325027 -240.889627) (xy 343.295003 -240.84559) (xy 343.271877 -240.797569)
			(xy 343.256167 -240.746639) (xy 343.248224 -240.693935) (xy 343.019644 -240.693935) (xy 343.011701 -240.746639)
			(xy 342.995991 -240.797569) (xy 342.972865 -240.84559) (xy 342.942841 -240.889627) (xy 342.906589 -240.928698)
			(xy 342.864918 -240.961929) (xy 342.81876 -240.988578) (xy 342.769146 -241.00805) (xy 342.717184 -241.01991)
			(xy 342.664034 -241.023894) (xy 342.610884 -241.01991) (xy 342.558922 -241.00805) (xy 342.509308 -240.988578)
			(xy 342.46315 -240.961929) (xy 342.421479 -240.928698) (xy 342.385227 -240.889627) (xy 342.355203 -240.84559)
			(xy 342.332077 -240.797569) (xy 342.316367 -240.746639) (xy 342.308424 -240.693935) (xy 342.079844 -240.693935)
			(xy 342.071901 -240.746639) (xy 342.056191 -240.797569) (xy 342.033065 -240.84559) (xy 342.003041 -240.889627)
			(xy 341.966789 -240.928698) (xy 341.925118 -240.961929) (xy 341.87896 -240.988578) (xy 341.829346 -241.00805)
			(xy 341.777384 -241.01991) (xy 341.724234 -241.023894) (xy 341.671084 -241.01991) (xy 341.619122 -241.00805)
			(xy 341.569508 -240.988578) (xy 341.52335 -240.961929) (xy 341.481679 -240.928698) (xy 341.445427 -240.889627)
			(xy 341.415403 -240.84559) (xy 341.392277 -240.797569) (xy 341.376567 -240.746639) (xy 341.368624 -240.693935)
			(xy 341.140044 -240.693935) (xy 341.132101 -240.746639) (xy 341.116391 -240.797569) (xy 341.093265 -240.84559)
			(xy 341.063241 -240.889627) (xy 341.026989 -240.928698) (xy 340.985318 -240.961929) (xy 340.93916 -240.988578)
			(xy 340.889546 -241.00805) (xy 340.837584 -241.01991) (xy 340.784434 -241.023894) (xy 340.731284 -241.01991)
			(xy 340.679322 -241.00805) (xy 340.629708 -240.988578) (xy 340.58355 -240.961929) (xy 340.541879 -240.928698)
			(xy 340.505627 -240.889627) (xy 340.475603 -240.84559) (xy 340.452477 -240.797569) (xy 340.436767 -240.746639)
			(xy 340.428824 -240.693935) (xy 340.200244 -240.693935) (xy 340.192301 -240.746639) (xy 340.176591 -240.797569)
			(xy 340.153465 -240.84559) (xy 340.123441 -240.889627) (xy 340.087189 -240.928698) (xy 340.045518 -240.961929)
			(xy 339.99936 -240.988578) (xy 339.949746 -241.00805) (xy 339.897784 -241.01991) (xy 339.844634 -241.023894)
			(xy 339.791484 -241.01991) (xy 339.739522 -241.00805) (xy 339.689908 -240.988578) (xy 339.64375 -240.961929)
			(xy 339.602079 -240.928698) (xy 339.565827 -240.889627) (xy 339.535803 -240.84559) (xy 339.512677 -240.797569)
			(xy 339.496967 -240.746639) (xy 339.489024 -240.693935) (xy 339.26019 -240.693935) (xy 339.252247 -240.746639)
			(xy 339.236537 -240.797569) (xy 339.213411 -240.84559) (xy 339.183387 -240.889627) (xy 339.147135 -240.928698)
			(xy 339.105464 -240.961929) (xy 339.059306 -240.988578) (xy 339.009692 -241.00805) (xy 338.95773 -241.01991)
			(xy 338.90458 -241.023894) (xy 338.85143 -241.01991) (xy 338.799468 -241.00805) (xy 338.749854 -240.988578)
			(xy 338.703696 -240.961929) (xy 338.662025 -240.928698) (xy 338.625773 -240.889627) (xy 338.595749 -240.84559)
			(xy 338.572623 -240.797569) (xy 338.556913 -240.746639) (xy 338.54897 -240.693935) (xy 338.320644 -240.693935)
			(xy 338.312701 -240.746639) (xy 338.296991 -240.797569) (xy 338.273865 -240.84559) (xy 338.243841 -240.889627)
			(xy 338.207589 -240.928698) (xy 338.165918 -240.961929) (xy 338.11976 -240.988578) (xy 338.070146 -241.00805)
			(xy 338.018184 -241.01991) (xy 337.965034 -241.023894) (xy 337.911884 -241.01991) (xy 337.859922 -241.00805)
			(xy 337.810308 -240.988578) (xy 337.76415 -240.961929) (xy 337.722479 -240.928698) (xy 337.686227 -240.889627)
			(xy 337.656203 -240.84559) (xy 337.633077 -240.797569) (xy 337.617367 -240.746639) (xy 337.609424 -240.693935)
			(xy 337.379826 -240.693935) (xy 337.377839 -240.720448) (xy 337.36598 -240.77241) (xy 337.346509 -240.822024)
			(xy 337.319862 -240.868181) (xy 337.286633 -240.909852) (xy 337.247565 -240.946106) (xy 337.20353 -240.976132)
			(xy 337.155513 -240.99926) (xy 337.104584 -241.014974) (xy 337.051883 -241.022922) (xy 337.025234 -241.023394)
			(xy 337.000538 -241.022995) (xy 336.951616 -241.016211) (xy 336.904101 -241.002728) (xy 336.858908 -240.982804)
			(xy 336.816903 -240.956822) (xy 336.79765 -240.941352) (xy 336.786265 -240.932573) (xy 336.759898 -240.921148)
			(xy 336.731391 -240.917525) (xy 336.703003 -240.92199) (xy 336.676985 -240.934189) (xy 336.655397 -240.953155)
			(xy 336.63995 -240.977387) (xy 336.631868 -241.004963) (xy 336.63128 -241.01933) (xy 336.63128 -241.131344)
			(xy 336.666332 -241.142774) (xy 336.691138 -241.151423) (xy 336.73809 -241.174983) (xy 336.781073 -241.205185)
			(xy 336.819153 -241.241373) (xy 336.851503 -241.282762) (xy 336.877423 -241.328454) (xy 336.89635 -241.377458)
			(xy 336.907873 -241.428711) (xy 336.911741 -241.481101) (xy 336.909773 -241.507751) (xy 337.13927 -241.507751)
			(xy 337.13927 -241.454453) (xy 337.147213 -241.401749) (xy 337.162923 -241.350819) (xy 337.186049 -241.302798)
			(xy 337.216073 -241.258761) (xy 337.252325 -241.21969) (xy 337.293996 -241.186459) (xy 337.340154 -241.15981)
			(xy 337.389768 -241.140338) (xy 337.44173 -241.128478) (xy 337.49488 -241.124495) (xy 337.54803 -241.128478)
			(xy 337.599992 -241.140338) (xy 337.649606 -241.15981) (xy 337.695764 -241.186459) (xy 337.737435 -241.21969)
			(xy 337.773687 -241.258761) (xy 337.803711 -241.302798) (xy 337.826837 -241.350819) (xy 337.842547 -241.401749)
			(xy 337.85049 -241.454453) (xy 337.850988 -241.481102) (xy 337.85049 -241.507751) (xy 338.07907 -241.507751)
			(xy 338.07907 -241.454453) (xy 338.087013 -241.401749) (xy 338.102723 -241.350819) (xy 338.125849 -241.302798)
			(xy 338.155873 -241.258761) (xy 338.192125 -241.21969) (xy 338.233796 -241.186459) (xy 338.279954 -241.15981)
			(xy 338.329568 -241.140338) (xy 338.38153 -241.128478) (xy 338.43468 -241.124495) (xy 338.48783 -241.128478)
			(xy 338.539792 -241.140338) (xy 338.589406 -241.15981) (xy 338.635564 -241.186459) (xy 338.677235 -241.21969)
			(xy 338.713487 -241.258761) (xy 338.743511 -241.302798) (xy 338.766637 -241.350819) (xy 338.782347 -241.401749)
			(xy 338.79029 -241.454453) (xy 338.790788 -241.481102) (xy 338.79029 -241.507751) (xy 339.01887 -241.507751)
			(xy 339.01887 -241.454453) (xy 339.026813 -241.401749) (xy 339.042523 -241.350819) (xy 339.065649 -241.302798)
			(xy 339.095673 -241.258761) (xy 339.131925 -241.21969) (xy 339.173596 -241.186459) (xy 339.219754 -241.15981)
			(xy 339.269368 -241.140338) (xy 339.32133 -241.128478) (xy 339.37448 -241.124495) (xy 339.42763 -241.128478)
			(xy 339.479592 -241.140338) (xy 339.529206 -241.15981) (xy 339.575364 -241.186459) (xy 339.617035 -241.21969)
			(xy 339.653287 -241.258761) (xy 339.683311 -241.302798) (xy 339.706437 -241.350819) (xy 339.722147 -241.401749)
			(xy 339.73009 -241.454453) (xy 339.730588 -241.481102) (xy 339.73009 -241.507751) (xy 339.95867 -241.507751)
			(xy 339.95867 -241.454453) (xy 339.966613 -241.401749) (xy 339.982323 -241.350819) (xy 340.005449 -241.302798)
			(xy 340.035473 -241.258761) (xy 340.071725 -241.21969) (xy 340.113396 -241.186459) (xy 340.159554 -241.15981)
			(xy 340.209168 -241.140338) (xy 340.26113 -241.128478) (xy 340.31428 -241.124495) (xy 340.36743 -241.128478)
			(xy 340.419392 -241.140338) (xy 340.469006 -241.15981) (xy 340.515164 -241.186459) (xy 340.556835 -241.21969)
			(xy 340.593087 -241.258761) (xy 340.623111 -241.302798) (xy 340.646237 -241.350819) (xy 340.661947 -241.401749)
			(xy 340.66989 -241.454453) (xy 340.670388 -241.481102) (xy 340.66989 -241.507751) (xy 340.89847 -241.507751)
			(xy 340.89847 -241.454453) (xy 340.906413 -241.401749) (xy 340.922123 -241.350819) (xy 340.945249 -241.302798)
			(xy 340.975273 -241.258761) (xy 341.011525 -241.21969) (xy 341.053196 -241.186459) (xy 341.099354 -241.15981)
			(xy 341.148968 -241.140338) (xy 341.20093 -241.128478) (xy 341.25408 -241.124495) (xy 341.30723 -241.128478)
			(xy 341.359192 -241.140338) (xy 341.408806 -241.15981) (xy 341.454964 -241.186459) (xy 341.496635 -241.21969)
			(xy 341.532887 -241.258761) (xy 341.562911 -241.302798) (xy 341.586037 -241.350819) (xy 341.601747 -241.401749)
			(xy 341.60969 -241.454453) (xy 341.610188 -241.481102) (xy 341.60969 -241.507751) (xy 341.838524 -241.507751)
			(xy 341.838524 -241.454453) (xy 341.846467 -241.401749) (xy 341.862177 -241.350819) (xy 341.885303 -241.302798)
			(xy 341.915327 -241.258761) (xy 341.951579 -241.21969) (xy 341.99325 -241.186459) (xy 342.039408 -241.15981)
			(xy 342.089022 -241.140338) (xy 342.140984 -241.128478) (xy 342.194134 -241.124495) (xy 342.247284 -241.128478)
			(xy 342.299246 -241.140338) (xy 342.34886 -241.15981) (xy 342.395018 -241.186459) (xy 342.436689 -241.21969)
			(xy 342.472941 -241.258761) (xy 342.502965 -241.302798) (xy 342.526091 -241.350819) (xy 342.541801 -241.401749)
			(xy 342.549744 -241.454453) (xy 342.550242 -241.481102) (xy 342.549744 -241.507751) (xy 342.77807 -241.507751)
			(xy 342.77807 -241.454453) (xy 342.786013 -241.401749) (xy 342.801723 -241.350819) (xy 342.824849 -241.302798)
			(xy 342.854873 -241.258761) (xy 342.891125 -241.21969) (xy 342.932796 -241.186459) (xy 342.978954 -241.15981)
			(xy 343.028568 -241.140338) (xy 343.08053 -241.128478) (xy 343.13368 -241.124495) (xy 343.18683 -241.128478)
			(xy 343.238792 -241.140338) (xy 343.288406 -241.15981) (xy 343.334564 -241.186459) (xy 343.376235 -241.21969)
			(xy 343.412487 -241.258761) (xy 343.442511 -241.302798) (xy 343.465637 -241.350819) (xy 343.481347 -241.401749)
			(xy 343.48929 -241.454453) (xy 343.489788 -241.481102) (xy 343.48929 -241.507751) (xy 343.71787 -241.507751)
			(xy 343.71787 -241.454453) (xy 343.725813 -241.401749) (xy 343.741523 -241.350819) (xy 343.764649 -241.302798)
			(xy 343.794673 -241.258761) (xy 343.830925 -241.21969) (xy 343.872596 -241.186459) (xy 343.918754 -241.15981)
			(xy 343.968368 -241.140338) (xy 344.02033 -241.128478) (xy 344.07348 -241.124495) (xy 344.12663 -241.128478)
			(xy 344.178592 -241.140338) (xy 344.228206 -241.15981) (xy 344.274364 -241.186459) (xy 344.316035 -241.21969)
			(xy 344.352287 -241.258761) (xy 344.382311 -241.302798) (xy 344.405437 -241.350819) (xy 344.421147 -241.401749)
			(xy 344.42909 -241.454453) (xy 344.429588 -241.481102) (xy 344.42909 -241.507751) (xy 344.65767 -241.507751)
			(xy 344.65767 -241.454453) (xy 344.665613 -241.401749) (xy 344.681323 -241.350819) (xy 344.704449 -241.302798)
			(xy 344.734473 -241.258761) (xy 344.770725 -241.21969) (xy 344.812396 -241.186459) (xy 344.858554 -241.15981)
			(xy 344.908168 -241.140338) (xy 344.96013 -241.128478) (xy 345.01328 -241.124495) (xy 345.06643 -241.128478)
			(xy 345.118392 -241.140338) (xy 345.168006 -241.15981) (xy 345.214164 -241.186459) (xy 345.255835 -241.21969)
			(xy 345.292087 -241.258761) (xy 345.322111 -241.302798) (xy 345.345237 -241.350819) (xy 345.360947 -241.401749)
			(xy 345.36889 -241.454453) (xy 345.369388 -241.481102) (xy 345.36889 -241.507751) (xy 345.59747 -241.507751)
			(xy 345.59747 -241.454453) (xy 345.605413 -241.401749) (xy 345.621123 -241.350819) (xy 345.644249 -241.302798)
			(xy 345.674273 -241.258761) (xy 345.710525 -241.21969) (xy 345.752196 -241.186459) (xy 345.798354 -241.15981)
			(xy 345.847968 -241.140338) (xy 345.89993 -241.128478) (xy 345.95308 -241.124495) (xy 346.00623 -241.128478)
			(xy 346.058192 -241.140338) (xy 346.107806 -241.15981) (xy 346.153964 -241.186459) (xy 346.195635 -241.21969)
			(xy 346.231887 -241.258761) (xy 346.261911 -241.302798) (xy 346.285037 -241.350819) (xy 346.300747 -241.401749)
			(xy 346.30869 -241.454453) (xy 346.309188 -241.481102) (xy 346.30869 -241.507751) (xy 346.300747 -241.560455)
			(xy 346.285037 -241.611385) (xy 346.261911 -241.659406) (xy 346.231887 -241.703443) (xy 346.195635 -241.742514)
			(xy 346.153964 -241.775745) (xy 346.107806 -241.802394) (xy 346.058192 -241.821866) (xy 346.00623 -241.833726)
			(xy 345.95308 -241.83771) (xy 345.89993 -241.833726) (xy 345.847968 -241.821866) (xy 345.798354 -241.802394)
			(xy 345.752196 -241.775745) (xy 345.710525 -241.742514) (xy 345.674273 -241.703443) (xy 345.644249 -241.659406)
			(xy 345.621123 -241.611385) (xy 345.605413 -241.560455) (xy 345.59747 -241.507751) (xy 345.36889 -241.507751)
			(xy 345.360947 -241.560455) (xy 345.345237 -241.611385) (xy 345.322111 -241.659406) (xy 345.292087 -241.703443)
			(xy 345.255835 -241.742514) (xy 345.214164 -241.775745) (xy 345.168006 -241.802394) (xy 345.118392 -241.821866)
			(xy 345.06643 -241.833726) (xy 345.01328 -241.83771) (xy 344.96013 -241.833726) (xy 344.908168 -241.821866)
			(xy 344.858554 -241.802394) (xy 344.812396 -241.775745) (xy 344.770725 -241.742514) (xy 344.734473 -241.703443)
			(xy 344.704449 -241.659406) (xy 344.681323 -241.611385) (xy 344.665613 -241.560455) (xy 344.65767 -241.507751)
			(xy 344.42909 -241.507751) (xy 344.421147 -241.560455) (xy 344.405437 -241.611385) (xy 344.382311 -241.659406)
			(xy 344.352287 -241.703443) (xy 344.316035 -241.742514) (xy 344.274364 -241.775745) (xy 344.228206 -241.802394)
			(xy 344.178592 -241.821866) (xy 344.12663 -241.833726) (xy 344.07348 -241.83771) (xy 344.02033 -241.833726)
			(xy 343.968368 -241.821866) (xy 343.918754 -241.802394) (xy 343.872596 -241.775745) (xy 343.830925 -241.742514)
			(xy 343.794673 -241.703443) (xy 343.764649 -241.659406) (xy 343.741523 -241.611385) (xy 343.725813 -241.560455)
			(xy 343.71787 -241.507751) (xy 343.48929 -241.507751) (xy 343.481347 -241.560455) (xy 343.465637 -241.611385)
			(xy 343.442511 -241.659406) (xy 343.412487 -241.703443) (xy 343.376235 -241.742514) (xy 343.334564 -241.775745)
			(xy 343.288406 -241.802394) (xy 343.238792 -241.821866) (xy 343.18683 -241.833726) (xy 343.13368 -241.83771)
			(xy 343.08053 -241.833726) (xy 343.028568 -241.821866) (xy 342.978954 -241.802394) (xy 342.932796 -241.775745)
			(xy 342.891125 -241.742514) (xy 342.854873 -241.703443) (xy 342.824849 -241.659406) (xy 342.801723 -241.611385)
			(xy 342.786013 -241.560455) (xy 342.77807 -241.507751) (xy 342.549744 -241.507751) (xy 342.541801 -241.560455)
			(xy 342.526091 -241.611385) (xy 342.502965 -241.659406) (xy 342.472941 -241.703443) (xy 342.436689 -241.742514)
			(xy 342.395018 -241.775745) (xy 342.34886 -241.802394) (xy 342.299246 -241.821866) (xy 342.247284 -241.833726)
			(xy 342.194134 -241.83771) (xy 342.140984 -241.833726) (xy 342.089022 -241.821866) (xy 342.039408 -241.802394)
			(xy 341.99325 -241.775745) (xy 341.951579 -241.742514) (xy 341.915327 -241.703443) (xy 341.885303 -241.659406)
			(xy 341.862177 -241.611385) (xy 341.846467 -241.560455) (xy 341.838524 -241.507751) (xy 341.60969 -241.507751)
			(xy 341.601747 -241.560455) (xy 341.586037 -241.611385) (xy 341.562911 -241.659406) (xy 341.532887 -241.703443)
			(xy 341.496635 -241.742514) (xy 341.454964 -241.775745) (xy 341.408806 -241.802394) (xy 341.359192 -241.821866)
			(xy 341.30723 -241.833726) (xy 341.25408 -241.83771) (xy 341.20093 -241.833726) (xy 341.148968 -241.821866)
			(xy 341.099354 -241.802394) (xy 341.053196 -241.775745) (xy 341.011525 -241.742514) (xy 340.975273 -241.703443)
			(xy 340.945249 -241.659406) (xy 340.922123 -241.611385) (xy 340.906413 -241.560455) (xy 340.89847 -241.507751)
			(xy 340.66989 -241.507751) (xy 340.661947 -241.560455) (xy 340.646237 -241.611385) (xy 340.623111 -241.659406)
			(xy 340.593087 -241.703443) (xy 340.556835 -241.742514) (xy 340.515164 -241.775745) (xy 340.469006 -241.802394)
			(xy 340.419392 -241.821866) (xy 340.36743 -241.833726) (xy 340.31428 -241.83771) (xy 340.26113 -241.833726)
			(xy 340.209168 -241.821866) (xy 340.159554 -241.802394) (xy 340.113396 -241.775745) (xy 340.071725 -241.742514)
			(xy 340.035473 -241.703443) (xy 340.005449 -241.659406) (xy 339.982323 -241.611385) (xy 339.966613 -241.560455)
			(xy 339.95867 -241.507751) (xy 339.73009 -241.507751) (xy 339.722147 -241.560455) (xy 339.706437 -241.611385)
			(xy 339.683311 -241.659406) (xy 339.653287 -241.703443) (xy 339.617035 -241.742514) (xy 339.575364 -241.775745)
			(xy 339.529206 -241.802394) (xy 339.479592 -241.821866) (xy 339.42763 -241.833726) (xy 339.37448 -241.83771)
			(xy 339.32133 -241.833726) (xy 339.269368 -241.821866) (xy 339.219754 -241.802394) (xy 339.173596 -241.775745)
			(xy 339.131925 -241.742514) (xy 339.095673 -241.703443) (xy 339.065649 -241.659406) (xy 339.042523 -241.611385)
			(xy 339.026813 -241.560455) (xy 339.01887 -241.507751) (xy 338.79029 -241.507751) (xy 338.782347 -241.560455)
			(xy 338.766637 -241.611385) (xy 338.743511 -241.659406) (xy 338.713487 -241.703443) (xy 338.677235 -241.742514)
			(xy 338.635564 -241.775745) (xy 338.589406 -241.802394) (xy 338.539792 -241.821866) (xy 338.48783 -241.833726)
			(xy 338.43468 -241.83771) (xy 338.38153 -241.833726) (xy 338.329568 -241.821866) (xy 338.279954 -241.802394)
			(xy 338.233796 -241.775745) (xy 338.192125 -241.742514) (xy 338.155873 -241.703443) (xy 338.125849 -241.659406)
			(xy 338.102723 -241.611385) (xy 338.087013 -241.560455) (xy 338.07907 -241.507751) (xy 337.85049 -241.507751)
			(xy 337.842547 -241.560455) (xy 337.826837 -241.611385) (xy 337.803711 -241.659406) (xy 337.773687 -241.703443)
			(xy 337.737435 -241.742514) (xy 337.695764 -241.775745) (xy 337.649606 -241.802394) (xy 337.599992 -241.821866)
			(xy 337.54803 -241.833726) (xy 337.49488 -241.83771) (xy 337.44173 -241.833726) (xy 337.389768 -241.821866)
			(xy 337.340154 -241.802394) (xy 337.293996 -241.775745) (xy 337.252325 -241.742514) (xy 337.216073 -241.703443)
			(xy 337.186049 -241.659406) (xy 337.162923 -241.611385) (xy 337.147213 -241.560455) (xy 337.13927 -241.507751)
			(xy 336.909773 -241.507751) (xy 336.907872 -241.53349) (xy 336.896349 -241.584743) (xy 336.877423 -241.633747)
			(xy 336.851503 -241.679439) (xy 336.819152 -241.720828) (xy 336.781072 -241.757016) (xy 336.738089 -241.787218)
			(xy 336.691136 -241.810777) (xy 336.666332 -241.81943) (xy 336.63128 -241.83086) (xy 336.63128 -241.942874)
			(xy 336.631813 -241.957239) (xy 336.639897 -241.984811) (xy 336.655347 -242.009036) (xy 336.676938 -242.027994)
			(xy 336.702958 -242.040181) (xy 336.731344 -242.044632) (xy 336.759845 -242.040993) (xy 336.786202 -242.029553)
			(xy 336.79765 -242.020852) (xy 336.816925 -242.005412) (xy 336.858929 -241.979437) (xy 336.904118 -241.959513)
			(xy 336.951625 -241.94602) (xy 337.000541 -241.939217) (xy 337.025234 -241.93881) (xy 337.05188 -241.939311)
			(xy 337.104577 -241.947258) (xy 337.155501 -241.96297) (xy 337.203514 -241.986096) (xy 337.247545 -242.01612)
			(xy 337.286609 -242.05237) (xy 337.319835 -242.094037) (xy 337.34648 -242.140191) (xy 337.365949 -242.1898)
			(xy 337.377807 -242.241756) (xy 337.381789 -242.2949) (xy 337.379791 -242.321567) (xy 337.609424 -242.321567)
			(xy 337.609424 -242.268269) (xy 337.617367 -242.215565) (xy 337.633077 -242.164635) (xy 337.656203 -242.116614)
			(xy 337.686227 -242.072577) (xy 337.722479 -242.033506) (xy 337.76415 -242.000275) (xy 337.810308 -241.973626)
			(xy 337.859922 -241.954154) (xy 337.911884 -241.942294) (xy 337.965034 -241.938311) (xy 338.018184 -241.942294)
			(xy 338.070146 -241.954154) (xy 338.11976 -241.973626) (xy 338.165918 -242.000275) (xy 338.207589 -242.033506)
			(xy 338.243841 -242.072577) (xy 338.273865 -242.116614) (xy 338.296991 -242.164635) (xy 338.312701 -242.215565)
			(xy 338.320644 -242.268269) (xy 338.321142 -242.294918) (xy 338.320644 -242.321567) (xy 338.549224 -242.321567)
			(xy 338.549224 -242.268269) (xy 338.557167 -242.215565) (xy 338.572877 -242.164635) (xy 338.596003 -242.116614)
			(xy 338.626027 -242.072577) (xy 338.662279 -242.033506) (xy 338.70395 -242.000275) (xy 338.750108 -241.973626)
			(xy 338.799722 -241.954154) (xy 338.851684 -241.942294) (xy 338.904834 -241.938311) (xy 338.957984 -241.942294)
			(xy 339.009946 -241.954154) (xy 339.05956 -241.973626) (xy 339.105718 -242.000275) (xy 339.147389 -242.033506)
			(xy 339.183641 -242.072577) (xy 339.213665 -242.116614) (xy 339.236791 -242.164635) (xy 339.252501 -242.215565)
			(xy 339.260444 -242.268269) (xy 339.260942 -242.294918) (xy 339.260444 -242.321567) (xy 339.489024 -242.321567)
			(xy 339.489024 -242.268269) (xy 339.496967 -242.215565) (xy 339.512677 -242.164635) (xy 339.535803 -242.116614)
			(xy 339.565827 -242.072577) (xy 339.602079 -242.033506) (xy 339.64375 -242.000275) (xy 339.689908 -241.973626)
			(xy 339.739522 -241.954154) (xy 339.791484 -241.942294) (xy 339.844634 -241.938311) (xy 339.897784 -241.942294)
			(xy 339.949746 -241.954154) (xy 339.99936 -241.973626) (xy 340.045518 -242.000275) (xy 340.087189 -242.033506)
			(xy 340.123441 -242.072577) (xy 340.153465 -242.116614) (xy 340.176591 -242.164635) (xy 340.192301 -242.215565)
			(xy 340.200244 -242.268269) (xy 340.200742 -242.294918) (xy 340.200244 -242.321567) (xy 340.428824 -242.321567)
			(xy 340.428824 -242.268269) (xy 340.436767 -242.215565) (xy 340.452477 -242.164635) (xy 340.475603 -242.116614)
			(xy 340.505627 -242.072577) (xy 340.541879 -242.033506) (xy 340.58355 -242.000275) (xy 340.629708 -241.973626)
			(xy 340.679322 -241.954154) (xy 340.731284 -241.942294) (xy 340.784434 -241.938311) (xy 340.837584 -241.942294)
			(xy 340.889546 -241.954154) (xy 340.93916 -241.973626) (xy 340.985318 -242.000275) (xy 341.026989 -242.033506)
			(xy 341.063241 -242.072577) (xy 341.093265 -242.116614) (xy 341.116391 -242.164635) (xy 341.132101 -242.215565)
			(xy 341.140044 -242.268269) (xy 341.140542 -242.294918) (xy 341.140044 -242.321567) (xy 341.368624 -242.321567)
			(xy 341.368624 -242.268269) (xy 341.376567 -242.215565) (xy 341.392277 -242.164635) (xy 341.415403 -242.116614)
			(xy 341.445427 -242.072577) (xy 341.481679 -242.033506) (xy 341.52335 -242.000275) (xy 341.569508 -241.973626)
			(xy 341.619122 -241.954154) (xy 341.671084 -241.942294) (xy 341.724234 -241.938311) (xy 341.777384 -241.942294)
			(xy 341.829346 -241.954154) (xy 341.87896 -241.973626) (xy 341.925118 -242.000275) (xy 341.966789 -242.033506)
			(xy 342.003041 -242.072577) (xy 342.033065 -242.116614) (xy 342.056191 -242.164635) (xy 342.071901 -242.215565)
			(xy 342.079844 -242.268269) (xy 342.080342 -242.294918) (xy 342.079844 -242.321567) (xy 342.308424 -242.321567)
			(xy 342.308424 -242.268269) (xy 342.316367 -242.215565) (xy 342.332077 -242.164635) (xy 342.355203 -242.116614)
			(xy 342.385227 -242.072577) (xy 342.421479 -242.033506) (xy 342.46315 -242.000275) (xy 342.509308 -241.973626)
			(xy 342.558922 -241.954154) (xy 342.610884 -241.942294) (xy 342.664034 -241.938311) (xy 342.717184 -241.942294)
			(xy 342.769146 -241.954154) (xy 342.81876 -241.973626) (xy 342.864918 -242.000275) (xy 342.906589 -242.033506)
			(xy 342.942841 -242.072577) (xy 342.972865 -242.116614) (xy 342.995991 -242.164635) (xy 343.011701 -242.215565)
			(xy 343.019644 -242.268269) (xy 343.020142 -242.294918) (xy 343.019644 -242.321567) (xy 343.248224 -242.321567)
			(xy 343.248224 -242.268269) (xy 343.256167 -242.215565) (xy 343.271877 -242.164635) (xy 343.295003 -242.116614)
			(xy 343.325027 -242.072577) (xy 343.361279 -242.033506) (xy 343.40295 -242.000275) (xy 343.449108 -241.973626)
			(xy 343.498722 -241.954154) (xy 343.550684 -241.942294) (xy 343.603834 -241.938311) (xy 343.656984 -241.942294)
			(xy 343.708946 -241.954154) (xy 343.75856 -241.973626) (xy 343.804718 -242.000275) (xy 343.846389 -242.033506)
			(xy 343.882641 -242.072577) (xy 343.912665 -242.116614) (xy 343.935791 -242.164635) (xy 343.951501 -242.215565)
			(xy 343.959444 -242.268269) (xy 343.959942 -242.294918) (xy 343.959444 -242.321567) (xy 344.188024 -242.321567)
			(xy 344.188024 -242.268269) (xy 344.195967 -242.215565) (xy 344.211677 -242.164635) (xy 344.234803 -242.116614)
			(xy 344.264827 -242.072577) (xy 344.301079 -242.033506) (xy 344.34275 -242.000275) (xy 344.388908 -241.973626)
			(xy 344.438522 -241.954154) (xy 344.490484 -241.942294) (xy 344.543634 -241.938311) (xy 344.596784 -241.942294)
			(xy 344.648746 -241.954154) (xy 344.69836 -241.973626) (xy 344.744518 -242.000275) (xy 344.786189 -242.033506)
			(xy 344.822441 -242.072577) (xy 344.852465 -242.116614) (xy 344.875591 -242.164635) (xy 344.891301 -242.215565)
			(xy 344.899244 -242.268269) (xy 344.899742 -242.294918) (xy 344.899244 -242.321567) (xy 345.127824 -242.321567)
			(xy 345.127824 -242.268269) (xy 345.135767 -242.215565) (xy 345.151477 -242.164635) (xy 345.174603 -242.116614)
			(xy 345.204627 -242.072577) (xy 345.240879 -242.033506) (xy 345.28255 -242.000275) (xy 345.328708 -241.973626)
			(xy 345.378322 -241.954154) (xy 345.430284 -241.942294) (xy 345.483434 -241.938311) (xy 345.536584 -241.942294)
			(xy 345.588546 -241.954154) (xy 345.63816 -241.973626) (xy 345.684318 -242.000275) (xy 345.725989 -242.033506)
			(xy 345.762241 -242.072577) (xy 345.792265 -242.116614) (xy 345.815391 -242.164635) (xy 345.831101 -242.215565)
			(xy 345.839044 -242.268269) (xy 345.839542 -242.294918) (xy 345.839044 -242.321567) (xy 346.067624 -242.321567)
			(xy 346.067624 -242.268269) (xy 346.075567 -242.215565) (xy 346.091277 -242.164635) (xy 346.114403 -242.116614)
			(xy 346.144427 -242.072577) (xy 346.180679 -242.033506) (xy 346.22235 -242.000275) (xy 346.268508 -241.973626)
			(xy 346.318122 -241.954154) (xy 346.370084 -241.942294) (xy 346.423234 -241.938311) (xy 346.476384 -241.942294)
			(xy 346.528346 -241.954154) (xy 346.57796 -241.973626) (xy 346.624118 -242.000275) (xy 346.665789 -242.033506)
			(xy 346.702041 -242.072577) (xy 346.732065 -242.116614) (xy 346.755191 -242.164635) (xy 346.770901 -242.215565)
			(xy 346.778844 -242.268269) (xy 346.779342 -242.294918) (xy 346.778844 -242.321567) (xy 346.770901 -242.374271)
			(xy 346.755191 -242.425201) (xy 346.732065 -242.473222) (xy 346.702041 -242.517259) (xy 346.665789 -242.55633)
			(xy 346.624118 -242.589561) (xy 346.57796 -242.61621) (xy 346.528346 -242.635682) (xy 346.476384 -242.647542)
			(xy 346.423234 -242.651526) (xy 346.370084 -242.647542) (xy 346.318122 -242.635682) (xy 346.268508 -242.61621)
			(xy 346.22235 -242.589561) (xy 346.180679 -242.55633) (xy 346.144427 -242.517259) (xy 346.114403 -242.473222)
			(xy 346.091277 -242.425201) (xy 346.075567 -242.374271) (xy 346.067624 -242.321567) (xy 345.839044 -242.321567)
			(xy 345.831101 -242.374271) (xy 345.815391 -242.425201) (xy 345.792265 -242.473222) (xy 345.762241 -242.517259)
			(xy 345.725989 -242.55633) (xy 345.684318 -242.589561) (xy 345.63816 -242.61621) (xy 345.588546 -242.635682)
			(xy 345.536584 -242.647542) (xy 345.483434 -242.651526) (xy 345.430284 -242.647542) (xy 345.378322 -242.635682)
			(xy 345.328708 -242.61621) (xy 345.28255 -242.589561) (xy 345.240879 -242.55633) (xy 345.204627 -242.517259)
			(xy 345.174603 -242.473222) (xy 345.151477 -242.425201) (xy 345.135767 -242.374271) (xy 345.127824 -242.321567)
			(xy 344.899244 -242.321567) (xy 344.891301 -242.374271) (xy 344.875591 -242.425201) (xy 344.852465 -242.473222)
			(xy 344.822441 -242.517259) (xy 344.786189 -242.55633) (xy 344.744518 -242.589561) (xy 344.69836 -242.61621)
			(xy 344.648746 -242.635682) (xy 344.596784 -242.647542) (xy 344.543634 -242.651526) (xy 344.490484 -242.647542)
			(xy 344.438522 -242.635682) (xy 344.388908 -242.61621) (xy 344.34275 -242.589561) (xy 344.301079 -242.55633)
			(xy 344.264827 -242.517259) (xy 344.234803 -242.473222) (xy 344.211677 -242.425201) (xy 344.195967 -242.374271)
			(xy 344.188024 -242.321567) (xy 343.959444 -242.321567) (xy 343.951501 -242.374271) (xy 343.935791 -242.425201)
			(xy 343.912665 -242.473222) (xy 343.882641 -242.517259) (xy 343.846389 -242.55633) (xy 343.804718 -242.589561)
			(xy 343.75856 -242.61621) (xy 343.708946 -242.635682) (xy 343.656984 -242.647542) (xy 343.603834 -242.651526)
			(xy 343.550684 -242.647542) (xy 343.498722 -242.635682) (xy 343.449108 -242.61621) (xy 343.40295 -242.589561)
			(xy 343.361279 -242.55633) (xy 343.325027 -242.517259) (xy 343.295003 -242.473222) (xy 343.271877 -242.425201)
			(xy 343.256167 -242.374271) (xy 343.248224 -242.321567) (xy 343.019644 -242.321567) (xy 343.011701 -242.374271)
			(xy 342.995991 -242.425201) (xy 342.972865 -242.473222) (xy 342.942841 -242.517259) (xy 342.906589 -242.55633)
			(xy 342.864918 -242.589561) (xy 342.81876 -242.61621) (xy 342.769146 -242.635682) (xy 342.717184 -242.647542)
			(xy 342.664034 -242.651526) (xy 342.610884 -242.647542) (xy 342.558922 -242.635682) (xy 342.509308 -242.61621)
			(xy 342.46315 -242.589561) (xy 342.421479 -242.55633) (xy 342.385227 -242.517259) (xy 342.355203 -242.473222)
			(xy 342.332077 -242.425201) (xy 342.316367 -242.374271) (xy 342.308424 -242.321567) (xy 342.079844 -242.321567)
			(xy 342.071901 -242.374271) (xy 342.056191 -242.425201) (xy 342.033065 -242.473222) (xy 342.003041 -242.517259)
			(xy 341.966789 -242.55633) (xy 341.925118 -242.589561) (xy 341.87896 -242.61621) (xy 341.829346 -242.635682)
			(xy 341.777384 -242.647542) (xy 341.724234 -242.651526) (xy 341.671084 -242.647542) (xy 341.619122 -242.635682)
			(xy 341.569508 -242.61621) (xy 341.52335 -242.589561) (xy 341.481679 -242.55633) (xy 341.445427 -242.517259)
			(xy 341.415403 -242.473222) (xy 341.392277 -242.425201) (xy 341.376567 -242.374271) (xy 341.368624 -242.321567)
			(xy 341.140044 -242.321567) (xy 341.132101 -242.374271) (xy 341.116391 -242.425201) (xy 341.093265 -242.473222)
			(xy 341.063241 -242.517259) (xy 341.026989 -242.55633) (xy 340.985318 -242.589561) (xy 340.93916 -242.61621)
			(xy 340.889546 -242.635682) (xy 340.837584 -242.647542) (xy 340.784434 -242.651526) (xy 340.731284 -242.647542)
			(xy 340.679322 -242.635682) (xy 340.629708 -242.61621) (xy 340.58355 -242.589561) (xy 340.541879 -242.55633)
			(xy 340.505627 -242.517259) (xy 340.475603 -242.473222) (xy 340.452477 -242.425201) (xy 340.436767 -242.374271)
			(xy 340.428824 -242.321567) (xy 340.200244 -242.321567) (xy 340.192301 -242.374271) (xy 340.176591 -242.425201)
			(xy 340.153465 -242.473222) (xy 340.123441 -242.517259) (xy 340.087189 -242.55633) (xy 340.045518 -242.589561)
			(xy 339.99936 -242.61621) (xy 339.949746 -242.635682) (xy 339.897784 -242.647542) (xy 339.844634 -242.651526)
			(xy 339.791484 -242.647542) (xy 339.739522 -242.635682) (xy 339.689908 -242.61621) (xy 339.64375 -242.589561)
			(xy 339.602079 -242.55633) (xy 339.565827 -242.517259) (xy 339.535803 -242.473222) (xy 339.512677 -242.425201)
			(xy 339.496967 -242.374271) (xy 339.489024 -242.321567) (xy 339.260444 -242.321567) (xy 339.252501 -242.374271)
			(xy 339.236791 -242.425201) (xy 339.213665 -242.473222) (xy 339.183641 -242.517259) (xy 339.147389 -242.55633)
			(xy 339.105718 -242.589561) (xy 339.05956 -242.61621) (xy 339.009946 -242.635682) (xy 338.957984 -242.647542)
			(xy 338.904834 -242.651526) (xy 338.851684 -242.647542) (xy 338.799722 -242.635682) (xy 338.750108 -242.61621)
			(xy 338.70395 -242.589561) (xy 338.662279 -242.55633) (xy 338.626027 -242.517259) (xy 338.596003 -242.473222)
			(xy 338.572877 -242.425201) (xy 338.557167 -242.374271) (xy 338.549224 -242.321567) (xy 338.320644 -242.321567)
			(xy 338.312701 -242.374271) (xy 338.296991 -242.425201) (xy 338.273865 -242.473222) (xy 338.243841 -242.517259)
			(xy 338.207589 -242.55633) (xy 338.165918 -242.589561) (xy 338.11976 -242.61621) (xy 338.070146 -242.635682)
			(xy 338.018184 -242.647542) (xy 337.965034 -242.651526) (xy 337.911884 -242.647542) (xy 337.859922 -242.635682)
			(xy 337.810308 -242.61621) (xy 337.76415 -242.589561) (xy 337.722479 -242.55633) (xy 337.686227 -242.517259)
			(xy 337.656203 -242.473222) (xy 337.633077 -242.425201) (xy 337.617367 -242.374271) (xy 337.609424 -242.321567)
			(xy 337.379791 -242.321567) (xy 337.377807 -242.348044) (xy 337.365949 -242.4) (xy 337.34648 -242.449609)
			(xy 337.319835 -242.495763) (xy 337.286609 -242.53743) (xy 337.247545 -242.57368) (xy 337.203514 -242.603704)
			(xy 337.155501 -242.62683) (xy 337.104577 -242.642542) (xy 337.05188 -242.650489) (xy 337.025234 -242.651026)
			(xy 337.000539 -242.650627) (xy 336.951617 -242.643842) (xy 336.904104 -242.630357) (xy 336.858912 -242.61043)
			(xy 336.816911 -242.584444) (xy 336.79765 -242.568984) (xy 336.786262 -242.560208) (xy 336.75989 -242.548791)
			(xy 336.731381 -242.545172) (xy 336.702993 -242.549637) (xy 336.676972 -242.561834) (xy 336.655379 -242.580796)
			(xy 336.639922 -242.605022) (xy 336.631825 -242.632595) (xy 336.63128 -242.646962) (xy 336.63128 -242.75923)
			(xy 336.666332 -242.77066) (xy 336.691139 -242.779309) (xy 336.738093 -242.802869) (xy 336.781078 -242.833072)
			(xy 336.81916 -242.86926) (xy 336.851512 -242.910651) (xy 336.877433 -242.956344) (xy 336.896361 -243.00535)
			(xy 336.907885 -243.056605) (xy 336.911755 -243.108996) (xy 336.909788 -243.135637) (xy 337.13927 -243.135637)
			(xy 337.13927 -243.082339) (xy 337.147213 -243.029635) (xy 337.162923 -242.978705) (xy 337.186049 -242.930684)
			(xy 337.216073 -242.886647) (xy 337.252325 -242.847576) (xy 337.293996 -242.814345) (xy 337.340154 -242.787696)
			(xy 337.389768 -242.768224) (xy 337.44173 -242.756364) (xy 337.49488 -242.752381) (xy 337.54803 -242.756364)
			(xy 337.599992 -242.768224) (xy 337.649606 -242.787696) (xy 337.695764 -242.814345) (xy 337.737435 -242.847576)
			(xy 337.773687 -242.886647) (xy 337.803711 -242.930684) (xy 337.826837 -242.978705) (xy 337.842547 -243.029635)
			(xy 337.85049 -243.082339) (xy 337.850988 -243.108988) (xy 337.85049 -243.135637) (xy 338.07907 -243.135637)
			(xy 338.07907 -243.082339) (xy 338.087013 -243.029635) (xy 338.102723 -242.978705) (xy 338.125849 -242.930684)
			(xy 338.155873 -242.886647) (xy 338.192125 -242.847576) (xy 338.233796 -242.814345) (xy 338.279954 -242.787696)
			(xy 338.329568 -242.768224) (xy 338.38153 -242.756364) (xy 338.43468 -242.752381) (xy 338.48783 -242.756364)
			(xy 338.539792 -242.768224) (xy 338.589406 -242.787696) (xy 338.635564 -242.814345) (xy 338.677235 -242.847576)
			(xy 338.713487 -242.886647) (xy 338.743511 -242.930684) (xy 338.766637 -242.978705) (xy 338.782347 -243.029635)
			(xy 338.79029 -243.082339) (xy 338.790788 -243.108988) (xy 338.79029 -243.135637) (xy 339.019124 -243.135637)
			(xy 339.019124 -243.082339) (xy 339.027067 -243.029635) (xy 339.042777 -242.978705) (xy 339.065903 -242.930684)
			(xy 339.095927 -242.886647) (xy 339.132179 -242.847576) (xy 339.17385 -242.814345) (xy 339.220008 -242.787696)
			(xy 339.269622 -242.768224) (xy 339.321584 -242.756364) (xy 339.374734 -242.752381) (xy 339.427884 -242.756364)
			(xy 339.479846 -242.768224) (xy 339.52946 -242.787696) (xy 339.575618 -242.814345) (xy 339.617289 -242.847576)
			(xy 339.653541 -242.886647) (xy 339.683565 -242.930684) (xy 339.706691 -242.978705) (xy 339.722401 -243.029635)
			(xy 339.730344 -243.082339) (xy 339.730842 -243.108988) (xy 339.730344 -243.135637) (xy 339.95867 -243.135637)
			(xy 339.95867 -243.082339) (xy 339.966613 -243.029635) (xy 339.982323 -242.978705) (xy 340.005449 -242.930684)
			(xy 340.035473 -242.886647) (xy 340.071725 -242.847576) (xy 340.113396 -242.814345) (xy 340.159554 -242.787696)
			(xy 340.209168 -242.768224) (xy 340.26113 -242.756364) (xy 340.31428 -242.752381) (xy 340.36743 -242.756364)
			(xy 340.419392 -242.768224) (xy 340.469006 -242.787696) (xy 340.515164 -242.814345) (xy 340.556835 -242.847576)
			(xy 340.593087 -242.886647) (xy 340.623111 -242.930684) (xy 340.646237 -242.978705) (xy 340.661947 -243.029635)
			(xy 340.66989 -243.082339) (xy 340.670388 -243.108988) (xy 340.66989 -243.135637) (xy 340.89847 -243.135637)
			(xy 340.89847 -243.082339) (xy 340.906413 -243.029635) (xy 340.922123 -242.978705) (xy 340.945249 -242.930684)
			(xy 340.975273 -242.886647) (xy 341.011525 -242.847576) (xy 341.053196 -242.814345) (xy 341.099354 -242.787696)
			(xy 341.148968 -242.768224) (xy 341.20093 -242.756364) (xy 341.25408 -242.752381) (xy 341.30723 -242.756364)
			(xy 341.359192 -242.768224) (xy 341.408806 -242.787696) (xy 341.454964 -242.814345) (xy 341.496635 -242.847576)
			(xy 341.532887 -242.886647) (xy 341.562911 -242.930684) (xy 341.586037 -242.978705) (xy 341.601747 -243.029635)
			(xy 341.60969 -243.082339) (xy 341.610188 -243.108988) (xy 341.60969 -243.135637) (xy 341.83827 -243.135637)
			(xy 341.83827 -243.082339) (xy 341.846213 -243.029635) (xy 341.861923 -242.978705) (xy 341.885049 -242.930684)
			(xy 341.915073 -242.886647) (xy 341.951325 -242.847576) (xy 341.992996 -242.814345) (xy 342.039154 -242.787696)
			(xy 342.088768 -242.768224) (xy 342.14073 -242.756364) (xy 342.19388 -242.752381) (xy 342.24703 -242.756364)
			(xy 342.298992 -242.768224) (xy 342.348606 -242.787696) (xy 342.394764 -242.814345) (xy 342.436435 -242.847576)
			(xy 342.472687 -242.886647) (xy 342.502711 -242.930684) (xy 342.525837 -242.978705) (xy 342.541547 -243.029635)
			(xy 342.54949 -243.082339) (xy 342.549988 -243.108988) (xy 342.54949 -243.135637) (xy 342.77807 -243.135637)
			(xy 342.77807 -243.082339) (xy 342.786013 -243.029635) (xy 342.801723 -242.978705) (xy 342.824849 -242.930684)
			(xy 342.854873 -242.886647) (xy 342.891125 -242.847576) (xy 342.932796 -242.814345) (xy 342.978954 -242.787696)
			(xy 343.028568 -242.768224) (xy 343.08053 -242.756364) (xy 343.13368 -242.752381) (xy 343.18683 -242.756364)
			(xy 343.238792 -242.768224) (xy 343.288406 -242.787696) (xy 343.334564 -242.814345) (xy 343.376235 -242.847576)
			(xy 343.412487 -242.886647) (xy 343.442511 -242.930684) (xy 343.465637 -242.978705) (xy 343.481347 -243.029635)
			(xy 343.48929 -243.082339) (xy 343.489788 -243.108988) (xy 343.48929 -243.135637) (xy 343.71787 -243.135637)
			(xy 343.71787 -243.082339) (xy 343.725813 -243.029635) (xy 343.741523 -242.978705) (xy 343.764649 -242.930684)
			(xy 343.794673 -242.886647) (xy 343.830925 -242.847576) (xy 343.872596 -242.814345) (xy 343.918754 -242.787696)
			(xy 343.968368 -242.768224) (xy 344.02033 -242.756364) (xy 344.07348 -242.752381) (xy 344.12663 -242.756364)
			(xy 344.178592 -242.768224) (xy 344.228206 -242.787696) (xy 344.274364 -242.814345) (xy 344.316035 -242.847576)
			(xy 344.352287 -242.886647) (xy 344.382311 -242.930684) (xy 344.405437 -242.978705) (xy 344.421147 -243.029635)
			(xy 344.42909 -243.082339) (xy 344.429588 -243.108988) (xy 344.42909 -243.135637) (xy 344.65767 -243.135637)
			(xy 344.65767 -243.082339) (xy 344.665613 -243.029635) (xy 344.681323 -242.978705) (xy 344.704449 -242.930684)
			(xy 344.734473 -242.886647) (xy 344.770725 -242.847576) (xy 344.812396 -242.814345) (xy 344.858554 -242.787696)
			(xy 344.908168 -242.768224) (xy 344.96013 -242.756364) (xy 345.01328 -242.752381) (xy 345.06643 -242.756364)
			(xy 345.118392 -242.768224) (xy 345.168006 -242.787696) (xy 345.214164 -242.814345) (xy 345.255835 -242.847576)
			(xy 345.292087 -242.886647) (xy 345.322111 -242.930684) (xy 345.345237 -242.978705) (xy 345.360947 -243.029635)
			(xy 345.36889 -243.082339) (xy 345.369388 -243.108988) (xy 345.36889 -243.135637) (xy 345.597724 -243.135637)
			(xy 345.597724 -243.082339) (xy 345.605667 -243.029635) (xy 345.621377 -242.978705) (xy 345.644503 -242.930684)
			(xy 345.674527 -242.886647) (xy 345.710779 -242.847576) (xy 345.75245 -242.814345) (xy 345.798608 -242.787696)
			(xy 345.848222 -242.768224) (xy 345.900184 -242.756364) (xy 345.953334 -242.752381) (xy 346.006484 -242.756364)
			(xy 346.058446 -242.768224) (xy 346.10806 -242.787696) (xy 346.154218 -242.814345) (xy 346.195889 -242.847576)
			(xy 346.232141 -242.886647) (xy 346.262165 -242.930684) (xy 346.285291 -242.978705) (xy 346.301001 -243.029635)
			(xy 346.308944 -243.082339) (xy 346.309442 -243.108988) (xy 346.308944 -243.135637) (xy 346.301001 -243.188341)
			(xy 346.285291 -243.239271) (xy 346.262165 -243.287292) (xy 346.232141 -243.331329) (xy 346.195889 -243.3704)
			(xy 346.154218 -243.403631) (xy 346.10806 -243.43028) (xy 346.058446 -243.449752) (xy 346.006484 -243.461612)
			(xy 345.953334 -243.465596) (xy 345.900184 -243.461612) (xy 345.848222 -243.449752) (xy 345.798608 -243.43028)
			(xy 345.75245 -243.403631) (xy 345.710779 -243.3704) (xy 345.674527 -243.331329) (xy 345.644503 -243.287292)
			(xy 345.621377 -243.239271) (xy 345.605667 -243.188341) (xy 345.597724 -243.135637) (xy 345.36889 -243.135637)
			(xy 345.360947 -243.188341) (xy 345.345237 -243.239271) (xy 345.322111 -243.287292) (xy 345.292087 -243.331329)
			(xy 345.255835 -243.3704) (xy 345.214164 -243.403631) (xy 345.168006 -243.43028) (xy 345.118392 -243.449752)
			(xy 345.06643 -243.461612) (xy 345.01328 -243.465596) (xy 344.96013 -243.461612) (xy 344.908168 -243.449752)
			(xy 344.858554 -243.43028) (xy 344.812396 -243.403631) (xy 344.770725 -243.3704) (xy 344.734473 -243.331329)
			(xy 344.704449 -243.287292) (xy 344.681323 -243.239271) (xy 344.665613 -243.188341) (xy 344.65767 -243.135637)
			(xy 344.42909 -243.135637) (xy 344.421147 -243.188341) (xy 344.405437 -243.239271) (xy 344.382311 -243.287292)
			(xy 344.352287 -243.331329) (xy 344.316035 -243.3704) (xy 344.274364 -243.403631) (xy 344.228206 -243.43028)
			(xy 344.178592 -243.449752) (xy 344.12663 -243.461612) (xy 344.07348 -243.465596) (xy 344.02033 -243.461612)
			(xy 343.968368 -243.449752) (xy 343.918754 -243.43028) (xy 343.872596 -243.403631) (xy 343.830925 -243.3704)
			(xy 343.794673 -243.331329) (xy 343.764649 -243.287292) (xy 343.741523 -243.239271) (xy 343.725813 -243.188341)
			(xy 343.71787 -243.135637) (xy 343.48929 -243.135637) (xy 343.481347 -243.188341) (xy 343.465637 -243.239271)
			(xy 343.442511 -243.287292) (xy 343.412487 -243.331329) (xy 343.376235 -243.3704) (xy 343.334564 -243.403631)
			(xy 343.288406 -243.43028) (xy 343.238792 -243.449752) (xy 343.18683 -243.461612) (xy 343.13368 -243.465596)
			(xy 343.08053 -243.461612) (xy 343.028568 -243.449752) (xy 342.978954 -243.43028) (xy 342.932796 -243.403631)
			(xy 342.891125 -243.3704) (xy 342.854873 -243.331329) (xy 342.824849 -243.287292) (xy 342.801723 -243.239271)
			(xy 342.786013 -243.188341) (xy 342.77807 -243.135637) (xy 342.54949 -243.135637) (xy 342.541547 -243.188341)
			(xy 342.525837 -243.239271) (xy 342.502711 -243.287292) (xy 342.472687 -243.331329) (xy 342.436435 -243.3704)
			(xy 342.394764 -243.403631) (xy 342.348606 -243.43028) (xy 342.298992 -243.449752) (xy 342.24703 -243.461612)
			(xy 342.19388 -243.465596) (xy 342.14073 -243.461612) (xy 342.088768 -243.449752) (xy 342.039154 -243.43028)
			(xy 341.992996 -243.403631) (xy 341.951325 -243.3704) (xy 341.915073 -243.331329) (xy 341.885049 -243.287292)
			(xy 341.861923 -243.239271) (xy 341.846213 -243.188341) (xy 341.83827 -243.135637) (xy 341.60969 -243.135637)
			(xy 341.601747 -243.188341) (xy 341.586037 -243.239271) (xy 341.562911 -243.287292) (xy 341.532887 -243.331329)
			(xy 341.496635 -243.3704) (xy 341.454964 -243.403631) (xy 341.408806 -243.43028) (xy 341.359192 -243.449752)
			(xy 341.30723 -243.461612) (xy 341.25408 -243.465596) (xy 341.20093 -243.461612) (xy 341.148968 -243.449752)
			(xy 341.099354 -243.43028) (xy 341.053196 -243.403631) (xy 341.011525 -243.3704) (xy 340.975273 -243.331329)
			(xy 340.945249 -243.287292) (xy 340.922123 -243.239271) (xy 340.906413 -243.188341) (xy 340.89847 -243.135637)
			(xy 340.66989 -243.135637) (xy 340.661947 -243.188341) (xy 340.646237 -243.239271) (xy 340.623111 -243.287292)
			(xy 340.593087 -243.331329) (xy 340.556835 -243.3704) (xy 340.515164 -243.403631) (xy 340.469006 -243.43028)
			(xy 340.419392 -243.449752) (xy 340.36743 -243.461612) (xy 340.31428 -243.465596) (xy 340.26113 -243.461612)
			(xy 340.209168 -243.449752) (xy 340.159554 -243.43028) (xy 340.113396 -243.403631) (xy 340.071725 -243.3704)
			(xy 340.035473 -243.331329) (xy 340.005449 -243.287292) (xy 339.982323 -243.239271) (xy 339.966613 -243.188341)
			(xy 339.95867 -243.135637) (xy 339.730344 -243.135637) (xy 339.722401 -243.188341) (xy 339.706691 -243.239271)
			(xy 339.683565 -243.287292) (xy 339.653541 -243.331329) (xy 339.617289 -243.3704) (xy 339.575618 -243.403631)
			(xy 339.52946 -243.43028) (xy 339.479846 -243.449752) (xy 339.427884 -243.461612) (xy 339.374734 -243.465596)
			(xy 339.321584 -243.461612) (xy 339.269622 -243.449752) (xy 339.220008 -243.43028) (xy 339.17385 -243.403631)
			(xy 339.132179 -243.3704) (xy 339.095927 -243.331329) (xy 339.065903 -243.287292) (xy 339.042777 -243.239271)
			(xy 339.027067 -243.188341) (xy 339.019124 -243.135637) (xy 338.79029 -243.135637) (xy 338.782347 -243.188341)
			(xy 338.766637 -243.239271) (xy 338.743511 -243.287292) (xy 338.713487 -243.331329) (xy 338.677235 -243.3704)
			(xy 338.635564 -243.403631) (xy 338.589406 -243.43028) (xy 338.539792 -243.449752) (xy 338.48783 -243.461612)
			(xy 338.43468 -243.465596) (xy 338.38153 -243.461612) (xy 338.329568 -243.449752) (xy 338.279954 -243.43028)
			(xy 338.233796 -243.403631) (xy 338.192125 -243.3704) (xy 338.155873 -243.331329) (xy 338.125849 -243.287292)
			(xy 338.102723 -243.239271) (xy 338.087013 -243.188341) (xy 338.07907 -243.135637) (xy 337.85049 -243.135637)
			(xy 337.842547 -243.188341) (xy 337.826837 -243.239271) (xy 337.803711 -243.287292) (xy 337.773687 -243.331329)
			(xy 337.737435 -243.3704) (xy 337.695764 -243.403631) (xy 337.649606 -243.43028) (xy 337.599992 -243.449752)
			(xy 337.54803 -243.461612) (xy 337.49488 -243.465596) (xy 337.44173 -243.461612) (xy 337.389768 -243.449752)
			(xy 337.340154 -243.43028) (xy 337.293996 -243.403631) (xy 337.252325 -243.3704) (xy 337.216073 -243.331329)
			(xy 337.186049 -243.287292) (xy 337.162923 -243.239271) (xy 337.147213 -243.188341) (xy 337.13927 -243.135637)
			(xy 336.909788 -243.135637) (xy 336.907886 -243.161388) (xy 336.896363 -243.212643) (xy 336.877437 -243.261649)
			(xy 336.851516 -243.307343) (xy 336.819165 -243.348734) (xy 336.781084 -243.384924) (xy 336.7381 -243.415127)
			(xy 336.691146 -243.438688) (xy 336.666332 -243.447316) (xy 336.63128 -243.458746) (xy 336.63128 -243.57076)
			(xy 336.631811 -243.585126) (xy 336.639893 -243.612702) (xy 336.655343 -243.636931) (xy 336.676935 -243.655892)
			(xy 336.702957 -243.668081) (xy 336.731346 -243.672532) (xy 336.75985 -243.668892) (xy 336.786209 -243.657449)
			(xy 336.79765 -243.648738) (xy 336.816926 -243.633299) (xy 336.85893 -243.607325) (xy 336.904118 -243.587401)
			(xy 336.951626 -243.573909) (xy 337.000541 -243.567107) (xy 337.025234 -243.566696) (xy 337.051881 -243.567196)
			(xy 337.10458 -243.575144) (xy 337.155506 -243.590857) (xy 337.203521 -243.613984) (xy 337.247554 -243.644008)
			(xy 337.28662 -243.68026) (xy 337.319847 -243.721929) (xy 337.346493 -243.768084) (xy 337.365963 -243.817695)
			(xy 337.377821 -243.869654) (xy 337.381804 -243.9228) (xy 337.379807 -243.949453) (xy 337.609424 -243.949453)
			(xy 337.609424 -243.896155) (xy 337.617367 -243.843451) (xy 337.633077 -243.792521) (xy 337.656203 -243.7445)
			(xy 337.686227 -243.700463) (xy 337.722479 -243.661392) (xy 337.76415 -243.628161) (xy 337.810308 -243.601512)
			(xy 337.859922 -243.58204) (xy 337.911884 -243.57018) (xy 337.965034 -243.566197) (xy 338.018184 -243.57018)
			(xy 338.070146 -243.58204) (xy 338.11976 -243.601512) (xy 338.165918 -243.628161) (xy 338.207589 -243.661392)
			(xy 338.243841 -243.700463) (xy 338.273865 -243.7445) (xy 338.296991 -243.792521) (xy 338.312701 -243.843451)
			(xy 338.320644 -243.896155) (xy 338.321142 -243.922804) (xy 338.320644 -243.949453) (xy 338.549224 -243.949453)
			(xy 338.549224 -243.896155) (xy 338.557167 -243.843451) (xy 338.572877 -243.792521) (xy 338.596003 -243.7445)
			(xy 338.626027 -243.700463) (xy 338.662279 -243.661392) (xy 338.70395 -243.628161) (xy 338.750108 -243.601512)
			(xy 338.799722 -243.58204) (xy 338.851684 -243.57018) (xy 338.904834 -243.566197) (xy 338.957984 -243.57018)
			(xy 339.009946 -243.58204) (xy 339.05956 -243.601512) (xy 339.105718 -243.628161) (xy 339.147389 -243.661392)
			(xy 339.183641 -243.700463) (xy 339.213665 -243.7445) (xy 339.236791 -243.792521) (xy 339.252501 -243.843451)
			(xy 339.260444 -243.896155) (xy 339.260942 -243.922804) (xy 339.260444 -243.949453) (xy 339.489024 -243.949453)
			(xy 339.489024 -243.896155) (xy 339.496967 -243.843451) (xy 339.512677 -243.792521) (xy 339.535803 -243.7445)
			(xy 339.565827 -243.700463) (xy 339.602079 -243.661392) (xy 339.64375 -243.628161) (xy 339.689908 -243.601512)
			(xy 339.739522 -243.58204) (xy 339.791484 -243.57018) (xy 339.844634 -243.566197) (xy 339.897784 -243.57018)
			(xy 339.949746 -243.58204) (xy 339.99936 -243.601512) (xy 340.045518 -243.628161) (xy 340.087189 -243.661392)
			(xy 340.123441 -243.700463) (xy 340.153465 -243.7445) (xy 340.176591 -243.792521) (xy 340.192301 -243.843451)
			(xy 340.200244 -243.896155) (xy 340.200742 -243.922804) (xy 340.200244 -243.949453) (xy 340.428824 -243.949453)
			(xy 340.428824 -243.896155) (xy 340.436767 -243.843451) (xy 340.452477 -243.792521) (xy 340.475603 -243.7445)
			(xy 340.505627 -243.700463) (xy 340.541879 -243.661392) (xy 340.58355 -243.628161) (xy 340.629708 -243.601512)
			(xy 340.679322 -243.58204) (xy 340.731284 -243.57018) (xy 340.784434 -243.566197) (xy 340.837584 -243.57018)
			(xy 340.889546 -243.58204) (xy 340.93916 -243.601512) (xy 340.985318 -243.628161) (xy 341.026989 -243.661392)
			(xy 341.063241 -243.700463) (xy 341.093265 -243.7445) (xy 341.116391 -243.792521) (xy 341.132101 -243.843451)
			(xy 341.140044 -243.896155) (xy 341.140542 -243.922804) (xy 341.140044 -243.949453) (xy 341.368624 -243.949453)
			(xy 341.368624 -243.896155) (xy 341.376567 -243.843451) (xy 341.392277 -243.792521) (xy 341.415403 -243.7445)
			(xy 341.445427 -243.700463) (xy 341.481679 -243.661392) (xy 341.52335 -243.628161) (xy 341.569508 -243.601512)
			(xy 341.619122 -243.58204) (xy 341.671084 -243.57018) (xy 341.724234 -243.566197) (xy 341.777384 -243.57018)
			(xy 341.829346 -243.58204) (xy 341.87896 -243.601512) (xy 341.925118 -243.628161) (xy 341.966789 -243.661392)
			(xy 342.003041 -243.700463) (xy 342.033065 -243.7445) (xy 342.056191 -243.792521) (xy 342.071901 -243.843451)
			(xy 342.079844 -243.896155) (xy 342.080342 -243.922804) (xy 342.079844 -243.949453) (xy 342.30817 -243.949453)
			(xy 342.30817 -243.896155) (xy 342.316113 -243.843451) (xy 342.331823 -243.792521) (xy 342.354949 -243.7445)
			(xy 342.384973 -243.700463) (xy 342.421225 -243.661392) (xy 342.462896 -243.628161) (xy 342.509054 -243.601512)
			(xy 342.558668 -243.58204) (xy 342.61063 -243.57018) (xy 342.66378 -243.566197) (xy 342.71693 -243.57018)
			(xy 342.768892 -243.58204) (xy 342.818506 -243.601512) (xy 342.864664 -243.628161) (xy 342.906335 -243.661392)
			(xy 342.942587 -243.700463) (xy 342.972611 -243.7445) (xy 342.995737 -243.792521) (xy 343.011447 -243.843451)
			(xy 343.01939 -243.896155) (xy 343.019888 -243.922804) (xy 343.01939 -243.949453) (xy 343.248224 -243.949453)
			(xy 343.248224 -243.896155) (xy 343.256167 -243.843451) (xy 343.271877 -243.792521) (xy 343.295003 -243.7445)
			(xy 343.325027 -243.700463) (xy 343.361279 -243.661392) (xy 343.40295 -243.628161) (xy 343.449108 -243.601512)
			(xy 343.498722 -243.58204) (xy 343.550684 -243.57018) (xy 343.603834 -243.566197) (xy 343.656984 -243.57018)
			(xy 343.708946 -243.58204) (xy 343.75856 -243.601512) (xy 343.804718 -243.628161) (xy 343.846389 -243.661392)
			(xy 343.882641 -243.700463) (xy 343.912665 -243.7445) (xy 343.935791 -243.792521) (xy 343.951501 -243.843451)
			(xy 343.959444 -243.896155) (xy 343.959942 -243.922804) (xy 343.959444 -243.949453) (xy 344.188024 -243.949453)
			(xy 344.188024 -243.896155) (xy 344.195967 -243.843451) (xy 344.211677 -243.792521) (xy 344.234803 -243.7445)
			(xy 344.264827 -243.700463) (xy 344.301079 -243.661392) (xy 344.34275 -243.628161) (xy 344.388908 -243.601512)
			(xy 344.438522 -243.58204) (xy 344.490484 -243.57018) (xy 344.543634 -243.566197) (xy 344.596784 -243.57018)
			(xy 344.648746 -243.58204) (xy 344.69836 -243.601512) (xy 344.744518 -243.628161) (xy 344.786189 -243.661392)
			(xy 344.822441 -243.700463) (xy 344.852465 -243.7445) (xy 344.875591 -243.792521) (xy 344.891301 -243.843451)
			(xy 344.899244 -243.896155) (xy 344.899742 -243.922804) (xy 344.899244 -243.949453) (xy 345.127824 -243.949453)
			(xy 345.127824 -243.896155) (xy 345.135767 -243.843451) (xy 345.151477 -243.792521) (xy 345.174603 -243.7445)
			(xy 345.204627 -243.700463) (xy 345.240879 -243.661392) (xy 345.28255 -243.628161) (xy 345.328708 -243.601512)
			(xy 345.378322 -243.58204) (xy 345.430284 -243.57018) (xy 345.483434 -243.566197) (xy 345.536584 -243.57018)
			(xy 345.588546 -243.58204) (xy 345.63816 -243.601512) (xy 345.684318 -243.628161) (xy 345.725989 -243.661392)
			(xy 345.762241 -243.700463) (xy 345.792265 -243.7445) (xy 345.815391 -243.792521) (xy 345.831101 -243.843451)
			(xy 345.839044 -243.896155) (xy 345.839542 -243.922804) (xy 345.839044 -243.949453) (xy 346.067624 -243.949453)
			(xy 346.067624 -243.896155) (xy 346.075567 -243.843451) (xy 346.091277 -243.792521) (xy 346.114403 -243.7445)
			(xy 346.144427 -243.700463) (xy 346.180679 -243.661392) (xy 346.22235 -243.628161) (xy 346.268508 -243.601512)
			(xy 346.318122 -243.58204) (xy 346.370084 -243.57018) (xy 346.423234 -243.566197) (xy 346.476384 -243.57018)
			(xy 346.528346 -243.58204) (xy 346.57796 -243.601512) (xy 346.624118 -243.628161) (xy 346.665789 -243.661392)
			(xy 346.702041 -243.700463) (xy 346.732065 -243.7445) (xy 346.755191 -243.792521) (xy 346.770901 -243.843451)
			(xy 346.778844 -243.896155) (xy 346.779342 -243.922804) (xy 346.778844 -243.949453) (xy 346.770901 -244.002157)
			(xy 346.755191 -244.053087) (xy 346.732065 -244.101108) (xy 346.702041 -244.145145) (xy 346.665789 -244.184216)
			(xy 346.624118 -244.217447) (xy 346.57796 -244.244096) (xy 346.528346 -244.263568) (xy 346.476384 -244.275428)
			(xy 346.423234 -244.279412) (xy 346.370084 -244.275428) (xy 346.318122 -244.263568) (xy 346.268508 -244.244096)
			(xy 346.22235 -244.217447) (xy 346.180679 -244.184216) (xy 346.144427 -244.145145) (xy 346.114403 -244.101108)
			(xy 346.091277 -244.053087) (xy 346.075567 -244.002157) (xy 346.067624 -243.949453) (xy 345.839044 -243.949453)
			(xy 345.831101 -244.002157) (xy 345.815391 -244.053087) (xy 345.792265 -244.101108) (xy 345.762241 -244.145145)
			(xy 345.725989 -244.184216) (xy 345.684318 -244.217447) (xy 345.63816 -244.244096) (xy 345.588546 -244.263568)
			(xy 345.536584 -244.275428) (xy 345.483434 -244.279412) (xy 345.430284 -244.275428) (xy 345.378322 -244.263568)
			(xy 345.328708 -244.244096) (xy 345.28255 -244.217447) (xy 345.240879 -244.184216) (xy 345.204627 -244.145145)
			(xy 345.174603 -244.101108) (xy 345.151477 -244.053087) (xy 345.135767 -244.002157) (xy 345.127824 -243.949453)
			(xy 344.899244 -243.949453) (xy 344.891301 -244.002157) (xy 344.875591 -244.053087) (xy 344.852465 -244.101108)
			(xy 344.822441 -244.145145) (xy 344.786189 -244.184216) (xy 344.744518 -244.217447) (xy 344.69836 -244.244096)
			(xy 344.648746 -244.263568) (xy 344.596784 -244.275428) (xy 344.543634 -244.279412) (xy 344.490484 -244.275428)
			(xy 344.438522 -244.263568) (xy 344.388908 -244.244096) (xy 344.34275 -244.217447) (xy 344.301079 -244.184216)
			(xy 344.264827 -244.145145) (xy 344.234803 -244.101108) (xy 344.211677 -244.053087) (xy 344.195967 -244.002157)
			(xy 344.188024 -243.949453) (xy 343.959444 -243.949453) (xy 343.951501 -244.002157) (xy 343.935791 -244.053087)
			(xy 343.912665 -244.101108) (xy 343.882641 -244.145145) (xy 343.846389 -244.184216) (xy 343.804718 -244.217447)
			(xy 343.75856 -244.244096) (xy 343.708946 -244.263568) (xy 343.656984 -244.275428) (xy 343.603834 -244.279412)
			(xy 343.550684 -244.275428) (xy 343.498722 -244.263568) (xy 343.449108 -244.244096) (xy 343.40295 -244.217447)
			(xy 343.361279 -244.184216) (xy 343.325027 -244.145145) (xy 343.295003 -244.101108) (xy 343.271877 -244.053087)
			(xy 343.256167 -244.002157) (xy 343.248224 -243.949453) (xy 343.01939 -243.949453) (xy 343.011447 -244.002157)
			(xy 342.995737 -244.053087) (xy 342.972611 -244.101108) (xy 342.942587 -244.145145) (xy 342.906335 -244.184216)
			(xy 342.864664 -244.217447) (xy 342.818506 -244.244096) (xy 342.768892 -244.263568) (xy 342.71693 -244.275428)
			(xy 342.66378 -244.279412) (xy 342.61063 -244.275428) (xy 342.558668 -244.263568) (xy 342.509054 -244.244096)
			(xy 342.462896 -244.217447) (xy 342.421225 -244.184216) (xy 342.384973 -244.145145) (xy 342.354949 -244.101108)
			(xy 342.331823 -244.053087) (xy 342.316113 -244.002157) (xy 342.30817 -243.949453) (xy 342.079844 -243.949453)
			(xy 342.071901 -244.002157) (xy 342.056191 -244.053087) (xy 342.033065 -244.101108) (xy 342.003041 -244.145145)
			(xy 341.966789 -244.184216) (xy 341.925118 -244.217447) (xy 341.87896 -244.244096) (xy 341.829346 -244.263568)
			(xy 341.777384 -244.275428) (xy 341.724234 -244.279412) (xy 341.671084 -244.275428) (xy 341.619122 -244.263568)
			(xy 341.569508 -244.244096) (xy 341.52335 -244.217447) (xy 341.481679 -244.184216) (xy 341.445427 -244.145145)
			(xy 341.415403 -244.101108) (xy 341.392277 -244.053087) (xy 341.376567 -244.002157) (xy 341.368624 -243.949453)
			(xy 341.140044 -243.949453) (xy 341.132101 -244.002157) (xy 341.116391 -244.053087) (xy 341.093265 -244.101108)
			(xy 341.063241 -244.145145) (xy 341.026989 -244.184216) (xy 340.985318 -244.217447) (xy 340.93916 -244.244096)
			(xy 340.889546 -244.263568) (xy 340.837584 -244.275428) (xy 340.784434 -244.279412) (xy 340.731284 -244.275428)
			(xy 340.679322 -244.263568) (xy 340.629708 -244.244096) (xy 340.58355 -244.217447) (xy 340.541879 -244.184216)
			(xy 340.505627 -244.145145) (xy 340.475603 -244.101108) (xy 340.452477 -244.053087) (xy 340.436767 -244.002157)
			(xy 340.428824 -243.949453) (xy 340.200244 -243.949453) (xy 340.192301 -244.002157) (xy 340.176591 -244.053087)
			(xy 340.153465 -244.101108) (xy 340.123441 -244.145145) (xy 340.087189 -244.184216) (xy 340.045518 -244.217447)
			(xy 339.99936 -244.244096) (xy 339.949746 -244.263568) (xy 339.897784 -244.275428) (xy 339.844634 -244.279412)
			(xy 339.791484 -244.275428) (xy 339.739522 -244.263568) (xy 339.689908 -244.244096) (xy 339.64375 -244.217447)
			(xy 339.602079 -244.184216) (xy 339.565827 -244.145145) (xy 339.535803 -244.101108) (xy 339.512677 -244.053087)
			(xy 339.496967 -244.002157) (xy 339.489024 -243.949453) (xy 339.260444 -243.949453) (xy 339.252501 -244.002157)
			(xy 339.236791 -244.053087) (xy 339.213665 -244.101108) (xy 339.183641 -244.145145) (xy 339.147389 -244.184216)
			(xy 339.105718 -244.217447) (xy 339.05956 -244.244096) (xy 339.009946 -244.263568) (xy 338.957984 -244.275428)
			(xy 338.904834 -244.279412) (xy 338.851684 -244.275428) (xy 338.799722 -244.263568) (xy 338.750108 -244.244096)
			(xy 338.70395 -244.217447) (xy 338.662279 -244.184216) (xy 338.626027 -244.145145) (xy 338.596003 -244.101108)
			(xy 338.572877 -244.053087) (xy 338.557167 -244.002157) (xy 338.549224 -243.949453) (xy 338.320644 -243.949453)
			(xy 338.312701 -244.002157) (xy 338.296991 -244.053087) (xy 338.273865 -244.101108) (xy 338.243841 -244.145145)
			(xy 338.207589 -244.184216) (xy 338.165918 -244.217447) (xy 338.11976 -244.244096) (xy 338.070146 -244.263568)
			(xy 338.018184 -244.275428) (xy 337.965034 -244.279412) (xy 337.911884 -244.275428) (xy 337.859922 -244.263568)
			(xy 337.810308 -244.244096) (xy 337.76415 -244.217447) (xy 337.722479 -244.184216) (xy 337.686227 -244.145145)
			(xy 337.656203 -244.101108) (xy 337.633077 -244.053087) (xy 337.617367 -244.002157) (xy 337.609424 -243.949453)
			(xy 337.379807 -243.949453) (xy 337.377821 -243.975946) (xy 337.365963 -244.027905) (xy 337.346493 -244.077516)
			(xy 337.319847 -244.123671) (xy 337.28662 -244.16534) (xy 337.247554 -244.201592) (xy 337.203521 -244.231616)
			(xy 337.155506 -244.254743) (xy 337.10458 -244.270456) (xy 337.051881 -244.278404) (xy 337.025234 -244.278912)
			(xy 337.000539 -244.278513) (xy 336.951617 -244.271728) (xy 336.904104 -244.258242) (xy 336.858913 -244.238314)
			(xy 336.816913 -244.212328) (xy 336.79765 -244.19687) (xy 336.786266 -244.18809) (xy 336.7599 -244.176663)
			(xy 336.731393 -244.173039) (xy 336.703006 -244.177503) (xy 336.676988 -244.189703) (xy 336.655402 -244.208671)
			(xy 336.639958 -244.232904) (xy 336.63188 -244.260481) (xy 336.63128 -244.274848) (xy 336.63128 -244.386862)
			(xy 336.666332 -244.398292) (xy 336.691136 -244.406941) (xy 336.738086 -244.430501) (xy 336.781066 -244.460701)
			(xy 336.819144 -244.496888) (xy 336.851492 -244.538276) (xy 336.87741 -244.583966) (xy 336.896335 -244.632969)
			(xy 336.907856 -244.684219) (xy 336.911724 -244.736606) (xy 336.909755 -244.763269) (xy 337.13927 -244.763269)
			(xy 337.13927 -244.709971) (xy 337.147213 -244.657267) (xy 337.162923 -244.606337) (xy 337.186049 -244.558316)
			(xy 337.216073 -244.514279) (xy 337.252325 -244.475208) (xy 337.293996 -244.441977) (xy 337.340154 -244.415328)
			(xy 337.389768 -244.395856) (xy 337.44173 -244.383996) (xy 337.49488 -244.380013) (xy 337.54803 -244.383996)
			(xy 337.599992 -244.395856) (xy 337.649606 -244.415328) (xy 337.695764 -244.441977) (xy 337.737435 -244.475208)
			(xy 337.773687 -244.514279) (xy 337.803711 -244.558316) (xy 337.826837 -244.606337) (xy 337.842547 -244.657267)
			(xy 337.85049 -244.709971) (xy 337.850988 -244.73662) (xy 337.85049 -244.763269) (xy 338.079324 -244.763269)
			(xy 338.079324 -244.709971) (xy 338.087267 -244.657267) (xy 338.102977 -244.606337) (xy 338.126103 -244.558316)
			(xy 338.156127 -244.514279) (xy 338.192379 -244.475208) (xy 338.23405 -244.441977) (xy 338.280208 -244.415328)
			(xy 338.329822 -244.395856) (xy 338.381784 -244.383996) (xy 338.434934 -244.380013) (xy 338.488084 -244.383996)
			(xy 338.540046 -244.395856) (xy 338.58966 -244.415328) (xy 338.635818 -244.441977) (xy 338.677489 -244.475208)
			(xy 338.713741 -244.514279) (xy 338.743765 -244.558316) (xy 338.766891 -244.606337) (xy 338.782601 -244.657267)
			(xy 338.790544 -244.709971) (xy 338.791042 -244.73662) (xy 338.790544 -244.763269) (xy 339.01887 -244.763269)
			(xy 339.01887 -244.709971) (xy 339.026813 -244.657267) (xy 339.042523 -244.606337) (xy 339.065649 -244.558316)
			(xy 339.095673 -244.514279) (xy 339.131925 -244.475208) (xy 339.173596 -244.441977) (xy 339.219754 -244.415328)
			(xy 339.269368 -244.395856) (xy 339.32133 -244.383996) (xy 339.37448 -244.380013) (xy 339.42763 -244.383996)
			(xy 339.479592 -244.395856) (xy 339.529206 -244.415328) (xy 339.575364 -244.441977) (xy 339.617035 -244.475208)
			(xy 339.653287 -244.514279) (xy 339.683311 -244.558316) (xy 339.706437 -244.606337) (xy 339.722147 -244.657267)
			(xy 339.73009 -244.709971) (xy 339.730588 -244.73662) (xy 339.73009 -244.763269) (xy 339.958924 -244.763269)
			(xy 339.958924 -244.709971) (xy 339.966867 -244.657267) (xy 339.982577 -244.606337) (xy 340.005703 -244.558316)
			(xy 340.035727 -244.514279) (xy 340.071979 -244.475208) (xy 340.11365 -244.441977) (xy 340.159808 -244.415328)
			(xy 340.209422 -244.395856) (xy 340.261384 -244.383996) (xy 340.314534 -244.380013) (xy 340.367684 -244.383996)
			(xy 340.419646 -244.395856) (xy 340.46926 -244.415328) (xy 340.515418 -244.441977) (xy 340.557089 -244.475208)
			(xy 340.593341 -244.514279) (xy 340.623365 -244.558316) (xy 340.646491 -244.606337) (xy 340.662201 -244.657267)
			(xy 340.670144 -244.709971) (xy 340.670642 -244.73662) (xy 340.670144 -244.763269) (xy 340.89847 -244.763269)
			(xy 340.89847 -244.709971) (xy 340.906413 -244.657267) (xy 340.922123 -244.606337) (xy 340.945249 -244.558316)
			(xy 340.975273 -244.514279) (xy 341.011525 -244.475208) (xy 341.053196 -244.441977) (xy 341.099354 -244.415328)
			(xy 341.148968 -244.395856) (xy 341.20093 -244.383996) (xy 341.25408 -244.380013) (xy 341.30723 -244.383996)
			(xy 341.359192 -244.395856) (xy 341.408806 -244.415328) (xy 341.454964 -244.441977) (xy 341.496635 -244.475208)
			(xy 341.532887 -244.514279) (xy 341.562911 -244.558316) (xy 341.586037 -244.606337) (xy 341.601747 -244.657267)
			(xy 341.60969 -244.709971) (xy 341.610188 -244.73662) (xy 341.60969 -244.763269) (xy 341.83827 -244.763269)
			(xy 341.83827 -244.709971) (xy 341.846213 -244.657267) (xy 341.861923 -244.606337) (xy 341.885049 -244.558316)
			(xy 341.915073 -244.514279) (xy 341.951325 -244.475208) (xy 341.992996 -244.441977) (xy 342.039154 -244.415328)
			(xy 342.088768 -244.395856) (xy 342.14073 -244.383996) (xy 342.19388 -244.380013) (xy 342.24703 -244.383996)
			(xy 342.298992 -244.395856) (xy 342.348606 -244.415328) (xy 342.394764 -244.441977) (xy 342.436435 -244.475208)
			(xy 342.472687 -244.514279) (xy 342.502711 -244.558316) (xy 342.525837 -244.606337) (xy 342.541547 -244.657267)
			(xy 342.54949 -244.709971) (xy 342.549988 -244.73662) (xy 342.54949 -244.763269) (xy 342.77807 -244.763269)
			(xy 342.77807 -244.709971) (xy 342.786013 -244.657267) (xy 342.801723 -244.606337) (xy 342.824849 -244.558316)
			(xy 342.854873 -244.514279) (xy 342.891125 -244.475208) (xy 342.932796 -244.441977) (xy 342.978954 -244.415328)
			(xy 343.028568 -244.395856) (xy 343.08053 -244.383996) (xy 343.13368 -244.380013) (xy 343.18683 -244.383996)
			(xy 343.238792 -244.395856) (xy 343.288406 -244.415328) (xy 343.334564 -244.441977) (xy 343.376235 -244.475208)
			(xy 343.412487 -244.514279) (xy 343.442511 -244.558316) (xy 343.465637 -244.606337) (xy 343.481347 -244.657267)
			(xy 343.48929 -244.709971) (xy 343.489788 -244.73662) (xy 343.48929 -244.763269) (xy 343.71787 -244.763269)
			(xy 343.71787 -244.709971) (xy 343.725813 -244.657267) (xy 343.741523 -244.606337) (xy 343.764649 -244.558316)
			(xy 343.794673 -244.514279) (xy 343.830925 -244.475208) (xy 343.872596 -244.441977) (xy 343.918754 -244.415328)
			(xy 343.968368 -244.395856) (xy 344.02033 -244.383996) (xy 344.07348 -244.380013) (xy 344.12663 -244.383996)
			(xy 344.178592 -244.395856) (xy 344.228206 -244.415328) (xy 344.274364 -244.441977) (xy 344.316035 -244.475208)
			(xy 344.352287 -244.514279) (xy 344.382311 -244.558316) (xy 344.405437 -244.606337) (xy 344.421147 -244.657267)
			(xy 344.42909 -244.709971) (xy 344.429588 -244.73662) (xy 344.42909 -244.763269) (xy 344.657924 -244.763269)
			(xy 344.657924 -244.709971) (xy 344.665867 -244.657267) (xy 344.681577 -244.606337) (xy 344.704703 -244.558316)
			(xy 344.734727 -244.514279) (xy 344.770979 -244.475208) (xy 344.81265 -244.441977) (xy 344.858808 -244.415328)
			(xy 344.908422 -244.395856) (xy 344.960384 -244.383996) (xy 345.013534 -244.380013) (xy 345.066684 -244.383996)
			(xy 345.118646 -244.395856) (xy 345.16826 -244.415328) (xy 345.214418 -244.441977) (xy 345.256089 -244.475208)
			(xy 345.292341 -244.514279) (xy 345.322365 -244.558316) (xy 345.345491 -244.606337) (xy 345.361201 -244.657267)
			(xy 345.369144 -244.709971) (xy 345.369642 -244.73662) (xy 345.369144 -244.763269) (xy 345.59747 -244.763269)
			(xy 345.59747 -244.709971) (xy 345.605413 -244.657267) (xy 345.621123 -244.606337) (xy 345.644249 -244.558316)
			(xy 345.674273 -244.514279) (xy 345.710525 -244.475208) (xy 345.752196 -244.441977) (xy 345.798354 -244.415328)
			(xy 345.847968 -244.395856) (xy 345.89993 -244.383996) (xy 345.95308 -244.380013) (xy 346.00623 -244.383996)
			(xy 346.058192 -244.395856) (xy 346.107806 -244.415328) (xy 346.153964 -244.441977) (xy 346.195635 -244.475208)
			(xy 346.231887 -244.514279) (xy 346.261911 -244.558316) (xy 346.285037 -244.606337) (xy 346.300747 -244.657267)
			(xy 346.30869 -244.709971) (xy 346.309188 -244.73662) (xy 346.30869 -244.763269) (xy 346.300747 -244.815973)
			(xy 346.285037 -244.866903) (xy 346.261911 -244.914924) (xy 346.231887 -244.958961) (xy 346.195635 -244.998032)
			(xy 346.153964 -245.031263) (xy 346.107806 -245.057912) (xy 346.058192 -245.077384) (xy 346.00623 -245.089244)
			(xy 345.95308 -245.093228) (xy 345.89993 -245.089244) (xy 345.847968 -245.077384) (xy 345.798354 -245.057912)
			(xy 345.752196 -245.031263) (xy 345.710525 -244.998032) (xy 345.674273 -244.958961) (xy 345.644249 -244.914924)
			(xy 345.621123 -244.866903) (xy 345.605413 -244.815973) (xy 345.59747 -244.763269) (xy 345.369144 -244.763269)
			(xy 345.361201 -244.815973) (xy 345.345491 -244.866903) (xy 345.322365 -244.914924) (xy 345.292341 -244.958961)
			(xy 345.256089 -244.998032) (xy 345.214418 -245.031263) (xy 345.16826 -245.057912) (xy 345.118646 -245.077384)
			(xy 345.066684 -245.089244) (xy 345.013534 -245.093228) (xy 344.960384 -245.089244) (xy 344.908422 -245.077384)
			(xy 344.858808 -245.057912) (xy 344.81265 -245.031263) (xy 344.770979 -244.998032) (xy 344.734727 -244.958961)
			(xy 344.704703 -244.914924) (xy 344.681577 -244.866903) (xy 344.665867 -244.815973) (xy 344.657924 -244.763269)
			(xy 344.42909 -244.763269) (xy 344.421147 -244.815973) (xy 344.405437 -244.866903) (xy 344.382311 -244.914924)
			(xy 344.352287 -244.958961) (xy 344.316035 -244.998032) (xy 344.274364 -245.031263) (xy 344.228206 -245.057912)
			(xy 344.178592 -245.077384) (xy 344.12663 -245.089244) (xy 344.07348 -245.093228) (xy 344.02033 -245.089244)
			(xy 343.968368 -245.077384) (xy 343.918754 -245.057912) (xy 343.872596 -245.031263) (xy 343.830925 -244.998032)
			(xy 343.794673 -244.958961) (xy 343.764649 -244.914924) (xy 343.741523 -244.866903) (xy 343.725813 -244.815973)
			(xy 343.71787 -244.763269) (xy 343.48929 -244.763269) (xy 343.481347 -244.815973) (xy 343.465637 -244.866903)
			(xy 343.442511 -244.914924) (xy 343.412487 -244.958961) (xy 343.376235 -244.998032) (xy 343.334564 -245.031263)
			(xy 343.288406 -245.057912) (xy 343.238792 -245.077384) (xy 343.18683 -245.089244) (xy 343.13368 -245.093228)
			(xy 343.08053 -245.089244) (xy 343.028568 -245.077384) (xy 342.978954 -245.057912) (xy 342.932796 -245.031263)
			(xy 342.891125 -244.998032) (xy 342.854873 -244.958961) (xy 342.824849 -244.914924) (xy 342.801723 -244.866903)
			(xy 342.786013 -244.815973) (xy 342.77807 -244.763269) (xy 342.54949 -244.763269) (xy 342.541547 -244.815973)
			(xy 342.525837 -244.866903) (xy 342.502711 -244.914924) (xy 342.472687 -244.958961) (xy 342.436435 -244.998032)
			(xy 342.394764 -245.031263) (xy 342.348606 -245.057912) (xy 342.298992 -245.077384) (xy 342.24703 -245.089244)
			(xy 342.19388 -245.093228) (xy 342.14073 -245.089244) (xy 342.088768 -245.077384) (xy 342.039154 -245.057912)
			(xy 341.992996 -245.031263) (xy 341.951325 -244.998032) (xy 341.915073 -244.958961) (xy 341.885049 -244.914924)
			(xy 341.861923 -244.866903) (xy 341.846213 -244.815973) (xy 341.83827 -244.763269) (xy 341.60969 -244.763269)
			(xy 341.601747 -244.815973) (xy 341.586037 -244.866903) (xy 341.562911 -244.914924) (xy 341.532887 -244.958961)
			(xy 341.496635 -244.998032) (xy 341.454964 -245.031263) (xy 341.408806 -245.057912) (xy 341.359192 -245.077384)
			(xy 341.30723 -245.089244) (xy 341.25408 -245.093228) (xy 341.20093 -245.089244) (xy 341.148968 -245.077384)
			(xy 341.099354 -245.057912) (xy 341.053196 -245.031263) (xy 341.011525 -244.998032) (xy 340.975273 -244.958961)
			(xy 340.945249 -244.914924) (xy 340.922123 -244.866903) (xy 340.906413 -244.815973) (xy 340.89847 -244.763269)
			(xy 340.670144 -244.763269) (xy 340.662201 -244.815973) (xy 340.646491 -244.866903) (xy 340.623365 -244.914924)
			(xy 340.593341 -244.958961) (xy 340.557089 -244.998032) (xy 340.515418 -245.031263) (xy 340.46926 -245.057912)
			(xy 340.419646 -245.077384) (xy 340.367684 -245.089244) (xy 340.314534 -245.093228) (xy 340.261384 -245.089244)
			(xy 340.209422 -245.077384) (xy 340.159808 -245.057912) (xy 340.11365 -245.031263) (xy 340.071979 -244.998032)
			(xy 340.035727 -244.958961) (xy 340.005703 -244.914924) (xy 339.982577 -244.866903) (xy 339.966867 -244.815973)
			(xy 339.958924 -244.763269) (xy 339.73009 -244.763269) (xy 339.722147 -244.815973) (xy 339.706437 -244.866903)
			(xy 339.683311 -244.914924) (xy 339.653287 -244.958961) (xy 339.617035 -244.998032) (xy 339.575364 -245.031263)
			(xy 339.529206 -245.057912) (xy 339.479592 -245.077384) (xy 339.42763 -245.089244) (xy 339.37448 -245.093228)
			(xy 339.32133 -245.089244) (xy 339.269368 -245.077384) (xy 339.219754 -245.057912) (xy 339.173596 -245.031263)
			(xy 339.131925 -244.998032) (xy 339.095673 -244.958961) (xy 339.065649 -244.914924) (xy 339.042523 -244.866903)
			(xy 339.026813 -244.815973) (xy 339.01887 -244.763269) (xy 338.790544 -244.763269) (xy 338.782601 -244.815973)
			(xy 338.766891 -244.866903) (xy 338.743765 -244.914924) (xy 338.713741 -244.958961) (xy 338.677489 -244.998032)
			(xy 338.635818 -245.031263) (xy 338.58966 -245.057912) (xy 338.540046 -245.077384) (xy 338.488084 -245.089244)
			(xy 338.434934 -245.093228) (xy 338.381784 -245.089244) (xy 338.329822 -245.077384) (xy 338.280208 -245.057912)
			(xy 338.23405 -245.031263) (xy 338.192379 -244.998032) (xy 338.156127 -244.958961) (xy 338.126103 -244.914924)
			(xy 338.102977 -244.866903) (xy 338.087267 -244.815973) (xy 338.079324 -244.763269) (xy 337.85049 -244.763269)
			(xy 337.842547 -244.815973) (xy 337.826837 -244.866903) (xy 337.803711 -244.914924) (xy 337.773687 -244.958961)
			(xy 337.737435 -244.998032) (xy 337.695764 -245.031263) (xy 337.649606 -245.057912) (xy 337.599992 -245.077384)
			(xy 337.54803 -245.089244) (xy 337.49488 -245.093228) (xy 337.44173 -245.089244) (xy 337.389768 -245.077384)
			(xy 337.340154 -245.057912) (xy 337.293996 -245.031263) (xy 337.252325 -244.998032) (xy 337.216073 -244.958961)
			(xy 337.186049 -244.914924) (xy 337.162923 -244.866903) (xy 337.147213 -244.815973) (xy 337.13927 -244.763269)
			(xy 336.909755 -244.763269) (xy 336.907855 -244.788993) (xy 336.896331 -244.840243) (xy 336.877405 -244.889245)
			(xy 336.851485 -244.934935) (xy 336.819135 -244.976321) (xy 336.781057 -245.012507) (xy 336.738076 -245.042706)
			(xy 336.691125 -245.066264) (xy 336.666332 -245.074948) (xy 336.63128 -245.086378) (xy 336.63128 -245.198646)
			(xy 336.63181 -245.213014) (xy 336.639889 -245.240593) (xy 336.655339 -245.264826) (xy 336.676932 -245.283789)
			(xy 336.702956 -245.295981) (xy 336.731348 -245.300432) (xy 336.759854 -245.296791) (xy 336.786215 -245.285345)
			(xy 336.79765 -245.276624) (xy 336.816926 -245.261185) (xy 336.85893 -245.235212) (xy 336.904119 -245.215289)
			(xy 336.951626 -245.201797) (xy 337.000541 -245.194996) (xy 337.025234 -245.194582) (xy 337.051882 -245.195082)
			(xy 337.104583 -245.20303) (xy 337.155511 -245.218744) (xy 337.203528 -245.241872) (xy 337.247563 -245.271897)
			(xy 337.28663 -245.30815) (xy 337.319859 -245.349821) (xy 337.346505 -245.395978) (xy 337.365976 -245.445591)
			(xy 337.377835 -245.497552) (xy 337.381818 -245.5507) (xy 337.379822 -245.577339) (xy 337.609424 -245.577339)
			(xy 337.609424 -245.524041) (xy 337.617367 -245.471337) (xy 337.633077 -245.420407) (xy 337.656203 -245.372386)
			(xy 337.686227 -245.328349) (xy 337.722479 -245.289278) (xy 337.76415 -245.256047) (xy 337.810308 -245.229398)
			(xy 337.859922 -245.209926) (xy 337.911884 -245.198066) (xy 337.965034 -245.194083) (xy 338.018184 -245.198066)
			(xy 338.070146 -245.209926) (xy 338.11976 -245.229398) (xy 338.165918 -245.256047) (xy 338.207589 -245.289278)
			(xy 338.243841 -245.328349) (xy 338.273865 -245.372386) (xy 338.296991 -245.420407) (xy 338.312701 -245.471337)
			(xy 338.320644 -245.524041) (xy 338.321142 -245.55069) (xy 338.320644 -245.577339) (xy 338.54897 -245.577339)
			(xy 338.54897 -245.524041) (xy 338.556913 -245.471337) (xy 338.572623 -245.420407) (xy 338.595749 -245.372386)
			(xy 338.625773 -245.328349) (xy 338.662025 -245.289278) (xy 338.703696 -245.256047) (xy 338.749854 -245.229398)
			(xy 338.799468 -245.209926) (xy 338.85143 -245.198066) (xy 338.90458 -245.194083) (xy 338.95773 -245.198066)
			(xy 339.009692 -245.209926) (xy 339.059306 -245.229398) (xy 339.105464 -245.256047) (xy 339.147135 -245.289278)
			(xy 339.183387 -245.328349) (xy 339.213411 -245.372386) (xy 339.236537 -245.420407) (xy 339.252247 -245.471337)
			(xy 339.26019 -245.524041) (xy 339.260688 -245.55069) (xy 339.26019 -245.577339) (xy 339.489024 -245.577339)
			(xy 339.489024 -245.524041) (xy 339.496967 -245.471337) (xy 339.512677 -245.420407) (xy 339.535803 -245.372386)
			(xy 339.565827 -245.328349) (xy 339.602079 -245.289278) (xy 339.64375 -245.256047) (xy 339.689908 -245.229398)
			(xy 339.739522 -245.209926) (xy 339.791484 -245.198066) (xy 339.844634 -245.194083) (xy 339.897784 -245.198066)
			(xy 339.949746 -245.209926) (xy 339.99936 -245.229398) (xy 340.045518 -245.256047) (xy 340.087189 -245.289278)
			(xy 340.123441 -245.328349) (xy 340.153465 -245.372386) (xy 340.176591 -245.420407) (xy 340.192301 -245.471337)
			(xy 340.200244 -245.524041) (xy 340.200742 -245.55069) (xy 340.200244 -245.577339) (xy 340.42857 -245.577339)
			(xy 340.42857 -245.524041) (xy 340.436513 -245.471337) (xy 340.452223 -245.420407) (xy 340.475349 -245.372386)
			(xy 340.505373 -245.328349) (xy 340.541625 -245.289278) (xy 340.583296 -245.256047) (xy 340.629454 -245.229398)
			(xy 340.679068 -245.209926) (xy 340.73103 -245.198066) (xy 340.78418 -245.194083) (xy 340.83733 -245.198066)
			(xy 340.889292 -245.209926) (xy 340.938906 -245.229398) (xy 340.985064 -245.256047) (xy 341.026735 -245.289278)
			(xy 341.062987 -245.328349) (xy 341.093011 -245.372386) (xy 341.116137 -245.420407) (xy 341.131847 -245.471337)
			(xy 341.13979 -245.524041) (xy 341.140288 -245.55069) (xy 341.13979 -245.577339) (xy 341.368624 -245.577339)
			(xy 341.368624 -245.524041) (xy 341.376567 -245.471337) (xy 341.392277 -245.420407) (xy 341.415403 -245.372386)
			(xy 341.445427 -245.328349) (xy 341.481679 -245.289278) (xy 341.52335 -245.256047) (xy 341.569508 -245.229398)
			(xy 341.619122 -245.209926) (xy 341.671084 -245.198066) (xy 341.724234 -245.194083) (xy 341.777384 -245.198066)
			(xy 341.829346 -245.209926) (xy 341.87896 -245.229398) (xy 341.925118 -245.256047) (xy 341.966789 -245.289278)
			(xy 342.003041 -245.328349) (xy 342.033065 -245.372386) (xy 342.056191 -245.420407) (xy 342.071901 -245.471337)
			(xy 342.079844 -245.524041) (xy 342.080342 -245.55069) (xy 342.079844 -245.577339) (xy 342.308424 -245.577339)
			(xy 342.308424 -245.524041) (xy 342.316367 -245.471337) (xy 342.332077 -245.420407) (xy 342.355203 -245.372386)
			(xy 342.385227 -245.328349) (xy 342.421479 -245.289278) (xy 342.46315 -245.256047) (xy 342.509308 -245.229398)
			(xy 342.558922 -245.209926) (xy 342.610884 -245.198066) (xy 342.664034 -245.194083) (xy 342.717184 -245.198066)
			(xy 342.769146 -245.209926) (xy 342.81876 -245.229398) (xy 342.864918 -245.256047) (xy 342.906589 -245.289278)
			(xy 342.942841 -245.328349) (xy 342.972865 -245.372386) (xy 342.995991 -245.420407) (xy 343.011701 -245.471337)
			(xy 343.019644 -245.524041) (xy 343.020142 -245.55069) (xy 343.019644 -245.577339) (xy 343.248224 -245.577339)
			(xy 343.248224 -245.524041) (xy 343.256167 -245.471337) (xy 343.271877 -245.420407) (xy 343.295003 -245.372386)
			(xy 343.325027 -245.328349) (xy 343.361279 -245.289278) (xy 343.40295 -245.256047) (xy 343.449108 -245.229398)
			(xy 343.498722 -245.209926) (xy 343.550684 -245.198066) (xy 343.603834 -245.194083) (xy 343.656984 -245.198066)
			(xy 343.708946 -245.209926) (xy 343.75856 -245.229398) (xy 343.804718 -245.256047) (xy 343.846389 -245.289278)
			(xy 343.882641 -245.328349) (xy 343.912665 -245.372386) (xy 343.935791 -245.420407) (xy 343.951501 -245.471337)
			(xy 343.959444 -245.524041) (xy 343.959942 -245.55069) (xy 343.959444 -245.577339) (xy 344.188024 -245.577339)
			(xy 344.188024 -245.524041) (xy 344.195967 -245.471337) (xy 344.211677 -245.420407) (xy 344.234803 -245.372386)
			(xy 344.264827 -245.328349) (xy 344.301079 -245.289278) (xy 344.34275 -245.256047) (xy 344.388908 -245.229398)
			(xy 344.438522 -245.209926) (xy 344.490484 -245.198066) (xy 344.543634 -245.194083) (xy 344.596784 -245.198066)
			(xy 344.648746 -245.209926) (xy 344.69836 -245.229398) (xy 344.744518 -245.256047) (xy 344.786189 -245.289278)
			(xy 344.822441 -245.328349) (xy 344.852465 -245.372386) (xy 344.875591 -245.420407) (xy 344.891301 -245.471337)
			(xy 344.899244 -245.524041) (xy 344.899742 -245.55069) (xy 344.899244 -245.577339) (xy 345.12757 -245.577339)
			(xy 345.12757 -245.524041) (xy 345.135513 -245.471337) (xy 345.151223 -245.420407) (xy 345.174349 -245.372386)
			(xy 345.204373 -245.328349) (xy 345.240625 -245.289278) (xy 345.282296 -245.256047) (xy 345.328454 -245.229398)
			(xy 345.378068 -245.209926) (xy 345.43003 -245.198066) (xy 345.48318 -245.194083) (xy 345.53633 -245.198066)
			(xy 345.588292 -245.209926) (xy 345.637906 -245.229398) (xy 345.684064 -245.256047) (xy 345.725735 -245.289278)
			(xy 345.761987 -245.328349) (xy 345.792011 -245.372386) (xy 345.815137 -245.420407) (xy 345.830847 -245.471337)
			(xy 345.83879 -245.524041) (xy 345.839288 -245.55069) (xy 345.83879 -245.577339) (xy 346.067624 -245.577339)
			(xy 346.067624 -245.524041) (xy 346.075567 -245.471337) (xy 346.091277 -245.420407) (xy 346.114403 -245.372386)
			(xy 346.144427 -245.328349) (xy 346.180679 -245.289278) (xy 346.22235 -245.256047) (xy 346.268508 -245.229398)
			(xy 346.318122 -245.209926) (xy 346.370084 -245.198066) (xy 346.423234 -245.194083) (xy 346.476384 -245.198066)
			(xy 346.528346 -245.209926) (xy 346.57796 -245.229398) (xy 346.624118 -245.256047) (xy 346.665789 -245.289278)
			(xy 346.702041 -245.328349) (xy 346.732065 -245.372386) (xy 346.755191 -245.420407) (xy 346.770901 -245.471337)
			(xy 346.778844 -245.524041) (xy 346.779342 -245.55069) (xy 346.778844 -245.577339) (xy 346.770901 -245.630043)
			(xy 346.755191 -245.680973) (xy 346.732065 -245.728994) (xy 346.702041 -245.773031) (xy 346.665789 -245.812102)
			(xy 346.624118 -245.845333) (xy 346.57796 -245.871982) (xy 346.528346 -245.891454) (xy 346.476384 -245.903314)
			(xy 346.423234 -245.907298) (xy 346.370084 -245.903314) (xy 346.318122 -245.891454) (xy 346.268508 -245.871982)
			(xy 346.22235 -245.845333) (xy 346.180679 -245.812102) (xy 346.144427 -245.773031) (xy 346.114403 -245.728994)
			(xy 346.091277 -245.680973) (xy 346.075567 -245.630043) (xy 346.067624 -245.577339) (xy 345.83879 -245.577339)
			(xy 345.830847 -245.630043) (xy 345.815137 -245.680973) (xy 345.792011 -245.728994) (xy 345.761987 -245.773031)
			(xy 345.725735 -245.812102) (xy 345.684064 -245.845333) (xy 345.637906 -245.871982) (xy 345.588292 -245.891454)
			(xy 345.53633 -245.903314) (xy 345.48318 -245.907298) (xy 345.43003 -245.903314) (xy 345.378068 -245.891454)
			(xy 345.328454 -245.871982) (xy 345.282296 -245.845333) (xy 345.240625 -245.812102) (xy 345.204373 -245.773031)
			(xy 345.174349 -245.728994) (xy 345.151223 -245.680973) (xy 345.135513 -245.630043) (xy 345.12757 -245.577339)
			(xy 344.899244 -245.577339) (xy 344.891301 -245.630043) (xy 344.875591 -245.680973) (xy 344.852465 -245.728994)
			(xy 344.822441 -245.773031) (xy 344.786189 -245.812102) (xy 344.744518 -245.845333) (xy 344.69836 -245.871982)
			(xy 344.648746 -245.891454) (xy 344.596784 -245.903314) (xy 344.543634 -245.907298) (xy 344.490484 -245.903314)
			(xy 344.438522 -245.891454) (xy 344.388908 -245.871982) (xy 344.34275 -245.845333) (xy 344.301079 -245.812102)
			(xy 344.264827 -245.773031) (xy 344.234803 -245.728994) (xy 344.211677 -245.680973) (xy 344.195967 -245.630043)
			(xy 344.188024 -245.577339) (xy 343.959444 -245.577339) (xy 343.951501 -245.630043) (xy 343.935791 -245.680973)
			(xy 343.912665 -245.728994) (xy 343.882641 -245.773031) (xy 343.846389 -245.812102) (xy 343.804718 -245.845333)
			(xy 343.75856 -245.871982) (xy 343.708946 -245.891454) (xy 343.656984 -245.903314) (xy 343.603834 -245.907298)
			(xy 343.550684 -245.903314) (xy 343.498722 -245.891454) (xy 343.449108 -245.871982) (xy 343.40295 -245.845333)
			(xy 343.361279 -245.812102) (xy 343.325027 -245.773031) (xy 343.295003 -245.728994) (xy 343.271877 -245.680973)
			(xy 343.256167 -245.630043) (xy 343.248224 -245.577339) (xy 343.019644 -245.577339) (xy 343.011701 -245.630043)
			(xy 342.995991 -245.680973) (xy 342.972865 -245.728994) (xy 342.942841 -245.773031) (xy 342.906589 -245.812102)
			(xy 342.864918 -245.845333) (xy 342.81876 -245.871982) (xy 342.769146 -245.891454) (xy 342.717184 -245.903314)
			(xy 342.664034 -245.907298) (xy 342.610884 -245.903314) (xy 342.558922 -245.891454) (xy 342.509308 -245.871982)
			(xy 342.46315 -245.845333) (xy 342.421479 -245.812102) (xy 342.385227 -245.773031) (xy 342.355203 -245.728994)
			(xy 342.332077 -245.680973) (xy 342.316367 -245.630043) (xy 342.308424 -245.577339) (xy 342.079844 -245.577339)
			(xy 342.071901 -245.630043) (xy 342.056191 -245.680973) (xy 342.033065 -245.728994) (xy 342.003041 -245.773031)
			(xy 341.966789 -245.812102) (xy 341.925118 -245.845333) (xy 341.87896 -245.871982) (xy 341.829346 -245.891454)
			(xy 341.777384 -245.903314) (xy 341.724234 -245.907298) (xy 341.671084 -245.903314) (xy 341.619122 -245.891454)
			(xy 341.569508 -245.871982) (xy 341.52335 -245.845333) (xy 341.481679 -245.812102) (xy 341.445427 -245.773031)
			(xy 341.415403 -245.728994) (xy 341.392277 -245.680973) (xy 341.376567 -245.630043) (xy 341.368624 -245.577339)
			(xy 341.13979 -245.577339) (xy 341.131847 -245.630043) (xy 341.116137 -245.680973) (xy 341.093011 -245.728994)
			(xy 341.062987 -245.773031) (xy 341.026735 -245.812102) (xy 340.985064 -245.845333) (xy 340.938906 -245.871982)
			(xy 340.889292 -245.891454) (xy 340.83733 -245.903314) (xy 340.78418 -245.907298) (xy 340.73103 -245.903314)
			(xy 340.679068 -245.891454) (xy 340.629454 -245.871982) (xy 340.583296 -245.845333) (xy 340.541625 -245.812102)
			(xy 340.505373 -245.773031) (xy 340.475349 -245.728994) (xy 340.452223 -245.680973) (xy 340.436513 -245.630043)
			(xy 340.42857 -245.577339) (xy 340.200244 -245.577339) (xy 340.192301 -245.630043) (xy 340.176591 -245.680973)
			(xy 340.153465 -245.728994) (xy 340.123441 -245.773031) (xy 340.087189 -245.812102) (xy 340.045518 -245.845333)
			(xy 339.99936 -245.871982) (xy 339.949746 -245.891454) (xy 339.897784 -245.903314) (xy 339.844634 -245.907298)
			(xy 339.791484 -245.903314) (xy 339.739522 -245.891454) (xy 339.689908 -245.871982) (xy 339.64375 -245.845333)
			(xy 339.602079 -245.812102) (xy 339.565827 -245.773031) (xy 339.535803 -245.728994) (xy 339.512677 -245.680973)
			(xy 339.496967 -245.630043) (xy 339.489024 -245.577339) (xy 339.26019 -245.577339) (xy 339.252247 -245.630043)
			(xy 339.236537 -245.680973) (xy 339.213411 -245.728994) (xy 339.183387 -245.773031) (xy 339.147135 -245.812102)
			(xy 339.105464 -245.845333) (xy 339.059306 -245.871982) (xy 339.009692 -245.891454) (xy 338.95773 -245.903314)
			(xy 338.90458 -245.907298) (xy 338.85143 -245.903314) (xy 338.799468 -245.891454) (xy 338.749854 -245.871982)
			(xy 338.703696 -245.845333) (xy 338.662025 -245.812102) (xy 338.625773 -245.773031) (xy 338.595749 -245.728994)
			(xy 338.572623 -245.680973) (xy 338.556913 -245.630043) (xy 338.54897 -245.577339) (xy 338.320644 -245.577339)
			(xy 338.312701 -245.630043) (xy 338.296991 -245.680973) (xy 338.273865 -245.728994) (xy 338.243841 -245.773031)
			(xy 338.207589 -245.812102) (xy 338.165918 -245.845333) (xy 338.11976 -245.871982) (xy 338.070146 -245.891454)
			(xy 338.018184 -245.903314) (xy 337.965034 -245.907298) (xy 337.911884 -245.903314) (xy 337.859922 -245.891454)
			(xy 337.810308 -245.871982) (xy 337.76415 -245.845333) (xy 337.722479 -245.812102) (xy 337.686227 -245.773031)
			(xy 337.656203 -245.728994) (xy 337.633077 -245.680973) (xy 337.617367 -245.630043) (xy 337.609424 -245.577339)
			(xy 337.379822 -245.577339) (xy 337.377835 -245.603848) (xy 337.365976 -245.655809) (xy 337.346505 -245.705422)
			(xy 337.319859 -245.751579) (xy 337.28663 -245.79325) (xy 337.247563 -245.829503) (xy 337.203528 -245.859528)
			(xy 337.155511 -245.882656) (xy 337.104583 -245.89837) (xy 337.051882 -245.906318) (xy 337.025234 -245.906798)
			(xy 337.000539 -245.906399) (xy 336.951618 -245.899614) (xy 336.904105 -245.886127) (xy 336.858914 -245.866199)
			(xy 336.816914 -245.840212) (xy 336.79765 -245.824756) (xy 336.786266 -245.815976) (xy 336.759898 -245.804552)
			(xy 336.731391 -245.800928) (xy 336.703004 -245.805393) (xy 336.676986 -245.817592) (xy 336.655398 -245.836559)
			(xy 336.639952 -245.860791) (xy 336.631871 -245.888367) (xy 336.63128 -245.902734) (xy 336.63128 -246.014748)
			(xy 336.666332 -246.026178) (xy 336.691137 -246.034827) (xy 336.73809 -246.058387) (xy 336.781071 -246.088588)
			(xy 336.819151 -246.124776) (xy 336.851501 -246.166165) (xy 336.87742 -246.211857) (xy 336.896347 -246.260861)
			(xy 336.907869 -246.312113) (xy 336.911738 -246.364502) (xy 336.909769 -246.391155) (xy 337.13927 -246.391155)
			(xy 337.13927 -246.337857) (xy 337.147213 -246.285153) (xy 337.162923 -246.234223) (xy 337.186049 -246.186202)
			(xy 337.216073 -246.142165) (xy 337.252325 -246.103094) (xy 337.293996 -246.069863) (xy 337.340154 -246.043214)
			(xy 337.389768 -246.023742) (xy 337.44173 -246.011882) (xy 337.49488 -246.007899) (xy 337.54803 -246.011882)
			(xy 337.599992 -246.023742) (xy 337.649606 -246.043214) (xy 337.695764 -246.069863) (xy 337.737435 -246.103094)
			(xy 337.773687 -246.142165) (xy 337.803711 -246.186202) (xy 337.826837 -246.234223) (xy 337.842547 -246.285153)
			(xy 337.85049 -246.337857) (xy 337.850988 -246.364506) (xy 337.85049 -246.391155) (xy 338.07907 -246.391155)
			(xy 338.07907 -246.337857) (xy 338.087013 -246.285153) (xy 338.102723 -246.234223) (xy 338.125849 -246.186202)
			(xy 338.155873 -246.142165) (xy 338.192125 -246.103094) (xy 338.233796 -246.069863) (xy 338.279954 -246.043214)
			(xy 338.329568 -246.023742) (xy 338.38153 -246.011882) (xy 338.43468 -246.007899) (xy 338.48783 -246.011882)
			(xy 338.539792 -246.023742) (xy 338.589406 -246.043214) (xy 338.635564 -246.069863) (xy 338.677235 -246.103094)
			(xy 338.713487 -246.142165) (xy 338.743511 -246.186202) (xy 338.766637 -246.234223) (xy 338.782347 -246.285153)
			(xy 338.79029 -246.337857) (xy 338.790788 -246.364506) (xy 338.79029 -246.391155) (xy 339.01887 -246.391155)
			(xy 339.01887 -246.337857) (xy 339.026813 -246.285153) (xy 339.042523 -246.234223) (xy 339.065649 -246.186202)
			(xy 339.095673 -246.142165) (xy 339.131925 -246.103094) (xy 339.173596 -246.069863) (xy 339.219754 -246.043214)
			(xy 339.269368 -246.023742) (xy 339.32133 -246.011882) (xy 339.37448 -246.007899) (xy 339.42763 -246.011882)
			(xy 339.479592 -246.023742) (xy 339.529206 -246.043214) (xy 339.575364 -246.069863) (xy 339.617035 -246.103094)
			(xy 339.653287 -246.142165) (xy 339.683311 -246.186202) (xy 339.706437 -246.234223) (xy 339.722147 -246.285153)
			(xy 339.73009 -246.337857) (xy 339.730588 -246.364506) (xy 339.73009 -246.391155) (xy 339.95867 -246.391155)
			(xy 339.95867 -246.337857) (xy 339.966613 -246.285153) (xy 339.982323 -246.234223) (xy 340.005449 -246.186202)
			(xy 340.035473 -246.142165) (xy 340.071725 -246.103094) (xy 340.113396 -246.069863) (xy 340.159554 -246.043214)
			(xy 340.209168 -246.023742) (xy 340.26113 -246.011882) (xy 340.31428 -246.007899) (xy 340.36743 -246.011882)
			(xy 340.419392 -246.023742) (xy 340.469006 -246.043214) (xy 340.515164 -246.069863) (xy 340.556835 -246.103094)
			(xy 340.593087 -246.142165) (xy 340.623111 -246.186202) (xy 340.646237 -246.234223) (xy 340.661947 -246.285153)
			(xy 340.66989 -246.337857) (xy 340.670388 -246.364506) (xy 340.66989 -246.391155) (xy 340.89847 -246.391155)
			(xy 340.89847 -246.337857) (xy 340.906413 -246.285153) (xy 340.922123 -246.234223) (xy 340.945249 -246.186202)
			(xy 340.975273 -246.142165) (xy 341.011525 -246.103094) (xy 341.053196 -246.069863) (xy 341.099354 -246.043214)
			(xy 341.148968 -246.023742) (xy 341.20093 -246.011882) (xy 341.25408 -246.007899) (xy 341.30723 -246.011882)
			(xy 341.359192 -246.023742) (xy 341.408806 -246.043214) (xy 341.454964 -246.069863) (xy 341.496635 -246.103094)
			(xy 341.532887 -246.142165) (xy 341.562911 -246.186202) (xy 341.586037 -246.234223) (xy 341.601747 -246.285153)
			(xy 341.60969 -246.337857) (xy 341.610188 -246.364506) (xy 341.60969 -246.391155) (xy 341.838524 -246.391155)
			(xy 341.838524 -246.337857) (xy 341.846467 -246.285153) (xy 341.862177 -246.234223) (xy 341.885303 -246.186202)
			(xy 341.915327 -246.142165) (xy 341.951579 -246.103094) (xy 341.99325 -246.069863) (xy 342.039408 -246.043214)
			(xy 342.089022 -246.023742) (xy 342.140984 -246.011882) (xy 342.194134 -246.007899) (xy 342.247284 -246.011882)
			(xy 342.299246 -246.023742) (xy 342.34886 -246.043214) (xy 342.395018 -246.069863) (xy 342.436689 -246.103094)
			(xy 342.472941 -246.142165) (xy 342.502965 -246.186202) (xy 342.526091 -246.234223) (xy 342.541801 -246.285153)
			(xy 342.549744 -246.337857) (xy 342.550242 -246.364506) (xy 342.549744 -246.391155) (xy 342.77807 -246.391155)
			(xy 342.77807 -246.337857) (xy 342.786013 -246.285153) (xy 342.801723 -246.234223) (xy 342.824849 -246.186202)
			(xy 342.854873 -246.142165) (xy 342.891125 -246.103094) (xy 342.932796 -246.069863) (xy 342.978954 -246.043214)
			(xy 343.028568 -246.023742) (xy 343.08053 -246.011882) (xy 343.13368 -246.007899) (xy 343.18683 -246.011882)
			(xy 343.238792 -246.023742) (xy 343.288406 -246.043214) (xy 343.334564 -246.069863) (xy 343.376235 -246.103094)
			(xy 343.412487 -246.142165) (xy 343.442511 -246.186202) (xy 343.465637 -246.234223) (xy 343.481347 -246.285153)
			(xy 343.48929 -246.337857) (xy 343.489788 -246.364506) (xy 343.48929 -246.391155) (xy 343.71787 -246.391155)
			(xy 343.71787 -246.337857) (xy 343.725813 -246.285153) (xy 343.741523 -246.234223) (xy 343.764649 -246.186202)
			(xy 343.794673 -246.142165) (xy 343.830925 -246.103094) (xy 343.872596 -246.069863) (xy 343.918754 -246.043214)
			(xy 343.968368 -246.023742) (xy 344.02033 -246.011882) (xy 344.07348 -246.007899) (xy 344.12663 -246.011882)
			(xy 344.178592 -246.023742) (xy 344.228206 -246.043214) (xy 344.274364 -246.069863) (xy 344.316035 -246.103094)
			(xy 344.352287 -246.142165) (xy 344.382311 -246.186202) (xy 344.405437 -246.234223) (xy 344.421147 -246.285153)
			(xy 344.42909 -246.337857) (xy 344.429588 -246.364506) (xy 344.42909 -246.391155) (xy 344.65767 -246.391155)
			(xy 344.65767 -246.337857) (xy 344.665613 -246.285153) (xy 344.681323 -246.234223) (xy 344.704449 -246.186202)
			(xy 344.734473 -246.142165) (xy 344.770725 -246.103094) (xy 344.812396 -246.069863) (xy 344.858554 -246.043214)
			(xy 344.908168 -246.023742) (xy 344.96013 -246.011882) (xy 345.01328 -246.007899) (xy 345.06643 -246.011882)
			(xy 345.118392 -246.023742) (xy 345.168006 -246.043214) (xy 345.214164 -246.069863) (xy 345.255835 -246.103094)
			(xy 345.292087 -246.142165) (xy 345.322111 -246.186202) (xy 345.345237 -246.234223) (xy 345.360947 -246.285153)
			(xy 345.36889 -246.337857) (xy 345.369388 -246.364506) (xy 345.36889 -246.391155) (xy 345.59747 -246.391155)
			(xy 345.59747 -246.337857) (xy 345.605413 -246.285153) (xy 345.621123 -246.234223) (xy 345.644249 -246.186202)
			(xy 345.674273 -246.142165) (xy 345.710525 -246.103094) (xy 345.752196 -246.069863) (xy 345.798354 -246.043214)
			(xy 345.847968 -246.023742) (xy 345.89993 -246.011882) (xy 345.95308 -246.007899) (xy 346.00623 -246.011882)
			(xy 346.058192 -246.023742) (xy 346.107806 -246.043214) (xy 346.153964 -246.069863) (xy 346.195635 -246.103094)
			(xy 346.231887 -246.142165) (xy 346.261911 -246.186202) (xy 346.285037 -246.234223) (xy 346.300747 -246.285153)
			(xy 346.30869 -246.337857) (xy 346.309188 -246.364506) (xy 346.30869 -246.391155) (xy 346.300747 -246.443859)
			(xy 346.285037 -246.494789) (xy 346.261911 -246.54281) (xy 346.231887 -246.586847) (xy 346.195635 -246.625918)
			(xy 346.153964 -246.659149) (xy 346.107806 -246.685798) (xy 346.058192 -246.70527) (xy 346.00623 -246.71713)
			(xy 345.95308 -246.721114) (xy 345.89993 -246.71713) (xy 345.847968 -246.70527) (xy 345.798354 -246.685798)
			(xy 345.752196 -246.659149) (xy 345.710525 -246.625918) (xy 345.674273 -246.586847) (xy 345.644249 -246.54281)
			(xy 345.621123 -246.494789) (xy 345.605413 -246.443859) (xy 345.59747 -246.391155) (xy 345.36889 -246.391155)
			(xy 345.360947 -246.443859) (xy 345.345237 -246.494789) (xy 345.322111 -246.54281) (xy 345.292087 -246.586847)
			(xy 345.255835 -246.625918) (xy 345.214164 -246.659149) (xy 345.168006 -246.685798) (xy 345.118392 -246.70527)
			(xy 345.06643 -246.71713) (xy 345.01328 -246.721114) (xy 344.96013 -246.71713) (xy 344.908168 -246.70527)
			(xy 344.858554 -246.685798) (xy 344.812396 -246.659149) (xy 344.770725 -246.625918) (xy 344.734473 -246.586847)
			(xy 344.704449 -246.54281) (xy 344.681323 -246.494789) (xy 344.665613 -246.443859) (xy 344.65767 -246.391155)
			(xy 344.42909 -246.391155) (xy 344.421147 -246.443859) (xy 344.405437 -246.494789) (xy 344.382311 -246.54281)
			(xy 344.352287 -246.586847) (xy 344.316035 -246.625918) (xy 344.274364 -246.659149) (xy 344.228206 -246.685798)
			(xy 344.178592 -246.70527) (xy 344.12663 -246.71713) (xy 344.07348 -246.721114) (xy 344.02033 -246.71713)
			(xy 343.968368 -246.70527) (xy 343.918754 -246.685798) (xy 343.872596 -246.659149) (xy 343.830925 -246.625918)
			(xy 343.794673 -246.586847) (xy 343.764649 -246.54281) (xy 343.741523 -246.494789) (xy 343.725813 -246.443859)
			(xy 343.71787 -246.391155) (xy 343.48929 -246.391155) (xy 343.481347 -246.443859) (xy 343.465637 -246.494789)
			(xy 343.442511 -246.54281) (xy 343.412487 -246.586847) (xy 343.376235 -246.625918) (xy 343.334564 -246.659149)
			(xy 343.288406 -246.685798) (xy 343.238792 -246.70527) (xy 343.18683 -246.71713) (xy 343.13368 -246.721114)
			(xy 343.08053 -246.71713) (xy 343.028568 -246.70527) (xy 342.978954 -246.685798) (xy 342.932796 -246.659149)
			(xy 342.891125 -246.625918) (xy 342.854873 -246.586847) (xy 342.824849 -246.54281) (xy 342.801723 -246.494789)
			(xy 342.786013 -246.443859) (xy 342.77807 -246.391155) (xy 342.549744 -246.391155) (xy 342.541801 -246.443859)
			(xy 342.526091 -246.494789) (xy 342.502965 -246.54281) (xy 342.472941 -246.586847) (xy 342.436689 -246.625918)
			(xy 342.395018 -246.659149) (xy 342.34886 -246.685798) (xy 342.299246 -246.70527) (xy 342.247284 -246.71713)
			(xy 342.194134 -246.721114) (xy 342.140984 -246.71713) (xy 342.089022 -246.70527) (xy 342.039408 -246.685798)
			(xy 341.99325 -246.659149) (xy 341.951579 -246.625918) (xy 341.915327 -246.586847) (xy 341.885303 -246.54281)
			(xy 341.862177 -246.494789) (xy 341.846467 -246.443859) (xy 341.838524 -246.391155) (xy 341.60969 -246.391155)
			(xy 341.601747 -246.443859) (xy 341.586037 -246.494789) (xy 341.562911 -246.54281) (xy 341.532887 -246.586847)
			(xy 341.496635 -246.625918) (xy 341.454964 -246.659149) (xy 341.408806 -246.685798) (xy 341.359192 -246.70527)
			(xy 341.30723 -246.71713) (xy 341.25408 -246.721114) (xy 341.20093 -246.71713) (xy 341.148968 -246.70527)
			(xy 341.099354 -246.685798) (xy 341.053196 -246.659149) (xy 341.011525 -246.625918) (xy 340.975273 -246.586847)
			(xy 340.945249 -246.54281) (xy 340.922123 -246.494789) (xy 340.906413 -246.443859) (xy 340.89847 -246.391155)
			(xy 340.66989 -246.391155) (xy 340.661947 -246.443859) (xy 340.646237 -246.494789) (xy 340.623111 -246.54281)
			(xy 340.593087 -246.586847) (xy 340.556835 -246.625918) (xy 340.515164 -246.659149) (xy 340.469006 -246.685798)
			(xy 340.419392 -246.70527) (xy 340.36743 -246.71713) (xy 340.31428 -246.721114) (xy 340.26113 -246.71713)
			(xy 340.209168 -246.70527) (xy 340.159554 -246.685798) (xy 340.113396 -246.659149) (xy 340.071725 -246.625918)
			(xy 340.035473 -246.586847) (xy 340.005449 -246.54281) (xy 339.982323 -246.494789) (xy 339.966613 -246.443859)
			(xy 339.95867 -246.391155) (xy 339.73009 -246.391155) (xy 339.722147 -246.443859) (xy 339.706437 -246.494789)
			(xy 339.683311 -246.54281) (xy 339.653287 -246.586847) (xy 339.617035 -246.625918) (xy 339.575364 -246.659149)
			(xy 339.529206 -246.685798) (xy 339.479592 -246.70527) (xy 339.42763 -246.71713) (xy 339.37448 -246.721114)
			(xy 339.32133 -246.71713) (xy 339.269368 -246.70527) (xy 339.219754 -246.685798) (xy 339.173596 -246.659149)
			(xy 339.131925 -246.625918) (xy 339.095673 -246.586847) (xy 339.065649 -246.54281) (xy 339.042523 -246.494789)
			(xy 339.026813 -246.443859) (xy 339.01887 -246.391155) (xy 338.79029 -246.391155) (xy 338.782347 -246.443859)
			(xy 338.766637 -246.494789) (xy 338.743511 -246.54281) (xy 338.713487 -246.586847) (xy 338.677235 -246.625918)
			(xy 338.635564 -246.659149) (xy 338.589406 -246.685798) (xy 338.539792 -246.70527) (xy 338.48783 -246.71713)
			(xy 338.43468 -246.721114) (xy 338.38153 -246.71713) (xy 338.329568 -246.70527) (xy 338.279954 -246.685798)
			(xy 338.233796 -246.659149) (xy 338.192125 -246.625918) (xy 338.155873 -246.586847) (xy 338.125849 -246.54281)
			(xy 338.102723 -246.494789) (xy 338.087013 -246.443859) (xy 338.07907 -246.391155) (xy 337.85049 -246.391155)
			(xy 337.842547 -246.443859) (xy 337.826837 -246.494789) (xy 337.803711 -246.54281) (xy 337.773687 -246.586847)
			(xy 337.737435 -246.625918) (xy 337.695764 -246.659149) (xy 337.649606 -246.685798) (xy 337.599992 -246.70527)
			(xy 337.54803 -246.71713) (xy 337.49488 -246.721114) (xy 337.44173 -246.71713) (xy 337.389768 -246.70527)
			(xy 337.340154 -246.685798) (xy 337.293996 -246.659149) (xy 337.252325 -246.625918) (xy 337.216073 -246.586847)
			(xy 337.186049 -246.54281) (xy 337.162923 -246.494789) (xy 337.147213 -246.443859) (xy 337.13927 -246.391155)
			(xy 336.909769 -246.391155) (xy 336.907868 -246.416891) (xy 336.896345 -246.468143) (xy 336.877419 -246.517147)
			(xy 336.851499 -246.562838) (xy 336.819148 -246.604227) (xy 336.781069 -246.640414) (xy 336.738086 -246.670615)
			(xy 336.691134 -246.694174) (xy 336.666332 -246.702834) (xy 336.63128 -246.714264) (xy 336.63128 -246.826278)
			(xy 336.631814 -246.840643) (xy 336.639899 -246.868213) (xy 336.655349 -246.892438) (xy 336.676939 -246.911395)
			(xy 336.702958 -246.923581) (xy 336.731344 -246.928032) (xy 336.759844 -246.924393) (xy 336.786201 -246.912954)
			(xy 336.79765 -246.904256) (xy 336.816925 -246.888816) (xy 336.858929 -246.862841) (xy 336.904118 -246.842916)
			(xy 336.951625 -246.829423) (xy 337.000541 -246.82262) (xy 337.025234 -246.822214) (xy 337.05188 -246.822715)
			(xy 337.104576 -246.830662) (xy 337.155499 -246.846374) (xy 337.203512 -246.8695) (xy 337.247542 -246.899523)
			(xy 337.286606 -246.935772) (xy 337.319832 -246.977439) (xy 337.346476 -247.023592) (xy 337.365945 -247.073201)
			(xy 337.377803 -247.125157) (xy 337.381785 -247.1783) (xy 337.379787 -247.204971) (xy 337.60917 -247.204971)
			(xy 337.60917 -247.151673) (xy 337.617113 -247.098969) (xy 337.632823 -247.048039) (xy 337.655949 -247.000018)
			(xy 337.685973 -246.955981) (xy 337.722225 -246.91691) (xy 337.763896 -246.883679) (xy 337.810054 -246.85703)
			(xy 337.859668 -246.837558) (xy 337.91163 -246.825698) (xy 337.96478 -246.821715) (xy 338.01793 -246.825698)
			(xy 338.069892 -246.837558) (xy 338.119506 -246.85703) (xy 338.165664 -246.883679) (xy 338.207335 -246.91691)
			(xy 338.243587 -246.955981) (xy 338.273611 -247.000018) (xy 338.296737 -247.048039) (xy 338.312447 -247.098969)
			(xy 338.32039 -247.151673) (xy 338.320888 -247.178322) (xy 338.32039 -247.204971) (xy 338.549224 -247.204971)
			(xy 338.549224 -247.151673) (xy 338.557167 -247.098969) (xy 338.572877 -247.048039) (xy 338.596003 -247.000018)
			(xy 338.626027 -246.955981) (xy 338.662279 -246.91691) (xy 338.70395 -246.883679) (xy 338.750108 -246.85703)
			(xy 338.799722 -246.837558) (xy 338.851684 -246.825698) (xy 338.904834 -246.821715) (xy 338.957984 -246.825698)
			(xy 339.009946 -246.837558) (xy 339.05956 -246.85703) (xy 339.105718 -246.883679) (xy 339.147389 -246.91691)
			(xy 339.183641 -246.955981) (xy 339.213665 -247.000018) (xy 339.236791 -247.048039) (xy 339.252501 -247.098969)
			(xy 339.260444 -247.151673) (xy 339.260942 -247.178322) (xy 339.260444 -247.204971) (xy 339.48877 -247.204971)
			(xy 339.48877 -247.151673) (xy 339.496713 -247.098969) (xy 339.512423 -247.048039) (xy 339.535549 -247.000018)
			(xy 339.565573 -246.955981) (xy 339.601825 -246.91691) (xy 339.643496 -246.883679) (xy 339.689654 -246.85703)
			(xy 339.739268 -246.837558) (xy 339.79123 -246.825698) (xy 339.84438 -246.821715) (xy 339.89753 -246.825698)
			(xy 339.949492 -246.837558) (xy 339.999106 -246.85703) (xy 340.045264 -246.883679) (xy 340.086935 -246.91691)
			(xy 340.123187 -246.955981) (xy 340.153211 -247.000018) (xy 340.176337 -247.048039) (xy 340.192047 -247.098969)
			(xy 340.19999 -247.151673) (xy 340.200488 -247.178322) (xy 340.19999 -247.204971) (xy 340.428824 -247.204971)
			(xy 340.428824 -247.151673) (xy 340.436767 -247.098969) (xy 340.452477 -247.048039) (xy 340.475603 -247.000018)
			(xy 340.505627 -246.955981) (xy 340.541879 -246.91691) (xy 340.58355 -246.883679) (xy 340.629708 -246.85703)
			(xy 340.679322 -246.837558) (xy 340.731284 -246.825698) (xy 340.784434 -246.821715) (xy 340.837584 -246.825698)
			(xy 340.889546 -246.837558) (xy 340.93916 -246.85703) (xy 340.985318 -246.883679) (xy 341.026989 -246.91691)
			(xy 341.063241 -246.955981) (xy 341.093265 -247.000018) (xy 341.116391 -247.048039) (xy 341.132101 -247.098969)
			(xy 341.140044 -247.151673) (xy 341.140542 -247.178322) (xy 341.140044 -247.204971) (xy 341.368624 -247.204971)
			(xy 341.368624 -247.151673) (xy 341.376567 -247.098969) (xy 341.392277 -247.048039) (xy 341.415403 -247.000018)
			(xy 341.445427 -246.955981) (xy 341.481679 -246.91691) (xy 341.52335 -246.883679) (xy 341.569508 -246.85703)
			(xy 341.619122 -246.837558) (xy 341.671084 -246.825698) (xy 341.724234 -246.821715) (xy 341.777384 -246.825698)
			(xy 341.829346 -246.837558) (xy 341.87896 -246.85703) (xy 341.925118 -246.883679) (xy 341.966789 -246.91691)
			(xy 342.003041 -246.955981) (xy 342.033065 -247.000018) (xy 342.056191 -247.048039) (xy 342.071901 -247.098969)
			(xy 342.079844 -247.151673) (xy 342.080342 -247.178322) (xy 342.079844 -247.204971) (xy 342.308424 -247.204971)
			(xy 342.308424 -247.151673) (xy 342.316367 -247.098969) (xy 342.332077 -247.048039) (xy 342.355203 -247.000018)
			(xy 342.385227 -246.955981) (xy 342.421479 -246.91691) (xy 342.46315 -246.883679) (xy 342.509308 -246.85703)
			(xy 342.558922 -246.837558) (xy 342.610884 -246.825698) (xy 342.664034 -246.821715) (xy 342.717184 -246.825698)
			(xy 342.769146 -246.837558) (xy 342.81876 -246.85703) (xy 342.864918 -246.883679) (xy 342.906589 -246.91691)
			(xy 342.942841 -246.955981) (xy 342.972865 -247.000018) (xy 342.995991 -247.048039) (xy 343.011701 -247.098969)
			(xy 343.019644 -247.151673) (xy 343.020142 -247.178322) (xy 343.019644 -247.204971) (xy 343.248224 -247.204971)
			(xy 343.248224 -247.151673) (xy 343.256167 -247.098969) (xy 343.271877 -247.048039) (xy 343.295003 -247.000018)
			(xy 343.325027 -246.955981) (xy 343.361279 -246.91691) (xy 343.40295 -246.883679) (xy 343.449108 -246.85703)
			(xy 343.498722 -246.837558) (xy 343.550684 -246.825698) (xy 343.603834 -246.821715) (xy 343.656984 -246.825698)
			(xy 343.708946 -246.837558) (xy 343.75856 -246.85703) (xy 343.804718 -246.883679) (xy 343.846389 -246.91691)
			(xy 343.882641 -246.955981) (xy 343.912665 -247.000018) (xy 343.935791 -247.048039) (xy 343.951501 -247.098969)
			(xy 343.959444 -247.151673) (xy 343.959942 -247.178322) (xy 343.959444 -247.204971) (xy 344.18777 -247.204971)
			(xy 344.18777 -247.151673) (xy 344.195713 -247.098969) (xy 344.211423 -247.048039) (xy 344.234549 -247.000018)
			(xy 344.264573 -246.955981) (xy 344.300825 -246.91691) (xy 344.342496 -246.883679) (xy 344.388654 -246.85703)
			(xy 344.438268 -246.837558) (xy 344.49023 -246.825698) (xy 344.54338 -246.821715) (xy 344.59653 -246.825698)
			(xy 344.648492 -246.837558) (xy 344.698106 -246.85703) (xy 344.744264 -246.883679) (xy 344.785935 -246.91691)
			(xy 344.822187 -246.955981) (xy 344.852211 -247.000018) (xy 344.875337 -247.048039) (xy 344.891047 -247.098969)
			(xy 344.89899 -247.151673) (xy 344.899488 -247.178322) (xy 344.89899 -247.204971) (xy 345.127824 -247.204971)
			(xy 345.127824 -247.151673) (xy 345.135767 -247.098969) (xy 345.151477 -247.048039) (xy 345.174603 -247.000018)
			(xy 345.204627 -246.955981) (xy 345.240879 -246.91691) (xy 345.28255 -246.883679) (xy 345.328708 -246.85703)
			(xy 345.378322 -246.837558) (xy 345.430284 -246.825698) (xy 345.483434 -246.821715) (xy 345.536584 -246.825698)
			(xy 345.588546 -246.837558) (xy 345.63816 -246.85703) (xy 345.684318 -246.883679) (xy 345.725989 -246.91691)
			(xy 345.762241 -246.955981) (xy 345.792265 -247.000018) (xy 345.815391 -247.048039) (xy 345.831101 -247.098969)
			(xy 345.839044 -247.151673) (xy 345.839542 -247.178322) (xy 345.839044 -247.204971) (xy 346.06737 -247.204971)
			(xy 346.06737 -247.151673) (xy 346.075313 -247.098969) (xy 346.091023 -247.048039) (xy 346.114149 -247.000018)
			(xy 346.144173 -246.955981) (xy 346.180425 -246.91691) (xy 346.222096 -246.883679) (xy 346.268254 -246.85703)
			(xy 346.317868 -246.837558) (xy 346.36983 -246.825698) (xy 346.42298 -246.821715) (xy 346.47613 -246.825698)
			(xy 346.528092 -246.837558) (xy 346.577706 -246.85703) (xy 346.623864 -246.883679) (xy 346.665535 -246.91691)
			(xy 346.701787 -246.955981) (xy 346.731811 -247.000018) (xy 346.754937 -247.048039) (xy 346.770647 -247.098969)
			(xy 346.77859 -247.151673) (xy 346.779088 -247.178322) (xy 346.77859 -247.204971) (xy 346.770647 -247.257675)
			(xy 346.754937 -247.308605) (xy 346.731811 -247.356626) (xy 346.701787 -247.400663) (xy 346.665535 -247.439734)
			(xy 346.623864 -247.472965) (xy 346.577706 -247.499614) (xy 346.528092 -247.519086) (xy 346.47613 -247.530946)
			(xy 346.42298 -247.53493) (xy 346.36983 -247.530946) (xy 346.317868 -247.519086) (xy 346.268254 -247.499614)
			(xy 346.222096 -247.472965) (xy 346.180425 -247.439734) (xy 346.144173 -247.400663) (xy 346.114149 -247.356626)
			(xy 346.091023 -247.308605) (xy 346.075313 -247.257675) (xy 346.06737 -247.204971) (xy 345.839044 -247.204971)
			(xy 345.831101 -247.257675) (xy 345.815391 -247.308605) (xy 345.792265 -247.356626) (xy 345.762241 -247.400663)
			(xy 345.725989 -247.439734) (xy 345.684318 -247.472965) (xy 345.63816 -247.499614) (xy 345.588546 -247.519086)
			(xy 345.536584 -247.530946) (xy 345.483434 -247.53493) (xy 345.430284 -247.530946) (xy 345.378322 -247.519086)
			(xy 345.328708 -247.499614) (xy 345.28255 -247.472965) (xy 345.240879 -247.439734) (xy 345.204627 -247.400663)
			(xy 345.174603 -247.356626) (xy 345.151477 -247.308605) (xy 345.135767 -247.257675) (xy 345.127824 -247.204971)
			(xy 344.89899 -247.204971) (xy 344.891047 -247.257675) (xy 344.875337 -247.308605) (xy 344.852211 -247.356626)
			(xy 344.822187 -247.400663) (xy 344.785935 -247.439734) (xy 344.744264 -247.472965) (xy 344.698106 -247.499614)
			(xy 344.648492 -247.519086) (xy 344.59653 -247.530946) (xy 344.54338 -247.53493) (xy 344.49023 -247.530946)
			(xy 344.438268 -247.519086) (xy 344.388654 -247.499614) (xy 344.342496 -247.472965) (xy 344.300825 -247.439734)
			(xy 344.264573 -247.400663) (xy 344.234549 -247.356626) (xy 344.211423 -247.308605) (xy 344.195713 -247.257675)
			(xy 344.18777 -247.204971) (xy 343.959444 -247.204971) (xy 343.951501 -247.257675) (xy 343.935791 -247.308605)
			(xy 343.912665 -247.356626) (xy 343.882641 -247.400663) (xy 343.846389 -247.439734) (xy 343.804718 -247.472965)
			(xy 343.75856 -247.499614) (xy 343.708946 -247.519086) (xy 343.656984 -247.530946) (xy 343.603834 -247.53493)
			(xy 343.550684 -247.530946) (xy 343.498722 -247.519086) (xy 343.449108 -247.499614) (xy 343.40295 -247.472965)
			(xy 343.361279 -247.439734) (xy 343.325027 -247.400663) (xy 343.295003 -247.356626) (xy 343.271877 -247.308605)
			(xy 343.256167 -247.257675) (xy 343.248224 -247.204971) (xy 343.019644 -247.204971) (xy 343.011701 -247.257675)
			(xy 342.995991 -247.308605) (xy 342.972865 -247.356626) (xy 342.942841 -247.400663) (xy 342.906589 -247.439734)
			(xy 342.864918 -247.472965) (xy 342.81876 -247.499614) (xy 342.769146 -247.519086) (xy 342.717184 -247.530946)
			(xy 342.664034 -247.53493) (xy 342.610884 -247.530946) (xy 342.558922 -247.519086) (xy 342.509308 -247.499614)
			(xy 342.46315 -247.472965) (xy 342.421479 -247.439734) (xy 342.385227 -247.400663) (xy 342.355203 -247.356626)
			(xy 342.332077 -247.308605) (xy 342.316367 -247.257675) (xy 342.308424 -247.204971) (xy 342.079844 -247.204971)
			(xy 342.071901 -247.257675) (xy 342.056191 -247.308605) (xy 342.033065 -247.356626) (xy 342.003041 -247.400663)
			(xy 341.966789 -247.439734) (xy 341.925118 -247.472965) (xy 341.87896 -247.499614) (xy 341.829346 -247.519086)
			(xy 341.777384 -247.530946) (xy 341.724234 -247.53493) (xy 341.671084 -247.530946) (xy 341.619122 -247.519086)
			(xy 341.569508 -247.499614) (xy 341.52335 -247.472965) (xy 341.481679 -247.439734) (xy 341.445427 -247.400663)
			(xy 341.415403 -247.356626) (xy 341.392277 -247.308605) (xy 341.376567 -247.257675) (xy 341.368624 -247.204971)
			(xy 341.140044 -247.204971) (xy 341.132101 -247.257675) (xy 341.116391 -247.308605) (xy 341.093265 -247.356626)
			(xy 341.063241 -247.400663) (xy 341.026989 -247.439734) (xy 340.985318 -247.472965) (xy 340.93916 -247.499614)
			(xy 340.889546 -247.519086) (xy 340.837584 -247.530946) (xy 340.784434 -247.53493) (xy 340.731284 -247.530946)
			(xy 340.679322 -247.519086) (xy 340.629708 -247.499614) (xy 340.58355 -247.472965) (xy 340.541879 -247.439734)
			(xy 340.505627 -247.400663) (xy 340.475603 -247.356626) (xy 340.452477 -247.308605) (xy 340.436767 -247.257675)
			(xy 340.428824 -247.204971) (xy 340.19999 -247.204971) (xy 340.192047 -247.257675) (xy 340.176337 -247.308605)
			(xy 340.153211 -247.356626) (xy 340.123187 -247.400663) (xy 340.086935 -247.439734) (xy 340.045264 -247.472965)
			(xy 339.999106 -247.499614) (xy 339.949492 -247.519086) (xy 339.89753 -247.530946) (xy 339.84438 -247.53493)
			(xy 339.79123 -247.530946) (xy 339.739268 -247.519086) (xy 339.689654 -247.499614) (xy 339.643496 -247.472965)
			(xy 339.601825 -247.439734) (xy 339.565573 -247.400663) (xy 339.535549 -247.356626) (xy 339.512423 -247.308605)
			(xy 339.496713 -247.257675) (xy 339.48877 -247.204971) (xy 339.260444 -247.204971) (xy 339.252501 -247.257675)
			(xy 339.236791 -247.308605) (xy 339.213665 -247.356626) (xy 339.183641 -247.400663) (xy 339.147389 -247.439734)
			(xy 339.105718 -247.472965) (xy 339.05956 -247.499614) (xy 339.009946 -247.519086) (xy 338.957984 -247.530946)
			(xy 338.904834 -247.53493) (xy 338.851684 -247.530946) (xy 338.799722 -247.519086) (xy 338.750108 -247.499614)
			(xy 338.70395 -247.472965) (xy 338.662279 -247.439734) (xy 338.626027 -247.400663) (xy 338.596003 -247.356626)
			(xy 338.572877 -247.308605) (xy 338.557167 -247.257675) (xy 338.549224 -247.204971) (xy 338.32039 -247.204971)
			(xy 338.312447 -247.257675) (xy 338.296737 -247.308605) (xy 338.273611 -247.356626) (xy 338.243587 -247.400663)
			(xy 338.207335 -247.439734) (xy 338.165664 -247.472965) (xy 338.119506 -247.499614) (xy 338.069892 -247.519086)
			(xy 338.01793 -247.530946) (xy 337.96478 -247.53493) (xy 337.91163 -247.530946) (xy 337.859668 -247.519086)
			(xy 337.810054 -247.499614) (xy 337.763896 -247.472965) (xy 337.722225 -247.439734) (xy 337.685973 -247.400663)
			(xy 337.655949 -247.356626) (xy 337.632823 -247.308605) (xy 337.617113 -247.257675) (xy 337.60917 -247.204971)
			(xy 337.379787 -247.204971) (xy 337.377803 -247.231443) (xy 337.365945 -247.283399) (xy 337.346476 -247.333008)
			(xy 337.319832 -247.379161) (xy 337.286606 -247.420828) (xy 337.247542 -247.457077) (xy 337.203512 -247.4871)
			(xy 337.155499 -247.510226) (xy 337.104576 -247.525938) (xy 337.05188 -247.533885) (xy 337.025234 -247.53443)
			(xy 337.000539 -247.534031) (xy 336.951617 -247.527246) (xy 336.904104 -247.513761) (xy 336.858912 -247.493834)
			(xy 336.816911 -247.467849) (xy 336.79765 -247.452388) (xy 336.786262 -247.443612) (xy 336.75989 -247.432195)
			(xy 336.731382 -247.428575) (xy 336.702994 -247.43304) (xy 336.676973 -247.445237) (xy 336.65538 -247.464199)
			(xy 336.639923 -247.488426) (xy 336.631827 -247.515999) (xy 336.63128 -247.530366) (xy 336.63128 -247.64238)
			(xy 336.666332 -247.65381) (xy 336.691135 -247.662459) (xy 336.738083 -247.686018) (xy 336.78106 -247.716218)
			(xy 336.819135 -247.752404) (xy 336.851481 -247.79379) (xy 336.877397 -247.839479) (xy 336.89632 -247.888479)
			(xy 336.90784 -247.939727) (xy 336.911707 -247.992112) (xy 336.909736 -248.018787) (xy 337.139524 -248.018787)
			(xy 337.139524 -247.965489) (xy 337.147467 -247.912785) (xy 337.163177 -247.861855) (xy 337.186303 -247.813834)
			(xy 337.216327 -247.769797) (xy 337.252579 -247.730726) (xy 337.29425 -247.697495) (xy 337.340408 -247.670846)
			(xy 337.390022 -247.651374) (xy 337.441984 -247.639514) (xy 337.495134 -247.635531) (xy 337.548284 -247.639514)
			(xy 337.600246 -247.651374) (xy 337.64986 -247.670846) (xy 337.696018 -247.697495) (xy 337.737689 -247.730726)
			(xy 337.773941 -247.769797) (xy 337.803965 -247.813834) (xy 337.827091 -247.861855) (xy 337.842801 -247.912785)
			(xy 337.850744 -247.965489) (xy 337.851242 -247.992138) (xy 337.850744 -248.018787) (xy 338.07907 -248.018787)
			(xy 338.07907 -247.965489) (xy 338.087013 -247.912785) (xy 338.102723 -247.861855) (xy 338.125849 -247.813834)
			(xy 338.155873 -247.769797) (xy 338.192125 -247.730726) (xy 338.233796 -247.697495) (xy 338.279954 -247.670846)
			(xy 338.329568 -247.651374) (xy 338.38153 -247.639514) (xy 338.43468 -247.635531) (xy 338.48783 -247.639514)
			(xy 338.539792 -247.651374) (xy 338.589406 -247.670846) (xy 338.635564 -247.697495) (xy 338.677235 -247.730726)
			(xy 338.713487 -247.769797) (xy 338.743511 -247.813834) (xy 338.766637 -247.861855) (xy 338.782347 -247.912785)
			(xy 338.79029 -247.965489) (xy 338.790788 -247.992138) (xy 338.79029 -248.018787) (xy 339.019124 -248.018787)
			(xy 339.019124 -247.965489) (xy 339.027067 -247.912785) (xy 339.042777 -247.861855) (xy 339.065903 -247.813834)
			(xy 339.095927 -247.769797) (xy 339.132179 -247.730726) (xy 339.17385 -247.697495) (xy 339.220008 -247.670846)
			(xy 339.269622 -247.651374) (xy 339.321584 -247.639514) (xy 339.374734 -247.635531) (xy 339.427884 -247.639514)
			(xy 339.479846 -247.651374) (xy 339.52946 -247.670846) (xy 339.575618 -247.697495) (xy 339.617289 -247.730726)
			(xy 339.653541 -247.769797) (xy 339.683565 -247.813834) (xy 339.706691 -247.861855) (xy 339.722401 -247.912785)
			(xy 339.730344 -247.965489) (xy 339.730842 -247.992138) (xy 339.730344 -248.018787) (xy 339.95867 -248.018787)
			(xy 339.95867 -247.965489) (xy 339.966613 -247.912785) (xy 339.982323 -247.861855) (xy 340.005449 -247.813834)
			(xy 340.035473 -247.769797) (xy 340.071725 -247.730726) (xy 340.113396 -247.697495) (xy 340.159554 -247.670846)
			(xy 340.209168 -247.651374) (xy 340.26113 -247.639514) (xy 340.31428 -247.635531) (xy 340.36743 -247.639514)
			(xy 340.419392 -247.651374) (xy 340.469006 -247.670846) (xy 340.515164 -247.697495) (xy 340.556835 -247.730726)
			(xy 340.593087 -247.769797) (xy 340.623111 -247.813834) (xy 340.646237 -247.861855) (xy 340.661947 -247.912785)
			(xy 340.66989 -247.965489) (xy 340.670388 -247.992138) (xy 340.66989 -248.018787) (xy 340.89847 -248.018787)
			(xy 340.89847 -247.965489) (xy 340.906413 -247.912785) (xy 340.922123 -247.861855) (xy 340.945249 -247.813834)
			(xy 340.975273 -247.769797) (xy 341.011525 -247.730726) (xy 341.053196 -247.697495) (xy 341.099354 -247.670846)
			(xy 341.148968 -247.651374) (xy 341.20093 -247.639514) (xy 341.25408 -247.635531) (xy 341.30723 -247.639514)
			(xy 341.359192 -247.651374) (xy 341.408806 -247.670846) (xy 341.454964 -247.697495) (xy 341.496635 -247.730726)
			(xy 341.532887 -247.769797) (xy 341.562911 -247.813834) (xy 341.586037 -247.861855) (xy 341.601747 -247.912785)
			(xy 341.60969 -247.965489) (xy 341.610188 -247.992138) (xy 341.60969 -248.018787) (xy 341.83827 -248.018787)
			(xy 341.83827 -247.965489) (xy 341.846213 -247.912785) (xy 341.861923 -247.861855) (xy 341.885049 -247.813834)
			(xy 341.915073 -247.769797) (xy 341.951325 -247.730726) (xy 341.992996 -247.697495) (xy 342.039154 -247.670846)
			(xy 342.088768 -247.651374) (xy 342.14073 -247.639514) (xy 342.19388 -247.635531) (xy 342.24703 -247.639514)
			(xy 342.298992 -247.651374) (xy 342.348606 -247.670846) (xy 342.394764 -247.697495) (xy 342.436435 -247.730726)
			(xy 342.472687 -247.769797) (xy 342.502711 -247.813834) (xy 342.525837 -247.861855) (xy 342.541547 -247.912785)
			(xy 342.54949 -247.965489) (xy 342.549988 -247.992138) (xy 342.54949 -248.018787) (xy 342.77807 -248.018787)
			(xy 342.77807 -247.965489) (xy 342.786013 -247.912785) (xy 342.801723 -247.861855) (xy 342.824849 -247.813834)
			(xy 342.854873 -247.769797) (xy 342.891125 -247.730726) (xy 342.932796 -247.697495) (xy 342.978954 -247.670846)
			(xy 343.028568 -247.651374) (xy 343.08053 -247.639514) (xy 343.13368 -247.635531) (xy 343.18683 -247.639514)
			(xy 343.238792 -247.651374) (xy 343.288406 -247.670846) (xy 343.334564 -247.697495) (xy 343.376235 -247.730726)
			(xy 343.412487 -247.769797) (xy 343.442511 -247.813834) (xy 343.465637 -247.861855) (xy 343.481347 -247.912785)
			(xy 343.48929 -247.965489) (xy 343.489788 -247.992138) (xy 343.48929 -248.018787) (xy 343.718124 -248.018787)
			(xy 343.718124 -247.965489) (xy 343.726067 -247.912785) (xy 343.741777 -247.861855) (xy 343.764903 -247.813834)
			(xy 343.794927 -247.769797) (xy 343.831179 -247.730726) (xy 343.87285 -247.697495) (xy 343.919008 -247.670846)
			(xy 343.968622 -247.651374) (xy 344.020584 -247.639514) (xy 344.073734 -247.635531) (xy 344.126884 -247.639514)
			(xy 344.178846 -247.651374) (xy 344.22846 -247.670846) (xy 344.274618 -247.697495) (xy 344.316289 -247.730726)
			(xy 344.352541 -247.769797) (xy 344.382565 -247.813834) (xy 344.405691 -247.861855) (xy 344.421401 -247.912785)
			(xy 344.429344 -247.965489) (xy 344.429842 -247.992138) (xy 344.429344 -248.018787) (xy 344.65767 -248.018787)
			(xy 344.65767 -247.965489) (xy 344.665613 -247.912785) (xy 344.681323 -247.861855) (xy 344.704449 -247.813834)
			(xy 344.734473 -247.769797) (xy 344.770725 -247.730726) (xy 344.812396 -247.697495) (xy 344.858554 -247.670846)
			(xy 344.908168 -247.651374) (xy 344.96013 -247.639514) (xy 345.01328 -247.635531) (xy 345.06643 -247.639514)
			(xy 345.118392 -247.651374) (xy 345.168006 -247.670846) (xy 345.214164 -247.697495) (xy 345.255835 -247.730726)
			(xy 345.292087 -247.769797) (xy 345.322111 -247.813834) (xy 345.345237 -247.861855) (xy 345.360947 -247.912785)
			(xy 345.36889 -247.965489) (xy 345.369388 -247.992138) (xy 345.36889 -248.018787) (xy 345.597724 -248.018787)
			(xy 345.597724 -247.965489) (xy 345.605667 -247.912785) (xy 345.621377 -247.861855) (xy 345.644503 -247.813834)
			(xy 345.674527 -247.769797) (xy 345.710779 -247.730726) (xy 345.75245 -247.697495) (xy 345.798608 -247.670846)
			(xy 345.848222 -247.651374) (xy 345.900184 -247.639514) (xy 345.953334 -247.635531) (xy 346.006484 -247.639514)
			(xy 346.058446 -247.651374) (xy 346.10806 -247.670846) (xy 346.154218 -247.697495) (xy 346.195889 -247.730726)
			(xy 346.232141 -247.769797) (xy 346.262165 -247.813834) (xy 346.285291 -247.861855) (xy 346.301001 -247.912785)
			(xy 346.308944 -247.965489) (xy 346.309442 -247.992138) (xy 346.308944 -248.018787) (xy 346.301001 -248.071491)
			(xy 346.285291 -248.122421) (xy 346.262165 -248.170442) (xy 346.232141 -248.214479) (xy 346.195889 -248.25355)
			(xy 346.154218 -248.286781) (xy 346.10806 -248.31343) (xy 346.058446 -248.332902) (xy 346.006484 -248.344762)
			(xy 345.953334 -248.348746) (xy 345.900184 -248.344762) (xy 345.848222 -248.332902) (xy 345.798608 -248.31343)
			(xy 345.75245 -248.286781) (xy 345.710779 -248.25355) (xy 345.674527 -248.214479) (xy 345.644503 -248.170442)
			(xy 345.621377 -248.122421) (xy 345.605667 -248.071491) (xy 345.597724 -248.018787) (xy 345.36889 -248.018787)
			(xy 345.360947 -248.071491) (xy 345.345237 -248.122421) (xy 345.322111 -248.170442) (xy 345.292087 -248.214479)
			(xy 345.255835 -248.25355) (xy 345.214164 -248.286781) (xy 345.168006 -248.31343) (xy 345.118392 -248.332902)
			(xy 345.06643 -248.344762) (xy 345.01328 -248.348746) (xy 344.96013 -248.344762) (xy 344.908168 -248.332902)
			(xy 344.858554 -248.31343) (xy 344.812396 -248.286781) (xy 344.770725 -248.25355) (xy 344.734473 -248.214479)
			(xy 344.704449 -248.170442) (xy 344.681323 -248.122421) (xy 344.665613 -248.071491) (xy 344.65767 -248.018787)
			(xy 344.429344 -248.018787) (xy 344.421401 -248.071491) (xy 344.405691 -248.122421) (xy 344.382565 -248.170442)
			(xy 344.352541 -248.214479) (xy 344.316289 -248.25355) (xy 344.274618 -248.286781) (xy 344.22846 -248.31343)
			(xy 344.178846 -248.332902) (xy 344.126884 -248.344762) (xy 344.073734 -248.348746) (xy 344.020584 -248.344762)
			(xy 343.968622 -248.332902) (xy 343.919008 -248.31343) (xy 343.87285 -248.286781) (xy 343.831179 -248.25355)
			(xy 343.794927 -248.214479) (xy 343.764903 -248.170442) (xy 343.741777 -248.122421) (xy 343.726067 -248.071491)
			(xy 343.718124 -248.018787) (xy 343.48929 -248.018787) (xy 343.481347 -248.071491) (xy 343.465637 -248.122421)
			(xy 343.442511 -248.170442) (xy 343.412487 -248.214479) (xy 343.376235 -248.25355) (xy 343.334564 -248.286781)
			(xy 343.288406 -248.31343) (xy 343.238792 -248.332902) (xy 343.18683 -248.344762) (xy 343.13368 -248.348746)
			(xy 343.08053 -248.344762) (xy 343.028568 -248.332902) (xy 342.978954 -248.31343) (xy 342.932796 -248.286781)
			(xy 342.891125 -248.25355) (xy 342.854873 -248.214479) (xy 342.824849 -248.170442) (xy 342.801723 -248.122421)
			(xy 342.786013 -248.071491) (xy 342.77807 -248.018787) (xy 342.54949 -248.018787) (xy 342.541547 -248.071491)
			(xy 342.525837 -248.122421) (xy 342.502711 -248.170442) (xy 342.472687 -248.214479) (xy 342.436435 -248.25355)
			(xy 342.394764 -248.286781) (xy 342.348606 -248.31343) (xy 342.298992 -248.332902) (xy 342.24703 -248.344762)
			(xy 342.19388 -248.348746) (xy 342.14073 -248.344762) (xy 342.088768 -248.332902) (xy 342.039154 -248.31343)
			(xy 341.992996 -248.286781) (xy 341.951325 -248.25355) (xy 341.915073 -248.214479) (xy 341.885049 -248.170442)
			(xy 341.861923 -248.122421) (xy 341.846213 -248.071491) (xy 341.83827 -248.018787) (xy 341.60969 -248.018787)
			(xy 341.601747 -248.071491) (xy 341.586037 -248.122421) (xy 341.562911 -248.170442) (xy 341.532887 -248.214479)
			(xy 341.496635 -248.25355) (xy 341.454964 -248.286781) (xy 341.408806 -248.31343) (xy 341.359192 -248.332902)
			(xy 341.30723 -248.344762) (xy 341.25408 -248.348746) (xy 341.20093 -248.344762) (xy 341.148968 -248.332902)
			(xy 341.099354 -248.31343) (xy 341.053196 -248.286781) (xy 341.011525 -248.25355) (xy 340.975273 -248.214479)
			(xy 340.945249 -248.170442) (xy 340.922123 -248.122421) (xy 340.906413 -248.071491) (xy 340.89847 -248.018787)
			(xy 340.66989 -248.018787) (xy 340.661947 -248.071491) (xy 340.646237 -248.122421) (xy 340.623111 -248.170442)
			(xy 340.593087 -248.214479) (xy 340.556835 -248.25355) (xy 340.515164 -248.286781) (xy 340.469006 -248.31343)
			(xy 340.419392 -248.332902) (xy 340.36743 -248.344762) (xy 340.31428 -248.348746) (xy 340.26113 -248.344762)
			(xy 340.209168 -248.332902) (xy 340.159554 -248.31343) (xy 340.113396 -248.286781) (xy 340.071725 -248.25355)
			(xy 340.035473 -248.214479) (xy 340.005449 -248.170442) (xy 339.982323 -248.122421) (xy 339.966613 -248.071491)
			(xy 339.95867 -248.018787) (xy 339.730344 -248.018787) (xy 339.722401 -248.071491) (xy 339.706691 -248.122421)
			(xy 339.683565 -248.170442) (xy 339.653541 -248.214479) (xy 339.617289 -248.25355) (xy 339.575618 -248.286781)
			(xy 339.52946 -248.31343) (xy 339.479846 -248.332902) (xy 339.427884 -248.344762) (xy 339.374734 -248.348746)
			(xy 339.321584 -248.344762) (xy 339.269622 -248.332902) (xy 339.220008 -248.31343) (xy 339.17385 -248.286781)
			(xy 339.132179 -248.25355) (xy 339.095927 -248.214479) (xy 339.065903 -248.170442) (xy 339.042777 -248.122421)
			(xy 339.027067 -248.071491) (xy 339.019124 -248.018787) (xy 338.79029 -248.018787) (xy 338.782347 -248.071491)
			(xy 338.766637 -248.122421) (xy 338.743511 -248.170442) (xy 338.713487 -248.214479) (xy 338.677235 -248.25355)
			(xy 338.635564 -248.286781) (xy 338.589406 -248.31343) (xy 338.539792 -248.332902) (xy 338.48783 -248.344762)
			(xy 338.43468 -248.348746) (xy 338.38153 -248.344762) (xy 338.329568 -248.332902) (xy 338.279954 -248.31343)
			(xy 338.233796 -248.286781) (xy 338.192125 -248.25355) (xy 338.155873 -248.214479) (xy 338.125849 -248.170442)
			(xy 338.102723 -248.122421) (xy 338.087013 -248.071491) (xy 338.07907 -248.018787) (xy 337.850744 -248.018787)
			(xy 337.842801 -248.071491) (xy 337.827091 -248.122421) (xy 337.803965 -248.170442) (xy 337.773941 -248.214479)
			(xy 337.737689 -248.25355) (xy 337.696018 -248.286781) (xy 337.64986 -248.31343) (xy 337.600246 -248.332902)
			(xy 337.548284 -248.344762) (xy 337.495134 -248.348746) (xy 337.441984 -248.344762) (xy 337.390022 -248.332902)
			(xy 337.340408 -248.31343) (xy 337.29425 -248.286781) (xy 337.252579 -248.25355) (xy 337.216327 -248.214479)
			(xy 337.186303 -248.170442) (xy 337.163177 -248.122421) (xy 337.147467 -248.071491) (xy 337.139524 -248.018787)
			(xy 336.909736 -248.018787) (xy 336.907837 -248.044496) (xy 336.896313 -248.095744) (xy 336.877387 -248.144743)
			(xy 336.851468 -248.19043) (xy 336.819119 -248.231814) (xy 336.781042 -248.267997) (xy 336.738062 -248.298194)
			(xy 336.691113 -248.32175) (xy 336.666332 -248.330466) (xy 336.63128 -248.341896) (xy 336.63128 -248.454164)
			(xy 336.631812 -248.46853) (xy 336.639895 -248.496104) (xy 336.655344 -248.520332) (xy 336.676936 -248.539292)
			(xy 336.702957 -248.551481) (xy 336.731345 -248.555932) (xy 336.759849 -248.552292) (xy 336.786207 -248.54085)
			(xy 336.79765 -248.532142) (xy 336.816926 -248.516703) (xy 336.85893 -248.490728) (xy 336.904118 -248.470804)
			(xy 336.951625 -248.457312) (xy 337.000541 -248.45051) (xy 337.025234 -248.4501) (xy 337.051881 -248.4506)
			(xy 337.104579 -248.458548) (xy 337.155505 -248.47426) (xy 337.203519 -248.497387) (xy 337.247551 -248.527411)
			(xy 337.286617 -248.563663) (xy 337.319844 -248.605331) (xy 337.346489 -248.651486) (xy 337.365959 -248.701097)
			(xy 337.377817 -248.753055) (xy 337.3818 -248.8062) (xy 337.379802 -248.832857) (xy 337.609424 -248.832857)
			(xy 337.609424 -248.779559) (xy 337.617367 -248.726855) (xy 337.633077 -248.675925) (xy 337.656203 -248.627904)
			(xy 337.686227 -248.583867) (xy 337.722479 -248.544796) (xy 337.76415 -248.511565) (xy 337.810308 -248.484916)
			(xy 337.859922 -248.465444) (xy 337.911884 -248.453584) (xy 337.965034 -248.449601) (xy 338.018184 -248.453584)
			(xy 338.070146 -248.465444) (xy 338.11976 -248.484916) (xy 338.165918 -248.511565) (xy 338.207589 -248.544796)
			(xy 338.243841 -248.583867) (xy 338.273865 -248.627904) (xy 338.296991 -248.675925) (xy 338.312701 -248.726855)
			(xy 338.320644 -248.779559) (xy 338.321142 -248.806208) (xy 338.320644 -248.832857) (xy 338.549224 -248.832857)
			(xy 338.549224 -248.779559) (xy 338.557167 -248.726855) (xy 338.572877 -248.675925) (xy 338.596003 -248.627904)
			(xy 338.626027 -248.583867) (xy 338.662279 -248.544796) (xy 338.70395 -248.511565) (xy 338.750108 -248.484916)
			(xy 338.799722 -248.465444) (xy 338.851684 -248.453584) (xy 338.904834 -248.449601) (xy 338.957984 -248.453584)
			(xy 339.009946 -248.465444) (xy 339.05956 -248.484916) (xy 339.105718 -248.511565) (xy 339.147389 -248.544796)
			(xy 339.183641 -248.583867) (xy 339.213665 -248.627904) (xy 339.236791 -248.675925) (xy 339.252501 -248.726855)
			(xy 339.260444 -248.779559) (xy 339.260942 -248.806208) (xy 339.260444 -248.832857) (xy 339.489024 -248.832857)
			(xy 339.489024 -248.779559) (xy 339.496967 -248.726855) (xy 339.512677 -248.675925) (xy 339.535803 -248.627904)
			(xy 339.565827 -248.583867) (xy 339.602079 -248.544796) (xy 339.64375 -248.511565) (xy 339.689908 -248.484916)
			(xy 339.739522 -248.465444) (xy 339.791484 -248.453584) (xy 339.844634 -248.449601) (xy 339.897784 -248.453584)
			(xy 339.949746 -248.465444) (xy 339.99936 -248.484916) (xy 340.045518 -248.511565) (xy 340.087189 -248.544796)
			(xy 340.123441 -248.583867) (xy 340.153465 -248.627904) (xy 340.176591 -248.675925) (xy 340.192301 -248.726855)
			(xy 340.200244 -248.779559) (xy 340.200742 -248.806208) (xy 340.200244 -248.832857) (xy 340.428824 -248.832857)
			(xy 340.428824 -248.779559) (xy 340.436767 -248.726855) (xy 340.452477 -248.675925) (xy 340.475603 -248.627904)
			(xy 340.505627 -248.583867) (xy 340.541879 -248.544796) (xy 340.58355 -248.511565) (xy 340.629708 -248.484916)
			(xy 340.679322 -248.465444) (xy 340.731284 -248.453584) (xy 340.784434 -248.449601) (xy 340.837584 -248.453584)
			(xy 340.889546 -248.465444) (xy 340.93916 -248.484916) (xy 340.985318 -248.511565) (xy 341.026989 -248.544796)
			(xy 341.063241 -248.583867) (xy 341.093265 -248.627904) (xy 341.116391 -248.675925) (xy 341.132101 -248.726855)
			(xy 341.140044 -248.779559) (xy 341.140542 -248.806208) (xy 341.140044 -248.832857) (xy 341.368624 -248.832857)
			(xy 341.368624 -248.779559) (xy 341.376567 -248.726855) (xy 341.392277 -248.675925) (xy 341.415403 -248.627904)
			(xy 341.445427 -248.583867) (xy 341.481679 -248.544796) (xy 341.52335 -248.511565) (xy 341.569508 -248.484916)
			(xy 341.619122 -248.465444) (xy 341.671084 -248.453584) (xy 341.724234 -248.449601) (xy 341.777384 -248.453584)
			(xy 341.829346 -248.465444) (xy 341.87896 -248.484916) (xy 341.925118 -248.511565) (xy 341.966789 -248.544796)
			(xy 342.003041 -248.583867) (xy 342.033065 -248.627904) (xy 342.056191 -248.675925) (xy 342.071901 -248.726855)
			(xy 342.079844 -248.779559) (xy 342.080342 -248.806208) (xy 342.079844 -248.832857) (xy 342.30817 -248.832857)
			(xy 342.30817 -248.779559) (xy 342.316113 -248.726855) (xy 342.331823 -248.675925) (xy 342.354949 -248.627904)
			(xy 342.384973 -248.583867) (xy 342.421225 -248.544796) (xy 342.462896 -248.511565) (xy 342.509054 -248.484916)
			(xy 342.558668 -248.465444) (xy 342.61063 -248.453584) (xy 342.66378 -248.449601) (xy 342.71693 -248.453584)
			(xy 342.768892 -248.465444) (xy 342.818506 -248.484916) (xy 342.864664 -248.511565) (xy 342.906335 -248.544796)
			(xy 342.942587 -248.583867) (xy 342.972611 -248.627904) (xy 342.995737 -248.675925) (xy 343.011447 -248.726855)
			(xy 343.01939 -248.779559) (xy 343.019888 -248.806208) (xy 343.01939 -248.832857) (xy 343.248224 -248.832857)
			(xy 343.248224 -248.779559) (xy 343.256167 -248.726855) (xy 343.271877 -248.675925) (xy 343.295003 -248.627904)
			(xy 343.325027 -248.583867) (xy 343.361279 -248.544796) (xy 343.40295 -248.511565) (xy 343.449108 -248.484916)
			(xy 343.498722 -248.465444) (xy 343.550684 -248.453584) (xy 343.603834 -248.449601) (xy 343.656984 -248.453584)
			(xy 343.708946 -248.465444) (xy 343.75856 -248.484916) (xy 343.804718 -248.511565) (xy 343.846389 -248.544796)
			(xy 343.882641 -248.583867) (xy 343.912665 -248.627904) (xy 343.935791 -248.675925) (xy 343.951501 -248.726855)
			(xy 343.959444 -248.779559) (xy 343.959942 -248.806208) (xy 343.959444 -248.832857) (xy 344.188024 -248.832857)
			(xy 344.188024 -248.779559) (xy 344.195967 -248.726855) (xy 344.211677 -248.675925) (xy 344.234803 -248.627904)
			(xy 344.264827 -248.583867) (xy 344.301079 -248.544796) (xy 344.34275 -248.511565) (xy 344.388908 -248.484916)
			(xy 344.438522 -248.465444) (xy 344.490484 -248.453584) (xy 344.543634 -248.449601) (xy 344.596784 -248.453584)
			(xy 344.648746 -248.465444) (xy 344.69836 -248.484916) (xy 344.744518 -248.511565) (xy 344.786189 -248.544796)
			(xy 344.822441 -248.583867) (xy 344.852465 -248.627904) (xy 344.875591 -248.675925) (xy 344.891301 -248.726855)
			(xy 344.899244 -248.779559) (xy 344.899742 -248.806208) (xy 344.899244 -248.832857) (xy 345.127824 -248.832857)
			(xy 345.127824 -248.779559) (xy 345.135767 -248.726855) (xy 345.151477 -248.675925) (xy 345.174603 -248.627904)
			(xy 345.204627 -248.583867) (xy 345.240879 -248.544796) (xy 345.28255 -248.511565) (xy 345.328708 -248.484916)
			(xy 345.378322 -248.465444) (xy 345.430284 -248.453584) (xy 345.483434 -248.449601) (xy 345.536584 -248.453584)
			(xy 345.588546 -248.465444) (xy 345.63816 -248.484916) (xy 345.684318 -248.511565) (xy 345.725989 -248.544796)
			(xy 345.762241 -248.583867) (xy 345.792265 -248.627904) (xy 345.815391 -248.675925) (xy 345.831101 -248.726855)
			(xy 345.839044 -248.779559) (xy 345.839542 -248.806208) (xy 345.839044 -248.832857) (xy 346.067624 -248.832857)
			(xy 346.067624 -248.779559) (xy 346.075567 -248.726855) (xy 346.091277 -248.675925) (xy 346.114403 -248.627904)
			(xy 346.144427 -248.583867) (xy 346.180679 -248.544796) (xy 346.22235 -248.511565) (xy 346.268508 -248.484916)
			(xy 346.318122 -248.465444) (xy 346.370084 -248.453584) (xy 346.423234 -248.449601) (xy 346.476384 -248.453584)
			(xy 346.528346 -248.465444) (xy 346.57796 -248.484916) (xy 346.624118 -248.511565) (xy 346.665789 -248.544796)
			(xy 346.702041 -248.583867) (xy 346.732065 -248.627904) (xy 346.755191 -248.675925) (xy 346.770901 -248.726855)
			(xy 346.778844 -248.779559) (xy 346.779342 -248.806208) (xy 346.778844 -248.832857) (xy 346.770901 -248.885561)
			(xy 346.755191 -248.936491) (xy 346.732065 -248.984512) (xy 346.702041 -249.028549) (xy 346.665789 -249.06762)
			(xy 346.624118 -249.100851) (xy 346.57796 -249.1275) (xy 346.528346 -249.146972) (xy 346.476384 -249.158832)
			(xy 346.423234 -249.162816) (xy 346.370084 -249.158832) (xy 346.318122 -249.146972) (xy 346.268508 -249.1275)
			(xy 346.22235 -249.100851) (xy 346.180679 -249.06762) (xy 346.144427 -249.028549) (xy 346.114403 -248.984512)
			(xy 346.091277 -248.936491) (xy 346.075567 -248.885561) (xy 346.067624 -248.832857) (xy 345.839044 -248.832857)
			(xy 345.831101 -248.885561) (xy 345.815391 -248.936491) (xy 345.792265 -248.984512) (xy 345.762241 -249.028549)
			(xy 345.725989 -249.06762) (xy 345.684318 -249.100851) (xy 345.63816 -249.1275) (xy 345.588546 -249.146972)
			(xy 345.536584 -249.158832) (xy 345.483434 -249.162816) (xy 345.430284 -249.158832) (xy 345.378322 -249.146972)
			(xy 345.328708 -249.1275) (xy 345.28255 -249.100851) (xy 345.240879 -249.06762) (xy 345.204627 -249.028549)
			(xy 345.174603 -248.984512) (xy 345.151477 -248.936491) (xy 345.135767 -248.885561) (xy 345.127824 -248.832857)
			(xy 344.899244 -248.832857) (xy 344.891301 -248.885561) (xy 344.875591 -248.936491) (xy 344.852465 -248.984512)
			(xy 344.822441 -249.028549) (xy 344.786189 -249.06762) (xy 344.744518 -249.100851) (xy 344.69836 -249.1275)
			(xy 344.648746 -249.146972) (xy 344.596784 -249.158832) (xy 344.543634 -249.162816) (xy 344.490484 -249.158832)
			(xy 344.438522 -249.146972) (xy 344.388908 -249.1275) (xy 344.34275 -249.100851) (xy 344.301079 -249.06762)
			(xy 344.264827 -249.028549) (xy 344.234803 -248.984512) (xy 344.211677 -248.936491) (xy 344.195967 -248.885561)
			(xy 344.188024 -248.832857) (xy 343.959444 -248.832857) (xy 343.951501 -248.885561) (xy 343.935791 -248.936491)
			(xy 343.912665 -248.984512) (xy 343.882641 -249.028549) (xy 343.846389 -249.06762) (xy 343.804718 -249.100851)
			(xy 343.75856 -249.1275) (xy 343.708946 -249.146972) (xy 343.656984 -249.158832) (xy 343.603834 -249.162816)
			(xy 343.550684 -249.158832) (xy 343.498722 -249.146972) (xy 343.449108 -249.1275) (xy 343.40295 -249.100851)
			(xy 343.361279 -249.06762) (xy 343.325027 -249.028549) (xy 343.295003 -248.984512) (xy 343.271877 -248.936491)
			(xy 343.256167 -248.885561) (xy 343.248224 -248.832857) (xy 343.01939 -248.832857) (xy 343.011447 -248.885561)
			(xy 342.995737 -248.936491) (xy 342.972611 -248.984512) (xy 342.942587 -249.028549) (xy 342.906335 -249.06762)
			(xy 342.864664 -249.100851) (xy 342.818506 -249.1275) (xy 342.768892 -249.146972) (xy 342.71693 -249.158832)
			(xy 342.66378 -249.162816) (xy 342.61063 -249.158832) (xy 342.558668 -249.146972) (xy 342.509054 -249.1275)
			(xy 342.462896 -249.100851) (xy 342.421225 -249.06762) (xy 342.384973 -249.028549) (xy 342.354949 -248.984512)
			(xy 342.331823 -248.936491) (xy 342.316113 -248.885561) (xy 342.30817 -248.832857) (xy 342.079844 -248.832857)
			(xy 342.071901 -248.885561) (xy 342.056191 -248.936491) (xy 342.033065 -248.984512) (xy 342.003041 -249.028549)
			(xy 341.966789 -249.06762) (xy 341.925118 -249.100851) (xy 341.87896 -249.1275) (xy 341.829346 -249.146972)
			(xy 341.777384 -249.158832) (xy 341.724234 -249.162816) (xy 341.671084 -249.158832) (xy 341.619122 -249.146972)
			(xy 341.569508 -249.1275) (xy 341.52335 -249.100851) (xy 341.481679 -249.06762) (xy 341.445427 -249.028549)
			(xy 341.415403 -248.984512) (xy 341.392277 -248.936491) (xy 341.376567 -248.885561) (xy 341.368624 -248.832857)
			(xy 341.140044 -248.832857) (xy 341.132101 -248.885561) (xy 341.116391 -248.936491) (xy 341.093265 -248.984512)
			(xy 341.063241 -249.028549) (xy 341.026989 -249.06762) (xy 340.985318 -249.100851) (xy 340.93916 -249.1275)
			(xy 340.889546 -249.146972) (xy 340.837584 -249.158832) (xy 340.784434 -249.162816) (xy 340.731284 -249.158832)
			(xy 340.679322 -249.146972) (xy 340.629708 -249.1275) (xy 340.58355 -249.100851) (xy 340.541879 -249.06762)
			(xy 340.505627 -249.028549) (xy 340.475603 -248.984512) (xy 340.452477 -248.936491) (xy 340.436767 -248.885561)
			(xy 340.428824 -248.832857) (xy 340.200244 -248.832857) (xy 340.192301 -248.885561) (xy 340.176591 -248.936491)
			(xy 340.153465 -248.984512) (xy 340.123441 -249.028549) (xy 340.087189 -249.06762) (xy 340.045518 -249.100851)
			(xy 339.99936 -249.1275) (xy 339.949746 -249.146972) (xy 339.897784 -249.158832) (xy 339.844634 -249.162816)
			(xy 339.791484 -249.158832) (xy 339.739522 -249.146972) (xy 339.689908 -249.1275) (xy 339.64375 -249.100851)
			(xy 339.602079 -249.06762) (xy 339.565827 -249.028549) (xy 339.535803 -248.984512) (xy 339.512677 -248.936491)
			(xy 339.496967 -248.885561) (xy 339.489024 -248.832857) (xy 339.260444 -248.832857) (xy 339.252501 -248.885561)
			(xy 339.236791 -248.936491) (xy 339.213665 -248.984512) (xy 339.183641 -249.028549) (xy 339.147389 -249.06762)
			(xy 339.105718 -249.100851) (xy 339.05956 -249.1275) (xy 339.009946 -249.146972) (xy 338.957984 -249.158832)
			(xy 338.904834 -249.162816) (xy 338.851684 -249.158832) (xy 338.799722 -249.146972) (xy 338.750108 -249.1275)
			(xy 338.70395 -249.100851) (xy 338.662279 -249.06762) (xy 338.626027 -249.028549) (xy 338.596003 -248.984512)
			(xy 338.572877 -248.936491) (xy 338.557167 -248.885561) (xy 338.549224 -248.832857) (xy 338.320644 -248.832857)
			(xy 338.312701 -248.885561) (xy 338.296991 -248.936491) (xy 338.273865 -248.984512) (xy 338.243841 -249.028549)
			(xy 338.207589 -249.06762) (xy 338.165918 -249.100851) (xy 338.11976 -249.1275) (xy 338.070146 -249.146972)
			(xy 338.018184 -249.158832) (xy 337.965034 -249.162816) (xy 337.911884 -249.158832) (xy 337.859922 -249.146972)
			(xy 337.810308 -249.1275) (xy 337.76415 -249.100851) (xy 337.722479 -249.06762) (xy 337.686227 -249.028549)
			(xy 337.656203 -248.984512) (xy 337.633077 -248.936491) (xy 337.617367 -248.885561) (xy 337.609424 -248.832857)
			(xy 337.379802 -248.832857) (xy 337.377817 -248.859345) (xy 337.365959 -248.911303) (xy 337.346489 -248.960914)
			(xy 337.319844 -249.007069) (xy 337.286617 -249.048737) (xy 337.247551 -249.084989) (xy 337.203519 -249.115013)
			(xy 337.155505 -249.13814) (xy 337.104579 -249.153852) (xy 337.051881 -249.1618) (xy 337.025234 -249.162316)
			(xy 337.000539 -249.161917) (xy 336.951617 -249.155132) (xy 336.904104 -249.141646) (xy 336.858913 -249.121719)
			(xy 336.816912 -249.095733) (xy 336.79765 -249.080274) (xy 336.786267 -249.071493) (xy 336.7599 -249.060067)
			(xy 336.731394 -249.056442) (xy 336.703007 -249.060906) (xy 336.676989 -249.073106) (xy 336.655403 -249.092075)
			(xy 336.639959 -249.116308) (xy 336.631882 -249.143885) (xy 336.63128 -249.158252) (xy 336.63128 -249.270266)
			(xy 336.666332 -249.281696) (xy 336.691136 -249.290345) (xy 336.738086 -249.313905) (xy 336.781065 -249.344105)
			(xy 336.819142 -249.380292) (xy 336.85149 -249.421679) (xy 336.877407 -249.467369) (xy 336.896332 -249.516371)
			(xy 336.907853 -249.567621) (xy 336.91172 -249.620008) (xy 336.909751 -249.646673) (xy 337.13927 -249.646673)
			(xy 337.13927 -249.593375) (xy 337.147213 -249.540671) (xy 337.162923 -249.489741) (xy 337.186049 -249.44172)
			(xy 337.216073 -249.397683) (xy 337.252325 -249.358612) (xy 337.293996 -249.325381) (xy 337.340154 -249.298732)
			(xy 337.389768 -249.27926) (xy 337.44173 -249.2674) (xy 337.49488 -249.263417) (xy 337.54803 -249.2674)
			(xy 337.599992 -249.27926) (xy 337.649606 -249.298732) (xy 337.695764 -249.325381) (xy 337.737435 -249.358612)
			(xy 337.773687 -249.397683) (xy 337.803711 -249.44172) (xy 337.826837 -249.489741) (xy 337.842547 -249.540671)
			(xy 337.85049 -249.593375) (xy 337.850988 -249.620024) (xy 337.85049 -249.646673) (xy 338.079324 -249.646673)
			(xy 338.079324 -249.593375) (xy 338.087267 -249.540671) (xy 338.102977 -249.489741) (xy 338.126103 -249.44172)
			(xy 338.156127 -249.397683) (xy 338.192379 -249.358612) (xy 338.23405 -249.325381) (xy 338.280208 -249.298732)
			(xy 338.329822 -249.27926) (xy 338.381784 -249.2674) (xy 338.434934 -249.263417) (xy 338.488084 -249.2674)
			(xy 338.540046 -249.27926) (xy 338.58966 -249.298732) (xy 338.635818 -249.325381) (xy 338.677489 -249.358612)
			(xy 338.713741 -249.397683) (xy 338.743765 -249.44172) (xy 338.766891 -249.489741) (xy 338.782601 -249.540671)
			(xy 338.790544 -249.593375) (xy 338.791042 -249.620024) (xy 338.790544 -249.646673) (xy 339.01887 -249.646673)
			(xy 339.01887 -249.593375) (xy 339.026813 -249.540671) (xy 339.042523 -249.489741) (xy 339.065649 -249.44172)
			(xy 339.095673 -249.397683) (xy 339.131925 -249.358612) (xy 339.173596 -249.325381) (xy 339.219754 -249.298732)
			(xy 339.269368 -249.27926) (xy 339.32133 -249.2674) (xy 339.37448 -249.263417) (xy 339.42763 -249.2674)
			(xy 339.479592 -249.27926) (xy 339.529206 -249.298732) (xy 339.575364 -249.325381) (xy 339.617035 -249.358612)
			(xy 339.653287 -249.397683) (xy 339.683311 -249.44172) (xy 339.706437 -249.489741) (xy 339.722147 -249.540671)
			(xy 339.73009 -249.593375) (xy 339.730588 -249.620024) (xy 339.73009 -249.646673) (xy 339.95867 -249.646673)
			(xy 339.95867 -249.593375) (xy 339.966613 -249.540671) (xy 339.982323 -249.489741) (xy 340.005449 -249.44172)
			(xy 340.035473 -249.397683) (xy 340.071725 -249.358612) (xy 340.113396 -249.325381) (xy 340.159554 -249.298732)
			(xy 340.209168 -249.27926) (xy 340.26113 -249.2674) (xy 340.31428 -249.263417) (xy 340.36743 -249.2674)
			(xy 340.419392 -249.27926) (xy 340.469006 -249.298732) (xy 340.515164 -249.325381) (xy 340.556835 -249.358612)
			(xy 340.593087 -249.397683) (xy 340.623111 -249.44172) (xy 340.646237 -249.489741) (xy 340.661947 -249.540671)
			(xy 340.66989 -249.593375) (xy 340.670388 -249.620024) (xy 340.66989 -249.646673) (xy 340.89847 -249.646673)
			(xy 340.89847 -249.593375) (xy 340.906413 -249.540671) (xy 340.922123 -249.489741) (xy 340.945249 -249.44172)
			(xy 340.975273 -249.397683) (xy 341.011525 -249.358612) (xy 341.053196 -249.325381) (xy 341.099354 -249.298732)
			(xy 341.148968 -249.27926) (xy 341.20093 -249.2674) (xy 341.25408 -249.263417) (xy 341.30723 -249.2674)
			(xy 341.359192 -249.27926) (xy 341.408806 -249.298732) (xy 341.454964 -249.325381) (xy 341.496635 -249.358612)
			(xy 341.532887 -249.397683) (xy 341.562911 -249.44172) (xy 341.586037 -249.489741) (xy 341.601747 -249.540671)
			(xy 341.60969 -249.593375) (xy 341.610188 -249.620024) (xy 341.60969 -249.646673) (xy 341.83827 -249.646673)
			(xy 341.83827 -249.593375) (xy 341.846213 -249.540671) (xy 341.861923 -249.489741) (xy 341.885049 -249.44172)
			(xy 341.915073 -249.397683) (xy 341.951325 -249.358612) (xy 341.992996 -249.325381) (xy 342.039154 -249.298732)
			(xy 342.088768 -249.27926) (xy 342.14073 -249.2674) (xy 342.19388 -249.263417) (xy 342.24703 -249.2674)
			(xy 342.298992 -249.27926) (xy 342.348606 -249.298732) (xy 342.394764 -249.325381) (xy 342.436435 -249.358612)
			(xy 342.472687 -249.397683) (xy 342.502711 -249.44172) (xy 342.525837 -249.489741) (xy 342.541547 -249.540671)
			(xy 342.54949 -249.593375) (xy 342.549988 -249.620024) (xy 342.54949 -249.646673) (xy 342.77807 -249.646673)
			(xy 342.77807 -249.593375) (xy 342.786013 -249.540671) (xy 342.801723 -249.489741) (xy 342.824849 -249.44172)
			(xy 342.854873 -249.397683) (xy 342.891125 -249.358612) (xy 342.932796 -249.325381) (xy 342.978954 -249.298732)
			(xy 343.028568 -249.27926) (xy 343.08053 -249.2674) (xy 343.13368 -249.263417) (xy 343.18683 -249.2674)
			(xy 343.238792 -249.27926) (xy 343.288406 -249.298732) (xy 343.334564 -249.325381) (xy 343.376235 -249.358612)
			(xy 343.412487 -249.397683) (xy 343.442511 -249.44172) (xy 343.465637 -249.489741) (xy 343.481347 -249.540671)
			(xy 343.48929 -249.593375) (xy 343.489788 -249.620024) (xy 343.48929 -249.646673) (xy 343.71787 -249.646673)
			(xy 343.71787 -249.593375) (xy 343.725813 -249.540671) (xy 343.741523 -249.489741) (xy 343.764649 -249.44172)
			(xy 343.794673 -249.397683) (xy 343.830925 -249.358612) (xy 343.872596 -249.325381) (xy 343.918754 -249.298732)
			(xy 343.968368 -249.27926) (xy 344.02033 -249.2674) (xy 344.07348 -249.263417) (xy 344.12663 -249.2674)
			(xy 344.178592 -249.27926) (xy 344.228206 -249.298732) (xy 344.274364 -249.325381) (xy 344.316035 -249.358612)
			(xy 344.352287 -249.397683) (xy 344.382311 -249.44172) (xy 344.405437 -249.489741) (xy 344.421147 -249.540671)
			(xy 344.42909 -249.593375) (xy 344.429588 -249.620024) (xy 344.42909 -249.646673) (xy 344.657924 -249.646673)
			(xy 344.657924 -249.593375) (xy 344.665867 -249.540671) (xy 344.681577 -249.489741) (xy 344.704703 -249.44172)
			(xy 344.734727 -249.397683) (xy 344.770979 -249.358612) (xy 344.81265 -249.325381) (xy 344.858808 -249.298732)
			(xy 344.908422 -249.27926) (xy 344.960384 -249.2674) (xy 345.013534 -249.263417) (xy 345.066684 -249.2674)
			(xy 345.118646 -249.27926) (xy 345.16826 -249.298732) (xy 345.214418 -249.325381) (xy 345.256089 -249.358612)
			(xy 345.292341 -249.397683) (xy 345.322365 -249.44172) (xy 345.345491 -249.489741) (xy 345.361201 -249.540671)
			(xy 345.369144 -249.593375) (xy 345.369642 -249.620024) (xy 345.369144 -249.646673) (xy 345.59747 -249.646673)
			(xy 345.59747 -249.593375) (xy 345.605413 -249.540671) (xy 345.621123 -249.489741) (xy 345.644249 -249.44172)
			(xy 345.674273 -249.397683) (xy 345.710525 -249.358612) (xy 345.752196 -249.325381) (xy 345.798354 -249.298732)
			(xy 345.847968 -249.27926) (xy 345.89993 -249.2674) (xy 345.95308 -249.263417) (xy 346.00623 -249.2674)
			(xy 346.058192 -249.27926) (xy 346.107806 -249.298732) (xy 346.153964 -249.325381) (xy 346.195635 -249.358612)
			(xy 346.231887 -249.397683) (xy 346.261911 -249.44172) (xy 346.285037 -249.489741) (xy 346.300747 -249.540671)
			(xy 346.30869 -249.593375) (xy 346.309188 -249.620024) (xy 346.30869 -249.646673) (xy 346.300747 -249.699377)
			(xy 346.285037 -249.750307) (xy 346.261911 -249.798328) (xy 346.231887 -249.842365) (xy 346.195635 -249.881436)
			(xy 346.153964 -249.914667) (xy 346.107806 -249.941316) (xy 346.058192 -249.960788) (xy 346.00623 -249.972648)
			(xy 345.95308 -249.976632) (xy 345.89993 -249.972648) (xy 345.847968 -249.960788) (xy 345.798354 -249.941316)
			(xy 345.752196 -249.914667) (xy 345.710525 -249.881436) (xy 345.674273 -249.842365) (xy 345.644249 -249.798328)
			(xy 345.621123 -249.750307) (xy 345.605413 -249.699377) (xy 345.59747 -249.646673) (xy 345.369144 -249.646673)
			(xy 345.361201 -249.699377) (xy 345.345491 -249.750307) (xy 345.322365 -249.798328) (xy 345.292341 -249.842365)
			(xy 345.256089 -249.881436) (xy 345.214418 -249.914667) (xy 345.16826 -249.941316) (xy 345.118646 -249.960788)
			(xy 345.066684 -249.972648) (xy 345.013534 -249.976632) (xy 344.960384 -249.972648) (xy 344.908422 -249.960788)
			(xy 344.858808 -249.941316) (xy 344.81265 -249.914667) (xy 344.770979 -249.881436) (xy 344.734727 -249.842365)
			(xy 344.704703 -249.798328) (xy 344.681577 -249.750307) (xy 344.665867 -249.699377) (xy 344.657924 -249.646673)
			(xy 344.42909 -249.646673) (xy 344.421147 -249.699377) (xy 344.405437 -249.750307) (xy 344.382311 -249.798328)
			(xy 344.352287 -249.842365) (xy 344.316035 -249.881436) (xy 344.274364 -249.914667) (xy 344.228206 -249.941316)
			(xy 344.178592 -249.960788) (xy 344.12663 -249.972648) (xy 344.07348 -249.976632) (xy 344.02033 -249.972648)
			(xy 343.968368 -249.960788) (xy 343.918754 -249.941316) (xy 343.872596 -249.914667) (xy 343.830925 -249.881436)
			(xy 343.794673 -249.842365) (xy 343.764649 -249.798328) (xy 343.741523 -249.750307) (xy 343.725813 -249.699377)
			(xy 343.71787 -249.646673) (xy 343.48929 -249.646673) (xy 343.481347 -249.699377) (xy 343.465637 -249.750307)
			(xy 343.442511 -249.798328) (xy 343.412487 -249.842365) (xy 343.376235 -249.881436) (xy 343.334564 -249.914667)
			(xy 343.288406 -249.941316) (xy 343.238792 -249.960788) (xy 343.18683 -249.972648) (xy 343.13368 -249.976632)
			(xy 343.08053 -249.972648) (xy 343.028568 -249.960788) (xy 342.978954 -249.941316) (xy 342.932796 -249.914667)
			(xy 342.891125 -249.881436) (xy 342.854873 -249.842365) (xy 342.824849 -249.798328) (xy 342.801723 -249.750307)
			(xy 342.786013 -249.699377) (xy 342.77807 -249.646673) (xy 342.54949 -249.646673) (xy 342.541547 -249.699377)
			(xy 342.525837 -249.750307) (xy 342.502711 -249.798328) (xy 342.472687 -249.842365) (xy 342.436435 -249.881436)
			(xy 342.394764 -249.914667) (xy 342.348606 -249.941316) (xy 342.298992 -249.960788) (xy 342.24703 -249.972648)
			(xy 342.19388 -249.976632) (xy 342.14073 -249.972648) (xy 342.088768 -249.960788) (xy 342.039154 -249.941316)
			(xy 341.992996 -249.914667) (xy 341.951325 -249.881436) (xy 341.915073 -249.842365) (xy 341.885049 -249.798328)
			(xy 341.861923 -249.750307) (xy 341.846213 -249.699377) (xy 341.83827 -249.646673) (xy 341.60969 -249.646673)
			(xy 341.601747 -249.699377) (xy 341.586037 -249.750307) (xy 341.562911 -249.798328) (xy 341.532887 -249.842365)
			(xy 341.496635 -249.881436) (xy 341.454964 -249.914667) (xy 341.408806 -249.941316) (xy 341.359192 -249.960788)
			(xy 341.30723 -249.972648) (xy 341.25408 -249.976632) (xy 341.20093 -249.972648) (xy 341.148968 -249.960788)
			(xy 341.099354 -249.941316) (xy 341.053196 -249.914667) (xy 341.011525 -249.881436) (xy 340.975273 -249.842365)
			(xy 340.945249 -249.798328) (xy 340.922123 -249.750307) (xy 340.906413 -249.699377) (xy 340.89847 -249.646673)
			(xy 340.66989 -249.646673) (xy 340.661947 -249.699377) (xy 340.646237 -249.750307) (xy 340.623111 -249.798328)
			(xy 340.593087 -249.842365) (xy 340.556835 -249.881436) (xy 340.515164 -249.914667) (xy 340.469006 -249.941316)
			(xy 340.419392 -249.960788) (xy 340.36743 -249.972648) (xy 340.31428 -249.976632) (xy 340.26113 -249.972648)
			(xy 340.209168 -249.960788) (xy 340.159554 -249.941316) (xy 340.113396 -249.914667) (xy 340.071725 -249.881436)
			(xy 340.035473 -249.842365) (xy 340.005449 -249.798328) (xy 339.982323 -249.750307) (xy 339.966613 -249.699377)
			(xy 339.95867 -249.646673) (xy 339.73009 -249.646673) (xy 339.722147 -249.699377) (xy 339.706437 -249.750307)
			(xy 339.683311 -249.798328) (xy 339.653287 -249.842365) (xy 339.617035 -249.881436) (xy 339.575364 -249.914667)
			(xy 339.529206 -249.941316) (xy 339.479592 -249.960788) (xy 339.42763 -249.972648) (xy 339.37448 -249.976632)
			(xy 339.32133 -249.972648) (xy 339.269368 -249.960788) (xy 339.219754 -249.941316) (xy 339.173596 -249.914667)
			(xy 339.131925 -249.881436) (xy 339.095673 -249.842365) (xy 339.065649 -249.798328) (xy 339.042523 -249.750307)
			(xy 339.026813 -249.699377) (xy 339.01887 -249.646673) (xy 338.790544 -249.646673) (xy 338.782601 -249.699377)
			(xy 338.766891 -249.750307) (xy 338.743765 -249.798328) (xy 338.713741 -249.842365) (xy 338.677489 -249.881436)
			(xy 338.635818 -249.914667) (xy 338.58966 -249.941316) (xy 338.540046 -249.960788) (xy 338.488084 -249.972648)
			(xy 338.434934 -249.976632) (xy 338.381784 -249.972648) (xy 338.329822 -249.960788) (xy 338.280208 -249.941316)
			(xy 338.23405 -249.914667) (xy 338.192379 -249.881436) (xy 338.156127 -249.842365) (xy 338.126103 -249.798328)
			(xy 338.102977 -249.750307) (xy 338.087267 -249.699377) (xy 338.079324 -249.646673) (xy 337.85049 -249.646673)
			(xy 337.842547 -249.699377) (xy 337.826837 -249.750307) (xy 337.803711 -249.798328) (xy 337.773687 -249.842365)
			(xy 337.737435 -249.881436) (xy 337.695764 -249.914667) (xy 337.649606 -249.941316) (xy 337.599992 -249.960788)
			(xy 337.54803 -249.972648) (xy 337.49488 -249.976632) (xy 337.44173 -249.972648) (xy 337.389768 -249.960788)
			(xy 337.340154 -249.941316) (xy 337.293996 -249.914667) (xy 337.252325 -249.881436) (xy 337.216073 -249.842365)
			(xy 337.186049 -249.798328) (xy 337.162923 -249.750307) (xy 337.147213 -249.699377) (xy 337.13927 -249.646673)
			(xy 336.909751 -249.646673) (xy 336.907851 -249.672394) (xy 336.896327 -249.723643) (xy 336.877401 -249.772644)
			(xy 336.851481 -249.818334) (xy 336.819132 -249.859719) (xy 336.781053 -249.895904) (xy 336.738073 -249.926103)
			(xy 336.691122 -249.949661) (xy 336.666332 -249.958352) (xy 336.63128 -249.969782) (xy 336.63128 -253.132569)
			(xy 342.887798 -253.132569) (xy 342.887798 -253.079271) (xy 342.895741 -253.026567) (xy 342.911451 -252.975637)
			(xy 342.934577 -252.927616) (xy 342.964601 -252.883579) (xy 343.000853 -252.844508) (xy 343.042524 -252.811277)
			(xy 343.088682 -252.784628) (xy 343.138296 -252.765156) (xy 343.190258 -252.753296) (xy 343.243408 -252.749313)
			(xy 343.296558 -252.753296) (xy 343.34852 -252.765156) (xy 343.398134 -252.784628) (xy 343.444292 -252.811277)
			(xy 343.485963 -252.844508) (xy 343.522215 -252.883579) (xy 343.552239 -252.927616) (xy 343.575365 -252.975637)
			(xy 343.591075 -253.026567) (xy 343.599018 -253.079271) (xy 343.599516 -253.10592) (xy 343.599018 -253.132569)
			(xy 343.591075 -253.185273) (xy 343.575365 -253.236203) (xy 343.552239 -253.284224) (xy 343.522215 -253.328261)
			(xy 343.485963 -253.367332) (xy 343.444292 -253.400563) (xy 343.398134 -253.427212) (xy 343.34852 -253.446684)
			(xy 343.296558 -253.458544) (xy 343.243408 -253.462528) (xy 343.190258 -253.458544) (xy 343.138296 -253.446684)
			(xy 343.088682 -253.427212) (xy 343.042524 -253.400563) (xy 343.000853 -253.367332) (xy 342.964601 -253.328261)
			(xy 342.934577 -253.284224) (xy 342.911451 -253.236203) (xy 342.895741 -253.185273) (xy 342.887798 -253.132569)
			(xy 336.63128 -253.132569) (xy 336.63128 -253.946385) (xy 336.779352 -253.946385) (xy 336.779352 -253.893087)
			(xy 336.787295 -253.840383) (xy 336.803005 -253.789453) (xy 336.826131 -253.741432) (xy 336.856155 -253.697395)
			(xy 336.892407 -253.658324) (xy 336.934078 -253.625093) (xy 336.980236 -253.598444) (xy 337.02985 -253.578972)
			(xy 337.081812 -253.567112) (xy 337.134962 -253.563129) (xy 337.188112 -253.567112) (xy 337.240074 -253.578972)
			(xy 337.289688 -253.598444) (xy 337.335846 -253.625093) (xy 337.377517 -253.658324) (xy 337.413769 -253.697395)
			(xy 337.443793 -253.741432) (xy 337.466919 -253.789453) (xy 337.482629 -253.840383) (xy 337.490572 -253.893087)
			(xy 337.49107 -253.919736) (xy 337.490572 -253.946385) (xy 337.719152 -253.946385) (xy 337.719152 -253.893087)
			(xy 337.727095 -253.840383) (xy 337.742805 -253.789453) (xy 337.765931 -253.741432) (xy 337.795955 -253.697395)
			(xy 337.832207 -253.658324) (xy 337.873878 -253.625093) (xy 337.920036 -253.598444) (xy 337.96965 -253.578972)
			(xy 338.021612 -253.567112) (xy 338.074762 -253.563129) (xy 338.127912 -253.567112) (xy 338.179874 -253.578972)
			(xy 338.229488 -253.598444) (xy 338.275646 -253.625093) (xy 338.317317 -253.658324) (xy 338.353569 -253.697395)
			(xy 338.383593 -253.741432) (xy 338.406719 -253.789453) (xy 338.422429 -253.840383) (xy 338.430372 -253.893087)
			(xy 338.43087 -253.919736) (xy 338.430372 -253.946385) (xy 338.659206 -253.946385) (xy 338.659206 -253.893087)
			(xy 338.667149 -253.840383) (xy 338.682859 -253.789453) (xy 338.705985 -253.741432) (xy 338.736009 -253.697395)
			(xy 338.772261 -253.658324) (xy 338.813932 -253.625093) (xy 338.86009 -253.598444) (xy 338.909704 -253.578972)
			(xy 338.961666 -253.567112) (xy 339.014816 -253.563129) (xy 339.067966 -253.567112) (xy 339.119928 -253.578972)
			(xy 339.169542 -253.598444) (xy 339.2157 -253.625093) (xy 339.257371 -253.658324) (xy 339.293623 -253.697395)
			(xy 339.323647 -253.741432) (xy 339.346773 -253.789453) (xy 339.362483 -253.840383) (xy 339.370426 -253.893087)
			(xy 339.370924 -253.919736) (xy 339.370426 -253.946385) (xy 339.599006 -253.946385) (xy 339.599006 -253.893087)
			(xy 339.606949 -253.840383) (xy 339.622659 -253.789453) (xy 339.645785 -253.741432) (xy 339.675809 -253.697395)
			(xy 339.712061 -253.658324) (xy 339.753732 -253.625093) (xy 339.79989 -253.598444) (xy 339.849504 -253.578972)
			(xy 339.901466 -253.567112) (xy 339.954616 -253.563129) (xy 340.007766 -253.567112) (xy 340.059728 -253.578972)
			(xy 340.109342 -253.598444) (xy 340.1555 -253.625093) (xy 340.197171 -253.658324) (xy 340.233423 -253.697395)
			(xy 340.263447 -253.741432) (xy 340.286573 -253.789453) (xy 340.302283 -253.840383) (xy 340.310226 -253.893087)
			(xy 340.310724 -253.919736) (xy 340.310226 -253.946385) (xy 340.538806 -253.946385) (xy 340.538806 -253.893087)
			(xy 340.546749 -253.840383) (xy 340.562459 -253.789453) (xy 340.585585 -253.741432) (xy 340.615609 -253.697395)
			(xy 340.651861 -253.658324) (xy 340.693532 -253.625093) (xy 340.73969 -253.598444) (xy 340.789304 -253.578972)
			(xy 340.841266 -253.567112) (xy 340.894416 -253.563129) (xy 340.947566 -253.567112) (xy 340.999528 -253.578972)
			(xy 341.049142 -253.598444) (xy 341.0953 -253.625093) (xy 341.136971 -253.658324) (xy 341.173223 -253.697395)
			(xy 341.203247 -253.741432) (xy 341.226373 -253.789453) (xy 341.242083 -253.840383) (xy 341.250026 -253.893087)
			(xy 341.250524 -253.919736) (xy 341.250026 -253.946385) (xy 341.478606 -253.946385) (xy 341.478606 -253.893087)
			(xy 341.486549 -253.840383) (xy 341.502259 -253.789453) (xy 341.525385 -253.741432) (xy 341.555409 -253.697395)
			(xy 341.591661 -253.658324) (xy 341.633332 -253.625093) (xy 341.67949 -253.598444) (xy 341.729104 -253.578972)
			(xy 341.781066 -253.567112) (xy 341.834216 -253.563129) (xy 341.887366 -253.567112) (xy 341.939328 -253.578972)
			(xy 341.988942 -253.598444) (xy 342.0351 -253.625093) (xy 342.076771 -253.658324) (xy 342.113023 -253.697395)
			(xy 342.143047 -253.741432) (xy 342.166173 -253.789453) (xy 342.181883 -253.840383) (xy 342.189826 -253.893087)
			(xy 342.190324 -253.919736) (xy 342.189826 -253.946385) (xy 342.418152 -253.946385) (xy 342.418152 -253.893087)
			(xy 342.426095 -253.840383) (xy 342.441805 -253.789453) (xy 342.464931 -253.741432) (xy 342.494955 -253.697395)
			(xy 342.531207 -253.658324) (xy 342.572878 -253.625093) (xy 342.619036 -253.598444) (xy 342.66865 -253.578972)
			(xy 342.720612 -253.567112) (xy 342.773762 -253.563129) (xy 342.826912 -253.567112) (xy 342.878874 -253.578972)
			(xy 342.928488 -253.598444) (xy 342.974646 -253.625093) (xy 343.016317 -253.658324) (xy 343.052569 -253.697395)
			(xy 343.082593 -253.741432) (xy 343.105719 -253.789453) (xy 343.121429 -253.840383) (xy 343.129372 -253.893087)
			(xy 343.12987 -253.919736) (xy 343.129372 -253.946385) (xy 343.358206 -253.946385) (xy 343.358206 -253.893087)
			(xy 343.366149 -253.840383) (xy 343.381859 -253.789453) (xy 343.404985 -253.741432) (xy 343.435009 -253.697395)
			(xy 343.471261 -253.658324) (xy 343.512932 -253.625093) (xy 343.55909 -253.598444) (xy 343.608704 -253.578972)
			(xy 343.660666 -253.567112) (xy 343.713816 -253.563129) (xy 343.766966 -253.567112) (xy 343.818928 -253.578972)
			(xy 343.868542 -253.598444) (xy 343.9147 -253.625093) (xy 343.956371 -253.658324) (xy 343.992623 -253.697395)
			(xy 344.022647 -253.741432) (xy 344.045773 -253.789453) (xy 344.061483 -253.840383) (xy 344.069426 -253.893087)
			(xy 344.069924 -253.919736) (xy 344.069426 -253.946385) (xy 344.298006 -253.946385) (xy 344.298006 -253.893087)
			(xy 344.305949 -253.840383) (xy 344.321659 -253.789453) (xy 344.344785 -253.741432) (xy 344.374809 -253.697395)
			(xy 344.411061 -253.658324) (xy 344.452732 -253.625093) (xy 344.49889 -253.598444) (xy 344.548504 -253.578972)
			(xy 344.600466 -253.567112) (xy 344.653616 -253.563129) (xy 344.706766 -253.567112) (xy 344.758728 -253.578972)
			(xy 344.808342 -253.598444) (xy 344.8545 -253.625093) (xy 344.896171 -253.658324) (xy 344.932423 -253.697395)
			(xy 344.962447 -253.741432) (xy 344.985573 -253.789453) (xy 345.001283 -253.840383) (xy 345.009226 -253.893087)
			(xy 345.009724 -253.919736) (xy 345.009226 -253.946385) (xy 345.237806 -253.946385) (xy 345.237806 -253.893087)
			(xy 345.245749 -253.840383) (xy 345.261459 -253.789453) (xy 345.284585 -253.741432) (xy 345.314609 -253.697395)
			(xy 345.350861 -253.658324) (xy 345.392532 -253.625093) (xy 345.43869 -253.598444) (xy 345.488304 -253.578972)
			(xy 345.540266 -253.567112) (xy 345.593416 -253.563129) (xy 345.646566 -253.567112) (xy 345.698528 -253.578972)
			(xy 345.748142 -253.598444) (xy 345.7943 -253.625093) (xy 345.835971 -253.658324) (xy 345.872223 -253.697395)
			(xy 345.902247 -253.741432) (xy 345.925373 -253.789453) (xy 345.941083 -253.840383) (xy 345.949026 -253.893087)
			(xy 345.949524 -253.919736) (xy 345.949026 -253.946385) (xy 346.177606 -253.946385) (xy 346.177606 -253.893087)
			(xy 346.185549 -253.840383) (xy 346.201259 -253.789453) (xy 346.224385 -253.741432) (xy 346.254409 -253.697395)
			(xy 346.290661 -253.658324) (xy 346.332332 -253.625093) (xy 346.37849 -253.598444) (xy 346.428104 -253.578972)
			(xy 346.480066 -253.567112) (xy 346.533216 -253.563129) (xy 346.586366 -253.567112) (xy 346.638328 -253.578972)
			(xy 346.687942 -253.598444) (xy 346.7341 -253.625093) (xy 346.775771 -253.658324) (xy 346.812023 -253.697395)
			(xy 346.842047 -253.741432) (xy 346.865173 -253.789453) (xy 346.880883 -253.840383) (xy 346.888826 -253.893087)
			(xy 346.889324 -253.919736) (xy 346.888826 -253.946385) (xy 346.880883 -253.999089) (xy 346.865173 -254.050019)
			(xy 346.842047 -254.09804) (xy 346.812023 -254.142077) (xy 346.775771 -254.181148) (xy 346.7341 -254.214379)
			(xy 346.687942 -254.241028) (xy 346.638328 -254.2605) (xy 346.586366 -254.27236) (xy 346.533216 -254.276344)
			(xy 346.480066 -254.27236) (xy 346.428104 -254.2605) (xy 346.37849 -254.241028) (xy 346.332332 -254.214379)
			(xy 346.290661 -254.181148) (xy 346.254409 -254.142077) (xy 346.224385 -254.09804) (xy 346.201259 -254.050019)
			(xy 346.185549 -253.999089) (xy 346.177606 -253.946385) (xy 345.949026 -253.946385) (xy 345.941083 -253.999089)
			(xy 345.925373 -254.050019) (xy 345.902247 -254.09804) (xy 345.872223 -254.142077) (xy 345.835971 -254.181148)
			(xy 345.7943 -254.214379) (xy 345.748142 -254.241028) (xy 345.698528 -254.2605) (xy 345.646566 -254.27236)
			(xy 345.593416 -254.276344) (xy 345.540266 -254.27236) (xy 345.488304 -254.2605) (xy 345.43869 -254.241028)
			(xy 345.392532 -254.214379) (xy 345.350861 -254.181148) (xy 345.314609 -254.142077) (xy 345.284585 -254.09804)
			(xy 345.261459 -254.050019) (xy 345.245749 -253.999089) (xy 345.237806 -253.946385) (xy 345.009226 -253.946385)
			(xy 345.001283 -253.999089) (xy 344.985573 -254.050019) (xy 344.962447 -254.09804) (xy 344.932423 -254.142077)
			(xy 344.896171 -254.181148) (xy 344.8545 -254.214379) (xy 344.808342 -254.241028) (xy 344.758728 -254.2605)
			(xy 344.706766 -254.27236) (xy 344.653616 -254.276344) (xy 344.600466 -254.27236) (xy 344.548504 -254.2605)
			(xy 344.49889 -254.241028) (xy 344.452732 -254.214379) (xy 344.411061 -254.181148) (xy 344.374809 -254.142077)
			(xy 344.344785 -254.09804) (xy 344.321659 -254.050019) (xy 344.305949 -253.999089) (xy 344.298006 -253.946385)
			(xy 344.069426 -253.946385) (xy 344.061483 -253.999089) (xy 344.045773 -254.050019) (xy 344.022647 -254.09804)
			(xy 343.992623 -254.142077) (xy 343.956371 -254.181148) (xy 343.9147 -254.214379) (xy 343.868542 -254.241028)
			(xy 343.818928 -254.2605) (xy 343.766966 -254.27236) (xy 343.713816 -254.276344) (xy 343.660666 -254.27236)
			(xy 343.608704 -254.2605) (xy 343.55909 -254.241028) (xy 343.512932 -254.214379) (xy 343.471261 -254.181148)
			(xy 343.435009 -254.142077) (xy 343.404985 -254.09804) (xy 343.381859 -254.050019) (xy 343.366149 -253.999089)
			(xy 343.358206 -253.946385) (xy 343.129372 -253.946385) (xy 343.121429 -253.999089) (xy 343.105719 -254.050019)
			(xy 343.082593 -254.09804) (xy 343.052569 -254.142077) (xy 343.016317 -254.181148) (xy 342.974646 -254.214379)
			(xy 342.928488 -254.241028) (xy 342.878874 -254.2605) (xy 342.826912 -254.27236) (xy 342.773762 -254.276344)
			(xy 342.720612 -254.27236) (xy 342.66865 -254.2605) (xy 342.619036 -254.241028) (xy 342.572878 -254.214379)
			(xy 342.531207 -254.181148) (xy 342.494955 -254.142077) (xy 342.464931 -254.09804) (xy 342.441805 -254.050019)
			(xy 342.426095 -253.999089) (xy 342.418152 -253.946385) (xy 342.189826 -253.946385) (xy 342.181883 -253.999089)
			(xy 342.166173 -254.050019) (xy 342.143047 -254.09804) (xy 342.113023 -254.142077) (xy 342.076771 -254.181148)
			(xy 342.0351 -254.214379) (xy 341.988942 -254.241028) (xy 341.939328 -254.2605) (xy 341.887366 -254.27236)
			(xy 341.834216 -254.276344) (xy 341.781066 -254.27236) (xy 341.729104 -254.2605) (xy 341.67949 -254.241028)
			(xy 341.633332 -254.214379) (xy 341.591661 -254.181148) (xy 341.555409 -254.142077) (xy 341.525385 -254.09804)
			(xy 341.502259 -254.050019) (xy 341.486549 -253.999089) (xy 341.478606 -253.946385) (xy 341.250026 -253.946385)
			(xy 341.242083 -253.999089) (xy 341.226373 -254.050019) (xy 341.203247 -254.09804) (xy 341.173223 -254.142077)
			(xy 341.136971 -254.181148) (xy 341.0953 -254.214379) (xy 341.049142 -254.241028) (xy 340.999528 -254.2605)
			(xy 340.947566 -254.27236) (xy 340.894416 -254.276344) (xy 340.841266 -254.27236) (xy 340.789304 -254.2605)
			(xy 340.73969 -254.241028) (xy 340.693532 -254.214379) (xy 340.651861 -254.181148) (xy 340.615609 -254.142077)
			(xy 340.585585 -254.09804) (xy 340.562459 -254.050019) (xy 340.546749 -253.999089) (xy 340.538806 -253.946385)
			(xy 340.310226 -253.946385) (xy 340.302283 -253.999089) (xy 340.286573 -254.050019) (xy 340.263447 -254.09804)
			(xy 340.233423 -254.142077) (xy 340.197171 -254.181148) (xy 340.1555 -254.214379) (xy 340.109342 -254.241028)
			(xy 340.059728 -254.2605) (xy 340.007766 -254.27236) (xy 339.954616 -254.276344) (xy 339.901466 -254.27236)
			(xy 339.849504 -254.2605) (xy 339.79989 -254.241028) (xy 339.753732 -254.214379) (xy 339.712061 -254.181148)
			(xy 339.675809 -254.142077) (xy 339.645785 -254.09804) (xy 339.622659 -254.050019) (xy 339.606949 -253.999089)
			(xy 339.599006 -253.946385) (xy 339.370426 -253.946385) (xy 339.362483 -253.999089) (xy 339.346773 -254.050019)
			(xy 339.323647 -254.09804) (xy 339.293623 -254.142077) (xy 339.257371 -254.181148) (xy 339.2157 -254.214379)
			(xy 339.169542 -254.241028) (xy 339.119928 -254.2605) (xy 339.067966 -254.27236) (xy 339.014816 -254.276344)
			(xy 338.961666 -254.27236) (xy 338.909704 -254.2605) (xy 338.86009 -254.241028) (xy 338.813932 -254.214379)
			(xy 338.772261 -254.181148) (xy 338.736009 -254.142077) (xy 338.705985 -254.09804) (xy 338.682859 -254.050019)
			(xy 338.667149 -253.999089) (xy 338.659206 -253.946385) (xy 338.430372 -253.946385) (xy 338.422429 -253.999089)
			(xy 338.406719 -254.050019) (xy 338.383593 -254.09804) (xy 338.353569 -254.142077) (xy 338.317317 -254.181148)
			(xy 338.275646 -254.214379) (xy 338.229488 -254.241028) (xy 338.179874 -254.2605) (xy 338.127912 -254.27236)
			(xy 338.074762 -254.276344) (xy 338.021612 -254.27236) (xy 337.96965 -254.2605) (xy 337.920036 -254.241028)
			(xy 337.873878 -254.214379) (xy 337.832207 -254.181148) (xy 337.795955 -254.142077) (xy 337.765931 -254.09804)
			(xy 337.742805 -254.050019) (xy 337.727095 -253.999089) (xy 337.719152 -253.946385) (xy 337.490572 -253.946385)
			(xy 337.482629 -253.999089) (xy 337.466919 -254.050019) (xy 337.443793 -254.09804) (xy 337.413769 -254.142077)
			(xy 337.377517 -254.181148) (xy 337.335846 -254.214379) (xy 337.289688 -254.241028) (xy 337.240074 -254.2605)
			(xy 337.188112 -254.27236) (xy 337.134962 -254.276344) (xy 337.081812 -254.27236) (xy 337.02985 -254.2605)
			(xy 336.980236 -254.241028) (xy 336.934078 -254.214379) (xy 336.892407 -254.181148) (xy 336.856155 -254.142077)
			(xy 336.826131 -254.09804) (xy 336.803005 -254.050019) (xy 336.787295 -253.999089) (xy 336.779352 -253.946385)
			(xy 336.63128 -253.946385) (xy 336.63128 -254.326898) (xy 336.631716 -254.336663) (xy 336.638998 -254.354783)
			(xy 336.652511 -254.368882) (xy 336.670307 -254.376925) (xy 336.680048 -254.377698) (xy 336.707245 -254.379358)
			(xy 336.7607 -254.389908) (xy 336.811924 -254.408476) (xy 336.859724 -254.434627) (xy 336.902984 -254.467753)
			(xy 336.940694 -254.50708) (xy 336.971975 -254.551692) (xy 336.996098 -254.600546) (xy 337.0125 -254.652505)
			(xy 337.020798 -254.706355) (xy 337.020798 -254.760201) (xy 337.249252 -254.760201) (xy 337.249252 -254.706903)
			(xy 337.257195 -254.654199) (xy 337.272905 -254.603269) (xy 337.296031 -254.555248) (xy 337.326055 -254.511211)
			(xy 337.362307 -254.47214) (xy 337.403978 -254.438909) (xy 337.450136 -254.41226) (xy 337.49975 -254.392788)
			(xy 337.551712 -254.380928) (xy 337.604862 -254.376945) (xy 337.658012 -254.380928) (xy 337.709974 -254.392788)
			(xy 337.759588 -254.41226) (xy 337.805746 -254.438909) (xy 337.847417 -254.47214) (xy 337.883669 -254.511211)
			(xy 337.913693 -254.555248) (xy 337.936819 -254.603269) (xy 337.952529 -254.654199) (xy 337.960472 -254.706903)
			(xy 337.96097 -254.733552) (xy 337.960472 -254.760201) (xy 338.189052 -254.760201) (xy 338.189052 -254.706903)
			(xy 338.196995 -254.654199) (xy 338.212705 -254.603269) (xy 338.235831 -254.555248) (xy 338.265855 -254.511211)
			(xy 338.302107 -254.47214) (xy 338.343778 -254.438909) (xy 338.389936 -254.41226) (xy 338.43955 -254.392788)
			(xy 338.491512 -254.380928) (xy 338.544662 -254.376945) (xy 338.597812 -254.380928) (xy 338.649774 -254.392788)
			(xy 338.699388 -254.41226) (xy 338.745546 -254.438909) (xy 338.787217 -254.47214) (xy 338.823469 -254.511211)
			(xy 338.853493 -254.555248) (xy 338.876619 -254.603269) (xy 338.892329 -254.654199) (xy 338.900272 -254.706903)
			(xy 338.90077 -254.733552) (xy 338.900272 -254.760201) (xy 339.129106 -254.760201) (xy 339.129106 -254.706903)
			(xy 339.137049 -254.654199) (xy 339.152759 -254.603269) (xy 339.175885 -254.555248) (xy 339.205909 -254.511211)
			(xy 339.242161 -254.47214) (xy 339.283832 -254.438909) (xy 339.32999 -254.41226) (xy 339.379604 -254.392788)
			(xy 339.431566 -254.380928) (xy 339.484716 -254.376945) (xy 339.537866 -254.380928) (xy 339.589828 -254.392788)
			(xy 339.639442 -254.41226) (xy 339.6856 -254.438909) (xy 339.727271 -254.47214) (xy 339.763523 -254.511211)
			(xy 339.793547 -254.555248) (xy 339.816673 -254.603269) (xy 339.832383 -254.654199) (xy 339.840326 -254.706903)
			(xy 339.840824 -254.733552) (xy 339.840326 -254.760201) (xy 340.068652 -254.760201) (xy 340.068652 -254.706903)
			(xy 340.076595 -254.654199) (xy 340.092305 -254.603269) (xy 340.115431 -254.555248) (xy 340.145455 -254.511211)
			(xy 340.181707 -254.47214) (xy 340.223378 -254.438909) (xy 340.269536 -254.41226) (xy 340.31915 -254.392788)
			(xy 340.371112 -254.380928) (xy 340.424262 -254.376945) (xy 340.477412 -254.380928) (xy 340.529374 -254.392788)
			(xy 340.578988 -254.41226) (xy 340.625146 -254.438909) (xy 340.666817 -254.47214) (xy 340.703069 -254.511211)
			(xy 340.733093 -254.555248) (xy 340.756219 -254.603269) (xy 340.771929 -254.654199) (xy 340.779872 -254.706903)
			(xy 340.78037 -254.733552) (xy 341.020149 -254.733552) (xy 341.024179 -254.681054) (xy 341.036176 -254.629786)
			(xy 341.055859 -254.580951) (xy 341.082765 -254.535692) (xy 341.116265 -254.495071) (xy 341.155573 -254.46004)
			(xy 341.199768 -254.43142) (xy 341.247813 -254.409881) (xy 341.298584 -254.395929) (xy 341.350889 -254.389891)
			(xy 341.403503 -254.391908) (xy 341.455193 -254.401932) (xy 341.504746 -254.41973) (xy 341.551002 -254.444883)
			(xy 341.592876 -254.476802) (xy 341.629388 -254.51474) (xy 341.65968 -254.557806) (xy 341.683043 -254.604991)
			(xy 341.698929 -254.65519) (xy 341.706966 -254.707226) (xy 341.70747 -254.733552) (xy 341.959949 -254.733552)
			(xy 341.963979 -254.681054) (xy 341.975976 -254.629786) (xy 341.995659 -254.580951) (xy 342.022565 -254.535692)
			(xy 342.056065 -254.495071) (xy 342.095373 -254.46004) (xy 342.139568 -254.43142) (xy 342.187613 -254.409881)
			(xy 342.238384 -254.395929) (xy 342.290689 -254.389891) (xy 342.343303 -254.391908) (xy 342.394993 -254.401932)
			(xy 342.444546 -254.41973) (xy 342.490802 -254.444883) (xy 342.532676 -254.476802) (xy 342.569188 -254.51474)
			(xy 342.59948 -254.557806) (xy 342.622843 -254.604991) (xy 342.638729 -254.65519) (xy 342.646766 -254.707226)
			(xy 342.64727 -254.733552) (xy 342.646766 -254.759878) (xy 342.646716 -254.760201) (xy 342.888052 -254.760201)
			(xy 342.888052 -254.706903) (xy 342.895995 -254.654199) (xy 342.911705 -254.603269) (xy 342.934831 -254.555248)
			(xy 342.964855 -254.511211) (xy 343.001107 -254.47214) (xy 343.042778 -254.438909) (xy 343.088936 -254.41226)
			(xy 343.13855 -254.392788) (xy 343.190512 -254.380928) (xy 343.243662 -254.376945) (xy 343.296812 -254.380928)
			(xy 343.348774 -254.392788) (xy 343.398388 -254.41226) (xy 343.444546 -254.438909) (xy 343.486217 -254.47214)
			(xy 343.522469 -254.511211) (xy 343.552493 -254.555248) (xy 343.575619 -254.603269) (xy 343.591329 -254.654199)
			(xy 343.599272 -254.706903) (xy 343.59977 -254.733552) (xy 343.599272 -254.760201) (xy 343.827852 -254.760201)
			(xy 343.827852 -254.706903) (xy 343.835795 -254.654199) (xy 343.851505 -254.603269) (xy 343.874631 -254.555248)
			(xy 343.904655 -254.511211) (xy 343.940907 -254.47214) (xy 343.982578 -254.438909) (xy 344.028736 -254.41226)
			(xy 344.07835 -254.392788) (xy 344.130312 -254.380928) (xy 344.183462 -254.376945) (xy 344.236612 -254.380928)
			(xy 344.288574 -254.392788) (xy 344.338188 -254.41226) (xy 344.384346 -254.438909) (xy 344.426017 -254.47214)
			(xy 344.462269 -254.511211) (xy 344.492293 -254.555248) (xy 344.515419 -254.603269) (xy 344.531129 -254.654199)
			(xy 344.539072 -254.706903) (xy 344.53957 -254.733552) (xy 344.539072 -254.760201) (xy 344.767652 -254.760201)
			(xy 344.767652 -254.706903) (xy 344.775595 -254.654199) (xy 344.791305 -254.603269) (xy 344.814431 -254.555248)
			(xy 344.844455 -254.511211) (xy 344.880707 -254.47214) (xy 344.922378 -254.438909) (xy 344.968536 -254.41226)
			(xy 345.01815 -254.392788) (xy 345.070112 -254.380928) (xy 345.123262 -254.376945) (xy 345.176412 -254.380928)
			(xy 345.228374 -254.392788) (xy 345.277988 -254.41226) (xy 345.324146 -254.438909) (xy 345.365817 -254.47214)
			(xy 345.402069 -254.511211) (xy 345.432093 -254.555248) (xy 345.455219 -254.603269) (xy 345.470929 -254.654199)
			(xy 345.478872 -254.706903) (xy 345.47937 -254.733552) (xy 345.478872 -254.760201) (xy 345.707706 -254.760201)
			(xy 345.707706 -254.706903) (xy 345.715649 -254.654199) (xy 345.731359 -254.603269) (xy 345.754485 -254.555248)
			(xy 345.784509 -254.511211) (xy 345.820761 -254.47214) (xy 345.862432 -254.438909) (xy 345.90859 -254.41226)
			(xy 345.958204 -254.392788) (xy 346.010166 -254.380928) (xy 346.063316 -254.376945) (xy 346.116466 -254.380928)
			(xy 346.168428 -254.392788) (xy 346.218042 -254.41226) (xy 346.2642 -254.438909) (xy 346.305871 -254.47214)
			(xy 346.342123 -254.511211) (xy 346.372147 -254.555248) (xy 346.395273 -254.603269) (xy 346.410983 -254.654199)
			(xy 346.418926 -254.706903) (xy 346.419424 -254.733552) (xy 346.418926 -254.760201) (xy 346.410983 -254.812905)
			(xy 346.395273 -254.863835) (xy 346.372147 -254.911856) (xy 346.342123 -254.955893) (xy 346.305871 -254.994964)
			(xy 346.2642 -255.028195) (xy 346.218042 -255.054844) (xy 346.168428 -255.074316) (xy 346.116466 -255.086176)
			(xy 346.063316 -255.09016) (xy 346.010166 -255.086176) (xy 345.958204 -255.074316) (xy 345.90859 -255.054844)
			(xy 345.862432 -255.028195) (xy 345.820761 -254.994964) (xy 345.784509 -254.955893) (xy 345.754485 -254.911856)
			(xy 345.731359 -254.863835) (xy 345.715649 -254.812905) (xy 345.707706 -254.760201) (xy 345.478872 -254.760201)
			(xy 345.470929 -254.812905) (xy 345.455219 -254.863835) (xy 345.432093 -254.911856) (xy 345.402069 -254.955893)
			(xy 345.365817 -254.994964) (xy 345.324146 -255.028195) (xy 345.277988 -255.054844) (xy 345.228374 -255.074316)
			(xy 345.176412 -255.086176) (xy 345.123262 -255.09016) (xy 345.070112 -255.086176) (xy 345.01815 -255.074316)
			(xy 344.968536 -255.054844) (xy 344.922378 -255.028195) (xy 344.880707 -254.994964) (xy 344.844455 -254.955893)
			(xy 344.814431 -254.911856) (xy 344.791305 -254.863835) (xy 344.775595 -254.812905) (xy 344.767652 -254.760201)
			(xy 344.539072 -254.760201) (xy 344.531129 -254.812905) (xy 344.515419 -254.863835) (xy 344.492293 -254.911856)
			(xy 344.462269 -254.955893) (xy 344.426017 -254.994964) (xy 344.384346 -255.028195) (xy 344.338188 -255.054844)
			(xy 344.288574 -255.074316) (xy 344.236612 -255.086176) (xy 344.183462 -255.09016) (xy 344.130312 -255.086176)
			(xy 344.07835 -255.074316) (xy 344.028736 -255.054844) (xy 343.982578 -255.028195) (xy 343.940907 -254.994964)
			(xy 343.904655 -254.955893) (xy 343.874631 -254.911856) (xy 343.851505 -254.863835) (xy 343.835795 -254.812905)
			(xy 343.827852 -254.760201) (xy 343.599272 -254.760201) (xy 343.591329 -254.812905) (xy 343.575619 -254.863835)
			(xy 343.552493 -254.911856) (xy 343.522469 -254.955893) (xy 343.486217 -254.994964) (xy 343.444546 -255.028195)
			(xy 343.398388 -255.054844) (xy 343.348774 -255.074316) (xy 343.296812 -255.086176) (xy 343.243662 -255.09016)
			(xy 343.190512 -255.086176) (xy 343.13855 -255.074316) (xy 343.088936 -255.054844) (xy 343.042778 -255.028195)
			(xy 343.001107 -254.994964) (xy 342.964855 -254.955893) (xy 342.934831 -254.911856) (xy 342.911705 -254.863835)
			(xy 342.895995 -254.812905) (xy 342.888052 -254.760201) (xy 342.646716 -254.760201) (xy 342.638729 -254.811914)
			(xy 342.622843 -254.862113) (xy 342.59948 -254.909298) (xy 342.569188 -254.952364) (xy 342.532676 -254.990302)
			(xy 342.490802 -255.022221) (xy 342.444546 -255.047374) (xy 342.394993 -255.065172) (xy 342.343303 -255.075196)
			(xy 342.290689 -255.077213) (xy 342.238384 -255.071175) (xy 342.187613 -255.057223) (xy 342.139568 -255.035684)
			(xy 342.095373 -255.007064) (xy 342.056065 -254.972033) (xy 342.022565 -254.931412) (xy 341.995659 -254.886153)
			(xy 341.975976 -254.837318) (xy 341.963979 -254.78605) (xy 341.959949 -254.733552) (xy 341.70747 -254.733552)
			(xy 341.706966 -254.759878) (xy 341.698929 -254.811914) (xy 341.683043 -254.862113) (xy 341.65968 -254.909298)
			(xy 341.629388 -254.952364) (xy 341.592876 -254.990302) (xy 341.551002 -255.022221) (xy 341.504746 -255.047374)
			(xy 341.455193 -255.065172) (xy 341.403503 -255.075196) (xy 341.350889 -255.077213) (xy 341.298584 -255.071175)
			(xy 341.247813 -255.057223) (xy 341.199768 -255.035684) (xy 341.155573 -255.007064) (xy 341.116265 -254.972033)
			(xy 341.082765 -254.931412) (xy 341.055859 -254.886153) (xy 341.036176 -254.837318) (xy 341.024179 -254.78605)
			(xy 341.020149 -254.733552) (xy 340.78037 -254.733552) (xy 340.779872 -254.760201) (xy 340.771929 -254.812905)
			(xy 340.756219 -254.863835) (xy 340.733093 -254.911856) (xy 340.703069 -254.955893) (xy 340.666817 -254.994964)
			(xy 340.625146 -255.028195) (xy 340.578988 -255.054844) (xy 340.529374 -255.074316) (xy 340.477412 -255.086176)
			(xy 340.424262 -255.09016) (xy 340.371112 -255.086176) (xy 340.31915 -255.074316) (xy 340.269536 -255.054844)
			(xy 340.223378 -255.028195) (xy 340.181707 -254.994964) (xy 340.145455 -254.955893) (xy 340.115431 -254.911856)
			(xy 340.092305 -254.863835) (xy 340.076595 -254.812905) (xy 340.068652 -254.760201) (xy 339.840326 -254.760201)
			(xy 339.832383 -254.812905) (xy 339.816673 -254.863835) (xy 339.793547 -254.911856) (xy 339.763523 -254.955893)
			(xy 339.727271 -254.994964) (xy 339.6856 -255.028195) (xy 339.639442 -255.054844) (xy 339.589828 -255.074316)
			(xy 339.537866 -255.086176) (xy 339.484716 -255.09016) (xy 339.431566 -255.086176) (xy 339.379604 -255.074316)
			(xy 339.32999 -255.054844) (xy 339.283832 -255.028195) (xy 339.242161 -254.994964) (xy 339.205909 -254.955893)
			(xy 339.175885 -254.911856) (xy 339.152759 -254.863835) (xy 339.137049 -254.812905) (xy 339.129106 -254.760201)
			(xy 338.900272 -254.760201) (xy 338.892329 -254.812905) (xy 338.876619 -254.863835) (xy 338.853493 -254.911856)
			(xy 338.823469 -254.955893) (xy 338.787217 -254.994964) (xy 338.745546 -255.028195) (xy 338.699388 -255.054844)
			(xy 338.649774 -255.074316) (xy 338.597812 -255.086176) (xy 338.544662 -255.09016) (xy 338.491512 -255.086176)
			(xy 338.43955 -255.074316) (xy 338.389936 -255.054844) (xy 338.343778 -255.028195) (xy 338.302107 -254.994964)
			(xy 338.265855 -254.955893) (xy 338.235831 -254.911856) (xy 338.212705 -254.863835) (xy 338.196995 -254.812905)
			(xy 338.189052 -254.760201) (xy 337.960472 -254.760201) (xy 337.952529 -254.812905) (xy 337.936819 -254.863835)
			(xy 337.913693 -254.911856) (xy 337.883669 -254.955893) (xy 337.847417 -254.994964) (xy 337.805746 -255.028195)
			(xy 337.759588 -255.054844) (xy 337.709974 -255.074316) (xy 337.658012 -255.086176) (xy 337.604862 -255.09016)
			(xy 337.551712 -255.086176) (xy 337.49975 -255.074316) (xy 337.450136 -255.054844) (xy 337.403978 -255.028195)
			(xy 337.362307 -254.994964) (xy 337.326055 -254.955893) (xy 337.296031 -254.911856) (xy 337.272905 -254.863835)
			(xy 337.257195 -254.812905) (xy 337.249252 -254.760201) (xy 337.020798 -254.760201) (xy 337.020798 -254.760841)
			(xy 337.012501 -254.814691) (xy 336.9961 -254.86665) (xy 336.971978 -254.915505) (xy 336.940697 -254.960117)
			(xy 336.902987 -254.999444) (xy 336.859727 -255.032571) (xy 336.811928 -255.058723) (xy 336.760704 -255.077291)
			(xy 336.707249 -255.087841) (xy 336.680048 -255.089406) (xy 336.670307 -255.090224) (xy 336.65249 -255.098225)
			(xy 336.638962 -255.112313) (xy 336.631691 -255.13044) (xy 336.63128 -255.140206) (xy 336.63128 -255.574271)
			(xy 336.779606 -255.574271) (xy 336.779606 -255.520973) (xy 336.787549 -255.468269) (xy 336.803259 -255.417339)
			(xy 336.826385 -255.369318) (xy 336.856409 -255.325281) (xy 336.892661 -255.28621) (xy 336.934332 -255.252979)
			(xy 336.98049 -255.22633) (xy 337.030104 -255.206858) (xy 337.082066 -255.194998) (xy 337.135216 -255.191015)
			(xy 337.188366 -255.194998) (xy 337.240328 -255.206858) (xy 337.289942 -255.22633) (xy 337.3361 -255.252979)
			(xy 337.377771 -255.28621) (xy 337.414023 -255.325281) (xy 337.444047 -255.369318) (xy 337.467173 -255.417339)
			(xy 337.482883 -255.468269) (xy 337.490826 -255.520973) (xy 337.491324 -255.547622) (xy 337.490826 -255.574271)
			(xy 337.719152 -255.574271) (xy 337.719152 -255.520973) (xy 337.727095 -255.468269) (xy 337.742805 -255.417339)
			(xy 337.765931 -255.369318) (xy 337.795955 -255.325281) (xy 337.832207 -255.28621) (xy 337.873878 -255.252979)
			(xy 337.920036 -255.22633) (xy 337.96965 -255.206858) (xy 338.021612 -255.194998) (xy 338.074762 -255.191015)
			(xy 338.127912 -255.194998) (xy 338.179874 -255.206858) (xy 338.229488 -255.22633) (xy 338.275646 -255.252979)
			(xy 338.317317 -255.28621) (xy 338.353569 -255.325281) (xy 338.383593 -255.369318) (xy 338.406719 -255.417339)
			(xy 338.422429 -255.468269) (xy 338.430372 -255.520973) (xy 338.43087 -255.547622) (xy 338.430372 -255.574271)
			(xy 338.659206 -255.574271) (xy 338.659206 -255.520973) (xy 338.667149 -255.468269) (xy 338.682859 -255.417339)
			(xy 338.705985 -255.369318) (xy 338.736009 -255.325281) (xy 338.772261 -255.28621) (xy 338.813932 -255.252979)
			(xy 338.86009 -255.22633) (xy 338.909704 -255.206858) (xy 338.961666 -255.194998) (xy 339.014816 -255.191015)
			(xy 339.067966 -255.194998) (xy 339.119928 -255.206858) (xy 339.169542 -255.22633) (xy 339.2157 -255.252979)
			(xy 339.257371 -255.28621) (xy 339.293623 -255.325281) (xy 339.323647 -255.369318) (xy 339.346773 -255.417339)
			(xy 339.362483 -255.468269) (xy 339.370426 -255.520973) (xy 339.370924 -255.547622) (xy 339.370426 -255.574271)
			(xy 339.598752 -255.574271) (xy 339.598752 -255.520973) (xy 339.606695 -255.468269) (xy 339.622405 -255.417339)
			(xy 339.645531 -255.369318) (xy 339.675555 -255.325281) (xy 339.711807 -255.28621) (xy 339.753478 -255.252979)
			(xy 339.799636 -255.22633) (xy 339.84925 -255.206858) (xy 339.901212 -255.194998) (xy 339.954362 -255.191015)
			(xy 340.007512 -255.194998) (xy 340.059474 -255.206858) (xy 340.109088 -255.22633) (xy 340.155246 -255.252979)
			(xy 340.196917 -255.28621) (xy 340.233169 -255.325281) (xy 340.263193 -255.369318) (xy 340.286319 -255.417339)
			(xy 340.302029 -255.468269) (xy 340.309972 -255.520973) (xy 340.31047 -255.547622) (xy 340.309972 -255.574271)
			(xy 340.538806 -255.574271) (xy 340.538806 -255.520973) (xy 340.546749 -255.468269) (xy 340.562459 -255.417339)
			(xy 340.585585 -255.369318) (xy 340.615609 -255.325281) (xy 340.651861 -255.28621) (xy 340.693532 -255.252979)
			(xy 340.73969 -255.22633) (xy 340.789304 -255.206858) (xy 340.841266 -255.194998) (xy 340.894416 -255.191015)
			(xy 340.947566 -255.194998) (xy 340.999528 -255.206858) (xy 341.049142 -255.22633) (xy 341.0953 -255.252979)
			(xy 341.136971 -255.28621) (xy 341.173223 -255.325281) (xy 341.203247 -255.369318) (xy 341.226373 -255.417339)
			(xy 341.242083 -255.468269) (xy 341.250026 -255.520973) (xy 341.250524 -255.547622) (xy 341.250026 -255.574271)
			(xy 341.478606 -255.574271) (xy 341.478606 -255.520973) (xy 341.486549 -255.468269) (xy 341.502259 -255.417339)
			(xy 341.525385 -255.369318) (xy 341.555409 -255.325281) (xy 341.591661 -255.28621) (xy 341.633332 -255.252979)
			(xy 341.67949 -255.22633) (xy 341.729104 -255.206858) (xy 341.781066 -255.194998) (xy 341.834216 -255.191015)
			(xy 341.887366 -255.194998) (xy 341.939328 -255.206858) (xy 341.988942 -255.22633) (xy 342.0351 -255.252979)
			(xy 342.076771 -255.28621) (xy 342.113023 -255.325281) (xy 342.143047 -255.369318) (xy 342.166173 -255.417339)
			(xy 342.181883 -255.468269) (xy 342.189826 -255.520973) (xy 342.190324 -255.547622) (xy 342.189826 -255.574271)
			(xy 342.418406 -255.574271) (xy 342.418406 -255.520973) (xy 342.426349 -255.468269) (xy 342.442059 -255.417339)
			(xy 342.465185 -255.369318) (xy 342.495209 -255.325281) (xy 342.531461 -255.28621) (xy 342.573132 -255.252979)
			(xy 342.61929 -255.22633) (xy 342.668904 -255.206858) (xy 342.720866 -255.194998) (xy 342.774016 -255.191015)
			(xy 342.827166 -255.194998) (xy 342.879128 -255.206858) (xy 342.928742 -255.22633) (xy 342.9749 -255.252979)
			(xy 343.016571 -255.28621) (xy 343.052823 -255.325281) (xy 343.082847 -255.369318) (xy 343.105973 -255.417339)
			(xy 343.121683 -255.468269) (xy 343.129626 -255.520973) (xy 343.130124 -255.547622) (xy 343.129626 -255.574271)
			(xy 343.358206 -255.574271) (xy 343.358206 -255.520973) (xy 343.366149 -255.468269) (xy 343.381859 -255.417339)
			(xy 343.404985 -255.369318) (xy 343.435009 -255.325281) (xy 343.471261 -255.28621) (xy 343.512932 -255.252979)
			(xy 343.55909 -255.22633) (xy 343.608704 -255.206858) (xy 343.660666 -255.194998) (xy 343.713816 -255.191015)
			(xy 343.766966 -255.194998) (xy 343.818928 -255.206858) (xy 343.868542 -255.22633) (xy 343.9147 -255.252979)
			(xy 343.956371 -255.28621) (xy 343.992623 -255.325281) (xy 344.022647 -255.369318) (xy 344.045773 -255.417339)
			(xy 344.061483 -255.468269) (xy 344.069426 -255.520973) (xy 344.069924 -255.547622) (xy 344.069426 -255.574271)
			(xy 344.298006 -255.574271) (xy 344.298006 -255.520973) (xy 344.305949 -255.468269) (xy 344.321659 -255.417339)
			(xy 344.344785 -255.369318) (xy 344.374809 -255.325281) (xy 344.411061 -255.28621) (xy 344.452732 -255.252979)
			(xy 344.49889 -255.22633) (xy 344.548504 -255.206858) (xy 344.600466 -255.194998) (xy 344.653616 -255.191015)
			(xy 344.706766 -255.194998) (xy 344.758728 -255.206858) (xy 344.808342 -255.22633) (xy 344.8545 -255.252979)
			(xy 344.896171 -255.28621) (xy 344.932423 -255.325281) (xy 344.962447 -255.369318) (xy 344.985573 -255.417339)
			(xy 345.001283 -255.468269) (xy 345.009226 -255.520973) (xy 345.009724 -255.547622) (xy 345.009226 -255.574271)
			(xy 345.237806 -255.574271) (xy 345.237806 -255.520973) (xy 345.245749 -255.468269) (xy 345.261459 -255.417339)
			(xy 345.284585 -255.369318) (xy 345.314609 -255.325281) (xy 345.350861 -255.28621) (xy 345.392532 -255.252979)
			(xy 345.43869 -255.22633) (xy 345.488304 -255.206858) (xy 345.540266 -255.194998) (xy 345.593416 -255.191015)
			(xy 345.646566 -255.194998) (xy 345.698528 -255.206858) (xy 345.748142 -255.22633) (xy 345.7943 -255.252979)
			(xy 345.835971 -255.28621) (xy 345.872223 -255.325281) (xy 345.902247 -255.369318) (xy 345.925373 -255.417339)
			(xy 345.941083 -255.468269) (xy 345.949026 -255.520973) (xy 345.949524 -255.547622) (xy 345.949026 -255.574271)
			(xy 346.177352 -255.574271) (xy 346.177352 -255.520973) (xy 346.185295 -255.468269) (xy 346.201005 -255.417339)
			(xy 346.224131 -255.369318) (xy 346.254155 -255.325281) (xy 346.290407 -255.28621) (xy 346.332078 -255.252979)
			(xy 346.378236 -255.22633) (xy 346.42785 -255.206858) (xy 346.479812 -255.194998) (xy 346.532962 -255.191015)
			(xy 346.586112 -255.194998) (xy 346.638074 -255.206858) (xy 346.687688 -255.22633) (xy 346.733846 -255.252979)
			(xy 346.775517 -255.28621) (xy 346.811769 -255.325281) (xy 346.841793 -255.369318) (xy 346.864919 -255.417339)
			(xy 346.880629 -255.468269) (xy 346.888572 -255.520973) (xy 346.88907 -255.547622) (xy 346.888572 -255.574271)
			(xy 346.880629 -255.626975) (xy 346.864919 -255.677905) (xy 346.841793 -255.725926) (xy 346.811769 -255.769963)
			(xy 346.775517 -255.809034) (xy 346.733846 -255.842265) (xy 346.687688 -255.868914) (xy 346.638074 -255.888386)
			(xy 346.586112 -255.900246) (xy 346.532962 -255.90423) (xy 346.479812 -255.900246) (xy 346.42785 -255.888386)
			(xy 346.378236 -255.868914) (xy 346.332078 -255.842265) (xy 346.290407 -255.809034) (xy 346.254155 -255.769963)
			(xy 346.224131 -255.725926) (xy 346.201005 -255.677905) (xy 346.185295 -255.626975) (xy 346.177352 -255.574271)
			(xy 345.949026 -255.574271) (xy 345.941083 -255.626975) (xy 345.925373 -255.677905) (xy 345.902247 -255.725926)
			(xy 345.872223 -255.769963) (xy 345.835971 -255.809034) (xy 345.7943 -255.842265) (xy 345.748142 -255.868914)
			(xy 345.698528 -255.888386) (xy 345.646566 -255.900246) (xy 345.593416 -255.90423) (xy 345.540266 -255.900246)
			(xy 345.488304 -255.888386) (xy 345.43869 -255.868914) (xy 345.392532 -255.842265) (xy 345.350861 -255.809034)
			(xy 345.314609 -255.769963) (xy 345.284585 -255.725926) (xy 345.261459 -255.677905) (xy 345.245749 -255.626975)
			(xy 345.237806 -255.574271) (xy 345.009226 -255.574271) (xy 345.001283 -255.626975) (xy 344.985573 -255.677905)
			(xy 344.962447 -255.725926) (xy 344.932423 -255.769963) (xy 344.896171 -255.809034) (xy 344.8545 -255.842265)
			(xy 344.808342 -255.868914) (xy 344.758728 -255.888386) (xy 344.706766 -255.900246) (xy 344.653616 -255.90423)
			(xy 344.600466 -255.900246) (xy 344.548504 -255.888386) (xy 344.49889 -255.868914) (xy 344.452732 -255.842265)
			(xy 344.411061 -255.809034) (xy 344.374809 -255.769963) (xy 344.344785 -255.725926) (xy 344.321659 -255.677905)
			(xy 344.305949 -255.626975) (xy 344.298006 -255.574271) (xy 344.069426 -255.574271) (xy 344.061483 -255.626975)
			(xy 344.045773 -255.677905) (xy 344.022647 -255.725926) (xy 343.992623 -255.769963) (xy 343.956371 -255.809034)
			(xy 343.9147 -255.842265) (xy 343.868542 -255.868914) (xy 343.818928 -255.888386) (xy 343.766966 -255.900246)
			(xy 343.713816 -255.90423) (xy 343.660666 -255.900246) (xy 343.608704 -255.888386) (xy 343.55909 -255.868914)
			(xy 343.512932 -255.842265) (xy 343.471261 -255.809034) (xy 343.435009 -255.769963) (xy 343.404985 -255.725926)
			(xy 343.381859 -255.677905) (xy 343.366149 -255.626975) (xy 343.358206 -255.574271) (xy 343.129626 -255.574271)
			(xy 343.121683 -255.626975) (xy 343.105973 -255.677905) (xy 343.082847 -255.725926) (xy 343.052823 -255.769963)
			(xy 343.016571 -255.809034) (xy 342.9749 -255.842265) (xy 342.928742 -255.868914) (xy 342.879128 -255.888386)
			(xy 342.827166 -255.900246) (xy 342.774016 -255.90423) (xy 342.720866 -255.900246) (xy 342.668904 -255.888386)
			(xy 342.61929 -255.868914) (xy 342.573132 -255.842265) (xy 342.531461 -255.809034) (xy 342.495209 -255.769963)
			(xy 342.465185 -255.725926) (xy 342.442059 -255.677905) (xy 342.426349 -255.626975) (xy 342.418406 -255.574271)
			(xy 342.189826 -255.574271) (xy 342.181883 -255.626975) (xy 342.166173 -255.677905) (xy 342.143047 -255.725926)
			(xy 342.113023 -255.769963) (xy 342.076771 -255.809034) (xy 342.0351 -255.842265) (xy 341.988942 -255.868914)
			(xy 341.939328 -255.888386) (xy 341.887366 -255.900246) (xy 341.834216 -255.90423) (xy 341.781066 -255.900246)
			(xy 341.729104 -255.888386) (xy 341.67949 -255.868914) (xy 341.633332 -255.842265) (xy 341.591661 -255.809034)
			(xy 341.555409 -255.769963) (xy 341.525385 -255.725926) (xy 341.502259 -255.677905) (xy 341.486549 -255.626975)
			(xy 341.478606 -255.574271) (xy 341.250026 -255.574271) (xy 341.242083 -255.626975) (xy 341.226373 -255.677905)
			(xy 341.203247 -255.725926) (xy 341.173223 -255.769963) (xy 341.136971 -255.809034) (xy 341.0953 -255.842265)
			(xy 341.049142 -255.868914) (xy 340.999528 -255.888386) (xy 340.947566 -255.900246) (xy 340.894416 -255.90423)
			(xy 340.841266 -255.900246) (xy 340.789304 -255.888386) (xy 340.73969 -255.868914) (xy 340.693532 -255.842265)
			(xy 340.651861 -255.809034) (xy 340.615609 -255.769963) (xy 340.585585 -255.725926) (xy 340.562459 -255.677905)
			(xy 340.546749 -255.626975) (xy 340.538806 -255.574271) (xy 340.309972 -255.574271) (xy 340.302029 -255.626975)
			(xy 340.286319 -255.677905) (xy 340.263193 -255.725926) (xy 340.233169 -255.769963) (xy 340.196917 -255.809034)
			(xy 340.155246 -255.842265) (xy 340.109088 -255.868914) (xy 340.059474 -255.888386) (xy 340.007512 -255.900246)
			(xy 339.954362 -255.90423) (xy 339.901212 -255.900246) (xy 339.84925 -255.888386) (xy 339.799636 -255.868914)
			(xy 339.753478 -255.842265) (xy 339.711807 -255.809034) (xy 339.675555 -255.769963) (xy 339.645531 -255.725926)
			(xy 339.622405 -255.677905) (xy 339.606695 -255.626975) (xy 339.598752 -255.574271) (xy 339.370426 -255.574271)
			(xy 339.362483 -255.626975) (xy 339.346773 -255.677905) (xy 339.323647 -255.725926) (xy 339.293623 -255.769963)
			(xy 339.257371 -255.809034) (xy 339.2157 -255.842265) (xy 339.169542 -255.868914) (xy 339.119928 -255.888386)
			(xy 339.067966 -255.900246) (xy 339.014816 -255.90423) (xy 338.961666 -255.900246) (xy 338.909704 -255.888386)
			(xy 338.86009 -255.868914) (xy 338.813932 -255.842265) (xy 338.772261 -255.809034) (xy 338.736009 -255.769963)
			(xy 338.705985 -255.725926) (xy 338.682859 -255.677905) (xy 338.667149 -255.626975) (xy 338.659206 -255.574271)
			(xy 338.430372 -255.574271) (xy 338.422429 -255.626975) (xy 338.406719 -255.677905) (xy 338.383593 -255.725926)
			(xy 338.353569 -255.769963) (xy 338.317317 -255.809034) (xy 338.275646 -255.842265) (xy 338.229488 -255.868914)
			(xy 338.179874 -255.888386) (xy 338.127912 -255.900246) (xy 338.074762 -255.90423) (xy 338.021612 -255.900246)
			(xy 337.96965 -255.888386) (xy 337.920036 -255.868914) (xy 337.873878 -255.842265) (xy 337.832207 -255.809034)
			(xy 337.795955 -255.769963) (xy 337.765931 -255.725926) (xy 337.742805 -255.677905) (xy 337.727095 -255.626975)
			(xy 337.719152 -255.574271) (xy 337.490826 -255.574271) (xy 337.482883 -255.626975) (xy 337.467173 -255.677905)
			(xy 337.444047 -255.725926) (xy 337.414023 -255.769963) (xy 337.377771 -255.809034) (xy 337.3361 -255.842265)
			(xy 337.289942 -255.868914) (xy 337.240328 -255.888386) (xy 337.188366 -255.900246) (xy 337.135216 -255.90423)
			(xy 337.082066 -255.900246) (xy 337.030104 -255.888386) (xy 336.98049 -255.868914) (xy 336.934332 -255.842265)
			(xy 336.892661 -255.809034) (xy 336.856409 -255.769963) (xy 336.826385 -255.725926) (xy 336.803259 -255.677905)
			(xy 336.787549 -255.626975) (xy 336.779606 -255.574271) (xy 336.63128 -255.574271) (xy 336.63128 -255.954784)
			(xy 336.631714 -255.96455) (xy 336.638993 -255.982676) (xy 336.652507 -255.996779) (xy 336.670305 -256.004824)
			(xy 336.680048 -256.005584) (xy 336.707239 -256.007244) (xy 336.76068 -256.017792) (xy 336.811892 -256.036355)
			(xy 336.85968 -256.062501) (xy 336.902929 -256.095619) (xy 336.94063 -256.134938) (xy 336.971903 -256.179538)
			(xy 336.99602 -256.228382) (xy 337.012417 -256.280328) (xy 337.020712 -256.334165) (xy 337.020712 -256.388087)
			(xy 337.249252 -256.388087) (xy 337.249252 -256.334789) (xy 337.257195 -256.282085) (xy 337.272905 -256.231155)
			(xy 337.296031 -256.183134) (xy 337.326055 -256.139097) (xy 337.362307 -256.100026) (xy 337.403978 -256.066795)
			(xy 337.450136 -256.040146) (xy 337.49975 -256.020674) (xy 337.551712 -256.008814) (xy 337.604862 -256.004831)
			(xy 337.658012 -256.008814) (xy 337.709974 -256.020674) (xy 337.759588 -256.040146) (xy 337.805746 -256.066795)
			(xy 337.847417 -256.100026) (xy 337.883669 -256.139097) (xy 337.913693 -256.183134) (xy 337.936819 -256.231155)
			(xy 337.952529 -256.282085) (xy 337.960472 -256.334789) (xy 337.96097 -256.361438) (xy 337.960472 -256.388087)
			(xy 338.189052 -256.388087) (xy 338.189052 -256.334789) (xy 338.196995 -256.282085) (xy 338.212705 -256.231155)
			(xy 338.235831 -256.183134) (xy 338.265855 -256.139097) (xy 338.302107 -256.100026) (xy 338.343778 -256.066795)
			(xy 338.389936 -256.040146) (xy 338.43955 -256.020674) (xy 338.491512 -256.008814) (xy 338.544662 -256.004831)
			(xy 338.597812 -256.008814) (xy 338.649774 -256.020674) (xy 338.699388 -256.040146) (xy 338.745546 -256.066795)
			(xy 338.787217 -256.100026) (xy 338.823469 -256.139097) (xy 338.853493 -256.183134) (xy 338.876619 -256.231155)
			(xy 338.892329 -256.282085) (xy 338.900272 -256.334789) (xy 338.90077 -256.361438) (xy 338.900272 -256.388087)
			(xy 339.128852 -256.388087) (xy 339.128852 -256.334789) (xy 339.136795 -256.282085) (xy 339.152505 -256.231155)
			(xy 339.175631 -256.183134) (xy 339.205655 -256.139097) (xy 339.241907 -256.100026) (xy 339.283578 -256.066795)
			(xy 339.329736 -256.040146) (xy 339.37935 -256.020674) (xy 339.431312 -256.008814) (xy 339.484462 -256.004831)
			(xy 339.537612 -256.008814) (xy 339.589574 -256.020674) (xy 339.639188 -256.040146) (xy 339.685346 -256.066795)
			(xy 339.727017 -256.100026) (xy 339.763269 -256.139097) (xy 339.793293 -256.183134) (xy 339.816419 -256.231155)
			(xy 339.832129 -256.282085) (xy 339.840072 -256.334789) (xy 339.84057 -256.361438) (xy 339.840072 -256.388087)
			(xy 340.068652 -256.388087) (xy 340.068652 -256.334789) (xy 340.076595 -256.282085) (xy 340.092305 -256.231155)
			(xy 340.115431 -256.183134) (xy 340.145455 -256.139097) (xy 340.181707 -256.100026) (xy 340.223378 -256.066795)
			(xy 340.269536 -256.040146) (xy 340.31915 -256.020674) (xy 340.371112 -256.008814) (xy 340.424262 -256.004831)
			(xy 340.477412 -256.008814) (xy 340.529374 -256.020674) (xy 340.578988 -256.040146) (xy 340.625146 -256.066795)
			(xy 340.666817 -256.100026) (xy 340.703069 -256.139097) (xy 340.733093 -256.183134) (xy 340.756219 -256.231155)
			(xy 340.771929 -256.282085) (xy 340.779872 -256.334789) (xy 340.78037 -256.361438) (xy 340.779872 -256.388087)
			(xy 341.008452 -256.388087) (xy 341.008452 -256.334789) (xy 341.016395 -256.282085) (xy 341.032105 -256.231155)
			(xy 341.055231 -256.183134) (xy 341.085255 -256.139097) (xy 341.121507 -256.100026) (xy 341.163178 -256.066795)
			(xy 341.209336 -256.040146) (xy 341.25895 -256.020674) (xy 341.310912 -256.008814) (xy 341.364062 -256.004831)
			(xy 341.417212 -256.008814) (xy 341.469174 -256.020674) (xy 341.518788 -256.040146) (xy 341.564946 -256.066795)
			(xy 341.606617 -256.100026) (xy 341.642869 -256.139097) (xy 341.672893 -256.183134) (xy 341.696019 -256.231155)
			(xy 341.711729 -256.282085) (xy 341.719672 -256.334789) (xy 341.72017 -256.361438) (xy 341.719672 -256.388087)
			(xy 341.948506 -256.388087) (xy 341.948506 -256.334789) (xy 341.956449 -256.282085) (xy 341.972159 -256.231155)
			(xy 341.995285 -256.183134) (xy 342.025309 -256.139097) (xy 342.061561 -256.100026) (xy 342.103232 -256.066795)
			(xy 342.14939 -256.040146) (xy 342.199004 -256.020674) (xy 342.250966 -256.008814) (xy 342.304116 -256.004831)
			(xy 342.357266 -256.008814) (xy 342.409228 -256.020674) (xy 342.458842 -256.040146) (xy 342.505 -256.066795)
			(xy 342.546671 -256.100026) (xy 342.582923 -256.139097) (xy 342.612947 -256.183134) (xy 342.636073 -256.231155)
			(xy 342.651783 -256.282085) (xy 342.659726 -256.334789) (xy 342.660224 -256.361438) (xy 342.659726 -256.388087)
			(xy 342.888052 -256.388087) (xy 342.888052 -256.334789) (xy 342.895995 -256.282085) (xy 342.911705 -256.231155)
			(xy 342.934831 -256.183134) (xy 342.964855 -256.139097) (xy 343.001107 -256.100026) (xy 343.042778 -256.066795)
			(xy 343.088936 -256.040146) (xy 343.13855 -256.020674) (xy 343.190512 -256.008814) (xy 343.243662 -256.004831)
			(xy 343.296812 -256.008814) (xy 343.348774 -256.020674) (xy 343.398388 -256.040146) (xy 343.444546 -256.066795)
			(xy 343.486217 -256.100026) (xy 343.522469 -256.139097) (xy 343.552493 -256.183134) (xy 343.575619 -256.231155)
			(xy 343.591329 -256.282085) (xy 343.599272 -256.334789) (xy 343.59977 -256.361438) (xy 343.599272 -256.388087)
			(xy 343.827852 -256.388087) (xy 343.827852 -256.334789) (xy 343.835795 -256.282085) (xy 343.851505 -256.231155)
			(xy 343.874631 -256.183134) (xy 343.904655 -256.139097) (xy 343.940907 -256.100026) (xy 343.982578 -256.066795)
			(xy 344.028736 -256.040146) (xy 344.07835 -256.020674) (xy 344.130312 -256.008814) (xy 344.183462 -256.004831)
			(xy 344.236612 -256.008814) (xy 344.288574 -256.020674) (xy 344.338188 -256.040146) (xy 344.384346 -256.066795)
			(xy 344.426017 -256.100026) (xy 344.462269 -256.139097) (xy 344.492293 -256.183134) (xy 344.515419 -256.231155)
			(xy 344.531129 -256.282085) (xy 344.539072 -256.334789) (xy 344.53957 -256.361438) (xy 344.539072 -256.388087)
			(xy 344.767652 -256.388087) (xy 344.767652 -256.334789) (xy 344.775595 -256.282085) (xy 344.791305 -256.231155)
			(xy 344.814431 -256.183134) (xy 344.844455 -256.139097) (xy 344.880707 -256.100026) (xy 344.922378 -256.066795)
			(xy 344.968536 -256.040146) (xy 345.01815 -256.020674) (xy 345.070112 -256.008814) (xy 345.123262 -256.004831)
			(xy 345.176412 -256.008814) (xy 345.228374 -256.020674) (xy 345.277988 -256.040146) (xy 345.324146 -256.066795)
			(xy 345.365817 -256.100026) (xy 345.402069 -256.139097) (xy 345.432093 -256.183134) (xy 345.455219 -256.231155)
			(xy 345.470929 -256.282085) (xy 345.478872 -256.334789) (xy 345.47937 -256.361438) (xy 345.478872 -256.388087)
			(xy 345.707452 -256.388087) (xy 345.707452 -256.334789) (xy 345.715395 -256.282085) (xy 345.731105 -256.231155)
			(xy 345.754231 -256.183134) (xy 345.784255 -256.139097) (xy 345.820507 -256.100026) (xy 345.862178 -256.066795)
			(xy 345.908336 -256.040146) (xy 345.95795 -256.020674) (xy 346.009912 -256.008814) (xy 346.063062 -256.004831)
			(xy 346.116212 -256.008814) (xy 346.168174 -256.020674) (xy 346.217788 -256.040146) (xy 346.263946 -256.066795)
			(xy 346.305617 -256.100026) (xy 346.341869 -256.139097) (xy 346.371893 -256.183134) (xy 346.395019 -256.231155)
			(xy 346.410729 -256.282085) (xy 346.418672 -256.334789) (xy 346.41917 -256.361438) (xy 346.418672 -256.388087)
			(xy 346.410729 -256.440791) (xy 346.395019 -256.491721) (xy 346.371893 -256.539742) (xy 346.341869 -256.583779)
			(xy 346.305617 -256.62285) (xy 346.263946 -256.656081) (xy 346.217788 -256.68273) (xy 346.168174 -256.702202)
			(xy 346.116212 -256.714062) (xy 346.063062 -256.718046) (xy 346.009912 -256.714062) (xy 345.95795 -256.702202)
			(xy 345.908336 -256.68273) (xy 345.862178 -256.656081) (xy 345.820507 -256.62285) (xy 345.784255 -256.583779)
			(xy 345.754231 -256.539742) (xy 345.731105 -256.491721) (xy 345.715395 -256.440791) (xy 345.707452 -256.388087)
			(xy 345.478872 -256.388087) (xy 345.470929 -256.440791) (xy 345.455219 -256.491721) (xy 345.432093 -256.539742)
			(xy 345.402069 -256.583779) (xy 345.365817 -256.62285) (xy 345.324146 -256.656081) (xy 345.277988 -256.68273)
			(xy 345.228374 -256.702202) (xy 345.176412 -256.714062) (xy 345.123262 -256.718046) (xy 345.070112 -256.714062)
			(xy 345.01815 -256.702202) (xy 344.968536 -256.68273) (xy 344.922378 -256.656081) (xy 344.880707 -256.62285)
			(xy 344.844455 -256.583779) (xy 344.814431 -256.539742) (xy 344.791305 -256.491721) (xy 344.775595 -256.440791)
			(xy 344.767652 -256.388087) (xy 344.539072 -256.388087) (xy 344.531129 -256.440791) (xy 344.515419 -256.491721)
			(xy 344.492293 -256.539742) (xy 344.462269 -256.583779) (xy 344.426017 -256.62285) (xy 344.384346 -256.656081)
			(xy 344.338188 -256.68273) (xy 344.288574 -256.702202) (xy 344.236612 -256.714062) (xy 344.183462 -256.718046)
			(xy 344.130312 -256.714062) (xy 344.07835 -256.702202) (xy 344.028736 -256.68273) (xy 343.982578 -256.656081)
			(xy 343.940907 -256.62285) (xy 343.904655 -256.583779) (xy 343.874631 -256.539742) (xy 343.851505 -256.491721)
			(xy 343.835795 -256.440791) (xy 343.827852 -256.388087) (xy 343.599272 -256.388087) (xy 343.591329 -256.440791)
			(xy 343.575619 -256.491721) (xy 343.552493 -256.539742) (xy 343.522469 -256.583779) (xy 343.486217 -256.62285)
			(xy 343.444546 -256.656081) (xy 343.398388 -256.68273) (xy 343.348774 -256.702202) (xy 343.296812 -256.714062)
			(xy 343.243662 -256.718046) (xy 343.190512 -256.714062) (xy 343.13855 -256.702202) (xy 343.088936 -256.68273)
			(xy 343.042778 -256.656081) (xy 343.001107 -256.62285) (xy 342.964855 -256.583779) (xy 342.934831 -256.539742)
			(xy 342.911705 -256.491721) (xy 342.895995 -256.440791) (xy 342.888052 -256.388087) (xy 342.659726 -256.388087)
			(xy 342.651783 -256.440791) (xy 342.636073 -256.491721) (xy 342.612947 -256.539742) (xy 342.582923 -256.583779)
			(xy 342.546671 -256.62285) (xy 342.505 -256.656081) (xy 342.458842 -256.68273) (xy 342.409228 -256.702202)
			(xy 342.357266 -256.714062) (xy 342.304116 -256.718046) (xy 342.250966 -256.714062) (xy 342.199004 -256.702202)
			(xy 342.14939 -256.68273) (xy 342.103232 -256.656081) (xy 342.061561 -256.62285) (xy 342.025309 -256.583779)
			(xy 341.995285 -256.539742) (xy 341.972159 -256.491721) (xy 341.956449 -256.440791) (xy 341.948506 -256.388087)
			(xy 341.719672 -256.388087) (xy 341.711729 -256.440791) (xy 341.696019 -256.491721) (xy 341.672893 -256.539742)
			(xy 341.642869 -256.583779) (xy 341.606617 -256.62285) (xy 341.564946 -256.656081) (xy 341.518788 -256.68273)
			(xy 341.469174 -256.702202) (xy 341.417212 -256.714062) (xy 341.364062 -256.718046) (xy 341.310912 -256.714062)
			(xy 341.25895 -256.702202) (xy 341.209336 -256.68273) (xy 341.163178 -256.656081) (xy 341.121507 -256.62285)
			(xy 341.085255 -256.583779) (xy 341.055231 -256.539742) (xy 341.032105 -256.491721) (xy 341.016395 -256.440791)
			(xy 341.008452 -256.388087) (xy 340.779872 -256.388087) (xy 340.771929 -256.440791) (xy 340.756219 -256.491721)
			(xy 340.733093 -256.539742) (xy 340.703069 -256.583779) (xy 340.666817 -256.62285) (xy 340.625146 -256.656081)
			(xy 340.578988 -256.68273) (xy 340.529374 -256.702202) (xy 340.477412 -256.714062) (xy 340.424262 -256.718046)
			(xy 340.371112 -256.714062) (xy 340.31915 -256.702202) (xy 340.269536 -256.68273) (xy 340.223378 -256.656081)
			(xy 340.181707 -256.62285) (xy 340.145455 -256.583779) (xy 340.115431 -256.539742) (xy 340.092305 -256.491721)
			(xy 340.076595 -256.440791) (xy 340.068652 -256.388087) (xy 339.840072 -256.388087) (xy 339.832129 -256.440791)
			(xy 339.816419 -256.491721) (xy 339.793293 -256.539742) (xy 339.763269 -256.583779) (xy 339.727017 -256.62285)
			(xy 339.685346 -256.656081) (xy 339.639188 -256.68273) (xy 339.589574 -256.702202) (xy 339.537612 -256.714062)
			(xy 339.484462 -256.718046) (xy 339.431312 -256.714062) (xy 339.37935 -256.702202) (xy 339.329736 -256.68273)
			(xy 339.283578 -256.656081) (xy 339.241907 -256.62285) (xy 339.205655 -256.583779) (xy 339.175631 -256.539742)
			(xy 339.152505 -256.491721) (xy 339.136795 -256.440791) (xy 339.128852 -256.388087) (xy 338.900272 -256.388087)
			(xy 338.892329 -256.440791) (xy 338.876619 -256.491721) (xy 338.853493 -256.539742) (xy 338.823469 -256.583779)
			(xy 338.787217 -256.62285) (xy 338.745546 -256.656081) (xy 338.699388 -256.68273) (xy 338.649774 -256.702202)
			(xy 338.597812 -256.714062) (xy 338.544662 -256.718046) (xy 338.491512 -256.714062) (xy 338.43955 -256.702202)
			(xy 338.389936 -256.68273) (xy 338.343778 -256.656081) (xy 338.302107 -256.62285) (xy 338.265855 -256.583779)
			(xy 338.235831 -256.539742) (xy 338.212705 -256.491721) (xy 338.196995 -256.440791) (xy 338.189052 -256.388087)
			(xy 337.960472 -256.388087) (xy 337.952529 -256.440791) (xy 337.936819 -256.491721) (xy 337.913693 -256.539742)
			(xy 337.883669 -256.583779) (xy 337.847417 -256.62285) (xy 337.805746 -256.656081) (xy 337.759588 -256.68273)
			(xy 337.709974 -256.702202) (xy 337.658012 -256.714062) (xy 337.604862 -256.718046) (xy 337.551712 -256.714062)
			(xy 337.49975 -256.702202) (xy 337.450136 -256.68273) (xy 337.403978 -256.656081) (xy 337.362307 -256.62285)
			(xy 337.326055 -256.583779) (xy 337.296031 -256.539742) (xy 337.272905 -256.491721) (xy 337.257195 -256.440791)
			(xy 337.249252 -256.388087) (xy 337.020712 -256.388087) (xy 337.020712 -256.388638) (xy 337.012417 -256.442475)
			(xy 336.996019 -256.494421) (xy 336.971902 -256.543264) (xy 336.940628 -256.587865) (xy 336.902927 -256.627183)
			(xy 336.859678 -256.660301) (xy 336.811889 -256.686446) (xy 336.760677 -256.705009) (xy 336.707235 -256.715556)
			(xy 336.680048 -256.717292) (xy 336.670306 -256.71811) (xy 336.652486 -256.72611) (xy 336.638956 -256.740198)
			(xy 336.631679 -256.758325) (xy 336.63128 -256.768092) (xy 336.63128 -257.201903) (xy 336.779352 -257.201903)
			(xy 336.779352 -257.148605) (xy 336.787295 -257.095901) (xy 336.803005 -257.044971) (xy 336.826131 -256.99695)
			(xy 336.856155 -256.952913) (xy 336.892407 -256.913842) (xy 336.934078 -256.880611) (xy 336.980236 -256.853962)
			(xy 337.02985 -256.83449) (xy 337.081812 -256.82263) (xy 337.134962 -256.818647) (xy 337.188112 -256.82263)
			(xy 337.240074 -256.83449) (xy 337.289688 -256.853962) (xy 337.335846 -256.880611) (xy 337.377517 -256.913842)
			(xy 337.413769 -256.952913) (xy 337.443793 -256.99695) (xy 337.466919 -257.044971) (xy 337.482629 -257.095901)
			(xy 337.490572 -257.148605) (xy 337.49107 -257.175254) (xy 337.490572 -257.201903) (xy 337.719152 -257.201903)
			(xy 337.719152 -257.148605) (xy 337.727095 -257.095901) (xy 337.742805 -257.044971) (xy 337.765931 -256.99695)
			(xy 337.795955 -256.952913) (xy 337.832207 -256.913842) (xy 337.873878 -256.880611) (xy 337.920036 -256.853962)
			(xy 337.96965 -256.83449) (xy 338.021612 -256.82263) (xy 338.074762 -256.818647) (xy 338.127912 -256.82263)
			(xy 338.179874 -256.83449) (xy 338.229488 -256.853962) (xy 338.275646 -256.880611) (xy 338.317317 -256.913842)
			(xy 338.353569 -256.952913) (xy 338.383593 -256.99695) (xy 338.406719 -257.044971) (xy 338.422429 -257.095901)
			(xy 338.430372 -257.148605) (xy 338.43087 -257.175254) (xy 338.430372 -257.201903) (xy 338.658952 -257.201903)
			(xy 338.658952 -257.148605) (xy 338.666895 -257.095901) (xy 338.682605 -257.044971) (xy 338.705731 -256.99695)
			(xy 338.735755 -256.952913) (xy 338.772007 -256.913842) (xy 338.813678 -256.880611) (xy 338.859836 -256.853962)
			(xy 338.90945 -256.83449) (xy 338.961412 -256.82263) (xy 339.014562 -256.818647) (xy 339.067712 -256.82263)
			(xy 339.119674 -256.83449) (xy 339.169288 -256.853962) (xy 339.215446 -256.880611) (xy 339.257117 -256.913842)
			(xy 339.293369 -256.952913) (xy 339.323393 -256.99695) (xy 339.346519 -257.044971) (xy 339.362229 -257.095901)
			(xy 339.370172 -257.148605) (xy 339.37067 -257.175254) (xy 339.370172 -257.201903) (xy 339.599006 -257.201903)
			(xy 339.599006 -257.148605) (xy 339.606949 -257.095901) (xy 339.622659 -257.044971) (xy 339.645785 -256.99695)
			(xy 339.675809 -256.952913) (xy 339.712061 -256.913842) (xy 339.753732 -256.880611) (xy 339.79989 -256.853962)
			(xy 339.849504 -256.83449) (xy 339.901466 -256.82263) (xy 339.954616 -256.818647) (xy 340.007766 -256.82263)
			(xy 340.059728 -256.83449) (xy 340.109342 -256.853962) (xy 340.1555 -256.880611) (xy 340.197171 -256.913842)
			(xy 340.233423 -256.952913) (xy 340.263447 -256.99695) (xy 340.286573 -257.044971) (xy 340.302283 -257.095901)
			(xy 340.310226 -257.148605) (xy 340.310724 -257.175254) (xy 340.310226 -257.201903) (xy 340.538552 -257.201903)
			(xy 340.538552 -257.148605) (xy 340.546495 -257.095901) (xy 340.562205 -257.044971) (xy 340.585331 -256.99695)
			(xy 340.615355 -256.952913) (xy 340.651607 -256.913842) (xy 340.693278 -256.880611) (xy 340.739436 -256.853962)
			(xy 340.78905 -256.83449) (xy 340.841012 -256.82263) (xy 340.894162 -256.818647) (xy 340.947312 -256.82263)
			(xy 340.999274 -256.83449) (xy 341.048888 -256.853962) (xy 341.095046 -256.880611) (xy 341.136717 -256.913842)
			(xy 341.172969 -256.952913) (xy 341.202993 -256.99695) (xy 341.226119 -257.044971) (xy 341.241829 -257.095901)
			(xy 341.249772 -257.148605) (xy 341.25027 -257.175254) (xy 341.249772 -257.201903) (xy 341.478606 -257.201903)
			(xy 341.478606 -257.148605) (xy 341.486549 -257.095901) (xy 341.502259 -257.044971) (xy 341.525385 -256.99695)
			(xy 341.555409 -256.952913) (xy 341.591661 -256.913842) (xy 341.633332 -256.880611) (xy 341.67949 -256.853962)
			(xy 341.729104 -256.83449) (xy 341.781066 -256.82263) (xy 341.834216 -256.818647) (xy 341.887366 -256.82263)
			(xy 341.939328 -256.83449) (xy 341.988942 -256.853962) (xy 342.0351 -256.880611) (xy 342.076771 -256.913842)
			(xy 342.113023 -256.952913) (xy 342.143047 -256.99695) (xy 342.166173 -257.044971) (xy 342.181883 -257.095901)
			(xy 342.189826 -257.148605) (xy 342.190324 -257.175254) (xy 342.189826 -257.201903) (xy 342.418406 -257.201903)
			(xy 342.418406 -257.148605) (xy 342.426349 -257.095901) (xy 342.442059 -257.044971) (xy 342.465185 -256.99695)
			(xy 342.495209 -256.952913) (xy 342.531461 -256.913842) (xy 342.573132 -256.880611) (xy 342.61929 -256.853962)
			(xy 342.668904 -256.83449) (xy 342.720866 -256.82263) (xy 342.774016 -256.818647) (xy 342.827166 -256.82263)
			(xy 342.879128 -256.83449) (xy 342.928742 -256.853962) (xy 342.9749 -256.880611) (xy 343.016571 -256.913842)
			(xy 343.052823 -256.952913) (xy 343.082847 -256.99695) (xy 343.105973 -257.044971) (xy 343.121683 -257.095901)
			(xy 343.129626 -257.148605) (xy 343.130124 -257.175254) (xy 343.129626 -257.201903) (xy 343.358206 -257.201903)
			(xy 343.358206 -257.148605) (xy 343.366149 -257.095901) (xy 343.381859 -257.044971) (xy 343.404985 -256.99695)
			(xy 343.435009 -256.952913) (xy 343.471261 -256.913842) (xy 343.512932 -256.880611) (xy 343.55909 -256.853962)
			(xy 343.608704 -256.83449) (xy 343.660666 -256.82263) (xy 343.713816 -256.818647) (xy 343.766966 -256.82263)
			(xy 343.818928 -256.83449) (xy 343.868542 -256.853962) (xy 343.9147 -256.880611) (xy 343.956371 -256.913842)
			(xy 343.992623 -256.952913) (xy 344.022647 -256.99695) (xy 344.045773 -257.044971) (xy 344.061483 -257.095901)
			(xy 344.069426 -257.148605) (xy 344.069924 -257.175254) (xy 344.069426 -257.201903) (xy 344.298006 -257.201903)
			(xy 344.298006 -257.148605) (xy 344.305949 -257.095901) (xy 344.321659 -257.044971) (xy 344.344785 -256.99695)
			(xy 344.374809 -256.952913) (xy 344.411061 -256.913842) (xy 344.452732 -256.880611) (xy 344.49889 -256.853962)
			(xy 344.548504 -256.83449) (xy 344.600466 -256.82263) (xy 344.653616 -256.818647) (xy 344.706766 -256.82263)
			(xy 344.758728 -256.83449) (xy 344.808342 -256.853962) (xy 344.8545 -256.880611) (xy 344.896171 -256.913842)
			(xy 344.932423 -256.952913) (xy 344.962447 -256.99695) (xy 344.985573 -257.044971) (xy 345.001283 -257.095901)
			(xy 345.009226 -257.148605) (xy 345.009724 -257.175254) (xy 345.009226 -257.201903) (xy 345.237552 -257.201903)
			(xy 345.237552 -257.148605) (xy 345.245495 -257.095901) (xy 345.261205 -257.044971) (xy 345.284331 -256.99695)
			(xy 345.314355 -256.952913) (xy 345.350607 -256.913842) (xy 345.392278 -256.880611) (xy 345.438436 -256.853962)
			(xy 345.48805 -256.83449) (xy 345.540012 -256.82263) (xy 345.593162 -256.818647) (xy 345.646312 -256.82263)
			(xy 345.698274 -256.83449) (xy 345.747888 -256.853962) (xy 345.794046 -256.880611) (xy 345.835717 -256.913842)
			(xy 345.871969 -256.952913) (xy 345.901993 -256.99695) (xy 345.925119 -257.044971) (xy 345.940829 -257.095901)
			(xy 345.948772 -257.148605) (xy 345.94927 -257.175254) (xy 345.948772 -257.201903) (xy 346.177606 -257.201903)
			(xy 346.177606 -257.148605) (xy 346.185549 -257.095901) (xy 346.201259 -257.044971) (xy 346.224385 -256.99695)
			(xy 346.254409 -256.952913) (xy 346.290661 -256.913842) (xy 346.332332 -256.880611) (xy 346.37849 -256.853962)
			(xy 346.428104 -256.83449) (xy 346.480066 -256.82263) (xy 346.533216 -256.818647) (xy 346.586366 -256.82263)
			(xy 346.638328 -256.83449) (xy 346.687942 -256.853962) (xy 346.7341 -256.880611) (xy 346.775771 -256.913842)
			(xy 346.812023 -256.952913) (xy 346.842047 -256.99695) (xy 346.865173 -257.044971) (xy 346.880883 -257.095901)
			(xy 346.888826 -257.148605) (xy 346.889324 -257.175254) (xy 346.888826 -257.201903) (xy 346.880883 -257.254607)
			(xy 346.865173 -257.305537) (xy 346.842047 -257.353558) (xy 346.812023 -257.397595) (xy 346.775771 -257.436666)
			(xy 346.7341 -257.469897) (xy 346.687942 -257.496546) (xy 346.638328 -257.516018) (xy 346.586366 -257.527878)
			(xy 346.533216 -257.531862) (xy 346.480066 -257.527878) (xy 346.428104 -257.516018) (xy 346.37849 -257.496546)
			(xy 346.332332 -257.469897) (xy 346.290661 -257.436666) (xy 346.254409 -257.397595) (xy 346.224385 -257.353558)
			(xy 346.201259 -257.305537) (xy 346.185549 -257.254607) (xy 346.177606 -257.201903) (xy 345.948772 -257.201903)
			(xy 345.940829 -257.254607) (xy 345.925119 -257.305537) (xy 345.901993 -257.353558) (xy 345.871969 -257.397595)
			(xy 345.835717 -257.436666) (xy 345.794046 -257.469897) (xy 345.747888 -257.496546) (xy 345.698274 -257.516018)
			(xy 345.646312 -257.527878) (xy 345.593162 -257.531862) (xy 345.540012 -257.527878) (xy 345.48805 -257.516018)
			(xy 345.438436 -257.496546) (xy 345.392278 -257.469897) (xy 345.350607 -257.436666) (xy 345.314355 -257.397595)
			(xy 345.284331 -257.353558) (xy 345.261205 -257.305537) (xy 345.245495 -257.254607) (xy 345.237552 -257.201903)
			(xy 345.009226 -257.201903) (xy 345.001283 -257.254607) (xy 344.985573 -257.305537) (xy 344.962447 -257.353558)
			(xy 344.932423 -257.397595) (xy 344.896171 -257.436666) (xy 344.8545 -257.469897) (xy 344.808342 -257.496546)
			(xy 344.758728 -257.516018) (xy 344.706766 -257.527878) (xy 344.653616 -257.531862) (xy 344.600466 -257.527878)
			(xy 344.548504 -257.516018) (xy 344.49889 -257.496546) (xy 344.452732 -257.469897) (xy 344.411061 -257.436666)
			(xy 344.374809 -257.397595) (xy 344.344785 -257.353558) (xy 344.321659 -257.305537) (xy 344.305949 -257.254607)
			(xy 344.298006 -257.201903) (xy 344.069426 -257.201903) (xy 344.061483 -257.254607) (xy 344.045773 -257.305537)
			(xy 344.022647 -257.353558) (xy 343.992623 -257.397595) (xy 343.956371 -257.436666) (xy 343.9147 -257.469897)
			(xy 343.868542 -257.496546) (xy 343.818928 -257.516018) (xy 343.766966 -257.527878) (xy 343.713816 -257.531862)
			(xy 343.660666 -257.527878) (xy 343.608704 -257.516018) (xy 343.55909 -257.496546) (xy 343.512932 -257.469897)
			(xy 343.471261 -257.436666) (xy 343.435009 -257.397595) (xy 343.404985 -257.353558) (xy 343.381859 -257.305537)
			(xy 343.366149 -257.254607) (xy 343.358206 -257.201903) (xy 343.129626 -257.201903) (xy 343.121683 -257.254607)
			(xy 343.105973 -257.305537) (xy 343.082847 -257.353558) (xy 343.052823 -257.397595) (xy 343.016571 -257.436666)
			(xy 342.9749 -257.469897) (xy 342.928742 -257.496546) (xy 342.879128 -257.516018) (xy 342.827166 -257.527878)
			(xy 342.774016 -257.531862) (xy 342.720866 -257.527878) (xy 342.668904 -257.516018) (xy 342.61929 -257.496546)
			(xy 342.573132 -257.469897) (xy 342.531461 -257.436666) (xy 342.495209 -257.397595) (xy 342.465185 -257.353558)
			(xy 342.442059 -257.305537) (xy 342.426349 -257.254607) (xy 342.418406 -257.201903) (xy 342.189826 -257.201903)
			(xy 342.181883 -257.254607) (xy 342.166173 -257.305537) (xy 342.143047 -257.353558) (xy 342.113023 -257.397595)
			(xy 342.076771 -257.436666) (xy 342.0351 -257.469897) (xy 341.988942 -257.496546) (xy 341.939328 -257.516018)
			(xy 341.887366 -257.527878) (xy 341.834216 -257.531862) (xy 341.781066 -257.527878) (xy 341.729104 -257.516018)
			(xy 341.67949 -257.496546) (xy 341.633332 -257.469897) (xy 341.591661 -257.436666) (xy 341.555409 -257.397595)
			(xy 341.525385 -257.353558) (xy 341.502259 -257.305537) (xy 341.486549 -257.254607) (xy 341.478606 -257.201903)
			(xy 341.249772 -257.201903) (xy 341.241829 -257.254607) (xy 341.226119 -257.305537) (xy 341.202993 -257.353558)
			(xy 341.172969 -257.397595) (xy 341.136717 -257.436666) (xy 341.095046 -257.469897) (xy 341.048888 -257.496546)
			(xy 340.999274 -257.516018) (xy 340.947312 -257.527878) (xy 340.894162 -257.531862) (xy 340.841012 -257.527878)
			(xy 340.78905 -257.516018) (xy 340.739436 -257.496546) (xy 340.693278 -257.469897) (xy 340.651607 -257.436666)
			(xy 340.615355 -257.397595) (xy 340.585331 -257.353558) (xy 340.562205 -257.305537) (xy 340.546495 -257.254607)
			(xy 340.538552 -257.201903) (xy 340.310226 -257.201903) (xy 340.302283 -257.254607) (xy 340.286573 -257.305537)
			(xy 340.263447 -257.353558) (xy 340.233423 -257.397595) (xy 340.197171 -257.436666) (xy 340.1555 -257.469897)
			(xy 340.109342 -257.496546) (xy 340.059728 -257.516018) (xy 340.007766 -257.527878) (xy 339.954616 -257.531862)
			(xy 339.901466 -257.527878) (xy 339.849504 -257.516018) (xy 339.79989 -257.496546) (xy 339.753732 -257.469897)
			(xy 339.712061 -257.436666) (xy 339.675809 -257.397595) (xy 339.645785 -257.353558) (xy 339.622659 -257.305537)
			(xy 339.606949 -257.254607) (xy 339.599006 -257.201903) (xy 339.370172 -257.201903) (xy 339.362229 -257.254607)
			(xy 339.346519 -257.305537) (xy 339.323393 -257.353558) (xy 339.293369 -257.397595) (xy 339.257117 -257.436666)
			(xy 339.215446 -257.469897) (xy 339.169288 -257.496546) (xy 339.119674 -257.516018) (xy 339.067712 -257.527878)
			(xy 339.014562 -257.531862) (xy 338.961412 -257.527878) (xy 338.90945 -257.516018) (xy 338.859836 -257.496546)
			(xy 338.813678 -257.469897) (xy 338.772007 -257.436666) (xy 338.735755 -257.397595) (xy 338.705731 -257.353558)
			(xy 338.682605 -257.305537) (xy 338.666895 -257.254607) (xy 338.658952 -257.201903) (xy 338.430372 -257.201903)
			(xy 338.422429 -257.254607) (xy 338.406719 -257.305537) (xy 338.383593 -257.353558) (xy 338.353569 -257.397595)
			(xy 338.317317 -257.436666) (xy 338.275646 -257.469897) (xy 338.229488 -257.496546) (xy 338.179874 -257.516018)
			(xy 338.127912 -257.527878) (xy 338.074762 -257.531862) (xy 338.021612 -257.527878) (xy 337.96965 -257.516018)
			(xy 337.920036 -257.496546) (xy 337.873878 -257.469897) (xy 337.832207 -257.436666) (xy 337.795955 -257.397595)
			(xy 337.765931 -257.353558) (xy 337.742805 -257.305537) (xy 337.727095 -257.254607) (xy 337.719152 -257.201903)
			(xy 337.490572 -257.201903) (xy 337.482629 -257.254607) (xy 337.466919 -257.305537) (xy 337.443793 -257.353558)
			(xy 337.413769 -257.397595) (xy 337.377517 -257.436666) (xy 337.335846 -257.469897) (xy 337.289688 -257.496546)
			(xy 337.240074 -257.516018) (xy 337.188112 -257.527878) (xy 337.134962 -257.531862) (xy 337.081812 -257.527878)
			(xy 337.02985 -257.516018) (xy 336.980236 -257.496546) (xy 336.934078 -257.469897) (xy 336.892407 -257.436666)
			(xy 336.856155 -257.397595) (xy 336.826131 -257.353558) (xy 336.803005 -257.305537) (xy 336.787295 -257.254607)
			(xy 336.779352 -257.201903) (xy 336.63128 -257.201903) (xy 336.63128 -257.582416) (xy 336.631719 -257.592178)
			(xy 336.639004 -257.610293) (xy 336.652517 -257.624386) (xy 336.67031 -257.632425) (xy 336.680048 -257.633216)
			(xy 336.707244 -257.634876) (xy 336.760696 -257.645426) (xy 336.811918 -257.663992) (xy 336.859715 -257.690143)
			(xy 336.902972 -257.723267) (xy 336.940681 -257.762592) (xy 336.97196 -257.807201) (xy 336.996082 -257.856054)
			(xy 337.012483 -257.90801) (xy 337.02078 -257.961857) (xy 337.02078 -258.015719) (xy 337.249252 -258.015719)
			(xy 337.249252 -257.962421) (xy 337.257195 -257.909717) (xy 337.272905 -257.858787) (xy 337.296031 -257.810766)
			(xy 337.326055 -257.766729) (xy 337.362307 -257.727658) (xy 337.403978 -257.694427) (xy 337.450136 -257.667778)
			(xy 337.49975 -257.648306) (xy 337.551712 -257.636446) (xy 337.604862 -257.632463) (xy 337.658012 -257.636446)
			(xy 337.709974 -257.648306) (xy 337.759588 -257.667778) (xy 337.805746 -257.694427) (xy 337.847417 -257.727658)
			(xy 337.883669 -257.766729) (xy 337.913693 -257.810766) (xy 337.936819 -257.858787) (xy 337.952529 -257.909717)
			(xy 337.960472 -257.962421) (xy 337.96097 -257.98907) (xy 337.960472 -258.015719) (xy 338.189306 -258.015719)
			(xy 338.189306 -257.962421) (xy 338.197249 -257.909717) (xy 338.212959 -257.858787) (xy 338.236085 -257.810766)
			(xy 338.266109 -257.766729) (xy 338.302361 -257.727658) (xy 338.344032 -257.694427) (xy 338.39019 -257.667778)
			(xy 338.439804 -257.648306) (xy 338.491766 -257.636446) (xy 338.544916 -257.632463) (xy 338.598066 -257.636446)
			(xy 338.650028 -257.648306) (xy 338.699642 -257.667778) (xy 338.7458 -257.694427) (xy 338.787471 -257.727658)
			(xy 338.823723 -257.766729) (xy 338.853747 -257.810766) (xy 338.876873 -257.858787) (xy 338.892583 -257.909717)
			(xy 338.900526 -257.962421) (xy 338.901024 -257.98907) (xy 338.900526 -258.015719) (xy 339.128852 -258.015719)
			(xy 339.128852 -257.962421) (xy 339.136795 -257.909717) (xy 339.152505 -257.858787) (xy 339.175631 -257.810766)
			(xy 339.205655 -257.766729) (xy 339.241907 -257.727658) (xy 339.283578 -257.694427) (xy 339.329736 -257.667778)
			(xy 339.37935 -257.648306) (xy 339.431312 -257.636446) (xy 339.484462 -257.632463) (xy 339.537612 -257.636446)
			(xy 339.589574 -257.648306) (xy 339.639188 -257.667778) (xy 339.685346 -257.694427) (xy 339.727017 -257.727658)
			(xy 339.763269 -257.766729) (xy 339.793293 -257.810766) (xy 339.816419 -257.858787) (xy 339.832129 -257.909717)
			(xy 339.840072 -257.962421) (xy 339.84057 -257.98907) (xy 339.840072 -258.015719) (xy 340.068906 -258.015719)
			(xy 340.068906 -257.962421) (xy 340.076849 -257.909717) (xy 340.092559 -257.858787) (xy 340.115685 -257.810766)
			(xy 340.145709 -257.766729) (xy 340.181961 -257.727658) (xy 340.223632 -257.694427) (xy 340.26979 -257.667778)
			(xy 340.319404 -257.648306) (xy 340.371366 -257.636446) (xy 340.424516 -257.632463) (xy 340.477666 -257.636446)
			(xy 340.529628 -257.648306) (xy 340.579242 -257.667778) (xy 340.6254 -257.694427) (xy 340.667071 -257.727658)
			(xy 340.703323 -257.766729) (xy 340.733347 -257.810766) (xy 340.756473 -257.858787) (xy 340.772183 -257.909717)
			(xy 340.780126 -257.962421) (xy 340.780624 -257.98907) (xy 340.780126 -258.015719) (xy 341.008452 -258.015719)
			(xy 341.008452 -257.962421) (xy 341.016395 -257.909717) (xy 341.032105 -257.858787) (xy 341.055231 -257.810766)
			(xy 341.085255 -257.766729) (xy 341.121507 -257.727658) (xy 341.163178 -257.694427) (xy 341.209336 -257.667778)
			(xy 341.25895 -257.648306) (xy 341.310912 -257.636446) (xy 341.364062 -257.632463) (xy 341.417212 -257.636446)
			(xy 341.469174 -257.648306) (xy 341.518788 -257.667778) (xy 341.564946 -257.694427) (xy 341.606617 -257.727658)
			(xy 341.642869 -257.766729) (xy 341.672893 -257.810766) (xy 341.696019 -257.858787) (xy 341.711729 -257.909717)
			(xy 341.719672 -257.962421) (xy 341.72017 -257.98907) (xy 341.719672 -258.015719) (xy 341.948252 -258.015719)
			(xy 341.948252 -257.962421) (xy 341.956195 -257.909717) (xy 341.971905 -257.858787) (xy 341.995031 -257.810766)
			(xy 342.025055 -257.766729) (xy 342.061307 -257.727658) (xy 342.102978 -257.694427) (xy 342.149136 -257.667778)
			(xy 342.19875 -257.648306) (xy 342.250712 -257.636446) (xy 342.303862 -257.632463) (xy 342.357012 -257.636446)
			(xy 342.408974 -257.648306) (xy 342.458588 -257.667778) (xy 342.504746 -257.694427) (xy 342.546417 -257.727658)
			(xy 342.582669 -257.766729) (xy 342.612693 -257.810766) (xy 342.635819 -257.858787) (xy 342.651529 -257.909717)
			(xy 342.659472 -257.962421) (xy 342.65997 -257.98907) (xy 342.659472 -258.015719) (xy 342.888052 -258.015719)
			(xy 342.888052 -257.962421) (xy 342.895995 -257.909717) (xy 342.911705 -257.858787) (xy 342.934831 -257.810766)
			(xy 342.964855 -257.766729) (xy 343.001107 -257.727658) (xy 343.042778 -257.694427) (xy 343.088936 -257.667778)
			(xy 343.13855 -257.648306) (xy 343.190512 -257.636446) (xy 343.243662 -257.632463) (xy 343.296812 -257.636446)
			(xy 343.348774 -257.648306) (xy 343.398388 -257.667778) (xy 343.444546 -257.694427) (xy 343.486217 -257.727658)
			(xy 343.522469 -257.766729) (xy 343.552493 -257.810766) (xy 343.575619 -257.858787) (xy 343.591329 -257.909717)
			(xy 343.599272 -257.962421) (xy 343.59977 -257.98907) (xy 343.599272 -258.015719) (xy 343.827852 -258.015719)
			(xy 343.827852 -257.962421) (xy 343.835795 -257.909717) (xy 343.851505 -257.858787) (xy 343.874631 -257.810766)
			(xy 343.904655 -257.766729) (xy 343.940907 -257.727658) (xy 343.982578 -257.694427) (xy 344.028736 -257.667778)
			(xy 344.07835 -257.648306) (xy 344.130312 -257.636446) (xy 344.183462 -257.632463) (xy 344.236612 -257.636446)
			(xy 344.288574 -257.648306) (xy 344.338188 -257.667778) (xy 344.384346 -257.694427) (xy 344.426017 -257.727658)
			(xy 344.462269 -257.766729) (xy 344.492293 -257.810766) (xy 344.515419 -257.858787) (xy 344.531129 -257.909717)
			(xy 344.539072 -257.962421) (xy 344.53957 -257.98907) (xy 344.539072 -258.015719) (xy 344.767906 -258.015719)
			(xy 344.767906 -257.962421) (xy 344.775849 -257.909717) (xy 344.791559 -257.858787) (xy 344.814685 -257.810766)
			(xy 344.844709 -257.766729) (xy 344.880961 -257.727658) (xy 344.922632 -257.694427) (xy 344.96879 -257.667778)
			(xy 345.018404 -257.648306) (xy 345.070366 -257.636446) (xy 345.123516 -257.632463) (xy 345.176666 -257.636446)
			(xy 345.228628 -257.648306) (xy 345.278242 -257.667778) (xy 345.3244 -257.694427) (xy 345.366071 -257.727658)
			(xy 345.402323 -257.766729) (xy 345.432347 -257.810766) (xy 345.455473 -257.858787) (xy 345.471183 -257.909717)
			(xy 345.479126 -257.962421) (xy 345.479624 -257.98907) (xy 345.479126 -258.015719) (xy 345.707452 -258.015719)
			(xy 345.707452 -257.962421) (xy 345.715395 -257.909717) (xy 345.731105 -257.858787) (xy 345.754231 -257.810766)
			(xy 345.784255 -257.766729) (xy 345.820507 -257.727658) (xy 345.862178 -257.694427) (xy 345.908336 -257.667778)
			(xy 345.95795 -257.648306) (xy 346.009912 -257.636446) (xy 346.063062 -257.632463) (xy 346.116212 -257.636446)
			(xy 346.168174 -257.648306) (xy 346.217788 -257.667778) (xy 346.263946 -257.694427) (xy 346.305617 -257.727658)
			(xy 346.341869 -257.766729) (xy 346.371893 -257.810766) (xy 346.395019 -257.858787) (xy 346.410729 -257.909717)
			(xy 346.418672 -257.962421) (xy 346.41917 -257.98907) (xy 346.418672 -258.015719) (xy 346.410729 -258.068423)
			(xy 346.395019 -258.119353) (xy 346.371893 -258.167374) (xy 346.341869 -258.211411) (xy 346.305617 -258.250482)
			(xy 346.263946 -258.283713) (xy 346.217788 -258.310362) (xy 346.168174 -258.329834) (xy 346.116212 -258.341694)
			(xy 346.063062 -258.345678) (xy 346.009912 -258.341694) (xy 345.95795 -258.329834) (xy 345.908336 -258.310362)
			(xy 345.862178 -258.283713) (xy 345.820507 -258.250482) (xy 345.784255 -258.211411) (xy 345.754231 -258.167374)
			(xy 345.731105 -258.119353) (xy 345.715395 -258.068423) (xy 345.707452 -258.015719) (xy 345.479126 -258.015719)
			(xy 345.471183 -258.068423) (xy 345.455473 -258.119353) (xy 345.432347 -258.167374) (xy 345.402323 -258.211411)
			(xy 345.366071 -258.250482) (xy 345.3244 -258.283713) (xy 345.278242 -258.310362) (xy 345.228628 -258.329834)
			(xy 345.176666 -258.341694) (xy 345.123516 -258.345678) (xy 345.070366 -258.341694) (xy 345.018404 -258.329834)
			(xy 344.96879 -258.310362) (xy 344.922632 -258.283713) (xy 344.880961 -258.250482) (xy 344.844709 -258.211411)
			(xy 344.814685 -258.167374) (xy 344.791559 -258.119353) (xy 344.775849 -258.068423) (xy 344.767906 -258.015719)
			(xy 344.539072 -258.015719) (xy 344.531129 -258.068423) (xy 344.515419 -258.119353) (xy 344.492293 -258.167374)
			(xy 344.462269 -258.211411) (xy 344.426017 -258.250482) (xy 344.384346 -258.283713) (xy 344.338188 -258.310362)
			(xy 344.288574 -258.329834) (xy 344.236612 -258.341694) (xy 344.183462 -258.345678) (xy 344.130312 -258.341694)
			(xy 344.07835 -258.329834) (xy 344.028736 -258.310362) (xy 343.982578 -258.283713) (xy 343.940907 -258.250482)
			(xy 343.904655 -258.211411) (xy 343.874631 -258.167374) (xy 343.851505 -258.119353) (xy 343.835795 -258.068423)
			(xy 343.827852 -258.015719) (xy 343.599272 -258.015719) (xy 343.591329 -258.068423) (xy 343.575619 -258.119353)
			(xy 343.552493 -258.167374) (xy 343.522469 -258.211411) (xy 343.486217 -258.250482) (xy 343.444546 -258.283713)
			(xy 343.398388 -258.310362) (xy 343.348774 -258.329834) (xy 343.296812 -258.341694) (xy 343.243662 -258.345678)
			(xy 343.190512 -258.341694) (xy 343.13855 -258.329834) (xy 343.088936 -258.310362) (xy 343.042778 -258.283713)
			(xy 343.001107 -258.250482) (xy 342.964855 -258.211411) (xy 342.934831 -258.167374) (xy 342.911705 -258.119353)
			(xy 342.895995 -258.068423) (xy 342.888052 -258.015719) (xy 342.659472 -258.015719) (xy 342.651529 -258.068423)
			(xy 342.635819 -258.119353) (xy 342.612693 -258.167374) (xy 342.582669 -258.211411) (xy 342.546417 -258.250482)
			(xy 342.504746 -258.283713) (xy 342.458588 -258.310362) (xy 342.408974 -258.329834) (xy 342.357012 -258.341694)
			(xy 342.303862 -258.345678) (xy 342.250712 -258.341694) (xy 342.19875 -258.329834) (xy 342.149136 -258.310362)
			(xy 342.102978 -258.283713) (xy 342.061307 -258.250482) (xy 342.025055 -258.211411) (xy 341.995031 -258.167374)
			(xy 341.971905 -258.119353) (xy 341.956195 -258.068423) (xy 341.948252 -258.015719) (xy 341.719672 -258.015719)
			(xy 341.711729 -258.068423) (xy 341.696019 -258.119353) (xy 341.672893 -258.167374) (xy 341.642869 -258.211411)
			(xy 341.606617 -258.250482) (xy 341.564946 -258.283713) (xy 341.518788 -258.310362) (xy 341.469174 -258.329834)
			(xy 341.417212 -258.341694) (xy 341.364062 -258.345678) (xy 341.310912 -258.341694) (xy 341.25895 -258.329834)
			(xy 341.209336 -258.310362) (xy 341.163178 -258.283713) (xy 341.121507 -258.250482) (xy 341.085255 -258.211411)
			(xy 341.055231 -258.167374) (xy 341.032105 -258.119353) (xy 341.016395 -258.068423) (xy 341.008452 -258.015719)
			(xy 340.780126 -258.015719) (xy 340.772183 -258.068423) (xy 340.756473 -258.119353) (xy 340.733347 -258.167374)
			(xy 340.703323 -258.211411) (xy 340.667071 -258.250482) (xy 340.6254 -258.283713) (xy 340.579242 -258.310362)
			(xy 340.529628 -258.329834) (xy 340.477666 -258.341694) (xy 340.424516 -258.345678) (xy 340.371366 -258.341694)
			(xy 340.319404 -258.329834) (xy 340.26979 -258.310362) (xy 340.223632 -258.283713) (xy 340.181961 -258.250482)
			(xy 340.145709 -258.211411) (xy 340.115685 -258.167374) (xy 340.092559 -258.119353) (xy 340.076849 -258.068423)
			(xy 340.068906 -258.015719) (xy 339.840072 -258.015719) (xy 339.832129 -258.068423) (xy 339.816419 -258.119353)
			(xy 339.793293 -258.167374) (xy 339.763269 -258.211411) (xy 339.727017 -258.250482) (xy 339.685346 -258.283713)
			(xy 339.639188 -258.310362) (xy 339.589574 -258.329834) (xy 339.537612 -258.341694) (xy 339.484462 -258.345678)
			(xy 339.431312 -258.341694) (xy 339.37935 -258.329834) (xy 339.329736 -258.310362) (xy 339.283578 -258.283713)
			(xy 339.241907 -258.250482) (xy 339.205655 -258.211411) (xy 339.175631 -258.167374) (xy 339.152505 -258.119353)
			(xy 339.136795 -258.068423) (xy 339.128852 -258.015719) (xy 338.900526 -258.015719) (xy 338.892583 -258.068423)
			(xy 338.876873 -258.119353) (xy 338.853747 -258.167374) (xy 338.823723 -258.211411) (xy 338.787471 -258.250482)
			(xy 338.7458 -258.283713) (xy 338.699642 -258.310362) (xy 338.650028 -258.329834) (xy 338.598066 -258.341694)
			(xy 338.544916 -258.345678) (xy 338.491766 -258.341694) (xy 338.439804 -258.329834) (xy 338.39019 -258.310362)
			(xy 338.344032 -258.283713) (xy 338.302361 -258.250482) (xy 338.266109 -258.211411) (xy 338.236085 -258.167374)
			(xy 338.212959 -258.119353) (xy 338.197249 -258.068423) (xy 338.189306 -258.015719) (xy 337.960472 -258.015719)
			(xy 337.952529 -258.068423) (xy 337.936819 -258.119353) (xy 337.913693 -258.167374) (xy 337.883669 -258.211411)
			(xy 337.847417 -258.250482) (xy 337.805746 -258.283713) (xy 337.759588 -258.310362) (xy 337.709974 -258.329834)
			(xy 337.658012 -258.341694) (xy 337.604862 -258.345678) (xy 337.551712 -258.341694) (xy 337.49975 -258.329834)
			(xy 337.450136 -258.310362) (xy 337.403978 -258.283713) (xy 337.362307 -258.250482) (xy 337.326055 -258.211411)
			(xy 337.296031 -258.167374) (xy 337.272905 -258.119353) (xy 337.257195 -258.068423) (xy 337.249252 -258.015719)
			(xy 337.02078 -258.015719) (xy 337.02078 -258.01634) (xy 337.012483 -258.070188) (xy 336.996083 -258.122144)
			(xy 336.971962 -258.170996) (xy 336.940682 -258.215606) (xy 336.902974 -258.254931) (xy 336.859717 -258.288056)
			(xy 336.81192 -258.314207) (xy 336.760698 -258.332773) (xy 336.707246 -258.343323) (xy 336.680048 -258.344924)
			(xy 336.670301 -258.345741) (xy 336.652469 -258.353739) (xy 336.638922 -258.367824) (xy 336.631623 -258.385952)
			(xy 336.63128 -258.395724) (xy 336.63128 -258.829789) (xy 336.779352 -258.829789) (xy 336.779352 -258.776491)
			(xy 336.787295 -258.723787) (xy 336.803005 -258.672857) (xy 336.826131 -258.624836) (xy 336.856155 -258.580799)
			(xy 336.892407 -258.541728) (xy 336.934078 -258.508497) (xy 336.980236 -258.481848) (xy 337.02985 -258.462376)
			(xy 337.081812 -258.450516) (xy 337.134962 -258.446533) (xy 337.188112 -258.450516) (xy 337.240074 -258.462376)
			(xy 337.289688 -258.481848) (xy 337.335846 -258.508497) (xy 337.377517 -258.541728) (xy 337.413769 -258.580799)
			(xy 337.443793 -258.624836) (xy 337.466919 -258.672857) (xy 337.482629 -258.723787) (xy 337.490572 -258.776491)
			(xy 337.49107 -258.80314) (xy 337.490572 -258.829789) (xy 337.719152 -258.829789) (xy 337.719152 -258.776491)
			(xy 337.727095 -258.723787) (xy 337.742805 -258.672857) (xy 337.765931 -258.624836) (xy 337.795955 -258.580799)
			(xy 337.832207 -258.541728) (xy 337.873878 -258.508497) (xy 337.920036 -258.481848) (xy 337.96965 -258.462376)
			(xy 338.021612 -258.450516) (xy 338.074762 -258.446533) (xy 338.127912 -258.450516) (xy 338.179874 -258.462376)
			(xy 338.229488 -258.481848) (xy 338.275646 -258.508497) (xy 338.317317 -258.541728) (xy 338.353569 -258.580799)
			(xy 338.383593 -258.624836) (xy 338.406719 -258.672857) (xy 338.422429 -258.723787) (xy 338.430372 -258.776491)
			(xy 338.43087 -258.80314) (xy 338.430372 -258.829789) (xy 338.659206 -258.829789) (xy 338.659206 -258.776491)
			(xy 338.667149 -258.723787) (xy 338.682859 -258.672857) (xy 338.705985 -258.624836) (xy 338.736009 -258.580799)
			(xy 338.772261 -258.541728) (xy 338.813932 -258.508497) (xy 338.86009 -258.481848) (xy 338.909704 -258.462376)
			(xy 338.961666 -258.450516) (xy 339.014816 -258.446533) (xy 339.067966 -258.450516) (xy 339.119928 -258.462376)
			(xy 339.169542 -258.481848) (xy 339.2157 -258.508497) (xy 339.257371 -258.541728) (xy 339.293623 -258.580799)
			(xy 339.323647 -258.624836) (xy 339.346773 -258.672857) (xy 339.362483 -258.723787) (xy 339.370426 -258.776491)
			(xy 339.370924 -258.80314) (xy 339.370426 -258.829789) (xy 339.599006 -258.829789) (xy 339.599006 -258.776491)
			(xy 339.606949 -258.723787) (xy 339.622659 -258.672857) (xy 339.645785 -258.624836) (xy 339.675809 -258.580799)
			(xy 339.712061 -258.541728) (xy 339.753732 -258.508497) (xy 339.79989 -258.481848) (xy 339.849504 -258.462376)
			(xy 339.901466 -258.450516) (xy 339.954616 -258.446533) (xy 340.007766 -258.450516) (xy 340.059728 -258.462376)
			(xy 340.109342 -258.481848) (xy 340.1555 -258.508497) (xy 340.197171 -258.541728) (xy 340.233423 -258.580799)
			(xy 340.263447 -258.624836) (xy 340.286573 -258.672857) (xy 340.302283 -258.723787) (xy 340.310226 -258.776491)
			(xy 340.310724 -258.80314) (xy 340.310226 -258.829789) (xy 340.538806 -258.829789) (xy 340.538806 -258.776491)
			(xy 340.546749 -258.723787) (xy 340.562459 -258.672857) (xy 340.585585 -258.624836) (xy 340.615609 -258.580799)
			(xy 340.651861 -258.541728) (xy 340.693532 -258.508497) (xy 340.73969 -258.481848) (xy 340.789304 -258.462376)
			(xy 340.841266 -258.450516) (xy 340.894416 -258.446533) (xy 340.947566 -258.450516) (xy 340.999528 -258.462376)
			(xy 341.049142 -258.481848) (xy 341.0953 -258.508497) (xy 341.136971 -258.541728) (xy 341.173223 -258.580799)
			(xy 341.203247 -258.624836) (xy 341.226373 -258.672857) (xy 341.242083 -258.723787) (xy 341.250026 -258.776491)
			(xy 341.250524 -258.80314) (xy 341.250026 -258.829789) (xy 341.478606 -258.829789) (xy 341.478606 -258.776491)
			(xy 341.486549 -258.723787) (xy 341.502259 -258.672857) (xy 341.525385 -258.624836) (xy 341.555409 -258.580799)
			(xy 341.591661 -258.541728) (xy 341.633332 -258.508497) (xy 341.67949 -258.481848) (xy 341.729104 -258.462376)
			(xy 341.781066 -258.450516) (xy 341.834216 -258.446533) (xy 341.887366 -258.450516) (xy 341.939328 -258.462376)
			(xy 341.988942 -258.481848) (xy 342.0351 -258.508497) (xy 342.076771 -258.541728) (xy 342.113023 -258.580799)
			(xy 342.143047 -258.624836) (xy 342.166173 -258.672857) (xy 342.181883 -258.723787) (xy 342.189826 -258.776491)
			(xy 342.190324 -258.80314) (xy 342.189826 -258.829789) (xy 342.418152 -258.829789) (xy 342.418152 -258.776491)
			(xy 342.426095 -258.723787) (xy 342.441805 -258.672857) (xy 342.464931 -258.624836) (xy 342.494955 -258.580799)
			(xy 342.531207 -258.541728) (xy 342.572878 -258.508497) (xy 342.619036 -258.481848) (xy 342.66865 -258.462376)
			(xy 342.720612 -258.450516) (xy 342.773762 -258.446533) (xy 342.826912 -258.450516) (xy 342.878874 -258.462376)
			(xy 342.928488 -258.481848) (xy 342.974646 -258.508497) (xy 343.016317 -258.541728) (xy 343.052569 -258.580799)
			(xy 343.082593 -258.624836) (xy 343.105719 -258.672857) (xy 343.121429 -258.723787) (xy 343.129372 -258.776491)
			(xy 343.12987 -258.80314) (xy 343.129372 -258.829789) (xy 343.358206 -258.829789) (xy 343.358206 -258.776491)
			(xy 343.366149 -258.723787) (xy 343.381859 -258.672857) (xy 343.404985 -258.624836) (xy 343.435009 -258.580799)
			(xy 343.471261 -258.541728) (xy 343.512932 -258.508497) (xy 343.55909 -258.481848) (xy 343.608704 -258.462376)
			(xy 343.660666 -258.450516) (xy 343.713816 -258.446533) (xy 343.766966 -258.450516) (xy 343.818928 -258.462376)
			(xy 343.868542 -258.481848) (xy 343.9147 -258.508497) (xy 343.956371 -258.541728) (xy 343.992623 -258.580799)
			(xy 344.022647 -258.624836) (xy 344.045773 -258.672857) (xy 344.061483 -258.723787) (xy 344.069426 -258.776491)
			(xy 344.069924 -258.80314) (xy 344.069426 -258.829789) (xy 344.298006 -258.829789) (xy 344.298006 -258.776491)
			(xy 344.305949 -258.723787) (xy 344.321659 -258.672857) (xy 344.344785 -258.624836) (xy 344.374809 -258.580799)
			(xy 344.411061 -258.541728) (xy 344.452732 -258.508497) (xy 344.49889 -258.481848) (xy 344.548504 -258.462376)
			(xy 344.600466 -258.450516) (xy 344.653616 -258.446533) (xy 344.706766 -258.450516) (xy 344.758728 -258.462376)
			(xy 344.808342 -258.481848) (xy 344.8545 -258.508497) (xy 344.896171 -258.541728) (xy 344.932423 -258.580799)
			(xy 344.962447 -258.624836) (xy 344.985573 -258.672857) (xy 345.001283 -258.723787) (xy 345.009226 -258.776491)
			(xy 345.009724 -258.80314) (xy 345.009226 -258.829789) (xy 345.237806 -258.829789) (xy 345.237806 -258.776491)
			(xy 345.245749 -258.723787) (xy 345.261459 -258.672857) (xy 345.284585 -258.624836) (xy 345.314609 -258.580799)
			(xy 345.350861 -258.541728) (xy 345.392532 -258.508497) (xy 345.43869 -258.481848) (xy 345.488304 -258.462376)
			(xy 345.540266 -258.450516) (xy 345.593416 -258.446533) (xy 345.646566 -258.450516) (xy 345.698528 -258.462376)
			(xy 345.748142 -258.481848) (xy 345.7943 -258.508497) (xy 345.835971 -258.541728) (xy 345.872223 -258.580799)
			(xy 345.902247 -258.624836) (xy 345.925373 -258.672857) (xy 345.941083 -258.723787) (xy 345.949026 -258.776491)
			(xy 345.949524 -258.80314) (xy 345.949026 -258.829789) (xy 346.177606 -258.829789) (xy 346.177606 -258.776491)
			(xy 346.185549 -258.723787) (xy 346.201259 -258.672857) (xy 346.224385 -258.624836) (xy 346.254409 -258.580799)
			(xy 346.290661 -258.541728) (xy 346.332332 -258.508497) (xy 346.37849 -258.481848) (xy 346.428104 -258.462376)
			(xy 346.480066 -258.450516) (xy 346.533216 -258.446533) (xy 346.586366 -258.450516) (xy 346.638328 -258.462376)
			(xy 346.687942 -258.481848) (xy 346.7341 -258.508497) (xy 346.775771 -258.541728) (xy 346.812023 -258.580799)
			(xy 346.842047 -258.624836) (xy 346.865173 -258.672857) (xy 346.880883 -258.723787) (xy 346.888826 -258.776491)
			(xy 346.889324 -258.80314) (xy 346.888826 -258.829789) (xy 346.880883 -258.882493) (xy 346.865173 -258.933423)
			(xy 346.842047 -258.981444) (xy 346.812023 -259.025481) (xy 346.775771 -259.064552) (xy 346.7341 -259.097783)
			(xy 346.687942 -259.124432) (xy 346.638328 -259.143904) (xy 346.586366 -259.155764) (xy 346.533216 -259.159748)
			(xy 346.480066 -259.155764) (xy 346.428104 -259.143904) (xy 346.37849 -259.124432) (xy 346.332332 -259.097783)
			(xy 346.290661 -259.064552) (xy 346.254409 -259.025481) (xy 346.224385 -258.981444) (xy 346.201259 -258.933423)
			(xy 346.185549 -258.882493) (xy 346.177606 -258.829789) (xy 345.949026 -258.829789) (xy 345.941083 -258.882493)
			(xy 345.925373 -258.933423) (xy 345.902247 -258.981444) (xy 345.872223 -259.025481) (xy 345.835971 -259.064552)
			(xy 345.7943 -259.097783) (xy 345.748142 -259.124432) (xy 345.698528 -259.143904) (xy 345.646566 -259.155764)
			(xy 345.593416 -259.159748) (xy 345.540266 -259.155764) (xy 345.488304 -259.143904) (xy 345.43869 -259.124432)
			(xy 345.392532 -259.097783) (xy 345.350861 -259.064552) (xy 345.314609 -259.025481) (xy 345.284585 -258.981444)
			(xy 345.261459 -258.933423) (xy 345.245749 -258.882493) (xy 345.237806 -258.829789) (xy 345.009226 -258.829789)
			(xy 345.001283 -258.882493) (xy 344.985573 -258.933423) (xy 344.962447 -258.981444) (xy 344.932423 -259.025481)
			(xy 344.896171 -259.064552) (xy 344.8545 -259.097783) (xy 344.808342 -259.124432) (xy 344.758728 -259.143904)
			(xy 344.706766 -259.155764) (xy 344.653616 -259.159748) (xy 344.600466 -259.155764) (xy 344.548504 -259.143904)
			(xy 344.49889 -259.124432) (xy 344.452732 -259.097783) (xy 344.411061 -259.064552) (xy 344.374809 -259.025481)
			(xy 344.344785 -258.981444) (xy 344.321659 -258.933423) (xy 344.305949 -258.882493) (xy 344.298006 -258.829789)
			(xy 344.069426 -258.829789) (xy 344.061483 -258.882493) (xy 344.045773 -258.933423) (xy 344.022647 -258.981444)
			(xy 343.992623 -259.025481) (xy 343.956371 -259.064552) (xy 343.9147 -259.097783) (xy 343.868542 -259.124432)
			(xy 343.818928 -259.143904) (xy 343.766966 -259.155764) (xy 343.713816 -259.159748) (xy 343.660666 -259.155764)
			(xy 343.608704 -259.143904) (xy 343.55909 -259.124432) (xy 343.512932 -259.097783) (xy 343.471261 -259.064552)
			(xy 343.435009 -259.025481) (xy 343.404985 -258.981444) (xy 343.381859 -258.933423) (xy 343.366149 -258.882493)
			(xy 343.358206 -258.829789) (xy 343.129372 -258.829789) (xy 343.121429 -258.882493) (xy 343.105719 -258.933423)
			(xy 343.082593 -258.981444) (xy 343.052569 -259.025481) (xy 343.016317 -259.064552) (xy 342.974646 -259.097783)
			(xy 342.928488 -259.124432) (xy 342.878874 -259.143904) (xy 342.826912 -259.155764) (xy 342.773762 -259.159748)
			(xy 342.720612 -259.155764) (xy 342.66865 -259.143904) (xy 342.619036 -259.124432) (xy 342.572878 -259.097783)
			(xy 342.531207 -259.064552) (xy 342.494955 -259.025481) (xy 342.464931 -258.981444) (xy 342.441805 -258.933423)
			(xy 342.426095 -258.882493) (xy 342.418152 -258.829789) (xy 342.189826 -258.829789) (xy 342.181883 -258.882493)
			(xy 342.166173 -258.933423) (xy 342.143047 -258.981444) (xy 342.113023 -259.025481) (xy 342.076771 -259.064552)
			(xy 342.0351 -259.097783) (xy 341.988942 -259.124432) (xy 341.939328 -259.143904) (xy 341.887366 -259.155764)
			(xy 341.834216 -259.159748) (xy 341.781066 -259.155764) (xy 341.729104 -259.143904) (xy 341.67949 -259.124432)
			(xy 341.633332 -259.097783) (xy 341.591661 -259.064552) (xy 341.555409 -259.025481) (xy 341.525385 -258.981444)
			(xy 341.502259 -258.933423) (xy 341.486549 -258.882493) (xy 341.478606 -258.829789) (xy 341.250026 -258.829789)
			(xy 341.242083 -258.882493) (xy 341.226373 -258.933423) (xy 341.203247 -258.981444) (xy 341.173223 -259.025481)
			(xy 341.136971 -259.064552) (xy 341.0953 -259.097783) (xy 341.049142 -259.124432) (xy 340.999528 -259.143904)
			(xy 340.947566 -259.155764) (xy 340.894416 -259.159748) (xy 340.841266 -259.155764) (xy 340.789304 -259.143904)
			(xy 340.73969 -259.124432) (xy 340.693532 -259.097783) (xy 340.651861 -259.064552) (xy 340.615609 -259.025481)
			(xy 340.585585 -258.981444) (xy 340.562459 -258.933423) (xy 340.546749 -258.882493) (xy 340.538806 -258.829789)
			(xy 340.310226 -258.829789) (xy 340.302283 -258.882493) (xy 340.286573 -258.933423) (xy 340.263447 -258.981444)
			(xy 340.233423 -259.025481) (xy 340.197171 -259.064552) (xy 340.1555 -259.097783) (xy 340.109342 -259.124432)
			(xy 340.059728 -259.143904) (xy 340.007766 -259.155764) (xy 339.954616 -259.159748) (xy 339.901466 -259.155764)
			(xy 339.849504 -259.143904) (xy 339.79989 -259.124432) (xy 339.753732 -259.097783) (xy 339.712061 -259.064552)
			(xy 339.675809 -259.025481) (xy 339.645785 -258.981444) (xy 339.622659 -258.933423) (xy 339.606949 -258.882493)
			(xy 339.599006 -258.829789) (xy 339.370426 -258.829789) (xy 339.362483 -258.882493) (xy 339.346773 -258.933423)
			(xy 339.323647 -258.981444) (xy 339.293623 -259.025481) (xy 339.257371 -259.064552) (xy 339.2157 -259.097783)
			(xy 339.169542 -259.124432) (xy 339.119928 -259.143904) (xy 339.067966 -259.155764) (xy 339.014816 -259.159748)
			(xy 338.961666 -259.155764) (xy 338.909704 -259.143904) (xy 338.86009 -259.124432) (xy 338.813932 -259.097783)
			(xy 338.772261 -259.064552) (xy 338.736009 -259.025481) (xy 338.705985 -258.981444) (xy 338.682859 -258.933423)
			(xy 338.667149 -258.882493) (xy 338.659206 -258.829789) (xy 338.430372 -258.829789) (xy 338.422429 -258.882493)
			(xy 338.406719 -258.933423) (xy 338.383593 -258.981444) (xy 338.353569 -259.025481) (xy 338.317317 -259.064552)
			(xy 338.275646 -259.097783) (xy 338.229488 -259.124432) (xy 338.179874 -259.143904) (xy 338.127912 -259.155764)
			(xy 338.074762 -259.159748) (xy 338.021612 -259.155764) (xy 337.96965 -259.143904) (xy 337.920036 -259.124432)
			(xy 337.873878 -259.097783) (xy 337.832207 -259.064552) (xy 337.795955 -259.025481) (xy 337.765931 -258.981444)
			(xy 337.742805 -258.933423) (xy 337.727095 -258.882493) (xy 337.719152 -258.829789) (xy 337.490572 -258.829789)
			(xy 337.482629 -258.882493) (xy 337.466919 -258.933423) (xy 337.443793 -258.981444) (xy 337.413769 -259.025481)
			(xy 337.377517 -259.064552) (xy 337.335846 -259.097783) (xy 337.289688 -259.124432) (xy 337.240074 -259.143904)
			(xy 337.188112 -259.155764) (xy 337.134962 -259.159748) (xy 337.081812 -259.155764) (xy 337.02985 -259.143904)
			(xy 336.980236 -259.124432) (xy 336.934078 -259.097783) (xy 336.892407 -259.064552) (xy 336.856155 -259.025481)
			(xy 336.826131 -258.981444) (xy 336.803005 -258.933423) (xy 336.787295 -258.882493) (xy 336.779352 -258.829789)
			(xy 336.63128 -258.829789) (xy 336.63128 -259.210302) (xy 336.631717 -259.220066) (xy 336.638999 -259.238186)
			(xy 336.652513 -259.252283) (xy 336.670308 -259.260325) (xy 336.680048 -259.261102) (xy 336.707245 -259.262762)
			(xy 336.760699 -259.273312) (xy 336.811923 -259.291879) (xy 336.859722 -259.318031) (xy 336.902981 -259.351156)
			(xy 336.940691 -259.390483) (xy 336.971972 -259.435094) (xy 336.996095 -259.483948) (xy 337.012496 -259.535906)
			(xy 337.020794 -259.589756) (xy 337.020794 -259.643605) (xy 337.249252 -259.643605) (xy 337.249252 -259.590307)
			(xy 337.257195 -259.537603) (xy 337.272905 -259.486673) (xy 337.296031 -259.438652) (xy 337.326055 -259.394615)
			(xy 337.362307 -259.355544) (xy 337.403978 -259.322313) (xy 337.450136 -259.295664) (xy 337.49975 -259.276192)
			(xy 337.551712 -259.264332) (xy 337.604862 -259.260349) (xy 337.658012 -259.264332) (xy 337.709974 -259.276192)
			(xy 337.759588 -259.295664) (xy 337.805746 -259.322313) (xy 337.847417 -259.355544) (xy 337.883669 -259.394615)
			(xy 337.913693 -259.438652) (xy 337.936819 -259.486673) (xy 337.952529 -259.537603) (xy 337.960472 -259.590307)
			(xy 337.96097 -259.616956) (xy 337.960472 -259.643605) (xy 338.189052 -259.643605) (xy 338.189052 -259.590307)
			(xy 338.196995 -259.537603) (xy 338.212705 -259.486673) (xy 338.235831 -259.438652) (xy 338.265855 -259.394615)
			(xy 338.302107 -259.355544) (xy 338.343778 -259.322313) (xy 338.389936 -259.295664) (xy 338.43955 -259.276192)
			(xy 338.491512 -259.264332) (xy 338.544662 -259.260349) (xy 338.597812 -259.264332) (xy 338.649774 -259.276192)
			(xy 338.699388 -259.295664) (xy 338.745546 -259.322313) (xy 338.787217 -259.355544) (xy 338.823469 -259.394615)
			(xy 338.853493 -259.438652) (xy 338.876619 -259.486673) (xy 338.892329 -259.537603) (xy 338.900272 -259.590307)
			(xy 338.90077 -259.616956) (xy 338.900272 -259.643605) (xy 339.129106 -259.643605) (xy 339.129106 -259.590307)
			(xy 339.137049 -259.537603) (xy 339.152759 -259.486673) (xy 339.175885 -259.438652) (xy 339.205909 -259.394615)
			(xy 339.242161 -259.355544) (xy 339.283832 -259.322313) (xy 339.32999 -259.295664) (xy 339.379604 -259.276192)
			(xy 339.431566 -259.264332) (xy 339.484716 -259.260349) (xy 339.537866 -259.264332) (xy 339.589828 -259.276192)
			(xy 339.639442 -259.295664) (xy 339.6856 -259.322313) (xy 339.727271 -259.355544) (xy 339.763523 -259.394615)
			(xy 339.793547 -259.438652) (xy 339.816673 -259.486673) (xy 339.832383 -259.537603) (xy 339.840326 -259.590307)
			(xy 339.840824 -259.616956) (xy 339.840326 -259.643605) (xy 340.068652 -259.643605) (xy 340.068652 -259.590307)
			(xy 340.076595 -259.537603) (xy 340.092305 -259.486673) (xy 340.115431 -259.438652) (xy 340.145455 -259.394615)
			(xy 340.181707 -259.355544) (xy 340.223378 -259.322313) (xy 340.269536 -259.295664) (xy 340.31915 -259.276192)
			(xy 340.371112 -259.264332) (xy 340.424262 -259.260349) (xy 340.477412 -259.264332) (xy 340.529374 -259.276192)
			(xy 340.578988 -259.295664) (xy 340.625146 -259.322313) (xy 340.666817 -259.355544) (xy 340.703069 -259.394615)
			(xy 340.733093 -259.438652) (xy 340.756219 -259.486673) (xy 340.771929 -259.537603) (xy 340.779872 -259.590307)
			(xy 340.78037 -259.616956) (xy 340.779872 -259.643605) (xy 341.008452 -259.643605) (xy 341.008452 -259.590307)
			(xy 341.016395 -259.537603) (xy 341.032105 -259.486673) (xy 341.055231 -259.438652) (xy 341.085255 -259.394615)
			(xy 341.121507 -259.355544) (xy 341.163178 -259.322313) (xy 341.209336 -259.295664) (xy 341.25895 -259.276192)
			(xy 341.310912 -259.264332) (xy 341.364062 -259.260349) (xy 341.417212 -259.264332) (xy 341.469174 -259.276192)
			(xy 341.518788 -259.295664) (xy 341.564946 -259.322313) (xy 341.606617 -259.355544) (xy 341.642869 -259.394615)
			(xy 341.672893 -259.438652) (xy 341.696019 -259.486673) (xy 341.711729 -259.537603) (xy 341.719672 -259.590307)
			(xy 341.72017 -259.616956) (xy 341.719672 -259.643605) (xy 341.948252 -259.643605) (xy 341.948252 -259.590307)
			(xy 341.956195 -259.537603) (xy 341.971905 -259.486673) (xy 341.995031 -259.438652) (xy 342.025055 -259.394615)
			(xy 342.061307 -259.355544) (xy 342.102978 -259.322313) (xy 342.149136 -259.295664) (xy 342.19875 -259.276192)
			(xy 342.250712 -259.264332) (xy 342.303862 -259.260349) (xy 342.357012 -259.264332) (xy 342.408974 -259.276192)
			(xy 342.458588 -259.295664) (xy 342.504746 -259.322313) (xy 342.546417 -259.355544) (xy 342.582669 -259.394615)
			(xy 342.612693 -259.438652) (xy 342.635819 -259.486673) (xy 342.651529 -259.537603) (xy 342.659472 -259.590307)
			(xy 342.65997 -259.616956) (xy 342.659472 -259.643605) (xy 342.888052 -259.643605) (xy 342.888052 -259.590307)
			(xy 342.895995 -259.537603) (xy 342.911705 -259.486673) (xy 342.934831 -259.438652) (xy 342.964855 -259.394615)
			(xy 343.001107 -259.355544) (xy 343.042778 -259.322313) (xy 343.088936 -259.295664) (xy 343.13855 -259.276192)
			(xy 343.190512 -259.264332) (xy 343.243662 -259.260349) (xy 343.296812 -259.264332) (xy 343.348774 -259.276192)
			(xy 343.398388 -259.295664) (xy 343.444546 -259.322313) (xy 343.486217 -259.355544) (xy 343.522469 -259.394615)
			(xy 343.552493 -259.438652) (xy 343.575619 -259.486673) (xy 343.591329 -259.537603) (xy 343.599272 -259.590307)
			(xy 343.59977 -259.616956) (xy 343.599272 -259.643605) (xy 343.827852 -259.643605) (xy 343.827852 -259.590307)
			(xy 343.835795 -259.537603) (xy 343.851505 -259.486673) (xy 343.874631 -259.438652) (xy 343.904655 -259.394615)
			(xy 343.940907 -259.355544) (xy 343.982578 -259.322313) (xy 344.028736 -259.295664) (xy 344.07835 -259.276192)
			(xy 344.130312 -259.264332) (xy 344.183462 -259.260349) (xy 344.236612 -259.264332) (xy 344.288574 -259.276192)
			(xy 344.338188 -259.295664) (xy 344.384346 -259.322313) (xy 344.426017 -259.355544) (xy 344.462269 -259.394615)
			(xy 344.492293 -259.438652) (xy 344.515419 -259.486673) (xy 344.531129 -259.537603) (xy 344.539072 -259.590307)
			(xy 344.53957 -259.616956) (xy 344.539072 -259.643605) (xy 344.767652 -259.643605) (xy 344.767652 -259.590307)
			(xy 344.775595 -259.537603) (xy 344.791305 -259.486673) (xy 344.814431 -259.438652) (xy 344.844455 -259.394615)
			(xy 344.880707 -259.355544) (xy 344.922378 -259.322313) (xy 344.968536 -259.295664) (xy 345.01815 -259.276192)
			(xy 345.070112 -259.264332) (xy 345.123262 -259.260349) (xy 345.176412 -259.264332) (xy 345.228374 -259.276192)
			(xy 345.277988 -259.295664) (xy 345.324146 -259.322313) (xy 345.365817 -259.355544) (xy 345.402069 -259.394615)
			(xy 345.432093 -259.438652) (xy 345.455219 -259.486673) (xy 345.470929 -259.537603) (xy 345.478872 -259.590307)
			(xy 345.47937 -259.616956) (xy 345.478872 -259.643605) (xy 345.707706 -259.643605) (xy 345.707706 -259.590307)
			(xy 345.715649 -259.537603) (xy 345.731359 -259.486673) (xy 345.754485 -259.438652) (xy 345.784509 -259.394615)
			(xy 345.820761 -259.355544) (xy 345.862432 -259.322313) (xy 345.90859 -259.295664) (xy 345.958204 -259.276192)
			(xy 346.010166 -259.264332) (xy 346.063316 -259.260349) (xy 346.116466 -259.264332) (xy 346.168428 -259.276192)
			(xy 346.218042 -259.295664) (xy 346.2642 -259.322313) (xy 346.305871 -259.355544) (xy 346.342123 -259.394615)
			(xy 346.372147 -259.438652) (xy 346.395273 -259.486673) (xy 346.410983 -259.537603) (xy 346.418926 -259.590307)
			(xy 346.419424 -259.616956) (xy 346.418926 -259.643605) (xy 346.410983 -259.696309) (xy 346.395273 -259.747239)
			(xy 346.372147 -259.79526) (xy 346.342123 -259.839297) (xy 346.305871 -259.878368) (xy 346.2642 -259.911599)
			(xy 346.218042 -259.938248) (xy 346.168428 -259.95772) (xy 346.116466 -259.96958) (xy 346.063316 -259.973564)
			(xy 346.010166 -259.96958) (xy 345.958204 -259.95772) (xy 345.90859 -259.938248) (xy 345.862432 -259.911599)
			(xy 345.820761 -259.878368) (xy 345.784509 -259.839297) (xy 345.754485 -259.79526) (xy 345.731359 -259.747239)
			(xy 345.715649 -259.696309) (xy 345.707706 -259.643605) (xy 345.478872 -259.643605) (xy 345.470929 -259.696309)
			(xy 345.455219 -259.747239) (xy 345.432093 -259.79526) (xy 345.402069 -259.839297) (xy 345.365817 -259.878368)
			(xy 345.324146 -259.911599) (xy 345.277988 -259.938248) (xy 345.228374 -259.95772) (xy 345.176412 -259.96958)
			(xy 345.123262 -259.973564) (xy 345.070112 -259.96958) (xy 345.01815 -259.95772) (xy 344.968536 -259.938248)
			(xy 344.922378 -259.911599) (xy 344.880707 -259.878368) (xy 344.844455 -259.839297) (xy 344.814431 -259.79526)
			(xy 344.791305 -259.747239) (xy 344.775595 -259.696309) (xy 344.767652 -259.643605) (xy 344.539072 -259.643605)
			(xy 344.531129 -259.696309) (xy 344.515419 -259.747239) (xy 344.492293 -259.79526) (xy 344.462269 -259.839297)
			(xy 344.426017 -259.878368) (xy 344.384346 -259.911599) (xy 344.338188 -259.938248) (xy 344.288574 -259.95772)
			(xy 344.236612 -259.96958) (xy 344.183462 -259.973564) (xy 344.130312 -259.96958) (xy 344.07835 -259.95772)
			(xy 344.028736 -259.938248) (xy 343.982578 -259.911599) (xy 343.940907 -259.878368) (xy 343.904655 -259.839297)
			(xy 343.874631 -259.79526) (xy 343.851505 -259.747239) (xy 343.835795 -259.696309) (xy 343.827852 -259.643605)
			(xy 343.599272 -259.643605) (xy 343.591329 -259.696309) (xy 343.575619 -259.747239) (xy 343.552493 -259.79526)
			(xy 343.522469 -259.839297) (xy 343.486217 -259.878368) (xy 343.444546 -259.911599) (xy 343.398388 -259.938248)
			(xy 343.348774 -259.95772) (xy 343.296812 -259.96958) (xy 343.243662 -259.973564) (xy 343.190512 -259.96958)
			(xy 343.13855 -259.95772) (xy 343.088936 -259.938248) (xy 343.042778 -259.911599) (xy 343.001107 -259.878368)
			(xy 342.964855 -259.839297) (xy 342.934831 -259.79526) (xy 342.911705 -259.747239) (xy 342.895995 -259.696309)
			(xy 342.888052 -259.643605) (xy 342.659472 -259.643605) (xy 342.651529 -259.696309) (xy 342.635819 -259.747239)
			(xy 342.612693 -259.79526) (xy 342.582669 -259.839297) (xy 342.546417 -259.878368) (xy 342.504746 -259.911599)
			(xy 342.458588 -259.938248) (xy 342.408974 -259.95772) (xy 342.357012 -259.96958) (xy 342.303862 -259.973564)
			(xy 342.250712 -259.96958) (xy 342.19875 -259.95772) (xy 342.149136 -259.938248) (xy 342.102978 -259.911599)
			(xy 342.061307 -259.878368) (xy 342.025055 -259.839297) (xy 341.995031 -259.79526) (xy 341.971905 -259.747239)
			(xy 341.956195 -259.696309) (xy 341.948252 -259.643605) (xy 341.719672 -259.643605) (xy 341.711729 -259.696309)
			(xy 341.696019 -259.747239) (xy 341.672893 -259.79526) (xy 341.642869 -259.839297) (xy 341.606617 -259.878368)
			(xy 341.564946 -259.911599) (xy 341.518788 -259.938248) (xy 341.469174 -259.95772) (xy 341.417212 -259.96958)
			(xy 341.364062 -259.973564) (xy 341.310912 -259.96958) (xy 341.25895 -259.95772) (xy 341.209336 -259.938248)
			(xy 341.163178 -259.911599) (xy 341.121507 -259.878368) (xy 341.085255 -259.839297) (xy 341.055231 -259.79526)
			(xy 341.032105 -259.747239) (xy 341.016395 -259.696309) (xy 341.008452 -259.643605) (xy 340.779872 -259.643605)
			(xy 340.771929 -259.696309) (xy 340.756219 -259.747239) (xy 340.733093 -259.79526) (xy 340.703069 -259.839297)
			(xy 340.666817 -259.878368) (xy 340.625146 -259.911599) (xy 340.578988 -259.938248) (xy 340.529374 -259.95772)
			(xy 340.477412 -259.96958) (xy 340.424262 -259.973564) (xy 340.371112 -259.96958) (xy 340.31915 -259.95772)
			(xy 340.269536 -259.938248) (xy 340.223378 -259.911599) (xy 340.181707 -259.878368) (xy 340.145455 -259.839297)
			(xy 340.115431 -259.79526) (xy 340.092305 -259.747239) (xy 340.076595 -259.696309) (xy 340.068652 -259.643605)
			(xy 339.840326 -259.643605) (xy 339.832383 -259.696309) (xy 339.816673 -259.747239) (xy 339.793547 -259.79526)
			(xy 339.763523 -259.839297) (xy 339.727271 -259.878368) (xy 339.6856 -259.911599) (xy 339.639442 -259.938248)
			(xy 339.589828 -259.95772) (xy 339.537866 -259.96958) (xy 339.484716 -259.973564) (xy 339.431566 -259.96958)
			(xy 339.379604 -259.95772) (xy 339.32999 -259.938248) (xy 339.283832 -259.911599) (xy 339.242161 -259.878368)
			(xy 339.205909 -259.839297) (xy 339.175885 -259.79526) (xy 339.152759 -259.747239) (xy 339.137049 -259.696309)
			(xy 339.129106 -259.643605) (xy 338.900272 -259.643605) (xy 338.892329 -259.696309) (xy 338.876619 -259.747239)
			(xy 338.853493 -259.79526) (xy 338.823469 -259.839297) (xy 338.787217 -259.878368) (xy 338.745546 -259.911599)
			(xy 338.699388 -259.938248) (xy 338.649774 -259.95772) (xy 338.597812 -259.96958) (xy 338.544662 -259.973564)
			(xy 338.491512 -259.96958) (xy 338.43955 -259.95772) (xy 338.389936 -259.938248) (xy 338.343778 -259.911599)
			(xy 338.302107 -259.878368) (xy 338.265855 -259.839297) (xy 338.235831 -259.79526) (xy 338.212705 -259.747239)
			(xy 338.196995 -259.696309) (xy 338.189052 -259.643605) (xy 337.960472 -259.643605) (xy 337.952529 -259.696309)
			(xy 337.936819 -259.747239) (xy 337.913693 -259.79526) (xy 337.883669 -259.839297) (xy 337.847417 -259.878368)
			(xy 337.805746 -259.911599) (xy 337.759588 -259.938248) (xy 337.709974 -259.95772) (xy 337.658012 -259.96958)
			(xy 337.604862 -259.973564) (xy 337.551712 -259.96958) (xy 337.49975 -259.95772) (xy 337.450136 -259.938248)
			(xy 337.403978 -259.911599) (xy 337.362307 -259.878368) (xy 337.326055 -259.839297) (xy 337.296031 -259.79526)
			(xy 337.272905 -259.747239) (xy 337.257195 -259.696309) (xy 337.249252 -259.643605) (xy 337.020794 -259.643605)
			(xy 337.020794 -259.644241) (xy 337.012497 -259.698091) (xy 336.996096 -259.750049) (xy 336.971974 -259.798903)
			(xy 336.940693 -259.843514) (xy 336.902984 -259.882841) (xy 336.859725 -259.915967) (xy 336.811926 -259.942119)
			(xy 336.760703 -259.960687) (xy 336.707249 -259.971237) (xy 336.680048 -259.97281) (xy 336.670307 -259.973628)
			(xy 336.652491 -259.981629) (xy 336.638964 -259.995717) (xy 336.631694 -260.013844) (xy 336.63128 -260.02361)
			(xy 336.63128 -260.457421) (xy 336.779606 -260.457421) (xy 336.779606 -260.404123) (xy 336.787549 -260.351419)
			(xy 336.803259 -260.300489) (xy 336.826385 -260.252468) (xy 336.856409 -260.208431) (xy 336.892661 -260.16936)
			(xy 336.934332 -260.136129) (xy 336.98049 -260.10948) (xy 337.030104 -260.090008) (xy 337.082066 -260.078148)
			(xy 337.135216 -260.074165) (xy 337.188366 -260.078148) (xy 337.240328 -260.090008) (xy 337.289942 -260.10948)
			(xy 337.3361 -260.136129) (xy 337.377771 -260.16936) (xy 337.414023 -260.208431) (xy 337.444047 -260.252468)
			(xy 337.467173 -260.300489) (xy 337.482883 -260.351419) (xy 337.490826 -260.404123) (xy 337.491324 -260.430772)
			(xy 337.490826 -260.457421) (xy 337.719406 -260.457421) (xy 337.719406 -260.404123) (xy 337.727349 -260.351419)
			(xy 337.743059 -260.300489) (xy 337.766185 -260.252468) (xy 337.796209 -260.208431) (xy 337.832461 -260.16936)
			(xy 337.874132 -260.136129) (xy 337.92029 -260.10948) (xy 337.969904 -260.090008) (xy 338.021866 -260.078148)
			(xy 338.075016 -260.074165) (xy 338.128166 -260.078148) (xy 338.180128 -260.090008) (xy 338.229742 -260.10948)
			(xy 338.2759 -260.136129) (xy 338.317571 -260.16936) (xy 338.353823 -260.208431) (xy 338.383847 -260.252468)
			(xy 338.406973 -260.300489) (xy 338.422683 -260.351419) (xy 338.430626 -260.404123) (xy 338.431124 -260.430772)
			(xy 338.430626 -260.457421) (xy 338.659206 -260.457421) (xy 338.659206 -260.404123) (xy 338.667149 -260.351419)
			(xy 338.682859 -260.300489) (xy 338.705985 -260.252468) (xy 338.736009 -260.208431) (xy 338.772261 -260.16936)
			(xy 338.813932 -260.136129) (xy 338.86009 -260.10948) (xy 338.909704 -260.090008) (xy 338.961666 -260.078148)
			(xy 339.014816 -260.074165) (xy 339.067966 -260.078148) (xy 339.119928 -260.090008) (xy 339.169542 -260.10948)
			(xy 339.2157 -260.136129) (xy 339.257371 -260.16936) (xy 339.293623 -260.208431) (xy 339.323647 -260.252468)
			(xy 339.346773 -260.300489) (xy 339.362483 -260.351419) (xy 339.370426 -260.404123) (xy 339.370924 -260.430772)
			(xy 339.370426 -260.457421) (xy 339.598752 -260.457421) (xy 339.598752 -260.404123) (xy 339.606695 -260.351419)
			(xy 339.622405 -260.300489) (xy 339.645531 -260.252468) (xy 339.675555 -260.208431) (xy 339.711807 -260.16936)
			(xy 339.753478 -260.136129) (xy 339.799636 -260.10948) (xy 339.84925 -260.090008) (xy 339.901212 -260.078148)
			(xy 339.954362 -260.074165) (xy 340.007512 -260.078148) (xy 340.059474 -260.090008) (xy 340.109088 -260.10948)
			(xy 340.155246 -260.136129) (xy 340.196917 -260.16936) (xy 340.233169 -260.208431) (xy 340.263193 -260.252468)
			(xy 340.286319 -260.300489) (xy 340.302029 -260.351419) (xy 340.309972 -260.404123) (xy 340.31047 -260.430772)
			(xy 340.309972 -260.457421) (xy 340.538806 -260.457421) (xy 340.538806 -260.404123) (xy 340.546749 -260.351419)
			(xy 340.562459 -260.300489) (xy 340.585585 -260.252468) (xy 340.615609 -260.208431) (xy 340.651861 -260.16936)
			(xy 340.693532 -260.136129) (xy 340.73969 -260.10948) (xy 340.789304 -260.090008) (xy 340.841266 -260.078148)
			(xy 340.894416 -260.074165) (xy 340.947566 -260.078148) (xy 340.999528 -260.090008) (xy 341.049142 -260.10948)
			(xy 341.0953 -260.136129) (xy 341.136971 -260.16936) (xy 341.173223 -260.208431) (xy 341.203247 -260.252468)
			(xy 341.226373 -260.300489) (xy 341.242083 -260.351419) (xy 341.250026 -260.404123) (xy 341.250524 -260.430772)
			(xy 341.250026 -260.457421) (xy 341.478606 -260.457421) (xy 341.478606 -260.404123) (xy 341.486549 -260.351419)
			(xy 341.502259 -260.300489) (xy 341.525385 -260.252468) (xy 341.555409 -260.208431) (xy 341.591661 -260.16936)
			(xy 341.633332 -260.136129) (xy 341.67949 -260.10948) (xy 341.729104 -260.090008) (xy 341.781066 -260.078148)
			(xy 341.834216 -260.074165) (xy 341.887366 -260.078148) (xy 341.939328 -260.090008) (xy 341.988942 -260.10948)
			(xy 342.0351 -260.136129) (xy 342.076771 -260.16936) (xy 342.113023 -260.208431) (xy 342.143047 -260.252468)
			(xy 342.166173 -260.300489) (xy 342.181883 -260.351419) (xy 342.189826 -260.404123) (xy 342.190324 -260.430772)
			(xy 342.189826 -260.457421) (xy 342.417898 -260.457421) (xy 342.417898 -260.404123) (xy 342.425841 -260.351419)
			(xy 342.441551 -260.300489) (xy 342.464677 -260.252468) (xy 342.494701 -260.208431) (xy 342.530953 -260.16936)
			(xy 342.572624 -260.136129) (xy 342.618782 -260.10948) (xy 342.668396 -260.090008) (xy 342.720358 -260.078148)
			(xy 342.773508 -260.074165) (xy 342.826658 -260.078148) (xy 342.87862 -260.090008) (xy 342.928234 -260.10948)
			(xy 342.974392 -260.136129) (xy 343.016063 -260.16936) (xy 343.052315 -260.208431) (xy 343.082339 -260.252468)
			(xy 343.105465 -260.300489) (xy 343.121175 -260.351419) (xy 343.129118 -260.404123) (xy 343.129616 -260.430772)
			(xy 343.129118 -260.457421) (xy 343.358206 -260.457421) (xy 343.358206 -260.404123) (xy 343.366149 -260.351419)
			(xy 343.381859 -260.300489) (xy 343.404985 -260.252468) (xy 343.435009 -260.208431) (xy 343.471261 -260.16936)
			(xy 343.512932 -260.136129) (xy 343.55909 -260.10948) (xy 343.608704 -260.090008) (xy 343.660666 -260.078148)
			(xy 343.713816 -260.074165) (xy 343.766966 -260.078148) (xy 343.818928 -260.090008) (xy 343.868542 -260.10948)
			(xy 343.9147 -260.136129) (xy 343.956371 -260.16936) (xy 343.992623 -260.208431) (xy 344.022647 -260.252468)
			(xy 344.045773 -260.300489) (xy 344.061483 -260.351419) (xy 344.069426 -260.404123) (xy 344.069924 -260.430772)
			(xy 344.069426 -260.457421) (xy 344.297498 -260.457421) (xy 344.297498 -260.404123) (xy 344.305441 -260.351419)
			(xy 344.321151 -260.300489) (xy 344.344277 -260.252468) (xy 344.374301 -260.208431) (xy 344.410553 -260.16936)
			(xy 344.452224 -260.136129) (xy 344.498382 -260.10948) (xy 344.547996 -260.090008) (xy 344.599958 -260.078148)
			(xy 344.653108 -260.074165) (xy 344.706258 -260.078148) (xy 344.75822 -260.090008) (xy 344.807834 -260.10948)
			(xy 344.853992 -260.136129) (xy 344.895663 -260.16936) (xy 344.931915 -260.208431) (xy 344.961939 -260.252468)
			(xy 344.985065 -260.300489) (xy 345.000775 -260.351419) (xy 345.008718 -260.404123) (xy 345.009216 -260.430772)
			(xy 345.008718 -260.457421) (xy 345.237806 -260.457421) (xy 345.237806 -260.404123) (xy 345.245749 -260.351419)
			(xy 345.261459 -260.300489) (xy 345.284585 -260.252468) (xy 345.314609 -260.208431) (xy 345.350861 -260.16936)
			(xy 345.392532 -260.136129) (xy 345.43869 -260.10948) (xy 345.488304 -260.090008) (xy 345.540266 -260.078148)
			(xy 345.593416 -260.074165) (xy 345.646566 -260.078148) (xy 345.698528 -260.090008) (xy 345.748142 -260.10948)
			(xy 345.7943 -260.136129) (xy 345.835971 -260.16936) (xy 345.872223 -260.208431) (xy 345.902247 -260.252468)
			(xy 345.925373 -260.300489) (xy 345.941083 -260.351419) (xy 345.949026 -260.404123) (xy 345.949524 -260.430772)
			(xy 345.949026 -260.457421) (xy 346.177352 -260.457421) (xy 346.177352 -260.404123) (xy 346.185295 -260.351419)
			(xy 346.201005 -260.300489) (xy 346.224131 -260.252468) (xy 346.254155 -260.208431) (xy 346.290407 -260.16936)
			(xy 346.332078 -260.136129) (xy 346.378236 -260.10948) (xy 346.42785 -260.090008) (xy 346.479812 -260.078148)
			(xy 346.532962 -260.074165) (xy 346.586112 -260.078148) (xy 346.638074 -260.090008) (xy 346.687688 -260.10948)
			(xy 346.733846 -260.136129) (xy 346.775517 -260.16936) (xy 346.811769 -260.208431) (xy 346.841793 -260.252468)
			(xy 346.864919 -260.300489) (xy 346.880629 -260.351419) (xy 346.888572 -260.404123) (xy 346.88907 -260.430772)
			(xy 346.888572 -260.457421) (xy 346.880629 -260.510125) (xy 346.864919 -260.561055) (xy 346.841793 -260.609076)
			(xy 346.811769 -260.653113) (xy 346.775517 -260.692184) (xy 346.733846 -260.725415) (xy 346.687688 -260.752064)
			(xy 346.638074 -260.771536) (xy 346.586112 -260.783396) (xy 346.532962 -260.78738) (xy 346.479812 -260.783396)
			(xy 346.42785 -260.771536) (xy 346.378236 -260.752064) (xy 346.332078 -260.725415) (xy 346.290407 -260.692184)
			(xy 346.254155 -260.653113) (xy 346.224131 -260.609076) (xy 346.201005 -260.561055) (xy 346.185295 -260.510125)
			(xy 346.177352 -260.457421) (xy 345.949026 -260.457421) (xy 345.941083 -260.510125) (xy 345.925373 -260.561055)
			(xy 345.902247 -260.609076) (xy 345.872223 -260.653113) (xy 345.835971 -260.692184) (xy 345.7943 -260.725415)
			(xy 345.748142 -260.752064) (xy 345.698528 -260.771536) (xy 345.646566 -260.783396) (xy 345.593416 -260.78738)
			(xy 345.540266 -260.783396) (xy 345.488304 -260.771536) (xy 345.43869 -260.752064) (xy 345.392532 -260.725415)
			(xy 345.350861 -260.692184) (xy 345.314609 -260.653113) (xy 345.284585 -260.609076) (xy 345.261459 -260.561055)
			(xy 345.245749 -260.510125) (xy 345.237806 -260.457421) (xy 345.008718 -260.457421) (xy 345.000775 -260.510125)
			(xy 344.985065 -260.561055) (xy 344.961939 -260.609076) (xy 344.931915 -260.653113) (xy 344.895663 -260.692184)
			(xy 344.853992 -260.725415) (xy 344.807834 -260.752064) (xy 344.75822 -260.771536) (xy 344.706258 -260.783396)
			(xy 344.653108 -260.78738) (xy 344.599958 -260.783396) (xy 344.547996 -260.771536) (xy 344.498382 -260.752064)
			(xy 344.452224 -260.725415) (xy 344.410553 -260.692184) (xy 344.374301 -260.653113) (xy 344.344277 -260.609076)
			(xy 344.321151 -260.561055) (xy 344.305441 -260.510125) (xy 344.297498 -260.457421) (xy 344.069426 -260.457421)
			(xy 344.061483 -260.510125) (xy 344.045773 -260.561055) (xy 344.022647 -260.609076) (xy 343.992623 -260.653113)
			(xy 343.956371 -260.692184) (xy 343.9147 -260.725415) (xy 343.868542 -260.752064) (xy 343.818928 -260.771536)
			(xy 343.766966 -260.783396) (xy 343.713816 -260.78738) (xy 343.660666 -260.783396) (xy 343.608704 -260.771536)
			(xy 343.55909 -260.752064) (xy 343.512932 -260.725415) (xy 343.471261 -260.692184) (xy 343.435009 -260.653113)
			(xy 343.404985 -260.609076) (xy 343.381859 -260.561055) (xy 343.366149 -260.510125) (xy 343.358206 -260.457421)
			(xy 343.129118 -260.457421) (xy 343.121175 -260.510125) (xy 343.105465 -260.561055) (xy 343.082339 -260.609076)
			(xy 343.052315 -260.653113) (xy 343.016063 -260.692184) (xy 342.974392 -260.725415) (xy 342.928234 -260.752064)
			(xy 342.87862 -260.771536) (xy 342.826658 -260.783396) (xy 342.773508 -260.78738) (xy 342.720358 -260.783396)
			(xy 342.668396 -260.771536) (xy 342.618782 -260.752064) (xy 342.572624 -260.725415) (xy 342.530953 -260.692184)
			(xy 342.494701 -260.653113) (xy 342.464677 -260.609076) (xy 342.441551 -260.561055) (xy 342.425841 -260.510125)
			(xy 342.417898 -260.457421) (xy 342.189826 -260.457421) (xy 342.181883 -260.510125) (xy 342.166173 -260.561055)
			(xy 342.143047 -260.609076) (xy 342.113023 -260.653113) (xy 342.076771 -260.692184) (xy 342.0351 -260.725415)
			(xy 341.988942 -260.752064) (xy 341.939328 -260.771536) (xy 341.887366 -260.783396) (xy 341.834216 -260.78738)
			(xy 341.781066 -260.783396) (xy 341.729104 -260.771536) (xy 341.67949 -260.752064) (xy 341.633332 -260.725415)
			(xy 341.591661 -260.692184) (xy 341.555409 -260.653113) (xy 341.525385 -260.609076) (xy 341.502259 -260.561055)
			(xy 341.486549 -260.510125) (xy 341.478606 -260.457421) (xy 341.250026 -260.457421) (xy 341.242083 -260.510125)
			(xy 341.226373 -260.561055) (xy 341.203247 -260.609076) (xy 341.173223 -260.653113) (xy 341.136971 -260.692184)
			(xy 341.0953 -260.725415) (xy 341.049142 -260.752064) (xy 340.999528 -260.771536) (xy 340.947566 -260.783396)
			(xy 340.894416 -260.78738) (xy 340.841266 -260.783396) (xy 340.789304 -260.771536) (xy 340.73969 -260.752064)
			(xy 340.693532 -260.725415) (xy 340.651861 -260.692184) (xy 340.615609 -260.653113) (xy 340.585585 -260.609076)
			(xy 340.562459 -260.561055) (xy 340.546749 -260.510125) (xy 340.538806 -260.457421) (xy 340.309972 -260.457421)
			(xy 340.302029 -260.510125) (xy 340.286319 -260.561055) (xy 340.263193 -260.609076) (xy 340.233169 -260.653113)
			(xy 340.196917 -260.692184) (xy 340.155246 -260.725415) (xy 340.109088 -260.752064) (xy 340.059474 -260.771536)
			(xy 340.007512 -260.783396) (xy 339.954362 -260.78738) (xy 339.901212 -260.783396) (xy 339.84925 -260.771536)
			(xy 339.799636 -260.752064) (xy 339.753478 -260.725415) (xy 339.711807 -260.692184) (xy 339.675555 -260.653113)
			(xy 339.645531 -260.609076) (xy 339.622405 -260.561055) (xy 339.606695 -260.510125) (xy 339.598752 -260.457421)
			(xy 339.370426 -260.457421) (xy 339.362483 -260.510125) (xy 339.346773 -260.561055) (xy 339.323647 -260.609076)
			(xy 339.293623 -260.653113) (xy 339.257371 -260.692184) (xy 339.2157 -260.725415) (xy 339.169542 -260.752064)
			(xy 339.119928 -260.771536) (xy 339.067966 -260.783396) (xy 339.014816 -260.78738) (xy 338.961666 -260.783396)
			(xy 338.909704 -260.771536) (xy 338.86009 -260.752064) (xy 338.813932 -260.725415) (xy 338.772261 -260.692184)
			(xy 338.736009 -260.653113) (xy 338.705985 -260.609076) (xy 338.682859 -260.561055) (xy 338.667149 -260.510125)
			(xy 338.659206 -260.457421) (xy 338.430626 -260.457421) (xy 338.422683 -260.510125) (xy 338.406973 -260.561055)
			(xy 338.383847 -260.609076) (xy 338.353823 -260.653113) (xy 338.317571 -260.692184) (xy 338.2759 -260.725415)
			(xy 338.229742 -260.752064) (xy 338.180128 -260.771536) (xy 338.128166 -260.783396) (xy 338.075016 -260.78738)
			(xy 338.021866 -260.783396) (xy 337.969904 -260.771536) (xy 337.92029 -260.752064) (xy 337.874132 -260.725415)
			(xy 337.832461 -260.692184) (xy 337.796209 -260.653113) (xy 337.766185 -260.609076) (xy 337.743059 -260.561055)
			(xy 337.727349 -260.510125) (xy 337.719406 -260.457421) (xy 337.490826 -260.457421) (xy 337.482883 -260.510125)
			(xy 337.467173 -260.561055) (xy 337.444047 -260.609076) (xy 337.414023 -260.653113) (xy 337.377771 -260.692184)
			(xy 337.3361 -260.725415) (xy 337.289942 -260.752064) (xy 337.240328 -260.771536) (xy 337.188366 -260.783396)
			(xy 337.135216 -260.78738) (xy 337.082066 -260.783396) (xy 337.030104 -260.771536) (xy 336.98049 -260.752064)
			(xy 336.934332 -260.725415) (xy 336.892661 -260.692184) (xy 336.856409 -260.653113) (xy 336.826385 -260.609076)
			(xy 336.803259 -260.561055) (xy 336.787549 -260.510125) (xy 336.779606 -260.457421) (xy 336.63128 -260.457421)
			(xy 336.63128 -260.838188) (xy 336.631715 -260.847954) (xy 336.638994 -260.866078) (xy 336.652508 -260.88018)
			(xy 336.670306 -260.888224) (xy 336.680048 -260.888988) (xy 336.707238 -260.890648) (xy 336.760679 -260.901196)
			(xy 336.811891 -260.919759) (xy 336.859678 -260.945905) (xy 336.902926 -260.979022) (xy 336.940627 -261.01834)
			(xy 336.9719 -261.062941) (xy 336.996016 -261.111783) (xy 337.012413 -261.163729) (xy 337.020709 -261.217566)
			(xy 337.020708 -261.271491) (xy 337.249252 -261.271491) (xy 337.249252 -261.218193) (xy 337.257195 -261.165489)
			(xy 337.272905 -261.114559) (xy 337.296031 -261.066538) (xy 337.326055 -261.022501) (xy 337.362307 -260.98343)
			(xy 337.403978 -260.950199) (xy 337.450136 -260.92355) (xy 337.49975 -260.904078) (xy 337.551712 -260.892218)
			(xy 337.604862 -260.888235) (xy 337.658012 -260.892218) (xy 337.709974 -260.904078) (xy 337.759588 -260.92355)
			(xy 337.805746 -260.950199) (xy 337.847417 -260.98343) (xy 337.883669 -261.022501) (xy 337.913693 -261.066538)
			(xy 337.936819 -261.114559) (xy 337.952529 -261.165489) (xy 337.960472 -261.218193) (xy 337.96097 -261.244842)
			(xy 337.960472 -261.271491) (xy 338.189052 -261.271491) (xy 338.189052 -261.218193) (xy 338.196995 -261.165489)
			(xy 338.212705 -261.114559) (xy 338.235831 -261.066538) (xy 338.265855 -261.022501) (xy 338.302107 -260.98343)
			(xy 338.343778 -260.950199) (xy 338.389936 -260.92355) (xy 338.43955 -260.904078) (xy 338.491512 -260.892218)
			(xy 338.544662 -260.888235) (xy 338.597812 -260.892218) (xy 338.649774 -260.904078) (xy 338.699388 -260.92355)
			(xy 338.745546 -260.950199) (xy 338.787217 -260.98343) (xy 338.823469 -261.022501) (xy 338.853493 -261.066538)
			(xy 338.876619 -261.114559) (xy 338.892329 -261.165489) (xy 338.900272 -261.218193) (xy 338.90077 -261.244842)
			(xy 338.900272 -261.271491) (xy 339.128852 -261.271491) (xy 339.128852 -261.218193) (xy 339.136795 -261.165489)
			(xy 339.152505 -261.114559) (xy 339.175631 -261.066538) (xy 339.205655 -261.022501) (xy 339.241907 -260.98343)
			(xy 339.283578 -260.950199) (xy 339.329736 -260.92355) (xy 339.37935 -260.904078) (xy 339.431312 -260.892218)
			(xy 339.484462 -260.888235) (xy 339.537612 -260.892218) (xy 339.589574 -260.904078) (xy 339.639188 -260.92355)
			(xy 339.685346 -260.950199) (xy 339.727017 -260.98343) (xy 339.763269 -261.022501) (xy 339.793293 -261.066538)
			(xy 339.816419 -261.114559) (xy 339.832129 -261.165489) (xy 339.840072 -261.218193) (xy 339.84057 -261.244842)
			(xy 339.840072 -261.271491) (xy 340.068652 -261.271491) (xy 340.068652 -261.218193) (xy 340.076595 -261.165489)
			(xy 340.092305 -261.114559) (xy 340.115431 -261.066538) (xy 340.145455 -261.022501) (xy 340.181707 -260.98343)
			(xy 340.223378 -260.950199) (xy 340.269536 -260.92355) (xy 340.31915 -260.904078) (xy 340.371112 -260.892218)
			(xy 340.424262 -260.888235) (xy 340.477412 -260.892218) (xy 340.529374 -260.904078) (xy 340.578988 -260.92355)
			(xy 340.625146 -260.950199) (xy 340.666817 -260.98343) (xy 340.703069 -261.022501) (xy 340.733093 -261.066538)
			(xy 340.756219 -261.114559) (xy 340.771929 -261.165489) (xy 340.779872 -261.218193) (xy 340.78037 -261.244842)
			(xy 340.779872 -261.271491) (xy 341.008452 -261.271491) (xy 341.008452 -261.218193) (xy 341.016395 -261.165489)
			(xy 341.032105 -261.114559) (xy 341.055231 -261.066538) (xy 341.085255 -261.022501) (xy 341.121507 -260.98343)
			(xy 341.163178 -260.950199) (xy 341.209336 -260.92355) (xy 341.25895 -260.904078) (xy 341.310912 -260.892218)
			(xy 341.364062 -260.888235) (xy 341.417212 -260.892218) (xy 341.469174 -260.904078) (xy 341.518788 -260.92355)
			(xy 341.564946 -260.950199) (xy 341.606617 -260.98343) (xy 341.642869 -261.022501) (xy 341.672893 -261.066538)
			(xy 341.696019 -261.114559) (xy 341.711729 -261.165489) (xy 341.719672 -261.218193) (xy 341.72017 -261.244842)
			(xy 341.719672 -261.271491) (xy 341.948252 -261.271491) (xy 341.948252 -261.218193) (xy 341.956195 -261.165489)
			(xy 341.971905 -261.114559) (xy 341.995031 -261.066538) (xy 342.025055 -261.022501) (xy 342.061307 -260.98343)
			(xy 342.102978 -260.950199) (xy 342.149136 -260.92355) (xy 342.19875 -260.904078) (xy 342.250712 -260.892218)
			(xy 342.303862 -260.888235) (xy 342.357012 -260.892218) (xy 342.408974 -260.904078) (xy 342.458588 -260.92355)
			(xy 342.504746 -260.950199) (xy 342.546417 -260.98343) (xy 342.582669 -261.022501) (xy 342.612693 -261.066538)
			(xy 342.635819 -261.114559) (xy 342.651529 -261.165489) (xy 342.659472 -261.218193) (xy 342.65997 -261.244842)
			(xy 342.659472 -261.271491) (xy 342.888052 -261.271491) (xy 342.888052 -261.218193) (xy 342.895995 -261.165489)
			(xy 342.911705 -261.114559) (xy 342.934831 -261.066538) (xy 342.964855 -261.022501) (xy 343.001107 -260.98343)
			(xy 343.042778 -260.950199) (xy 343.088936 -260.92355) (xy 343.13855 -260.904078) (xy 343.190512 -260.892218)
			(xy 343.243662 -260.888235) (xy 343.296812 -260.892218) (xy 343.348774 -260.904078) (xy 343.398388 -260.92355)
			(xy 343.444546 -260.950199) (xy 343.486217 -260.98343) (xy 343.522469 -261.022501) (xy 343.552493 -261.066538)
			(xy 343.575619 -261.114559) (xy 343.591329 -261.165489) (xy 343.599272 -261.218193) (xy 343.59977 -261.244842)
			(xy 343.599272 -261.271491) (xy 343.827852 -261.271491) (xy 343.827852 -261.218193) (xy 343.835795 -261.165489)
			(xy 343.851505 -261.114559) (xy 343.874631 -261.066538) (xy 343.904655 -261.022501) (xy 343.940907 -260.98343)
			(xy 343.982578 -260.950199) (xy 344.028736 -260.92355) (xy 344.07835 -260.904078) (xy 344.130312 -260.892218)
			(xy 344.183462 -260.888235) (xy 344.236612 -260.892218) (xy 344.288574 -260.904078) (xy 344.338188 -260.92355)
			(xy 344.384346 -260.950199) (xy 344.426017 -260.98343) (xy 344.462269 -261.022501) (xy 344.492293 -261.066538)
			(xy 344.515419 -261.114559) (xy 344.531129 -261.165489) (xy 344.539072 -261.218193) (xy 344.53957 -261.244842)
			(xy 344.539072 -261.271491) (xy 344.767652 -261.271491) (xy 344.767652 -261.218193) (xy 344.775595 -261.165489)
			(xy 344.791305 -261.114559) (xy 344.814431 -261.066538) (xy 344.844455 -261.022501) (xy 344.880707 -260.98343)
			(xy 344.922378 -260.950199) (xy 344.968536 -260.92355) (xy 345.01815 -260.904078) (xy 345.070112 -260.892218)
			(xy 345.123262 -260.888235) (xy 345.176412 -260.892218) (xy 345.228374 -260.904078) (xy 345.277988 -260.92355)
			(xy 345.324146 -260.950199) (xy 345.365817 -260.98343) (xy 345.402069 -261.022501) (xy 345.432093 -261.066538)
			(xy 345.455219 -261.114559) (xy 345.470929 -261.165489) (xy 345.478872 -261.218193) (xy 345.47937 -261.244842)
			(xy 345.478872 -261.271491) (xy 345.707452 -261.271491) (xy 345.707452 -261.218193) (xy 345.715395 -261.165489)
			(xy 345.731105 -261.114559) (xy 345.754231 -261.066538) (xy 345.784255 -261.022501) (xy 345.820507 -260.98343)
			(xy 345.862178 -260.950199) (xy 345.908336 -260.92355) (xy 345.95795 -260.904078) (xy 346.009912 -260.892218)
			(xy 346.063062 -260.888235) (xy 346.116212 -260.892218) (xy 346.168174 -260.904078) (xy 346.217788 -260.92355)
			(xy 346.263946 -260.950199) (xy 346.305617 -260.98343) (xy 346.341869 -261.022501) (xy 346.371893 -261.066538)
			(xy 346.395019 -261.114559) (xy 346.410729 -261.165489) (xy 346.418672 -261.218193) (xy 346.41917 -261.244842)
			(xy 346.418672 -261.271491) (xy 346.647252 -261.271491) (xy 346.647252 -261.218193) (xy 346.655195 -261.165489)
			(xy 346.670905 -261.114559) (xy 346.694031 -261.066538) (xy 346.724055 -261.022501) (xy 346.760307 -260.98343)
			(xy 346.801978 -260.950199) (xy 346.848136 -260.92355) (xy 346.89775 -260.904078) (xy 346.949712 -260.892218)
			(xy 347.002862 -260.888235) (xy 347.056012 -260.892218) (xy 347.107974 -260.904078) (xy 347.157588 -260.92355)
			(xy 347.203746 -260.950199) (xy 347.245417 -260.98343) (xy 347.281669 -261.022501) (xy 347.311693 -261.066538)
			(xy 347.334819 -261.114559) (xy 347.350529 -261.165489) (xy 347.358472 -261.218193) (xy 347.35897 -261.244842)
			(xy 347.358472 -261.271491) (xy 347.350529 -261.324195) (xy 347.334819 -261.375125) (xy 347.311693 -261.423146)
			(xy 347.281669 -261.467183) (xy 347.245417 -261.506254) (xy 347.203746 -261.539485) (xy 347.157588 -261.566134)
			(xy 347.107974 -261.585606) (xy 347.056012 -261.597466) (xy 347.002862 -261.60145) (xy 346.949712 -261.597466)
			(xy 346.89775 -261.585606) (xy 346.848136 -261.566134) (xy 346.801978 -261.539485) (xy 346.760307 -261.506254)
			(xy 346.724055 -261.467183) (xy 346.694031 -261.423146) (xy 346.670905 -261.375125) (xy 346.655195 -261.324195)
			(xy 346.647252 -261.271491) (xy 346.418672 -261.271491) (xy 346.410729 -261.324195) (xy 346.395019 -261.375125)
			(xy 346.371893 -261.423146) (xy 346.341869 -261.467183) (xy 346.305617 -261.506254) (xy 346.263946 -261.539485)
			(xy 346.217788 -261.566134) (xy 346.168174 -261.585606) (xy 346.116212 -261.597466) (xy 346.063062 -261.60145)
			(xy 346.009912 -261.597466) (xy 345.95795 -261.585606) (xy 345.908336 -261.566134) (xy 345.862178 -261.539485)
			(xy 345.820507 -261.506254) (xy 345.784255 -261.467183) (xy 345.754231 -261.423146) (xy 345.731105 -261.375125)
			(xy 345.715395 -261.324195) (xy 345.707452 -261.271491) (xy 345.478872 -261.271491) (xy 345.470929 -261.324195)
			(xy 345.455219 -261.375125) (xy 345.432093 -261.423146) (xy 345.402069 -261.467183) (xy 345.365817 -261.506254)
			(xy 345.324146 -261.539485) (xy 345.277988 -261.566134) (xy 345.228374 -261.585606) (xy 345.176412 -261.597466)
			(xy 345.123262 -261.60145) (xy 345.070112 -261.597466) (xy 345.01815 -261.585606) (xy 344.968536 -261.566134)
			(xy 344.922378 -261.539485) (xy 344.880707 -261.506254) (xy 344.844455 -261.467183) (xy 344.814431 -261.423146)
			(xy 344.791305 -261.375125) (xy 344.775595 -261.324195) (xy 344.767652 -261.271491) (xy 344.539072 -261.271491)
			(xy 344.531129 -261.324195) (xy 344.515419 -261.375125) (xy 344.492293 -261.423146) (xy 344.462269 -261.467183)
			(xy 344.426017 -261.506254) (xy 344.384346 -261.539485) (xy 344.338188 -261.566134) (xy 344.288574 -261.585606)
			(xy 344.236612 -261.597466) (xy 344.183462 -261.60145) (xy 344.130312 -261.597466) (xy 344.07835 -261.585606)
			(xy 344.028736 -261.566134) (xy 343.982578 -261.539485) (xy 343.940907 -261.506254) (xy 343.904655 -261.467183)
			(xy 343.874631 -261.423146) (xy 343.851505 -261.375125) (xy 343.835795 -261.324195) (xy 343.827852 -261.271491)
			(xy 343.599272 -261.271491) (xy 343.591329 -261.324195) (xy 343.575619 -261.375125) (xy 343.552493 -261.423146)
			(xy 343.522469 -261.467183) (xy 343.486217 -261.506254) (xy 343.444546 -261.539485) (xy 343.398388 -261.566134)
			(xy 343.348774 -261.585606) (xy 343.296812 -261.597466) (xy 343.243662 -261.60145) (xy 343.190512 -261.597466)
			(xy 343.13855 -261.585606) (xy 343.088936 -261.566134) (xy 343.042778 -261.539485) (xy 343.001107 -261.506254)
			(xy 342.964855 -261.467183) (xy 342.934831 -261.423146) (xy 342.911705 -261.375125) (xy 342.895995 -261.324195)
			(xy 342.888052 -261.271491) (xy 342.659472 -261.271491) (xy 342.651529 -261.324195) (xy 342.635819 -261.375125)
			(xy 342.612693 -261.423146) (xy 342.582669 -261.467183) (xy 342.546417 -261.506254) (xy 342.504746 -261.539485)
			(xy 342.458588 -261.566134) (xy 342.408974 -261.585606) (xy 342.357012 -261.597466) (xy 342.303862 -261.60145)
			(xy 342.250712 -261.597466) (xy 342.19875 -261.585606) (xy 342.149136 -261.566134) (xy 342.102978 -261.539485)
			(xy 342.061307 -261.506254) (xy 342.025055 -261.467183) (xy 341.995031 -261.423146) (xy 341.971905 -261.375125)
			(xy 341.956195 -261.324195) (xy 341.948252 -261.271491) (xy 341.719672 -261.271491) (xy 341.711729 -261.324195)
			(xy 341.696019 -261.375125) (xy 341.672893 -261.423146) (xy 341.642869 -261.467183) (xy 341.606617 -261.506254)
			(xy 341.564946 -261.539485) (xy 341.518788 -261.566134) (xy 341.469174 -261.585606) (xy 341.417212 -261.597466)
			(xy 341.364062 -261.60145) (xy 341.310912 -261.597466) (xy 341.25895 -261.585606) (xy 341.209336 -261.566134)
			(xy 341.163178 -261.539485) (xy 341.121507 -261.506254) (xy 341.085255 -261.467183) (xy 341.055231 -261.423146)
			(xy 341.032105 -261.375125) (xy 341.016395 -261.324195) (xy 341.008452 -261.271491) (xy 340.779872 -261.271491)
			(xy 340.771929 -261.324195) (xy 340.756219 -261.375125) (xy 340.733093 -261.423146) (xy 340.703069 -261.467183)
			(xy 340.666817 -261.506254) (xy 340.625146 -261.539485) (xy 340.578988 -261.566134) (xy 340.529374 -261.585606)
			(xy 340.477412 -261.597466) (xy 340.424262 -261.60145) (xy 340.371112 -261.597466) (xy 340.31915 -261.585606)
			(xy 340.269536 -261.566134) (xy 340.223378 -261.539485) (xy 340.181707 -261.506254) (xy 340.145455 -261.467183)
			(xy 340.115431 -261.423146) (xy 340.092305 -261.375125) (xy 340.076595 -261.324195) (xy 340.068652 -261.271491)
			(xy 339.840072 -261.271491) (xy 339.832129 -261.324195) (xy 339.816419 -261.375125) (xy 339.793293 -261.423146)
			(xy 339.763269 -261.467183) (xy 339.727017 -261.506254) (xy 339.685346 -261.539485) (xy 339.639188 -261.566134)
			(xy 339.589574 -261.585606) (xy 339.537612 -261.597466) (xy 339.484462 -261.60145) (xy 339.431312 -261.597466)
			(xy 339.37935 -261.585606) (xy 339.329736 -261.566134) (xy 339.283578 -261.539485) (xy 339.241907 -261.506254)
			(xy 339.205655 -261.467183) (xy 339.175631 -261.423146) (xy 339.152505 -261.375125) (xy 339.136795 -261.324195)
			(xy 339.128852 -261.271491) (xy 338.900272 -261.271491) (xy 338.892329 -261.324195) (xy 338.876619 -261.375125)
			(xy 338.853493 -261.423146) (xy 338.823469 -261.467183) (xy 338.787217 -261.506254) (xy 338.745546 -261.539485)
			(xy 338.699388 -261.566134) (xy 338.649774 -261.585606) (xy 338.597812 -261.597466) (xy 338.544662 -261.60145)
			(xy 338.491512 -261.597466) (xy 338.43955 -261.585606) (xy 338.389936 -261.566134) (xy 338.343778 -261.539485)
			(xy 338.302107 -261.506254) (xy 338.265855 -261.467183) (xy 338.235831 -261.423146) (xy 338.212705 -261.375125)
			(xy 338.196995 -261.324195) (xy 338.189052 -261.271491) (xy 337.960472 -261.271491) (xy 337.952529 -261.324195)
			(xy 337.936819 -261.375125) (xy 337.913693 -261.423146) (xy 337.883669 -261.467183) (xy 337.847417 -261.506254)
			(xy 337.805746 -261.539485) (xy 337.759588 -261.566134) (xy 337.709974 -261.585606) (xy 337.658012 -261.597466)
			(xy 337.604862 -261.60145) (xy 337.551712 -261.597466) (xy 337.49975 -261.585606) (xy 337.450136 -261.566134)
			(xy 337.403978 -261.539485) (xy 337.362307 -261.506254) (xy 337.326055 -261.467183) (xy 337.296031 -261.423146)
			(xy 337.272905 -261.375125) (xy 337.257195 -261.324195) (xy 337.249252 -261.271491) (xy 337.020708 -261.271491)
			(xy 337.020708 -261.272038) (xy 337.012413 -261.325874) (xy 336.996015 -261.37782) (xy 336.971898 -261.426662)
			(xy 336.940625 -261.471263) (xy 336.902924 -261.51058) (xy 336.859675 -261.543697) (xy 336.811888 -261.569842)
			(xy 336.760676 -261.588405) (xy 336.707235 -261.598952) (xy 336.680048 -261.600696) (xy 336.670306 -261.601514)
			(xy 336.652487 -261.609514) (xy 336.638957 -261.623602) (xy 336.631682 -261.641729) (xy 336.63128 -261.651496)
			(xy 336.63128 -262.085307) (xy 336.779606 -262.085307) (xy 336.779606 -262.032009) (xy 336.787549 -261.979305)
			(xy 336.803259 -261.928375) (xy 336.826385 -261.880354) (xy 336.856409 -261.836317) (xy 336.892661 -261.797246)
			(xy 336.934332 -261.764015) (xy 336.98049 -261.737366) (xy 337.030104 -261.717894) (xy 337.082066 -261.706034)
			(xy 337.135216 -261.702051) (xy 337.188366 -261.706034) (xy 337.240328 -261.717894) (xy 337.289942 -261.737366)
			(xy 337.3361 -261.764015) (xy 337.377771 -261.797246) (xy 337.414023 -261.836317) (xy 337.444047 -261.880354)
			(xy 337.467173 -261.928375) (xy 337.482883 -261.979305) (xy 337.490826 -262.032009) (xy 337.491324 -262.058658)
			(xy 337.490826 -262.085307) (xy 337.719152 -262.085307) (xy 337.719152 -262.032009) (xy 337.727095 -261.979305)
			(xy 337.742805 -261.928375) (xy 337.765931 -261.880354) (xy 337.795955 -261.836317) (xy 337.832207 -261.797246)
			(xy 337.873878 -261.764015) (xy 337.920036 -261.737366) (xy 337.96965 -261.717894) (xy 338.021612 -261.706034)
			(xy 338.074762 -261.702051) (xy 338.127912 -261.706034) (xy 338.179874 -261.717894) (xy 338.229488 -261.737366)
			(xy 338.275646 -261.764015) (xy 338.317317 -261.797246) (xy 338.353569 -261.836317) (xy 338.383593 -261.880354)
			(xy 338.406719 -261.928375) (xy 338.422429 -261.979305) (xy 338.430372 -262.032009) (xy 338.43087 -262.058658)
			(xy 338.430372 -262.085307) (xy 338.658952 -262.085307) (xy 338.658952 -262.032009) (xy 338.666895 -261.979305)
			(xy 338.682605 -261.928375) (xy 338.705731 -261.880354) (xy 338.735755 -261.836317) (xy 338.772007 -261.797246)
			(xy 338.813678 -261.764015) (xy 338.859836 -261.737366) (xy 338.90945 -261.717894) (xy 338.961412 -261.706034)
			(xy 339.014562 -261.702051) (xy 339.067712 -261.706034) (xy 339.119674 -261.717894) (xy 339.169288 -261.737366)
			(xy 339.215446 -261.764015) (xy 339.257117 -261.797246) (xy 339.293369 -261.836317) (xy 339.323393 -261.880354)
			(xy 339.346519 -261.928375) (xy 339.362229 -261.979305) (xy 339.370172 -262.032009) (xy 339.37067 -262.058658)
			(xy 339.370172 -262.085307) (xy 339.599006 -262.085307) (xy 339.599006 -262.032009) (xy 339.606949 -261.979305)
			(xy 339.622659 -261.928375) (xy 339.645785 -261.880354) (xy 339.675809 -261.836317) (xy 339.712061 -261.797246)
			(xy 339.753732 -261.764015) (xy 339.79989 -261.737366) (xy 339.849504 -261.717894) (xy 339.901466 -261.706034)
			(xy 339.954616 -261.702051) (xy 340.007766 -261.706034) (xy 340.059728 -261.717894) (xy 340.109342 -261.737366)
			(xy 340.1555 -261.764015) (xy 340.197171 -261.797246) (xy 340.233423 -261.836317) (xy 340.263447 -261.880354)
			(xy 340.286573 -261.928375) (xy 340.302283 -261.979305) (xy 340.310226 -262.032009) (xy 340.310724 -262.058658)
			(xy 340.310226 -262.085307) (xy 340.538806 -262.085307) (xy 340.538806 -262.032009) (xy 340.546749 -261.979305)
			(xy 340.562459 -261.928375) (xy 340.585585 -261.880354) (xy 340.615609 -261.836317) (xy 340.651861 -261.797246)
			(xy 340.693532 -261.764015) (xy 340.73969 -261.737366) (xy 340.789304 -261.717894) (xy 340.841266 -261.706034)
			(xy 340.894416 -261.702051) (xy 340.947566 -261.706034) (xy 340.999528 -261.717894) (xy 341.049142 -261.737366)
			(xy 341.0953 -261.764015) (xy 341.136971 -261.797246) (xy 341.173223 -261.836317) (xy 341.203247 -261.880354)
			(xy 341.226373 -261.928375) (xy 341.242083 -261.979305) (xy 341.250026 -262.032009) (xy 341.250524 -262.058658)
			(xy 341.250026 -262.085307) (xy 341.478606 -262.085307) (xy 341.478606 -262.032009) (xy 341.486549 -261.979305)
			(xy 341.502259 -261.928375) (xy 341.525385 -261.880354) (xy 341.555409 -261.836317) (xy 341.591661 -261.797246)
			(xy 341.633332 -261.764015) (xy 341.67949 -261.737366) (xy 341.729104 -261.717894) (xy 341.781066 -261.706034)
			(xy 341.834216 -261.702051) (xy 341.887366 -261.706034) (xy 341.939328 -261.717894) (xy 341.988942 -261.737366)
			(xy 342.0351 -261.764015) (xy 342.076771 -261.797246) (xy 342.113023 -261.836317) (xy 342.143047 -261.880354)
			(xy 342.166173 -261.928375) (xy 342.181883 -261.979305) (xy 342.189826 -262.032009) (xy 342.190324 -262.058658)
			(xy 342.189826 -262.085307) (xy 342.418406 -262.085307) (xy 342.418406 -262.032009) (xy 342.426349 -261.979305)
			(xy 342.442059 -261.928375) (xy 342.465185 -261.880354) (xy 342.495209 -261.836317) (xy 342.531461 -261.797246)
			(xy 342.573132 -261.764015) (xy 342.61929 -261.737366) (xy 342.668904 -261.717894) (xy 342.720866 -261.706034)
			(xy 342.774016 -261.702051) (xy 342.827166 -261.706034) (xy 342.879128 -261.717894) (xy 342.928742 -261.737366)
			(xy 342.9749 -261.764015) (xy 343.016571 -261.797246) (xy 343.052823 -261.836317) (xy 343.082847 -261.880354)
			(xy 343.105973 -261.928375) (xy 343.121683 -261.979305) (xy 343.129626 -262.032009) (xy 343.130124 -262.058658)
			(xy 343.129626 -262.085307) (xy 343.358206 -262.085307) (xy 343.358206 -262.032009) (xy 343.366149 -261.979305)
			(xy 343.381859 -261.928375) (xy 343.404985 -261.880354) (xy 343.435009 -261.836317) (xy 343.471261 -261.797246)
			(xy 343.512932 -261.764015) (xy 343.55909 -261.737366) (xy 343.608704 -261.717894) (xy 343.660666 -261.706034)
			(xy 343.713816 -261.702051) (xy 343.766966 -261.706034) (xy 343.818928 -261.717894) (xy 343.868542 -261.737366)
			(xy 343.9147 -261.764015) (xy 343.956371 -261.797246) (xy 343.992623 -261.836317) (xy 344.022647 -261.880354)
			(xy 344.045773 -261.928375) (xy 344.061483 -261.979305) (xy 344.069426 -262.032009) (xy 344.069924 -262.058658)
			(xy 344.069426 -262.085307) (xy 344.298006 -262.085307) (xy 344.298006 -262.032009) (xy 344.305949 -261.979305)
			(xy 344.321659 -261.928375) (xy 344.344785 -261.880354) (xy 344.374809 -261.836317) (xy 344.411061 -261.797246)
			(xy 344.452732 -261.764015) (xy 344.49889 -261.737366) (xy 344.548504 -261.717894) (xy 344.600466 -261.706034)
			(xy 344.653616 -261.702051) (xy 344.706766 -261.706034) (xy 344.758728 -261.717894) (xy 344.808342 -261.737366)
			(xy 344.8545 -261.764015) (xy 344.896171 -261.797246) (xy 344.932423 -261.836317) (xy 344.962447 -261.880354)
			(xy 344.985573 -261.928375) (xy 345.001283 -261.979305) (xy 345.009226 -262.032009) (xy 345.009724 -262.058658)
			(xy 345.009226 -262.085307) (xy 345.237552 -262.085307) (xy 345.237552 -262.032009) (xy 345.245495 -261.979305)
			(xy 345.261205 -261.928375) (xy 345.284331 -261.880354) (xy 345.314355 -261.836317) (xy 345.350607 -261.797246)
			(xy 345.392278 -261.764015) (xy 345.438436 -261.737366) (xy 345.48805 -261.717894) (xy 345.540012 -261.706034)
			(xy 345.593162 -261.702051) (xy 345.646312 -261.706034) (xy 345.698274 -261.717894) (xy 345.747888 -261.737366)
			(xy 345.794046 -261.764015) (xy 345.835717 -261.797246) (xy 345.871969 -261.836317) (xy 345.901993 -261.880354)
			(xy 345.925119 -261.928375) (xy 345.940829 -261.979305) (xy 345.948772 -262.032009) (xy 345.94927 -262.058658)
			(xy 345.948772 -262.085307) (xy 346.177606 -262.085307) (xy 346.177606 -262.032009) (xy 346.185549 -261.979305)
			(xy 346.201259 -261.928375) (xy 346.224385 -261.880354) (xy 346.254409 -261.836317) (xy 346.290661 -261.797246)
			(xy 346.332332 -261.764015) (xy 346.37849 -261.737366) (xy 346.428104 -261.717894) (xy 346.480066 -261.706034)
			(xy 346.533216 -261.702051) (xy 346.586366 -261.706034) (xy 346.638328 -261.717894) (xy 346.687942 -261.737366)
			(xy 346.7341 -261.764015) (xy 346.775771 -261.797246) (xy 346.812023 -261.836317) (xy 346.842047 -261.880354)
			(xy 346.865173 -261.928375) (xy 346.880883 -261.979305) (xy 346.888826 -262.032009) (xy 346.889324 -262.058658)
			(xy 346.888826 -262.085307) (xy 347.117406 -262.085307) (xy 347.117406 -262.032009) (xy 347.125349 -261.979305)
			(xy 347.141059 -261.928375) (xy 347.164185 -261.880354) (xy 347.194209 -261.836317) (xy 347.230461 -261.797246)
			(xy 347.272132 -261.764015) (xy 347.31829 -261.737366) (xy 347.367904 -261.717894) (xy 347.419866 -261.706034)
			(xy 347.473016 -261.702051) (xy 347.526166 -261.706034) (xy 347.578128 -261.717894) (xy 347.627742 -261.737366)
			(xy 347.6739 -261.764015) (xy 347.715571 -261.797246) (xy 347.751823 -261.836317) (xy 347.781847 -261.880354)
			(xy 347.804973 -261.928375) (xy 347.820683 -261.979305) (xy 347.828626 -262.032009) (xy 347.829124 -262.058658)
			(xy 347.828626 -262.085307) (xy 348.057206 -262.085307) (xy 348.057206 -262.032009) (xy 348.065149 -261.979305)
			(xy 348.080859 -261.928375) (xy 348.103985 -261.880354) (xy 348.134009 -261.836317) (xy 348.170261 -261.797246)
			(xy 348.211932 -261.764015) (xy 348.25809 -261.737366) (xy 348.307704 -261.717894) (xy 348.359666 -261.706034)
			(xy 348.412816 -261.702051) (xy 348.465966 -261.706034) (xy 348.517928 -261.717894) (xy 348.567542 -261.737366)
			(xy 348.6137 -261.764015) (xy 348.655371 -261.797246) (xy 348.691623 -261.836317) (xy 348.721647 -261.880354)
			(xy 348.744773 -261.928375) (xy 348.760483 -261.979305) (xy 348.768426 -262.032009) (xy 348.768924 -262.058658)
			(xy 348.768426 -262.085307) (xy 348.997006 -262.085307) (xy 348.997006 -262.032009) (xy 349.004949 -261.979305)
			(xy 349.020659 -261.928375) (xy 349.043785 -261.880354) (xy 349.073809 -261.836317) (xy 349.110061 -261.797246)
			(xy 349.151732 -261.764015) (xy 349.19789 -261.737366) (xy 349.247504 -261.717894) (xy 349.299466 -261.706034)
			(xy 349.352616 -261.702051) (xy 349.405766 -261.706034) (xy 349.457728 -261.717894) (xy 349.507342 -261.737366)
			(xy 349.5535 -261.764015) (xy 349.595171 -261.797246) (xy 349.631423 -261.836317) (xy 349.661447 -261.880354)
			(xy 349.684573 -261.928375) (xy 349.700283 -261.979305) (xy 349.708226 -262.032009) (xy 349.708724 -262.058658)
			(xy 349.708226 -262.085307) (xy 349.936806 -262.085307) (xy 349.936806 -262.032009) (xy 349.944749 -261.979305)
			(xy 349.960459 -261.928375) (xy 349.983585 -261.880354) (xy 350.013609 -261.836317) (xy 350.049861 -261.797246)
			(xy 350.091532 -261.764015) (xy 350.13769 -261.737366) (xy 350.187304 -261.717894) (xy 350.239266 -261.706034)
			(xy 350.292416 -261.702051) (xy 350.345566 -261.706034) (xy 350.397528 -261.717894) (xy 350.447142 -261.737366)
			(xy 350.4933 -261.764015) (xy 350.534971 -261.797246) (xy 350.571223 -261.836317) (xy 350.601247 -261.880354)
			(xy 350.624373 -261.928375) (xy 350.640083 -261.979305) (xy 350.648026 -262.032009) (xy 350.648524 -262.058658)
			(xy 350.648026 -262.085307) (xy 350.640083 -262.138011) (xy 350.624373 -262.188941) (xy 350.601247 -262.236962)
			(xy 350.571223 -262.280999) (xy 350.534971 -262.32007) (xy 350.4933 -262.353301) (xy 350.447142 -262.37995)
			(xy 350.397528 -262.399422) (xy 350.345566 -262.411282) (xy 350.292416 -262.415266) (xy 350.239266 -262.411282)
			(xy 350.187304 -262.399422) (xy 350.13769 -262.37995) (xy 350.091532 -262.353301) (xy 350.049861 -262.32007)
			(xy 350.013609 -262.280999) (xy 349.983585 -262.236962) (xy 349.960459 -262.188941) (xy 349.944749 -262.138011)
			(xy 349.936806 -262.085307) (xy 349.708226 -262.085307) (xy 349.700283 -262.138011) (xy 349.684573 -262.188941)
			(xy 349.661447 -262.236962) (xy 349.631423 -262.280999) (xy 349.595171 -262.32007) (xy 349.5535 -262.353301)
			(xy 349.507342 -262.37995) (xy 349.457728 -262.399422) (xy 349.405766 -262.411282) (xy 349.352616 -262.415266)
			(xy 349.299466 -262.411282) (xy 349.247504 -262.399422) (xy 349.19789 -262.37995) (xy 349.151732 -262.353301)
			(xy 349.110061 -262.32007) (xy 349.073809 -262.280999) (xy 349.043785 -262.236962) (xy 349.020659 -262.188941)
			(xy 349.004949 -262.138011) (xy 348.997006 -262.085307) (xy 348.768426 -262.085307) (xy 348.760483 -262.138011)
			(xy 348.744773 -262.188941) (xy 348.721647 -262.236962) (xy 348.691623 -262.280999) (xy 348.655371 -262.32007)
			(xy 348.6137 -262.353301) (xy 348.567542 -262.37995) (xy 348.517928 -262.399422) (xy 348.465966 -262.411282)
			(xy 348.412816 -262.415266) (xy 348.359666 -262.411282) (xy 348.307704 -262.399422) (xy 348.25809 -262.37995)
			(xy 348.211932 -262.353301) (xy 348.170261 -262.32007) (xy 348.134009 -262.280999) (xy 348.103985 -262.236962)
			(xy 348.080859 -262.188941) (xy 348.065149 -262.138011) (xy 348.057206 -262.085307) (xy 347.828626 -262.085307)
			(xy 347.820683 -262.138011) (xy 347.804973 -262.188941) (xy 347.781847 -262.236962) (xy 347.751823 -262.280999)
			(xy 347.715571 -262.32007) (xy 347.6739 -262.353301) (xy 347.627742 -262.37995) (xy 347.578128 -262.399422)
			(xy 347.526166 -262.411282) (xy 347.473016 -262.415266) (xy 347.419866 -262.411282) (xy 347.367904 -262.399422)
			(xy 347.31829 -262.37995) (xy 347.272132 -262.353301) (xy 347.230461 -262.32007) (xy 347.194209 -262.280999)
			(xy 347.164185 -262.236962) (xy 347.141059 -262.188941) (xy 347.125349 -262.138011) (xy 347.117406 -262.085307)
			(xy 346.888826 -262.085307) (xy 346.880883 -262.138011) (xy 346.865173 -262.188941) (xy 346.842047 -262.236962)
			(xy 346.812023 -262.280999) (xy 346.775771 -262.32007) (xy 346.7341 -262.353301) (xy 346.687942 -262.37995)
			(xy 346.638328 -262.399422) (xy 346.586366 -262.411282) (xy 346.533216 -262.415266) (xy 346.480066 -262.411282)
			(xy 346.428104 -262.399422) (xy 346.37849 -262.37995) (xy 346.332332 -262.353301) (xy 346.290661 -262.32007)
			(xy 346.254409 -262.280999) (xy 346.224385 -262.236962) (xy 346.201259 -262.188941) (xy 346.185549 -262.138011)
			(xy 346.177606 -262.085307) (xy 345.948772 -262.085307) (xy 345.940829 -262.138011) (xy 345.925119 -262.188941)
			(xy 345.901993 -262.236962) (xy 345.871969 -262.280999) (xy 345.835717 -262.32007) (xy 345.794046 -262.353301)
			(xy 345.747888 -262.37995) (xy 345.698274 -262.399422) (xy 345.646312 -262.411282) (xy 345.593162 -262.415266)
			(xy 345.540012 -262.411282) (xy 345.48805 -262.399422) (xy 345.438436 -262.37995) (xy 345.392278 -262.353301)
			(xy 345.350607 -262.32007) (xy 345.314355 -262.280999) (xy 345.284331 -262.236962) (xy 345.261205 -262.188941)
			(xy 345.245495 -262.138011) (xy 345.237552 -262.085307) (xy 345.009226 -262.085307) (xy 345.001283 -262.138011)
			(xy 344.985573 -262.188941) (xy 344.962447 -262.236962) (xy 344.932423 -262.280999) (xy 344.896171 -262.32007)
			(xy 344.8545 -262.353301) (xy 344.808342 -262.37995) (xy 344.758728 -262.399422) (xy 344.706766 -262.411282)
			(xy 344.653616 -262.415266) (xy 344.600466 -262.411282) (xy 344.548504 -262.399422) (xy 344.49889 -262.37995)
			(xy 344.452732 -262.353301) (xy 344.411061 -262.32007) (xy 344.374809 -262.280999) (xy 344.344785 -262.236962)
			(xy 344.321659 -262.188941) (xy 344.305949 -262.138011) (xy 344.298006 -262.085307) (xy 344.069426 -262.085307)
			(xy 344.061483 -262.138011) (xy 344.045773 -262.188941) (xy 344.022647 -262.236962) (xy 343.992623 -262.280999)
			(xy 343.956371 -262.32007) (xy 343.9147 -262.353301) (xy 343.868542 -262.37995) (xy 343.818928 -262.399422)
			(xy 343.766966 -262.411282) (xy 343.713816 -262.415266) (xy 343.660666 -262.411282) (xy 343.608704 -262.399422)
			(xy 343.55909 -262.37995) (xy 343.512932 -262.353301) (xy 343.471261 -262.32007) (xy 343.435009 -262.280999)
			(xy 343.404985 -262.236962) (xy 343.381859 -262.188941) (xy 343.366149 -262.138011) (xy 343.358206 -262.085307)
			(xy 343.129626 -262.085307) (xy 343.121683 -262.138011) (xy 343.105973 -262.188941) (xy 343.082847 -262.236962)
			(xy 343.052823 -262.280999) (xy 343.016571 -262.32007) (xy 342.9749 -262.353301) (xy 342.928742 -262.37995)
			(xy 342.879128 -262.399422) (xy 342.827166 -262.411282) (xy 342.774016 -262.415266) (xy 342.720866 -262.411282)
			(xy 342.668904 -262.399422) (xy 342.61929 -262.37995) (xy 342.573132 -262.353301) (xy 342.531461 -262.32007)
			(xy 342.495209 -262.280999) (xy 342.465185 -262.236962) (xy 342.442059 -262.188941) (xy 342.426349 -262.138011)
			(xy 342.418406 -262.085307) (xy 342.189826 -262.085307) (xy 342.181883 -262.138011) (xy 342.166173 -262.188941)
			(xy 342.143047 -262.236962) (xy 342.113023 -262.280999) (xy 342.076771 -262.32007) (xy 342.0351 -262.353301)
			(xy 341.988942 -262.37995) (xy 341.939328 -262.399422) (xy 341.887366 -262.411282) (xy 341.834216 -262.415266)
			(xy 341.781066 -262.411282) (xy 341.729104 -262.399422) (xy 341.67949 -262.37995) (xy 341.633332 -262.353301)
			(xy 341.591661 -262.32007) (xy 341.555409 -262.280999) (xy 341.525385 -262.236962) (xy 341.502259 -262.188941)
			(xy 341.486549 -262.138011) (xy 341.478606 -262.085307) (xy 341.250026 -262.085307) (xy 341.242083 -262.138011)
			(xy 341.226373 -262.188941) (xy 341.203247 -262.236962) (xy 341.173223 -262.280999) (xy 341.136971 -262.32007)
			(xy 341.0953 -262.353301) (xy 341.049142 -262.37995) (xy 340.999528 -262.399422) (xy 340.947566 -262.411282)
			(xy 340.894416 -262.415266) (xy 340.841266 -262.411282) (xy 340.789304 -262.399422) (xy 340.73969 -262.37995)
			(xy 340.693532 -262.353301) (xy 340.651861 -262.32007) (xy 340.615609 -262.280999) (xy 340.585585 -262.236962)
			(xy 340.562459 -262.188941) (xy 340.546749 -262.138011) (xy 340.538806 -262.085307) (xy 340.310226 -262.085307)
			(xy 340.302283 -262.138011) (xy 340.286573 -262.188941) (xy 340.263447 -262.236962) (xy 340.233423 -262.280999)
			(xy 340.197171 -262.32007) (xy 340.1555 -262.353301) (xy 340.109342 -262.37995) (xy 340.059728 -262.399422)
			(xy 340.007766 -262.411282) (xy 339.954616 -262.415266) (xy 339.901466 -262.411282) (xy 339.849504 -262.399422)
			(xy 339.79989 -262.37995) (xy 339.753732 -262.353301) (xy 339.712061 -262.32007) (xy 339.675809 -262.280999)
			(xy 339.645785 -262.236962) (xy 339.622659 -262.188941) (xy 339.606949 -262.138011) (xy 339.599006 -262.085307)
			(xy 339.370172 -262.085307) (xy 339.362229 -262.138011) (xy 339.346519 -262.188941) (xy 339.323393 -262.236962)
			(xy 339.293369 -262.280999) (xy 339.257117 -262.32007) (xy 339.215446 -262.353301) (xy 339.169288 -262.37995)
			(xy 339.119674 -262.399422) (xy 339.067712 -262.411282) (xy 339.014562 -262.415266) (xy 338.961412 -262.411282)
			(xy 338.90945 -262.399422) (xy 338.859836 -262.37995) (xy 338.813678 -262.353301) (xy 338.772007 -262.32007)
			(xy 338.735755 -262.280999) (xy 338.705731 -262.236962) (xy 338.682605 -262.188941) (xy 338.666895 -262.138011)
			(xy 338.658952 -262.085307) (xy 338.430372 -262.085307) (xy 338.422429 -262.138011) (xy 338.406719 -262.188941)
			(xy 338.383593 -262.236962) (xy 338.353569 -262.280999) (xy 338.317317 -262.32007) (xy 338.275646 -262.353301)
			(xy 338.229488 -262.37995) (xy 338.179874 -262.399422) (xy 338.127912 -262.411282) (xy 338.074762 -262.415266)
			(xy 338.021612 -262.411282) (xy 337.96965 -262.399422) (xy 337.920036 -262.37995) (xy 337.873878 -262.353301)
			(xy 337.832207 -262.32007) (xy 337.795955 -262.280999) (xy 337.765931 -262.236962) (xy 337.742805 -262.188941)
			(xy 337.727095 -262.138011) (xy 337.719152 -262.085307) (xy 337.490826 -262.085307) (xy 337.482883 -262.138011)
			(xy 337.467173 -262.188941) (xy 337.444047 -262.236962) (xy 337.414023 -262.280999) (xy 337.377771 -262.32007)
			(xy 337.3361 -262.353301) (xy 337.289942 -262.37995) (xy 337.240328 -262.399422) (xy 337.188366 -262.411282)
			(xy 337.135216 -262.415266) (xy 337.082066 -262.411282) (xy 337.030104 -262.399422) (xy 336.98049 -262.37995)
			(xy 336.934332 -262.353301) (xy 336.892661 -262.32007) (xy 336.856409 -262.280999) (xy 336.826385 -262.236962)
			(xy 336.803259 -262.188941) (xy 336.787549 -262.138011) (xy 336.779606 -262.085307) (xy 336.63128 -262.085307)
			(xy 336.63128 -262.46582) (xy 336.63172 -262.475582) (xy 336.639006 -262.493695) (xy 336.652519 -262.507787)
			(xy 336.670311 -262.515826) (xy 336.680048 -262.51662) (xy 336.707244 -262.51828) (xy 336.760695 -262.52883)
			(xy 336.811916 -262.547396) (xy 336.859713 -262.573546) (xy 336.90297 -262.60667) (xy 336.940678 -262.645995)
			(xy 336.971957 -262.690604) (xy 336.996078 -262.739455) (xy 337.012479 -262.791411) (xy 337.020776 -262.845258)
			(xy 337.020776 -262.899123) (xy 337.249252 -262.899123) (xy 337.249252 -262.845825) (xy 337.257195 -262.793121)
			(xy 337.272905 -262.742191) (xy 337.296031 -262.69417) (xy 337.326055 -262.650133) (xy 337.362307 -262.611062)
			(xy 337.403978 -262.577831) (xy 337.450136 -262.551182) (xy 337.49975 -262.53171) (xy 337.551712 -262.51985)
			(xy 337.604862 -262.515867) (xy 337.658012 -262.51985) (xy 337.709974 -262.53171) (xy 337.759588 -262.551182)
			(xy 337.805746 -262.577831) (xy 337.847417 -262.611062) (xy 337.883669 -262.650133) (xy 337.913693 -262.69417)
			(xy 337.936819 -262.742191) (xy 337.952529 -262.793121) (xy 337.960472 -262.845825) (xy 337.96097 -262.872474)
			(xy 337.960472 -262.899123) (xy 338.189306 -262.899123) (xy 338.189306 -262.845825) (xy 338.197249 -262.793121)
			(xy 338.212959 -262.742191) (xy 338.236085 -262.69417) (xy 338.266109 -262.650133) (xy 338.302361 -262.611062)
			(xy 338.344032 -262.577831) (xy 338.39019 -262.551182) (xy 338.439804 -262.53171) (xy 338.491766 -262.51985)
			(xy 338.544916 -262.515867) (xy 338.598066 -262.51985) (xy 338.650028 -262.53171) (xy 338.699642 -262.551182)
			(xy 338.7458 -262.577831) (xy 338.787471 -262.611062) (xy 338.823723 -262.650133) (xy 338.853747 -262.69417)
			(xy 338.876873 -262.742191) (xy 338.892583 -262.793121) (xy 338.900526 -262.845825) (xy 338.901024 -262.872474)
			(xy 338.900526 -262.899123) (xy 339.128852 -262.899123) (xy 339.128852 -262.845825) (xy 339.136795 -262.793121)
			(xy 339.152505 -262.742191) (xy 339.175631 -262.69417) (xy 339.205655 -262.650133) (xy 339.241907 -262.611062)
			(xy 339.283578 -262.577831) (xy 339.329736 -262.551182) (xy 339.37935 -262.53171) (xy 339.431312 -262.51985)
			(xy 339.484462 -262.515867) (xy 339.537612 -262.51985) (xy 339.589574 -262.53171) (xy 339.639188 -262.551182)
			(xy 339.685346 -262.577831) (xy 339.727017 -262.611062) (xy 339.763269 -262.650133) (xy 339.793293 -262.69417)
			(xy 339.816419 -262.742191) (xy 339.832129 -262.793121) (xy 339.840072 -262.845825) (xy 339.84057 -262.872474)
			(xy 339.840072 -262.899123) (xy 340.068652 -262.899123) (xy 340.068652 -262.845825) (xy 340.076595 -262.793121)
			(xy 340.092305 -262.742191) (xy 340.115431 -262.69417) (xy 340.145455 -262.650133) (xy 340.181707 -262.611062)
			(xy 340.223378 -262.577831) (xy 340.269536 -262.551182) (xy 340.31915 -262.53171) (xy 340.371112 -262.51985)
			(xy 340.424262 -262.515867) (xy 340.477412 -262.51985) (xy 340.529374 -262.53171) (xy 340.578988 -262.551182)
			(xy 340.625146 -262.577831) (xy 340.666817 -262.611062) (xy 340.703069 -262.650133) (xy 340.733093 -262.69417)
			(xy 340.756219 -262.742191) (xy 340.771929 -262.793121) (xy 340.779872 -262.845825) (xy 340.78037 -262.872474)
			(xy 340.779872 -262.899123) (xy 341.008452 -262.899123) (xy 341.008452 -262.845825) (xy 341.016395 -262.793121)
			(xy 341.032105 -262.742191) (xy 341.055231 -262.69417) (xy 341.085255 -262.650133) (xy 341.121507 -262.611062)
			(xy 341.163178 -262.577831) (xy 341.209336 -262.551182) (xy 341.25895 -262.53171) (xy 341.310912 -262.51985)
			(xy 341.364062 -262.515867) (xy 341.417212 -262.51985) (xy 341.469174 -262.53171) (xy 341.518788 -262.551182)
			(xy 341.564946 -262.577831) (xy 341.606617 -262.611062) (xy 341.642869 -262.650133) (xy 341.672893 -262.69417)
			(xy 341.696019 -262.742191) (xy 341.711729 -262.793121) (xy 341.719672 -262.845825) (xy 341.72017 -262.872474)
			(xy 341.719672 -262.899123) (xy 341.948252 -262.899123) (xy 341.948252 -262.845825) (xy 341.956195 -262.793121)
			(xy 341.971905 -262.742191) (xy 341.995031 -262.69417) (xy 342.025055 -262.650133) (xy 342.061307 -262.611062)
			(xy 342.102978 -262.577831) (xy 342.149136 -262.551182) (xy 342.19875 -262.53171) (xy 342.250712 -262.51985)
			(xy 342.303862 -262.515867) (xy 342.357012 -262.51985) (xy 342.408974 -262.53171) (xy 342.458588 -262.551182)
			(xy 342.504746 -262.577831) (xy 342.546417 -262.611062) (xy 342.582669 -262.650133) (xy 342.612693 -262.69417)
			(xy 342.635819 -262.742191) (xy 342.651529 -262.793121) (xy 342.659472 -262.845825) (xy 342.65997 -262.872474)
			(xy 342.659472 -262.899123) (xy 342.888052 -262.899123) (xy 342.888052 -262.845825) (xy 342.895995 -262.793121)
			(xy 342.911705 -262.742191) (xy 342.934831 -262.69417) (xy 342.964855 -262.650133) (xy 343.001107 -262.611062)
			(xy 343.042778 -262.577831) (xy 343.088936 -262.551182) (xy 343.13855 -262.53171) (xy 343.190512 -262.51985)
			(xy 343.243662 -262.515867) (xy 343.296812 -262.51985) (xy 343.348774 -262.53171) (xy 343.398388 -262.551182)
			(xy 343.444546 -262.577831) (xy 343.486217 -262.611062) (xy 343.522469 -262.650133) (xy 343.552493 -262.69417)
			(xy 343.575619 -262.742191) (xy 343.591329 -262.793121) (xy 343.599272 -262.845825) (xy 343.59977 -262.872474)
			(xy 343.599272 -262.899123) (xy 343.827852 -262.899123) (xy 343.827852 -262.845825) (xy 343.835795 -262.793121)
			(xy 343.851505 -262.742191) (xy 343.874631 -262.69417) (xy 343.904655 -262.650133) (xy 343.940907 -262.611062)
			(xy 343.982578 -262.577831) (xy 344.028736 -262.551182) (xy 344.07835 -262.53171) (xy 344.130312 -262.51985)
			(xy 344.183462 -262.515867) (xy 344.236612 -262.51985) (xy 344.288574 -262.53171) (xy 344.338188 -262.551182)
			(xy 344.384346 -262.577831) (xy 344.426017 -262.611062) (xy 344.462269 -262.650133) (xy 344.492293 -262.69417)
			(xy 344.515419 -262.742191) (xy 344.531129 -262.793121) (xy 344.539072 -262.845825) (xy 344.53957 -262.872474)
			(xy 344.539072 -262.899123) (xy 344.767906 -262.899123) (xy 344.767906 -262.845825) (xy 344.775849 -262.793121)
			(xy 344.791559 -262.742191) (xy 344.814685 -262.69417) (xy 344.844709 -262.650133) (xy 344.880961 -262.611062)
			(xy 344.922632 -262.577831) (xy 344.96879 -262.551182) (xy 345.018404 -262.53171) (xy 345.070366 -262.51985)
			(xy 345.123516 -262.515867) (xy 345.176666 -262.51985) (xy 345.228628 -262.53171) (xy 345.278242 -262.551182)
			(xy 345.3244 -262.577831) (xy 345.366071 -262.611062) (xy 345.402323 -262.650133) (xy 345.432347 -262.69417)
			(xy 345.455473 -262.742191) (xy 345.471183 -262.793121) (xy 345.479126 -262.845825) (xy 345.479624 -262.872474)
			(xy 345.479126 -262.899123) (xy 345.707452 -262.899123) (xy 345.707452 -262.845825) (xy 345.715395 -262.793121)
			(xy 345.731105 -262.742191) (xy 345.754231 -262.69417) (xy 345.784255 -262.650133) (xy 345.820507 -262.611062)
			(xy 345.862178 -262.577831) (xy 345.908336 -262.551182) (xy 345.95795 -262.53171) (xy 346.009912 -262.51985)
			(xy 346.063062 -262.515867) (xy 346.116212 -262.51985) (xy 346.168174 -262.53171) (xy 346.217788 -262.551182)
			(xy 346.263946 -262.577831) (xy 346.305617 -262.611062) (xy 346.341869 -262.650133) (xy 346.371893 -262.69417)
			(xy 346.395019 -262.742191) (xy 346.410729 -262.793121) (xy 346.418672 -262.845825) (xy 346.41917 -262.872474)
			(xy 346.418672 -262.899123) (xy 346.647252 -262.899123) (xy 346.647252 -262.845825) (xy 346.655195 -262.793121)
			(xy 346.670905 -262.742191) (xy 346.694031 -262.69417) (xy 346.724055 -262.650133) (xy 346.760307 -262.611062)
			(xy 346.801978 -262.577831) (xy 346.848136 -262.551182) (xy 346.89775 -262.53171) (xy 346.949712 -262.51985)
			(xy 347.002862 -262.515867) (xy 347.056012 -262.51985) (xy 347.107974 -262.53171) (xy 347.157588 -262.551182)
			(xy 347.203746 -262.577831) (xy 347.245417 -262.611062) (xy 347.281669 -262.650133) (xy 347.311693 -262.69417)
			(xy 347.334819 -262.742191) (xy 347.350529 -262.793121) (xy 347.358472 -262.845825) (xy 347.35897 -262.872474)
			(xy 347.358472 -262.899123) (xy 347.587052 -262.899123) (xy 347.587052 -262.845825) (xy 347.594995 -262.793121)
			(xy 347.610705 -262.742191) (xy 347.633831 -262.69417) (xy 347.663855 -262.650133) (xy 347.700107 -262.611062)
			(xy 347.741778 -262.577831) (xy 347.787936 -262.551182) (xy 347.83755 -262.53171) (xy 347.889512 -262.51985)
			(xy 347.942662 -262.515867) (xy 347.995812 -262.51985) (xy 348.047774 -262.53171) (xy 348.097388 -262.551182)
			(xy 348.143546 -262.577831) (xy 348.185217 -262.611062) (xy 348.221469 -262.650133) (xy 348.251493 -262.69417)
			(xy 348.274619 -262.742191) (xy 348.290329 -262.793121) (xy 348.298272 -262.845825) (xy 348.29877 -262.872474)
			(xy 348.298272 -262.899123) (xy 348.526852 -262.899123) (xy 348.526852 -262.845825) (xy 348.534795 -262.793121)
			(xy 348.550505 -262.742191) (xy 348.573631 -262.69417) (xy 348.603655 -262.650133) (xy 348.639907 -262.611062)
			(xy 348.681578 -262.577831) (xy 348.727736 -262.551182) (xy 348.77735 -262.53171) (xy 348.829312 -262.51985)
			(xy 348.882462 -262.515867) (xy 348.935612 -262.51985) (xy 348.987574 -262.53171) (xy 349.037188 -262.551182)
			(xy 349.083346 -262.577831) (xy 349.125017 -262.611062) (xy 349.161269 -262.650133) (xy 349.191293 -262.69417)
			(xy 349.196306 -262.70458) (xy 351.298256 -262.70458) (xy 351.298646 -262.67991) (xy 351.305455 -262.631041)
			(xy 351.318954 -262.583583) (xy 351.338883 -262.538446) (xy 351.364859 -262.496497) (xy 351.380298 -262.47725)
			(xy 351.388946 -262.466135) (xy 351.400295 -262.44037) (xy 351.404173 -262.412485) (xy 351.400286 -262.3846)
			(xy 351.38893 -262.358839) (xy 351.380298 -262.34771) (xy 351.364895 -262.328438) (xy 351.33893 -262.286489)
			(xy 351.319006 -262.241357) (xy 351.305504 -262.193907) (xy 351.298682 -262.145047) (xy 351.298256 -262.12038)
			(xy 351.298754 -262.093731) (xy 351.306697 -262.041027) (xy 351.322407 -261.990097) (xy 351.345533 -261.942076)
			(xy 351.375557 -261.898039) (xy 351.411809 -261.858968) (xy 351.45348 -261.825737) (xy 351.499638 -261.799088)
			(xy 351.549252 -261.779616) (xy 351.601214 -261.767756) (xy 351.654364 -261.763773) (xy 351.707514 -261.767756)
			(xy 351.759476 -261.779616) (xy 351.80909 -261.799088) (xy 351.855248 -261.825737) (xy 351.896919 -261.858968)
			(xy 351.933171 -261.898039) (xy 351.963195 -261.942076) (xy 351.986321 -261.990097) (xy 352.002031 -262.041027)
			(xy 352.009974 -262.093731) (xy 352.010472 -262.12038) (xy 352.010052 -262.145049) (xy 352.003249 -262.193916)
			(xy 351.989757 -262.241374) (xy 351.969835 -262.286511) (xy 351.943865 -262.328462) (xy 351.92843 -262.34771)
			(xy 351.919825 -262.358854) (xy 351.908479 -262.38461) (xy 351.904596 -262.412485) (xy 351.908471 -262.44036)
			(xy 351.919808 -262.466119) (xy 351.92843 -262.47725) (xy 351.943865 -262.496497) (xy 351.969824 -262.538453)
			(xy 351.989741 -262.583591) (xy 352.003236 -262.631047) (xy 352.010051 -262.679911) (xy 352.010472 -262.70458)
			(xy 352.009974 -262.731229) (xy 352.002031 -262.783933) (xy 351.986321 -262.834863) (xy 351.963195 -262.882884)
			(xy 351.933171 -262.926921) (xy 351.896919 -262.965992) (xy 351.855248 -262.999223) (xy 351.80909 -263.025872)
			(xy 351.759476 -263.045344) (xy 351.707514 -263.057204) (xy 351.654364 -263.061188) (xy 351.601214 -263.057204)
			(xy 351.549252 -263.045344) (xy 351.499638 -263.025872) (xy 351.45348 -262.999223) (xy 351.411809 -262.965992)
			(xy 351.375557 -262.926921) (xy 351.345533 -262.882884) (xy 351.322407 -262.834863) (xy 351.306697 -262.783933)
			(xy 351.298754 -262.731229) (xy 351.298256 -262.70458) (xy 349.196306 -262.70458) (xy 349.214419 -262.742191)
			(xy 349.230129 -262.793121) (xy 349.238072 -262.845825) (xy 349.23857 -262.872474) (xy 349.238072 -262.899123)
			(xy 349.230129 -262.951827) (xy 349.214419 -263.002757) (xy 349.191293 -263.050778) (xy 349.161269 -263.094815)
			(xy 349.125017 -263.133886) (xy 349.083346 -263.167117) (xy 349.037188 -263.193766) (xy 348.987574 -263.213238)
			(xy 348.935612 -263.225098) (xy 348.882462 -263.229082) (xy 348.829312 -263.225098) (xy 348.77735 -263.213238)
			(xy 348.727736 -263.193766) (xy 348.681578 -263.167117) (xy 348.639907 -263.133886) (xy 348.603655 -263.094815)
			(xy 348.573631 -263.050778) (xy 348.550505 -263.002757) (xy 348.534795 -262.951827) (xy 348.526852 -262.899123)
			(xy 348.298272 -262.899123) (xy 348.290329 -262.951827) (xy 348.274619 -263.002757) (xy 348.251493 -263.050778)
			(xy 348.221469 -263.094815) (xy 348.185217 -263.133886) (xy 348.143546 -263.167117) (xy 348.097388 -263.193766)
			(xy 348.047774 -263.213238) (xy 347.995812 -263.225098) (xy 347.942662 -263.229082) (xy 347.889512 -263.225098)
			(xy 347.83755 -263.213238) (xy 347.787936 -263.193766) (xy 347.741778 -263.167117) (xy 347.700107 -263.133886)
			(xy 347.663855 -263.094815) (xy 347.633831 -263.050778) (xy 347.610705 -263.002757) (xy 347.594995 -262.951827)
			(xy 347.587052 -262.899123) (xy 347.358472 -262.899123) (xy 347.350529 -262.951827) (xy 347.334819 -263.002757)
			(xy 347.311693 -263.050778) (xy 347.281669 -263.094815) (xy 347.245417 -263.133886) (xy 347.203746 -263.167117)
			(xy 347.157588 -263.193766) (xy 347.107974 -263.213238) (xy 347.056012 -263.225098) (xy 347.002862 -263.229082)
			(xy 346.949712 -263.225098) (xy 346.89775 -263.213238) (xy 346.848136 -263.193766) (xy 346.801978 -263.167117)
			(xy 346.760307 -263.133886) (xy 346.724055 -263.094815) (xy 346.694031 -263.050778) (xy 346.670905 -263.002757)
			(xy 346.655195 -262.951827) (xy 346.647252 -262.899123) (xy 346.418672 -262.899123) (xy 346.410729 -262.951827)
			(xy 346.395019 -263.002757) (xy 346.371893 -263.050778) (xy 346.341869 -263.094815) (xy 346.305617 -263.133886)
			(xy 346.263946 -263.167117) (xy 346.217788 -263.193766) (xy 346.168174 -263.213238) (xy 346.116212 -263.225098)
			(xy 346.063062 -263.229082) (xy 346.009912 -263.225098) (xy 345.95795 -263.213238) (xy 345.908336 -263.193766)
			(xy 345.862178 -263.167117) (xy 345.820507 -263.133886) (xy 345.784255 -263.094815) (xy 345.754231 -263.050778)
			(xy 345.731105 -263.002757) (xy 345.715395 -262.951827) (xy 345.707452 -262.899123) (xy 345.479126 -262.899123)
			(xy 345.471183 -262.951827) (xy 345.455473 -263.002757) (xy 345.432347 -263.050778) (xy 345.402323 -263.094815)
			(xy 345.366071 -263.133886) (xy 345.3244 -263.167117) (xy 345.278242 -263.193766) (xy 345.228628 -263.213238)
			(xy 345.176666 -263.225098) (xy 345.123516 -263.229082) (xy 345.070366 -263.225098) (xy 345.018404 -263.213238)
			(xy 344.96879 -263.193766) (xy 344.922632 -263.167117) (xy 344.880961 -263.133886) (xy 344.844709 -263.094815)
			(xy 344.814685 -263.050778) (xy 344.791559 -263.002757) (xy 344.775849 -262.951827) (xy 344.767906 -262.899123)
			(xy 344.539072 -262.899123) (xy 344.531129 -262.951827) (xy 344.515419 -263.002757) (xy 344.492293 -263.050778)
			(xy 344.462269 -263.094815) (xy 344.426017 -263.133886) (xy 344.384346 -263.167117) (xy 344.338188 -263.193766)
			(xy 344.288574 -263.213238) (xy 344.236612 -263.225098) (xy 344.183462 -263.229082) (xy 344.130312 -263.225098)
			(xy 344.07835 -263.213238) (xy 344.028736 -263.193766) (xy 343.982578 -263.167117) (xy 343.940907 -263.133886)
			(xy 343.904655 -263.094815) (xy 343.874631 -263.050778) (xy 343.851505 -263.002757) (xy 343.835795 -262.951827)
			(xy 343.827852 -262.899123) (xy 343.599272 -262.899123) (xy 343.591329 -262.951827) (xy 343.575619 -263.002757)
			(xy 343.552493 -263.050778) (xy 343.522469 -263.094815) (xy 343.486217 -263.133886) (xy 343.444546 -263.167117)
			(xy 343.398388 -263.193766) (xy 343.348774 -263.213238) (xy 343.296812 -263.225098) (xy 343.243662 -263.229082)
			(xy 343.190512 -263.225098) (xy 343.13855 -263.213238) (xy 343.088936 -263.193766) (xy 343.042778 -263.167117)
			(xy 343.001107 -263.133886) (xy 342.964855 -263.094815) (xy 342.934831 -263.050778) (xy 342.911705 -263.002757)
			(xy 342.895995 -262.951827) (xy 342.888052 -262.899123) (xy 342.659472 -262.899123) (xy 342.651529 -262.951827)
			(xy 342.635819 -263.002757) (xy 342.612693 -263.050778) (xy 342.582669 -263.094815) (xy 342.546417 -263.133886)
			(xy 342.504746 -263.167117) (xy 342.458588 -263.193766) (xy 342.408974 -263.213238) (xy 342.357012 -263.225098)
			(xy 342.303862 -263.229082) (xy 342.250712 -263.225098) (xy 342.19875 -263.213238) (xy 342.149136 -263.193766)
			(xy 342.102978 -263.167117) (xy 342.061307 -263.133886) (xy 342.025055 -263.094815) (xy 341.995031 -263.050778)
			(xy 341.971905 -263.002757) (xy 341.956195 -262.951827) (xy 341.948252 -262.899123) (xy 341.719672 -262.899123)
			(xy 341.711729 -262.951827) (xy 341.696019 -263.002757) (xy 341.672893 -263.050778) (xy 341.642869 -263.094815)
			(xy 341.606617 -263.133886) (xy 341.564946 -263.167117) (xy 341.518788 -263.193766) (xy 341.469174 -263.213238)
			(xy 341.417212 -263.225098) (xy 341.364062 -263.229082) (xy 341.310912 -263.225098) (xy 341.25895 -263.213238)
			(xy 341.209336 -263.193766) (xy 341.163178 -263.167117) (xy 341.121507 -263.133886) (xy 341.085255 -263.094815)
			(xy 341.055231 -263.050778) (xy 341.032105 -263.002757) (xy 341.016395 -262.951827) (xy 341.008452 -262.899123)
			(xy 340.779872 -262.899123) (xy 340.771929 -262.951827) (xy 340.756219 -263.002757) (xy 340.733093 -263.050778)
			(xy 340.703069 -263.094815) (xy 340.666817 -263.133886) (xy 340.625146 -263.167117) (xy 340.578988 -263.193766)
			(xy 340.529374 -263.213238) (xy 340.477412 -263.225098) (xy 340.424262 -263.229082) (xy 340.371112 -263.225098)
			(xy 340.31915 -263.213238) (xy 340.269536 -263.193766) (xy 340.223378 -263.167117) (xy 340.181707 -263.133886)
			(xy 340.145455 -263.094815) (xy 340.115431 -263.050778) (xy 340.092305 -263.002757) (xy 340.076595 -262.951827)
			(xy 340.068652 -262.899123) (xy 339.840072 -262.899123) (xy 339.832129 -262.951827) (xy 339.816419 -263.002757)
			(xy 339.793293 -263.050778) (xy 339.763269 -263.094815) (xy 339.727017 -263.133886) (xy 339.685346 -263.167117)
			(xy 339.639188 -263.193766) (xy 339.589574 -263.213238) (xy 339.537612 -263.225098) (xy 339.484462 -263.229082)
			(xy 339.431312 -263.225098) (xy 339.37935 -263.213238) (xy 339.329736 -263.193766) (xy 339.283578 -263.167117)
			(xy 339.241907 -263.133886) (xy 339.205655 -263.094815) (xy 339.175631 -263.050778) (xy 339.152505 -263.002757)
			(xy 339.136795 -262.951827) (xy 339.128852 -262.899123) (xy 338.900526 -262.899123) (xy 338.892583 -262.951827)
			(xy 338.876873 -263.002757) (xy 338.853747 -263.050778) (xy 338.823723 -263.094815) (xy 338.787471 -263.133886)
			(xy 338.7458 -263.167117) (xy 338.699642 -263.193766) (xy 338.650028 -263.213238) (xy 338.598066 -263.225098)
			(xy 338.544916 -263.229082) (xy 338.491766 -263.225098) (xy 338.439804 -263.213238) (xy 338.39019 -263.193766)
			(xy 338.344032 -263.167117) (xy 338.302361 -263.133886) (xy 338.266109 -263.094815) (xy 338.236085 -263.050778)
			(xy 338.212959 -263.002757) (xy 338.197249 -262.951827) (xy 338.189306 -262.899123) (xy 337.960472 -262.899123)
			(xy 337.952529 -262.951827) (xy 337.936819 -263.002757) (xy 337.913693 -263.050778) (xy 337.883669 -263.094815)
			(xy 337.847417 -263.133886) (xy 337.805746 -263.167117) (xy 337.759588 -263.193766) (xy 337.709974 -263.213238)
			(xy 337.658012 -263.225098) (xy 337.604862 -263.229082) (xy 337.551712 -263.225098) (xy 337.49975 -263.213238)
			(xy 337.450136 -263.193766) (xy 337.403978 -263.167117) (xy 337.362307 -263.133886) (xy 337.326055 -263.094815)
			(xy 337.296031 -263.050778) (xy 337.272905 -263.002757) (xy 337.257195 -262.951827) (xy 337.249252 -262.899123)
			(xy 337.020776 -262.899123) (xy 337.020776 -262.89974) (xy 337.012479 -262.953587) (xy 336.996079 -263.005543)
			(xy 336.971958 -263.054395) (xy 336.940679 -263.099003) (xy 336.902971 -263.138329) (xy 336.859715 -263.171453)
			(xy 336.811918 -263.197603) (xy 336.760697 -263.21617) (xy 336.707246 -263.226719) (xy 336.680048 -263.228328)
			(xy 336.670301 -263.229145) (xy 336.65247 -263.237143) (xy 336.638924 -263.251228) (xy 336.631627 -263.269357)
			(xy 336.63128 -263.279128) (xy 336.63128 -263.713193) (xy 336.779352 -263.713193) (xy 336.779352 -263.659895)
			(xy 336.787295 -263.607191) (xy 336.803005 -263.556261) (xy 336.826131 -263.50824) (xy 336.856155 -263.464203)
			(xy 336.892407 -263.425132) (xy 336.934078 -263.391901) (xy 336.980236 -263.365252) (xy 337.02985 -263.34578)
			(xy 337.081812 -263.33392) (xy 337.134962 -263.329937) (xy 337.188112 -263.33392) (xy 337.240074 -263.34578)
			(xy 337.289688 -263.365252) (xy 337.335846 -263.391901) (xy 337.377517 -263.425132) (xy 337.413769 -263.464203)
			(xy 337.443793 -263.50824) (xy 337.466919 -263.556261) (xy 337.482629 -263.607191) (xy 337.490572 -263.659895)
			(xy 337.49107 -263.686544) (xy 337.490572 -263.713193) (xy 337.719152 -263.713193) (xy 337.719152 -263.659895)
			(xy 337.727095 -263.607191) (xy 337.742805 -263.556261) (xy 337.765931 -263.50824) (xy 337.795955 -263.464203)
			(xy 337.832207 -263.425132) (xy 337.873878 -263.391901) (xy 337.920036 -263.365252) (xy 337.96965 -263.34578)
			(xy 338.021612 -263.33392) (xy 338.074762 -263.329937) (xy 338.127912 -263.33392) (xy 338.179874 -263.34578)
			(xy 338.229488 -263.365252) (xy 338.275646 -263.391901) (xy 338.317317 -263.425132) (xy 338.353569 -263.464203)
			(xy 338.383593 -263.50824) (xy 338.406719 -263.556261) (xy 338.422429 -263.607191) (xy 338.430372 -263.659895)
			(xy 338.43087 -263.686544) (xy 338.430372 -263.713193) (xy 338.659206 -263.713193) (xy 338.659206 -263.659895)
			(xy 338.667149 -263.607191) (xy 338.682859 -263.556261) (xy 338.705985 -263.50824) (xy 338.736009 -263.464203)
			(xy 338.772261 -263.425132) (xy 338.813932 -263.391901) (xy 338.86009 -263.365252) (xy 338.909704 -263.34578)
			(xy 338.961666 -263.33392) (xy 339.014816 -263.329937) (xy 339.067966 -263.33392) (xy 339.119928 -263.34578)
			(xy 339.169542 -263.365252) (xy 339.2157 -263.391901) (xy 339.257371 -263.425132) (xy 339.293623 -263.464203)
			(xy 339.323647 -263.50824) (xy 339.346773 -263.556261) (xy 339.362483 -263.607191) (xy 339.370426 -263.659895)
			(xy 339.370924 -263.686544) (xy 339.370426 -263.713193) (xy 339.599006 -263.713193) (xy 339.599006 -263.659895)
			(xy 339.606949 -263.607191) (xy 339.622659 -263.556261) (xy 339.645785 -263.50824) (xy 339.675809 -263.464203)
			(xy 339.712061 -263.425132) (xy 339.753732 -263.391901) (xy 339.79989 -263.365252) (xy 339.849504 -263.34578)
			(xy 339.901466 -263.33392) (xy 339.954616 -263.329937) (xy 340.007766 -263.33392) (xy 340.059728 -263.34578)
			(xy 340.109342 -263.365252) (xy 340.1555 -263.391901) (xy 340.197171 -263.425132) (xy 340.233423 -263.464203)
			(xy 340.263447 -263.50824) (xy 340.286573 -263.556261) (xy 340.302283 -263.607191) (xy 340.310226 -263.659895)
			(xy 340.310724 -263.686544) (xy 340.310226 -263.713193) (xy 340.538806 -263.713193) (xy 340.538806 -263.659895)
			(xy 340.546749 -263.607191) (xy 340.562459 -263.556261) (xy 340.585585 -263.50824) (xy 340.615609 -263.464203)
			(xy 340.651861 -263.425132) (xy 340.693532 -263.391901) (xy 340.73969 -263.365252) (xy 340.789304 -263.34578)
			(xy 340.841266 -263.33392) (xy 340.894416 -263.329937) (xy 340.947566 -263.33392) (xy 340.999528 -263.34578)
			(xy 341.049142 -263.365252) (xy 341.0953 -263.391901) (xy 341.136971 -263.425132) (xy 341.173223 -263.464203)
			(xy 341.203247 -263.50824) (xy 341.226373 -263.556261) (xy 341.242083 -263.607191) (xy 341.250026 -263.659895)
			(xy 341.250524 -263.686544) (xy 341.250026 -263.713193) (xy 341.478606 -263.713193) (xy 341.478606 -263.659895)
			(xy 341.486549 -263.607191) (xy 341.502259 -263.556261) (xy 341.525385 -263.50824) (xy 341.555409 -263.464203)
			(xy 341.591661 -263.425132) (xy 341.633332 -263.391901) (xy 341.67949 -263.365252) (xy 341.729104 -263.34578)
			(xy 341.781066 -263.33392) (xy 341.834216 -263.329937) (xy 341.887366 -263.33392) (xy 341.939328 -263.34578)
			(xy 341.988942 -263.365252) (xy 342.0351 -263.391901) (xy 342.076771 -263.425132) (xy 342.113023 -263.464203)
			(xy 342.143047 -263.50824) (xy 342.166173 -263.556261) (xy 342.181883 -263.607191) (xy 342.189826 -263.659895)
			(xy 342.190324 -263.686544) (xy 342.189826 -263.713193) (xy 342.418152 -263.713193) (xy 342.418152 -263.659895)
			(xy 342.426095 -263.607191) (xy 342.441805 -263.556261) (xy 342.464931 -263.50824) (xy 342.494955 -263.464203)
			(xy 342.531207 -263.425132) (xy 342.572878 -263.391901) (xy 342.619036 -263.365252) (xy 342.66865 -263.34578)
			(xy 342.720612 -263.33392) (xy 342.773762 -263.329937) (xy 342.826912 -263.33392) (xy 342.878874 -263.34578)
			(xy 342.928488 -263.365252) (xy 342.974646 -263.391901) (xy 343.016317 -263.425132) (xy 343.052569 -263.464203)
			(xy 343.082593 -263.50824) (xy 343.105719 -263.556261) (xy 343.121429 -263.607191) (xy 343.129372 -263.659895)
			(xy 343.12987 -263.686544) (xy 343.129372 -263.713193) (xy 343.358206 -263.713193) (xy 343.358206 -263.659895)
			(xy 343.366149 -263.607191) (xy 343.381859 -263.556261) (xy 343.404985 -263.50824) (xy 343.435009 -263.464203)
			(xy 343.471261 -263.425132) (xy 343.512932 -263.391901) (xy 343.55909 -263.365252) (xy 343.608704 -263.34578)
			(xy 343.660666 -263.33392) (xy 343.713816 -263.329937) (xy 343.766966 -263.33392) (xy 343.818928 -263.34578)
			(xy 343.868542 -263.365252) (xy 343.9147 -263.391901) (xy 343.956371 -263.425132) (xy 343.992623 -263.464203)
			(xy 344.022647 -263.50824) (xy 344.045773 -263.556261) (xy 344.061483 -263.607191) (xy 344.069426 -263.659895)
			(xy 344.069924 -263.686544) (xy 344.069426 -263.713193) (xy 344.298006 -263.713193) (xy 344.298006 -263.659895)
			(xy 344.305949 -263.607191) (xy 344.321659 -263.556261) (xy 344.344785 -263.50824) (xy 344.374809 -263.464203)
			(xy 344.411061 -263.425132) (xy 344.452732 -263.391901) (xy 344.49889 -263.365252) (xy 344.548504 -263.34578)
			(xy 344.600466 -263.33392) (xy 344.653616 -263.329937) (xy 344.706766 -263.33392) (xy 344.758728 -263.34578)
			(xy 344.808342 -263.365252) (xy 344.8545 -263.391901) (xy 344.896171 -263.425132) (xy 344.932423 -263.464203)
			(xy 344.962447 -263.50824) (xy 344.985573 -263.556261) (xy 345.001283 -263.607191) (xy 345.009226 -263.659895)
			(xy 345.009724 -263.686544) (xy 345.009226 -263.713193) (xy 345.237806 -263.713193) (xy 345.237806 -263.659895)
			(xy 345.245749 -263.607191) (xy 345.261459 -263.556261) (xy 345.284585 -263.50824) (xy 345.314609 -263.464203)
			(xy 345.350861 -263.425132) (xy 345.392532 -263.391901) (xy 345.43869 -263.365252) (xy 345.488304 -263.34578)
			(xy 345.540266 -263.33392) (xy 345.593416 -263.329937) (xy 345.646566 -263.33392) (xy 345.698528 -263.34578)
			(xy 345.748142 -263.365252) (xy 345.7943 -263.391901) (xy 345.835971 -263.425132) (xy 345.872223 -263.464203)
			(xy 345.902247 -263.50824) (xy 345.925373 -263.556261) (xy 345.941083 -263.607191) (xy 345.949026 -263.659895)
			(xy 345.949524 -263.686544) (xy 345.949026 -263.713193) (xy 346.177606 -263.713193) (xy 346.177606 -263.659895)
			(xy 346.185549 -263.607191) (xy 346.201259 -263.556261) (xy 346.224385 -263.50824) (xy 346.254409 -263.464203)
			(xy 346.290661 -263.425132) (xy 346.332332 -263.391901) (xy 346.37849 -263.365252) (xy 346.428104 -263.34578)
			(xy 346.480066 -263.33392) (xy 346.533216 -263.329937) (xy 346.586366 -263.33392) (xy 346.638328 -263.34578)
			(xy 346.687942 -263.365252) (xy 346.7341 -263.391901) (xy 346.775771 -263.425132) (xy 346.812023 -263.464203)
			(xy 346.842047 -263.50824) (xy 346.865173 -263.556261) (xy 346.880883 -263.607191) (xy 346.888826 -263.659895)
			(xy 346.889324 -263.686544) (xy 346.888826 -263.713193) (xy 347.117406 -263.713193) (xy 347.117406 -263.659895)
			(xy 347.125349 -263.607191) (xy 347.141059 -263.556261) (xy 347.164185 -263.50824) (xy 347.194209 -263.464203)
			(xy 347.230461 -263.425132) (xy 347.272132 -263.391901) (xy 347.31829 -263.365252) (xy 347.367904 -263.34578)
			(xy 347.419866 -263.33392) (xy 347.473016 -263.329937) (xy 347.526166 -263.33392) (xy 347.578128 -263.34578)
			(xy 347.627742 -263.365252) (xy 347.6739 -263.391901) (xy 347.715571 -263.425132) (xy 347.751823 -263.464203)
			(xy 347.781847 -263.50824) (xy 347.804973 -263.556261) (xy 347.820683 -263.607191) (xy 347.828626 -263.659895)
			(xy 347.829124 -263.686544) (xy 347.828626 -263.713193) (xy 348.057206 -263.713193) (xy 348.057206 -263.659895)
			(xy 348.065149 -263.607191) (xy 348.080859 -263.556261) (xy 348.103985 -263.50824) (xy 348.134009 -263.464203)
			(xy 348.170261 -263.425132) (xy 348.211932 -263.391901) (xy 348.25809 -263.365252) (xy 348.307704 -263.34578)
			(xy 348.359666 -263.33392) (xy 348.412816 -263.329937) (xy 348.465966 -263.33392) (xy 348.517928 -263.34578)
			(xy 348.567542 -263.365252) (xy 348.6137 -263.391901) (xy 348.655371 -263.425132) (xy 348.691623 -263.464203)
			(xy 348.721647 -263.50824) (xy 348.744773 -263.556261) (xy 348.760483 -263.607191) (xy 348.768426 -263.659895)
			(xy 348.768924 -263.686544) (xy 348.768426 -263.713193) (xy 348.996752 -263.713193) (xy 348.996752 -263.659895)
			(xy 349.004695 -263.607191) (xy 349.020405 -263.556261) (xy 349.043531 -263.50824) (xy 349.073555 -263.464203)
			(xy 349.109807 -263.425132) (xy 349.151478 -263.391901) (xy 349.197636 -263.365252) (xy 349.24725 -263.34578)
			(xy 349.299212 -263.33392) (xy 349.352362 -263.329937) (xy 349.405512 -263.33392) (xy 349.457474 -263.34578)
			(xy 349.507088 -263.365252) (xy 349.553246 -263.391901) (xy 349.594917 -263.425132) (xy 349.631169 -263.464203)
			(xy 349.661193 -263.50824) (xy 349.684319 -263.556261) (xy 349.700029 -263.607191) (xy 349.707972 -263.659895)
			(xy 349.70847 -263.686544) (xy 349.707972 -263.713193) (xy 349.936806 -263.713193) (xy 349.936806 -263.659895)
			(xy 349.944749 -263.607191) (xy 349.960459 -263.556261) (xy 349.983585 -263.50824) (xy 350.013609 -263.464203)
			(xy 350.049861 -263.425132) (xy 350.091532 -263.391901) (xy 350.13769 -263.365252) (xy 350.187304 -263.34578)
			(xy 350.239266 -263.33392) (xy 350.292416 -263.329937) (xy 350.345566 -263.33392) (xy 350.397528 -263.34578)
			(xy 350.447142 -263.365252) (xy 350.4933 -263.391901) (xy 350.534971 -263.425132) (xy 350.571223 -263.464203)
			(xy 350.601247 -263.50824) (xy 350.624373 -263.556261) (xy 350.640083 -263.607191) (xy 350.648026 -263.659895)
			(xy 350.648524 -263.686544) (xy 350.648026 -263.713193) (xy 350.640083 -263.765897) (xy 350.624373 -263.816827)
			(xy 350.601247 -263.864848) (xy 350.571223 -263.908885) (xy 350.534971 -263.947956) (xy 350.4933 -263.981187)
			(xy 350.447142 -264.007836) (xy 350.397528 -264.027308) (xy 350.345566 -264.039168) (xy 350.292416 -264.043152)
			(xy 350.239266 -264.039168) (xy 350.187304 -264.027308) (xy 350.13769 -264.007836) (xy 350.091532 -263.981187)
			(xy 350.049861 -263.947956) (xy 350.013609 -263.908885) (xy 349.983585 -263.864848) (xy 349.960459 -263.816827)
			(xy 349.944749 -263.765897) (xy 349.936806 -263.713193) (xy 349.707972 -263.713193) (xy 349.700029 -263.765897)
			(xy 349.684319 -263.816827) (xy 349.661193 -263.864848) (xy 349.631169 -263.908885) (xy 349.594917 -263.947956)
			(xy 349.553246 -263.981187) (xy 349.507088 -264.007836) (xy 349.457474 -264.027308) (xy 349.405512 -264.039168)
			(xy 349.352362 -264.043152) (xy 349.299212 -264.039168) (xy 349.24725 -264.027308) (xy 349.197636 -264.007836)
			(xy 349.151478 -263.981187) (xy 349.109807 -263.947956) (xy 349.073555 -263.908885) (xy 349.043531 -263.864848)
			(xy 349.020405 -263.816827) (xy 349.004695 -263.765897) (xy 348.996752 -263.713193) (xy 348.768426 -263.713193)
			(xy 348.760483 -263.765897) (xy 348.744773 -263.816827) (xy 348.721647 -263.864848) (xy 348.691623 -263.908885)
			(xy 348.655371 -263.947956) (xy 348.6137 -263.981187) (xy 348.567542 -264.007836) (xy 348.517928 -264.027308)
			(xy 348.465966 -264.039168) (xy 348.412816 -264.043152) (xy 348.359666 -264.039168) (xy 348.307704 -264.027308)
			(xy 348.25809 -264.007836) (xy 348.211932 -263.981187) (xy 348.170261 -263.947956) (xy 348.134009 -263.908885)
			(xy 348.103985 -263.864848) (xy 348.080859 -263.816827) (xy 348.065149 -263.765897) (xy 348.057206 -263.713193)
			(xy 347.828626 -263.713193) (xy 347.820683 -263.765897) (xy 347.804973 -263.816827) (xy 347.781847 -263.864848)
			(xy 347.751823 -263.908885) (xy 347.715571 -263.947956) (xy 347.6739 -263.981187) (xy 347.627742 -264.007836)
			(xy 347.578128 -264.027308) (xy 347.526166 -264.039168) (xy 347.473016 -264.043152) (xy 347.419866 -264.039168)
			(xy 347.367904 -264.027308) (xy 347.31829 -264.007836) (xy 347.272132 -263.981187) (xy 347.230461 -263.947956)
			(xy 347.194209 -263.908885) (xy 347.164185 -263.864848) (xy 347.141059 -263.816827) (xy 347.125349 -263.765897)
			(xy 347.117406 -263.713193) (xy 346.888826 -263.713193) (xy 346.880883 -263.765897) (xy 346.865173 -263.816827)
			(xy 346.842047 -263.864848) (xy 346.812023 -263.908885) (xy 346.775771 -263.947956) (xy 346.7341 -263.981187)
			(xy 346.687942 -264.007836) (xy 346.638328 -264.027308) (xy 346.586366 -264.039168) (xy 346.533216 -264.043152)
			(xy 346.480066 -264.039168) (xy 346.428104 -264.027308) (xy 346.37849 -264.007836) (xy 346.332332 -263.981187)
			(xy 346.290661 -263.947956) (xy 346.254409 -263.908885) (xy 346.224385 -263.864848) (xy 346.201259 -263.816827)
			(xy 346.185549 -263.765897) (xy 346.177606 -263.713193) (xy 345.949026 -263.713193) (xy 345.941083 -263.765897)
			(xy 345.925373 -263.816827) (xy 345.902247 -263.864848) (xy 345.872223 -263.908885) (xy 345.835971 -263.947956)
			(xy 345.7943 -263.981187) (xy 345.748142 -264.007836) (xy 345.698528 -264.027308) (xy 345.646566 -264.039168)
			(xy 345.593416 -264.043152) (xy 345.540266 -264.039168) (xy 345.488304 -264.027308) (xy 345.43869 -264.007836)
			(xy 345.392532 -263.981187) (xy 345.350861 -263.947956) (xy 345.314609 -263.908885) (xy 345.284585 -263.864848)
			(xy 345.261459 -263.816827) (xy 345.245749 -263.765897) (xy 345.237806 -263.713193) (xy 345.009226 -263.713193)
			(xy 345.001283 -263.765897) (xy 344.985573 -263.816827) (xy 344.962447 -263.864848) (xy 344.932423 -263.908885)
			(xy 344.896171 -263.947956) (xy 344.8545 -263.981187) (xy 344.808342 -264.007836) (xy 344.758728 -264.027308)
			(xy 344.706766 -264.039168) (xy 344.653616 -264.043152) (xy 344.600466 -264.039168) (xy 344.548504 -264.027308)
			(xy 344.49889 -264.007836) (xy 344.452732 -263.981187) (xy 344.411061 -263.947956) (xy 344.374809 -263.908885)
			(xy 344.344785 -263.864848) (xy 344.321659 -263.816827) (xy 344.305949 -263.765897) (xy 344.298006 -263.713193)
			(xy 344.069426 -263.713193) (xy 344.061483 -263.765897) (xy 344.045773 -263.816827) (xy 344.022647 -263.864848)
			(xy 343.992623 -263.908885) (xy 343.956371 -263.947956) (xy 343.9147 -263.981187) (xy 343.868542 -264.007836)
			(xy 343.818928 -264.027308) (xy 343.766966 -264.039168) (xy 343.713816 -264.043152) (xy 343.660666 -264.039168)
			(xy 343.608704 -264.027308) (xy 343.55909 -264.007836) (xy 343.512932 -263.981187) (xy 343.471261 -263.947956)
			(xy 343.435009 -263.908885) (xy 343.404985 -263.864848) (xy 343.381859 -263.816827) (xy 343.366149 -263.765897)
			(xy 343.358206 -263.713193) (xy 343.129372 -263.713193) (xy 343.121429 -263.765897) (xy 343.105719 -263.816827)
			(xy 343.082593 -263.864848) (xy 343.052569 -263.908885) (xy 343.016317 -263.947956) (xy 342.974646 -263.981187)
			(xy 342.928488 -264.007836) (xy 342.878874 -264.027308) (xy 342.826912 -264.039168) (xy 342.773762 -264.043152)
			(xy 342.720612 -264.039168) (xy 342.66865 -264.027308) (xy 342.619036 -264.007836) (xy 342.572878 -263.981187)
			(xy 342.531207 -263.947956) (xy 342.494955 -263.908885) (xy 342.464931 -263.864848) (xy 342.441805 -263.816827)
			(xy 342.426095 -263.765897) (xy 342.418152 -263.713193) (xy 342.189826 -263.713193) (xy 342.181883 -263.765897)
			(xy 342.166173 -263.816827) (xy 342.143047 -263.864848) (xy 342.113023 -263.908885) (xy 342.076771 -263.947956)
			(xy 342.0351 -263.981187) (xy 341.988942 -264.007836) (xy 341.939328 -264.027308) (xy 341.887366 -264.039168)
			(xy 341.834216 -264.043152) (xy 341.781066 -264.039168) (xy 341.729104 -264.027308) (xy 341.67949 -264.007836)
			(xy 341.633332 -263.981187) (xy 341.591661 -263.947956) (xy 341.555409 -263.908885) (xy 341.525385 -263.864848)
			(xy 341.502259 -263.816827) (xy 341.486549 -263.765897) (xy 341.478606 -263.713193) (xy 341.250026 -263.713193)
			(xy 341.242083 -263.765897) (xy 341.226373 -263.816827) (xy 341.203247 -263.864848) (xy 341.173223 -263.908885)
			(xy 341.136971 -263.947956) (xy 341.0953 -263.981187) (xy 341.049142 -264.007836) (xy 340.999528 -264.027308)
			(xy 340.947566 -264.039168) (xy 340.894416 -264.043152) (xy 340.841266 -264.039168) (xy 340.789304 -264.027308)
			(xy 340.73969 -264.007836) (xy 340.693532 -263.981187) (xy 340.651861 -263.947956) (xy 340.615609 -263.908885)
			(xy 340.585585 -263.864848) (xy 340.562459 -263.816827) (xy 340.546749 -263.765897) (xy 340.538806 -263.713193)
			(xy 340.310226 -263.713193) (xy 340.302283 -263.765897) (xy 340.286573 -263.816827) (xy 340.263447 -263.864848)
			(xy 340.233423 -263.908885) (xy 340.197171 -263.947956) (xy 340.1555 -263.981187) (xy 340.109342 -264.007836)
			(xy 340.059728 -264.027308) (xy 340.007766 -264.039168) (xy 339.954616 -264.043152) (xy 339.901466 -264.039168)
			(xy 339.849504 -264.027308) (xy 339.79989 -264.007836) (xy 339.753732 -263.981187) (xy 339.712061 -263.947956)
			(xy 339.675809 -263.908885) (xy 339.645785 -263.864848) (xy 339.622659 -263.816827) (xy 339.606949 -263.765897)
			(xy 339.599006 -263.713193) (xy 339.370426 -263.713193) (xy 339.362483 -263.765897) (xy 339.346773 -263.816827)
			(xy 339.323647 -263.864848) (xy 339.293623 -263.908885) (xy 339.257371 -263.947956) (xy 339.2157 -263.981187)
			(xy 339.169542 -264.007836) (xy 339.119928 -264.027308) (xy 339.067966 -264.039168) (xy 339.014816 -264.043152)
			(xy 338.961666 -264.039168) (xy 338.909704 -264.027308) (xy 338.86009 -264.007836) (xy 338.813932 -263.981187)
			(xy 338.772261 -263.947956) (xy 338.736009 -263.908885) (xy 338.705985 -263.864848) (xy 338.682859 -263.816827)
			(xy 338.667149 -263.765897) (xy 338.659206 -263.713193) (xy 338.430372 -263.713193) (xy 338.422429 -263.765897)
			(xy 338.406719 -263.816827) (xy 338.383593 -263.864848) (xy 338.353569 -263.908885) (xy 338.317317 -263.947956)
			(xy 338.275646 -263.981187) (xy 338.229488 -264.007836) (xy 338.179874 -264.027308) (xy 338.127912 -264.039168)
			(xy 338.074762 -264.043152) (xy 338.021612 -264.039168) (xy 337.96965 -264.027308) (xy 337.920036 -264.007836)
			(xy 337.873878 -263.981187) (xy 337.832207 -263.947956) (xy 337.795955 -263.908885) (xy 337.765931 -263.864848)
			(xy 337.742805 -263.816827) (xy 337.727095 -263.765897) (xy 337.719152 -263.713193) (xy 337.490572 -263.713193)
			(xy 337.482629 -263.765897) (xy 337.466919 -263.816827) (xy 337.443793 -263.864848) (xy 337.413769 -263.908885)
			(xy 337.377517 -263.947956) (xy 337.335846 -263.981187) (xy 337.289688 -264.007836) (xy 337.240074 -264.027308)
			(xy 337.188112 -264.039168) (xy 337.134962 -264.043152) (xy 337.081812 -264.039168) (xy 337.02985 -264.027308)
			(xy 336.980236 -264.007836) (xy 336.934078 -263.981187) (xy 336.892407 -263.947956) (xy 336.856155 -263.908885)
			(xy 336.826131 -263.864848) (xy 336.803005 -263.816827) (xy 336.787295 -263.765897) (xy 336.779352 -263.713193)
			(xy 336.63128 -263.713193) (xy 336.63128 -264.093706) (xy 336.631718 -264.10347) (xy 336.639001 -264.121588)
			(xy 336.652514 -264.135684) (xy 336.670309 -264.143725) (xy 336.680048 -264.144506) (xy 336.707237 -264.146167)
			(xy 336.760675 -264.156717) (xy 336.811882 -264.175284) (xy 336.859663 -264.201435) (xy 336.902903 -264.23456)
			(xy 336.940593 -264.273884) (xy 336.971852 -264.318491) (xy 336.995952 -264.367339) (xy 337.012329 -264.419288)
			(xy 337.020602 -264.473125) (xy 337.02117 -264.50036) (xy 337.020727 -264.52588) (xy 337.020564 -264.527009)
			(xy 337.249252 -264.527009) (xy 337.249252 -264.473711) (xy 337.257195 -264.421007) (xy 337.272905 -264.370077)
			(xy 337.296031 -264.322056) (xy 337.326055 -264.278019) (xy 337.362307 -264.238948) (xy 337.403978 -264.205717)
			(xy 337.450136 -264.179068) (xy 337.49975 -264.159596) (xy 337.551712 -264.147736) (xy 337.604862 -264.143753)
			(xy 337.658012 -264.147736) (xy 337.709974 -264.159596) (xy 337.759588 -264.179068) (xy 337.805746 -264.205717)
			(xy 337.847417 -264.238948) (xy 337.883669 -264.278019) (xy 337.913693 -264.322056) (xy 337.936819 -264.370077)
			(xy 337.952529 -264.421007) (xy 337.960472 -264.473711) (xy 337.96097 -264.50036) (xy 337.960472 -264.527009)
			(xy 338.189052 -264.527009) (xy 338.189052 -264.473711) (xy 338.196995 -264.421007) (xy 338.212705 -264.370077)
			(xy 338.235831 -264.322056) (xy 338.265855 -264.278019) (xy 338.302107 -264.238948) (xy 338.343778 -264.205717)
			(xy 338.389936 -264.179068) (xy 338.43955 -264.159596) (xy 338.491512 -264.147736) (xy 338.544662 -264.143753)
			(xy 338.597812 -264.147736) (xy 338.649774 -264.159596) (xy 338.699388 -264.179068) (xy 338.745546 -264.205717)
			(xy 338.787217 -264.238948) (xy 338.823469 -264.278019) (xy 338.853493 -264.322056) (xy 338.876619 -264.370077)
			(xy 338.892329 -264.421007) (xy 338.900272 -264.473711) (xy 338.90077 -264.50036) (xy 338.900272 -264.527009)
			(xy 339.129106 -264.527009) (xy 339.129106 -264.473711) (xy 339.137049 -264.421007) (xy 339.152759 -264.370077)
			(xy 339.175885 -264.322056) (xy 339.205909 -264.278019) (xy 339.242161 -264.238948) (xy 339.283832 -264.205717)
			(xy 339.32999 -264.179068) (xy 339.379604 -264.159596) (xy 339.431566 -264.147736) (xy 339.484716 -264.143753)
			(xy 339.537866 -264.147736) (xy 339.589828 -264.159596) (xy 339.639442 -264.179068) (xy 339.6856 -264.205717)
			(xy 339.727271 -264.238948) (xy 339.763523 -264.278019) (xy 339.793547 -264.322056) (xy 339.816673 -264.370077)
			(xy 339.832383 -264.421007) (xy 339.840326 -264.473711) (xy 339.840824 -264.50036) (xy 339.840326 -264.527009)
			(xy 340.068652 -264.527009) (xy 340.068652 -264.473711) (xy 340.076595 -264.421007) (xy 340.092305 -264.370077)
			(xy 340.115431 -264.322056) (xy 340.145455 -264.278019) (xy 340.181707 -264.238948) (xy 340.223378 -264.205717)
			(xy 340.269536 -264.179068) (xy 340.31915 -264.159596) (xy 340.371112 -264.147736) (xy 340.424262 -264.143753)
			(xy 340.477412 -264.147736) (xy 340.529374 -264.159596) (xy 340.578988 -264.179068) (xy 340.625146 -264.205717)
			(xy 340.666817 -264.238948) (xy 340.703069 -264.278019) (xy 340.733093 -264.322056) (xy 340.756219 -264.370077)
			(xy 340.771929 -264.421007) (xy 340.779872 -264.473711) (xy 340.78037 -264.50036) (xy 340.779872 -264.527009)
			(xy 341.008452 -264.527009) (xy 341.008452 -264.473711) (xy 341.016395 -264.421007) (xy 341.032105 -264.370077)
			(xy 341.055231 -264.322056) (xy 341.085255 -264.278019) (xy 341.121507 -264.238948) (xy 341.163178 -264.205717)
			(xy 341.209336 -264.179068) (xy 341.25895 -264.159596) (xy 341.310912 -264.147736) (xy 341.364062 -264.143753)
			(xy 341.417212 -264.147736) (xy 341.469174 -264.159596) (xy 341.518788 -264.179068) (xy 341.564946 -264.205717)
			(xy 341.606617 -264.238948) (xy 341.642869 -264.278019) (xy 341.672893 -264.322056) (xy 341.696019 -264.370077)
			(xy 341.711729 -264.421007) (xy 341.719672 -264.473711) (xy 341.72017 -264.50036) (xy 341.719672 -264.527009)
			(xy 341.948252 -264.527009) (xy 341.948252 -264.473711) (xy 341.956195 -264.421007) (xy 341.971905 -264.370077)
			(xy 341.995031 -264.322056) (xy 342.025055 -264.278019) (xy 342.061307 -264.238948) (xy 342.102978 -264.205717)
			(xy 342.149136 -264.179068) (xy 342.19875 -264.159596) (xy 342.250712 -264.147736) (xy 342.303862 -264.143753)
			(xy 342.357012 -264.147736) (xy 342.408974 -264.159596) (xy 342.458588 -264.179068) (xy 342.504746 -264.205717)
			(xy 342.546417 -264.238948) (xy 342.582669 -264.278019) (xy 342.612693 -264.322056) (xy 342.635819 -264.370077)
			(xy 342.651529 -264.421007) (xy 342.659472 -264.473711) (xy 342.65997 -264.50036) (xy 342.659472 -264.527009)
			(xy 342.888052 -264.527009) (xy 342.888052 -264.473711) (xy 342.895995 -264.421007) (xy 342.911705 -264.370077)
			(xy 342.934831 -264.322056) (xy 342.964855 -264.278019) (xy 343.001107 -264.238948) (xy 343.042778 -264.205717)
			(xy 343.088936 -264.179068) (xy 343.13855 -264.159596) (xy 343.190512 -264.147736) (xy 343.243662 -264.143753)
			(xy 343.296812 -264.147736) (xy 343.348774 -264.159596) (xy 343.398388 -264.179068) (xy 343.444546 -264.205717)
			(xy 343.486217 -264.238948) (xy 343.522469 -264.278019) (xy 343.552493 -264.322056) (xy 343.575619 -264.370077)
			(xy 343.591329 -264.421007) (xy 343.599272 -264.473711) (xy 343.59977 -264.50036) (xy 343.599272 -264.527009)
			(xy 343.827852 -264.527009) (xy 343.827852 -264.473711) (xy 343.835795 -264.421007) (xy 343.851505 -264.370077)
			(xy 343.874631 -264.322056) (xy 343.904655 -264.278019) (xy 343.940907 -264.238948) (xy 343.982578 -264.205717)
			(xy 344.028736 -264.179068) (xy 344.07835 -264.159596) (xy 344.130312 -264.147736) (xy 344.183462 -264.143753)
			(xy 344.236612 -264.147736) (xy 344.288574 -264.159596) (xy 344.338188 -264.179068) (xy 344.384346 -264.205717)
			(xy 344.426017 -264.238948) (xy 344.462269 -264.278019) (xy 344.492293 -264.322056) (xy 344.515419 -264.370077)
			(xy 344.531129 -264.421007) (xy 344.539072 -264.473711) (xy 344.53957 -264.50036) (xy 344.539072 -264.527009)
			(xy 344.767652 -264.527009) (xy 344.767652 -264.473711) (xy 344.775595 -264.421007) (xy 344.791305 -264.370077)
			(xy 344.814431 -264.322056) (xy 344.844455 -264.278019) (xy 344.880707 -264.238948) (xy 344.922378 -264.205717)
			(xy 344.968536 -264.179068) (xy 345.01815 -264.159596) (xy 345.070112 -264.147736) (xy 345.123262 -264.143753)
			(xy 345.176412 -264.147736) (xy 345.228374 -264.159596) (xy 345.277988 -264.179068) (xy 345.324146 -264.205717)
			(xy 345.365817 -264.238948) (xy 345.402069 -264.278019) (xy 345.432093 -264.322056) (xy 345.455219 -264.370077)
			(xy 345.470929 -264.421007) (xy 345.478872 -264.473711) (xy 345.47937 -264.50036) (xy 345.478872 -264.527009)
			(xy 345.707706 -264.527009) (xy 345.707706 -264.473711) (xy 345.715649 -264.421007) (xy 345.731359 -264.370077)
			(xy 345.754485 -264.322056) (xy 345.784509 -264.278019) (xy 345.820761 -264.238948) (xy 345.862432 -264.205717)
			(xy 345.90859 -264.179068) (xy 345.958204 -264.159596) (xy 346.010166 -264.147736) (xy 346.063316 -264.143753)
			(xy 346.116466 -264.147736) (xy 346.168428 -264.159596) (xy 346.218042 -264.179068) (xy 346.2642 -264.205717)
			(xy 346.305871 -264.238948) (xy 346.342123 -264.278019) (xy 346.372147 -264.322056) (xy 346.395273 -264.370077)
			(xy 346.410983 -264.421007) (xy 346.418926 -264.473711) (xy 346.419424 -264.50036) (xy 346.418926 -264.527009)
			(xy 346.647252 -264.527009) (xy 346.647252 -264.473711) (xy 346.655195 -264.421007) (xy 346.670905 -264.370077)
			(xy 346.694031 -264.322056) (xy 346.724055 -264.278019) (xy 346.760307 -264.238948) (xy 346.801978 -264.205717)
			(xy 346.848136 -264.179068) (xy 346.89775 -264.159596) (xy 346.949712 -264.147736) (xy 347.002862 -264.143753)
			(xy 347.056012 -264.147736) (xy 347.107974 -264.159596) (xy 347.157588 -264.179068) (xy 347.203746 -264.205717)
			(xy 347.245417 -264.238948) (xy 347.281669 -264.278019) (xy 347.311693 -264.322056) (xy 347.334819 -264.370077)
			(xy 347.350529 -264.421007) (xy 347.358472 -264.473711) (xy 347.35897 -264.50036) (xy 347.358472 -264.527009)
			(xy 347.587052 -264.527009) (xy 347.587052 -264.473711) (xy 347.594995 -264.421007) (xy 347.610705 -264.370077)
			(xy 347.633831 -264.322056) (xy 347.663855 -264.278019) (xy 347.700107 -264.238948) (xy 347.741778 -264.205717)
			(xy 347.787936 -264.179068) (xy 347.83755 -264.159596) (xy 347.889512 -264.147736) (xy 347.942662 -264.143753)
			(xy 347.995812 -264.147736) (xy 348.047774 -264.159596) (xy 348.097388 -264.179068) (xy 348.143546 -264.205717)
			(xy 348.185217 -264.238948) (xy 348.221469 -264.278019) (xy 348.251493 -264.322056) (xy 348.274619 -264.370077)
			(xy 348.290329 -264.421007) (xy 348.298272 -264.473711) (xy 348.29877 -264.50036) (xy 348.298272 -264.527009)
			(xy 348.526852 -264.527009) (xy 348.526852 -264.473711) (xy 348.534795 -264.421007) (xy 348.550505 -264.370077)
			(xy 348.573631 -264.322056) (xy 348.603655 -264.278019) (xy 348.639907 -264.238948) (xy 348.681578 -264.205717)
			(xy 348.727736 -264.179068) (xy 348.77735 -264.159596) (xy 348.829312 -264.147736) (xy 348.882462 -264.143753)
			(xy 348.935612 -264.147736) (xy 348.987574 -264.159596) (xy 349.037188 -264.179068) (xy 349.083346 -264.205717)
			(xy 349.125017 -264.238948) (xy 349.161269 -264.278019) (xy 349.191293 -264.322056) (xy 349.214419 -264.370077)
			(xy 349.230129 -264.421007) (xy 349.238072 -264.473711) (xy 349.23857 -264.50036) (xy 349.238072 -264.527009)
			(xy 351.346252 -264.527009) (xy 351.346252 -264.473711) (xy 351.354195 -264.421007) (xy 351.369905 -264.370077)
			(xy 351.393031 -264.322056) (xy 351.423055 -264.278019) (xy 351.459307 -264.238948) (xy 351.500978 -264.205717)
			(xy 351.547136 -264.179068) (xy 351.59675 -264.159596) (xy 351.648712 -264.147736) (xy 351.701862 -264.143753)
			(xy 351.755012 -264.147736) (xy 351.806974 -264.159596) (xy 351.856588 -264.179068) (xy 351.902746 -264.205717)
			(xy 351.944417 -264.238948) (xy 351.980669 -264.278019) (xy 352.010693 -264.322056) (xy 352.033819 -264.370077)
			(xy 352.049529 -264.421007) (xy 352.057472 -264.473711) (xy 352.05797 -264.50036) (xy 352.057472 -264.527009)
			(xy 352.049529 -264.579713) (xy 352.033819 -264.630643) (xy 352.010693 -264.678664) (xy 351.980669 -264.722701)
			(xy 351.944417 -264.761772) (xy 351.902746 -264.795003) (xy 351.856588 -264.821652) (xy 351.806974 -264.841124)
			(xy 351.755012 -264.852984) (xy 351.701862 -264.856968) (xy 351.648712 -264.852984) (xy 351.59675 -264.841124)
			(xy 351.547136 -264.821652) (xy 351.500978 -264.795003) (xy 351.459307 -264.761772) (xy 351.423055 -264.722701)
			(xy 351.393031 -264.678664) (xy 351.369905 -264.630643) (xy 351.354195 -264.579713) (xy 351.346252 -264.527009)
			(xy 349.238072 -264.527009) (xy 349.230129 -264.579713) (xy 349.214419 -264.630643) (xy 349.191293 -264.678664)
			(xy 349.161269 -264.722701) (xy 349.125017 -264.761772) (xy 349.083346 -264.795003) (xy 349.037188 -264.821652)
			(xy 348.987574 -264.841124) (xy 348.935612 -264.852984) (xy 348.882462 -264.856968) (xy 348.829312 -264.852984)
			(xy 348.77735 -264.841124) (xy 348.727736 -264.821652) (xy 348.681578 -264.795003) (xy 348.639907 -264.761772)
			(xy 348.603655 -264.722701) (xy 348.573631 -264.678664) (xy 348.550505 -264.630643) (xy 348.534795 -264.579713)
			(xy 348.526852 -264.527009) (xy 348.298272 -264.527009) (xy 348.290329 -264.579713) (xy 348.274619 -264.630643)
			(xy 348.251493 -264.678664) (xy 348.221469 -264.722701) (xy 348.185217 -264.761772) (xy 348.143546 -264.795003)
			(xy 348.097388 -264.821652) (xy 348.047774 -264.841124) (xy 347.995812 -264.852984) (xy 347.942662 -264.856968)
			(xy 347.889512 -264.852984) (xy 347.83755 -264.841124) (xy 347.787936 -264.821652) (xy 347.741778 -264.795003)
			(xy 347.700107 -264.761772) (xy 347.663855 -264.722701) (xy 347.633831 -264.678664) (xy 347.610705 -264.630643)
			(xy 347.594995 -264.579713) (xy 347.587052 -264.527009) (xy 347.358472 -264.527009) (xy 347.350529 -264.579713)
			(xy 347.334819 -264.630643) (xy 347.311693 -264.678664) (xy 347.281669 -264.722701) (xy 347.245417 -264.761772)
			(xy 347.203746 -264.795003) (xy 347.157588 -264.821652) (xy 347.107974 -264.841124) (xy 347.056012 -264.852984)
			(xy 347.002862 -264.856968) (xy 346.949712 -264.852984) (xy 346.89775 -264.841124) (xy 346.848136 -264.821652)
			(xy 346.801978 -264.795003) (xy 346.760307 -264.761772) (xy 346.724055 -264.722701) (xy 346.694031 -264.678664)
			(xy 346.670905 -264.630643) (xy 346.655195 -264.579713) (xy 346.647252 -264.527009) (xy 346.418926 -264.527009)
			(xy 346.410983 -264.579713) (xy 346.395273 -264.630643) (xy 346.372147 -264.678664) (xy 346.342123 -264.722701)
			(xy 346.305871 -264.761772) (xy 346.2642 -264.795003) (xy 346.218042 -264.821652) (xy 346.168428 -264.841124)
			(xy 346.116466 -264.852984) (xy 346.063316 -264.856968) (xy 346.010166 -264.852984) (xy 345.958204 -264.841124)
			(xy 345.90859 -264.821652) (xy 345.862432 -264.795003) (xy 345.820761 -264.761772) (xy 345.784509 -264.722701)
			(xy 345.754485 -264.678664) (xy 345.731359 -264.630643) (xy 345.715649 -264.579713) (xy 345.707706 -264.527009)
			(xy 345.478872 -264.527009) (xy 345.470929 -264.579713) (xy 345.455219 -264.630643) (xy 345.432093 -264.678664)
			(xy 345.402069 -264.722701) (xy 345.365817 -264.761772) (xy 345.324146 -264.795003) (xy 345.277988 -264.821652)
			(xy 345.228374 -264.841124) (xy 345.176412 -264.852984) (xy 345.123262 -264.856968) (xy 345.070112 -264.852984)
			(xy 345.01815 -264.841124) (xy 344.968536 -264.821652) (xy 344.922378 -264.795003) (xy 344.880707 -264.761772)
			(xy 344.844455 -264.722701) (xy 344.814431 -264.678664) (xy 344.791305 -264.630643) (xy 344.775595 -264.579713)
			(xy 344.767652 -264.527009) (xy 344.539072 -264.527009) (xy 344.531129 -264.579713) (xy 344.515419 -264.630643)
			(xy 344.492293 -264.678664) (xy 344.462269 -264.722701) (xy 344.426017 -264.761772) (xy 344.384346 -264.795003)
			(xy 344.338188 -264.821652) (xy 344.288574 -264.841124) (xy 344.236612 -264.852984) (xy 344.183462 -264.856968)
			(xy 344.130312 -264.852984) (xy 344.07835 -264.841124) (xy 344.028736 -264.821652) (xy 343.982578 -264.795003)
			(xy 343.940907 -264.761772) (xy 343.904655 -264.722701) (xy 343.874631 -264.678664) (xy 343.851505 -264.630643)
			(xy 343.835795 -264.579713) (xy 343.827852 -264.527009) (xy 343.599272 -264.527009) (xy 343.591329 -264.579713)
			(xy 343.575619 -264.630643) (xy 343.552493 -264.678664) (xy 343.522469 -264.722701) (xy 343.486217 -264.761772)
			(xy 343.444546 -264.795003) (xy 343.398388 -264.821652) (xy 343.348774 -264.841124) (xy 343.296812 -264.852984)
			(xy 343.243662 -264.856968) (xy 343.190512 -264.852984) (xy 343.13855 -264.841124) (xy 343.088936 -264.821652)
			(xy 343.042778 -264.795003) (xy 343.001107 -264.761772) (xy 342.964855 -264.722701) (xy 342.934831 -264.678664)
			(xy 342.911705 -264.630643) (xy 342.895995 -264.579713) (xy 342.888052 -264.527009) (xy 342.659472 -264.527009)
			(xy 342.651529 -264.579713) (xy 342.635819 -264.630643) (xy 342.612693 -264.678664) (xy 342.582669 -264.722701)
			(xy 342.546417 -264.761772) (xy 342.504746 -264.795003) (xy 342.458588 -264.821652) (xy 342.408974 -264.841124)
			(xy 342.357012 -264.852984) (xy 342.303862 -264.856968) (xy 342.250712 -264.852984) (xy 342.19875 -264.841124)
			(xy 342.149136 -264.821652) (xy 342.102978 -264.795003) (xy 342.061307 -264.761772) (xy 342.025055 -264.722701)
			(xy 341.995031 -264.678664) (xy 341.971905 -264.630643) (xy 341.956195 -264.579713) (xy 341.948252 -264.527009)
			(xy 341.719672 -264.527009) (xy 341.711729 -264.579713) (xy 341.696019 -264.630643) (xy 341.672893 -264.678664)
			(xy 341.642869 -264.722701) (xy 341.606617 -264.761772) (xy 341.564946 -264.795003) (xy 341.518788 -264.821652)
			(xy 341.469174 -264.841124) (xy 341.417212 -264.852984) (xy 341.364062 -264.856968) (xy 341.310912 -264.852984)
			(xy 341.25895 -264.841124) (xy 341.209336 -264.821652) (xy 341.163178 -264.795003) (xy 341.121507 -264.761772)
			(xy 341.085255 -264.722701) (xy 341.055231 -264.678664) (xy 341.032105 -264.630643) (xy 341.016395 -264.579713)
			(xy 341.008452 -264.527009) (xy 340.779872 -264.527009) (xy 340.771929 -264.579713) (xy 340.756219 -264.630643)
			(xy 340.733093 -264.678664) (xy 340.703069 -264.722701) (xy 340.666817 -264.761772) (xy 340.625146 -264.795003)
			(xy 340.578988 -264.821652) (xy 340.529374 -264.841124) (xy 340.477412 -264.852984) (xy 340.424262 -264.856968)
			(xy 340.371112 -264.852984) (xy 340.31915 -264.841124) (xy 340.269536 -264.821652) (xy 340.223378 -264.795003)
			(xy 340.181707 -264.761772) (xy 340.145455 -264.722701) (xy 340.115431 -264.678664) (xy 340.092305 -264.630643)
			(xy 340.076595 -264.579713) (xy 340.068652 -264.527009) (xy 339.840326 -264.527009) (xy 339.832383 -264.579713)
			(xy 339.816673 -264.630643) (xy 339.793547 -264.678664) (xy 339.763523 -264.722701) (xy 339.727271 -264.761772)
			(xy 339.6856 -264.795003) (xy 339.639442 -264.821652) (xy 339.589828 -264.841124) (xy 339.537866 -264.852984)
			(xy 339.484716 -264.856968) (xy 339.431566 -264.852984) (xy 339.379604 -264.841124) (xy 339.32999 -264.821652)
			(xy 339.283832 -264.795003) (xy 339.242161 -264.761772) (xy 339.205909 -264.722701) (xy 339.175885 -264.678664)
			(xy 339.152759 -264.630643) (xy 339.137049 -264.579713) (xy 339.129106 -264.527009) (xy 338.900272 -264.527009)
			(xy 338.892329 -264.579713) (xy 338.876619 -264.630643) (xy 338.853493 -264.678664) (xy 338.823469 -264.722701)
			(xy 338.787217 -264.761772) (xy 338.745546 -264.795003) (xy 338.699388 -264.821652) (xy 338.649774 -264.841124)
			(xy 338.597812 -264.852984) (xy 338.544662 -264.856968) (xy 338.491512 -264.852984) (xy 338.43955 -264.841124)
			(xy 338.389936 -264.821652) (xy 338.343778 -264.795003) (xy 338.302107 -264.761772) (xy 338.265855 -264.722701)
			(xy 338.235831 -264.678664) (xy 338.212705 -264.630643) (xy 338.196995 -264.579713) (xy 338.189052 -264.527009)
			(xy 337.960472 -264.527009) (xy 337.952529 -264.579713) (xy 337.936819 -264.630643) (xy 337.913693 -264.678664)
			(xy 337.883669 -264.722701) (xy 337.847417 -264.761772) (xy 337.805746 -264.795003) (xy 337.759588 -264.821652)
			(xy 337.709974 -264.841124) (xy 337.658012 -264.852984) (xy 337.604862 -264.856968) (xy 337.551712 -264.852984)
			(xy 337.49975 -264.841124) (xy 337.450136 -264.821652) (xy 337.403978 -264.795003) (xy 337.362307 -264.761772)
			(xy 337.326055 -264.722701) (xy 337.296031 -264.678664) (xy 337.272905 -264.630643) (xy 337.257195 -264.579713)
			(xy 337.249252 -264.527009) (xy 337.020564 -264.527009) (xy 337.013431 -264.576395) (xy 336.998997 -264.625352)
			(xy 336.97772 -264.671745) (xy 336.950038 -264.714626) (xy 336.916516 -264.753114) (xy 336.897472 -264.770108)
			(xy 336.887192 -264.779551) (xy 336.871781 -264.802814) (xy 336.863237 -264.829378) (xy 336.862196 -264.857263)
			(xy 336.868734 -264.884391) (xy 336.882366 -264.908739) (xy 336.891884 -264.918952) (xy 336.969862 -264.99693)
			(xy 337.001104 -264.98423) (xy 337.022446 -264.975973) (xy 337.066702 -264.96434) (xy 337.112082 -264.958453)
			(xy 337.134962 -264.958068) (xy 337.16295 -264.958585) (xy 337.218238 -264.967336) (xy 337.271476 -264.984628)
			(xy 337.321353 -265.010036) (xy 337.366641 -265.042934) (xy 337.406226 -265.082511) (xy 337.439131 -265.127794)
			(xy 337.464548 -265.177667) (xy 337.481849 -265.230902) (xy 337.49061 -265.286188) (xy 337.49107 -265.314176)
			(xy 337.490721 -265.337059) (xy 337.490234 -265.340825) (xy 337.719152 -265.340825) (xy 337.719152 -265.287527)
			(xy 337.727095 -265.234823) (xy 337.742805 -265.183893) (xy 337.765931 -265.135872) (xy 337.795955 -265.091835)
			(xy 337.832207 -265.052764) (xy 337.873878 -265.019533) (xy 337.920036 -264.992884) (xy 337.96965 -264.973412)
			(xy 338.021612 -264.961552) (xy 338.074762 -264.957569) (xy 338.127912 -264.961552) (xy 338.179874 -264.973412)
			(xy 338.229488 -264.992884) (xy 338.275646 -265.019533) (xy 338.317317 -265.052764) (xy 338.353569 -265.091835)
			(xy 338.383593 -265.135872) (xy 338.406719 -265.183893) (xy 338.422429 -265.234823) (xy 338.430372 -265.287527)
			(xy 338.43087 -265.314176) (xy 338.430372 -265.340825) (xy 338.659206 -265.340825) (xy 338.659206 -265.287527)
			(xy 338.667149 -265.234823) (xy 338.682859 -265.183893) (xy 338.705985 -265.135872) (xy 338.736009 -265.091835)
			(xy 338.772261 -265.052764) (xy 338.813932 -265.019533) (xy 338.86009 -264.992884) (xy 338.909704 -264.973412)
			(xy 338.961666 -264.961552) (xy 339.014816 -264.957569) (xy 339.067966 -264.961552) (xy 339.119928 -264.973412)
			(xy 339.169542 -264.992884) (xy 339.2157 -265.019533) (xy 339.257371 -265.052764) (xy 339.293623 -265.091835)
			(xy 339.323647 -265.135872) (xy 339.346773 -265.183893) (xy 339.362483 -265.234823) (xy 339.370426 -265.287527)
			(xy 339.370924 -265.314176) (xy 339.370426 -265.340825) (xy 339.598752 -265.340825) (xy 339.598752 -265.287527)
			(xy 339.606695 -265.234823) (xy 339.622405 -265.183893) (xy 339.645531 -265.135872) (xy 339.675555 -265.091835)
			(xy 339.711807 -265.052764) (xy 339.753478 -265.019533) (xy 339.799636 -264.992884) (xy 339.84925 -264.973412)
			(xy 339.901212 -264.961552) (xy 339.954362 -264.957569) (xy 340.007512 -264.961552) (xy 340.059474 -264.973412)
			(xy 340.109088 -264.992884) (xy 340.155246 -265.019533) (xy 340.196917 -265.052764) (xy 340.233169 -265.091835)
			(xy 340.263193 -265.135872) (xy 340.286319 -265.183893) (xy 340.302029 -265.234823) (xy 340.309972 -265.287527)
			(xy 340.31047 -265.314176) (xy 340.309972 -265.340825) (xy 340.538806 -265.340825) (xy 340.538806 -265.287527)
			(xy 340.546749 -265.234823) (xy 340.562459 -265.183893) (xy 340.585585 -265.135872) (xy 340.615609 -265.091835)
			(xy 340.651861 -265.052764) (xy 340.693532 -265.019533) (xy 340.73969 -264.992884) (xy 340.789304 -264.973412)
			(xy 340.841266 -264.961552) (xy 340.894416 -264.957569) (xy 340.947566 -264.961552) (xy 340.999528 -264.973412)
			(xy 341.049142 -264.992884) (xy 341.0953 -265.019533) (xy 341.136971 -265.052764) (xy 341.173223 -265.091835)
			(xy 341.203247 -265.135872) (xy 341.226373 -265.183893) (xy 341.242083 -265.234823) (xy 341.250026 -265.287527)
			(xy 341.250524 -265.314176) (xy 341.250026 -265.340825) (xy 341.478606 -265.340825) (xy 341.478606 -265.287527)
			(xy 341.486549 -265.234823) (xy 341.502259 -265.183893) (xy 341.525385 -265.135872) (xy 341.555409 -265.091835)
			(xy 341.591661 -265.052764) (xy 341.633332 -265.019533) (xy 341.67949 -264.992884) (xy 341.729104 -264.973412)
			(xy 341.781066 -264.961552) (xy 341.834216 -264.957569) (xy 341.887366 -264.961552) (xy 341.939328 -264.973412)
			(xy 341.988942 -264.992884) (xy 342.0351 -265.019533) (xy 342.076771 -265.052764) (xy 342.113023 -265.091835)
			(xy 342.143047 -265.135872) (xy 342.166173 -265.183893) (xy 342.181883 -265.234823) (xy 342.189826 -265.287527)
			(xy 342.190324 -265.314176) (xy 342.189826 -265.340825) (xy 342.418406 -265.340825) (xy 342.418406 -265.287527)
			(xy 342.426349 -265.234823) (xy 342.442059 -265.183893) (xy 342.465185 -265.135872) (xy 342.495209 -265.091835)
			(xy 342.531461 -265.052764) (xy 342.573132 -265.019533) (xy 342.61929 -264.992884) (xy 342.668904 -264.973412)
			(xy 342.720866 -264.961552) (xy 342.774016 -264.957569) (xy 342.827166 -264.961552) (xy 342.879128 -264.973412)
			(xy 342.928742 -264.992884) (xy 342.9749 -265.019533) (xy 343.016571 -265.052764) (xy 343.052823 -265.091835)
			(xy 343.082847 -265.135872) (xy 343.105973 -265.183893) (xy 343.121683 -265.234823) (xy 343.129626 -265.287527)
			(xy 343.130124 -265.314176) (xy 343.129626 -265.340825) (xy 343.358206 -265.340825) (xy 343.358206 -265.287527)
			(xy 343.366149 -265.234823) (xy 343.381859 -265.183893) (xy 343.404985 -265.135872) (xy 343.435009 -265.091835)
			(xy 343.471261 -265.052764) (xy 343.512932 -265.019533) (xy 343.55909 -264.992884) (xy 343.608704 -264.973412)
			(xy 343.660666 -264.961552) (xy 343.713816 -264.957569) (xy 343.766966 -264.961552) (xy 343.818928 -264.973412)
			(xy 343.868542 -264.992884) (xy 343.9147 -265.019533) (xy 343.956371 -265.052764) (xy 343.992623 -265.091835)
			(xy 344.022647 -265.135872) (xy 344.045773 -265.183893) (xy 344.061483 -265.234823) (xy 344.069426 -265.287527)
			(xy 344.069924 -265.314176) (xy 344.069426 -265.340825) (xy 344.298006 -265.340825) (xy 344.298006 -265.287527)
			(xy 344.305949 -265.234823) (xy 344.321659 -265.183893) (xy 344.344785 -265.135872) (xy 344.374809 -265.091835)
			(xy 344.411061 -265.052764) (xy 344.452732 -265.019533) (xy 344.49889 -264.992884) (xy 344.548504 -264.973412)
			(xy 344.600466 -264.961552) (xy 344.653616 -264.957569) (xy 344.706766 -264.961552) (xy 344.758728 -264.973412)
			(xy 344.808342 -264.992884) (xy 344.8545 -265.019533) (xy 344.896171 -265.052764) (xy 344.932423 -265.091835)
			(xy 344.962447 -265.135872) (xy 344.985573 -265.183893) (xy 345.001283 -265.234823) (xy 345.009226 -265.287527)
			(xy 345.009724 -265.314176) (xy 345.009226 -265.340825) (xy 345.237806 -265.340825) (xy 345.237806 -265.287527)
			(xy 345.245749 -265.234823) (xy 345.261459 -265.183893) (xy 345.284585 -265.135872) (xy 345.314609 -265.091835)
			(xy 345.350861 -265.052764) (xy 345.392532 -265.019533) (xy 345.43869 -264.992884) (xy 345.488304 -264.973412)
			(xy 345.540266 -264.961552) (xy 345.593416 -264.957569) (xy 345.646566 -264.961552) (xy 345.698528 -264.973412)
			(xy 345.748142 -264.992884) (xy 345.7943 -265.019533) (xy 345.835971 -265.052764) (xy 345.872223 -265.091835)
			(xy 345.902247 -265.135872) (xy 345.925373 -265.183893) (xy 345.941083 -265.234823) (xy 345.949026 -265.287527)
			(xy 345.949524 -265.314176) (xy 345.949026 -265.340825) (xy 346.177352 -265.340825) (xy 346.177352 -265.287527)
			(xy 346.185295 -265.234823) (xy 346.201005 -265.183893) (xy 346.224131 -265.135872) (xy 346.254155 -265.091835)
			(xy 346.290407 -265.052764) (xy 346.332078 -265.019533) (xy 346.378236 -264.992884) (xy 346.42785 -264.973412)
			(xy 346.479812 -264.961552) (xy 346.532962 -264.957569) (xy 346.586112 -264.961552) (xy 346.638074 -264.973412)
			(xy 346.687688 -264.992884) (xy 346.733846 -265.019533) (xy 346.775517 -265.052764) (xy 346.811769 -265.091835)
			(xy 346.841793 -265.135872) (xy 346.864919 -265.183893) (xy 346.880629 -265.234823) (xy 346.888572 -265.287527)
			(xy 346.88907 -265.314176) (xy 346.888572 -265.340825) (xy 347.117406 -265.340825) (xy 347.117406 -265.287527)
			(xy 347.125349 -265.234823) (xy 347.141059 -265.183893) (xy 347.164185 -265.135872) (xy 347.194209 -265.091835)
			(xy 347.230461 -265.052764) (xy 347.272132 -265.019533) (xy 347.31829 -264.992884) (xy 347.367904 -264.973412)
			(xy 347.419866 -264.961552) (xy 347.473016 -264.957569) (xy 347.526166 -264.961552) (xy 347.578128 -264.973412)
			(xy 347.627742 -264.992884) (xy 347.6739 -265.019533) (xy 347.715571 -265.052764) (xy 347.751823 -265.091835)
			(xy 347.781847 -265.135872) (xy 347.804973 -265.183893) (xy 347.820683 -265.234823) (xy 347.828626 -265.287527)
			(xy 347.829124 -265.314176) (xy 347.828626 -265.340825) (xy 348.057206 -265.340825) (xy 348.057206 -265.287527)
			(xy 348.065149 -265.234823) (xy 348.080859 -265.183893) (xy 348.103985 -265.135872) (xy 348.134009 -265.091835)
			(xy 348.170261 -265.052764) (xy 348.211932 -265.019533) (xy 348.25809 -264.992884) (xy 348.307704 -264.973412)
			(xy 348.359666 -264.961552) (xy 348.412816 -264.957569) (xy 348.465966 -264.961552) (xy 348.517928 -264.973412)
			(xy 348.567542 -264.992884) (xy 348.6137 -265.019533) (xy 348.655371 -265.052764) (xy 348.691623 -265.091835)
			(xy 348.721647 -265.135872) (xy 348.744773 -265.183893) (xy 348.760483 -265.234823) (xy 348.768426 -265.287527)
			(xy 348.768924 -265.314176) (xy 348.768426 -265.340825) (xy 350.876606 -265.340825) (xy 350.876606 -265.287527)
			(xy 350.884549 -265.234823) (xy 350.900259 -265.183893) (xy 350.923385 -265.135872) (xy 350.953409 -265.091835)
			(xy 350.989661 -265.052764) (xy 351.031332 -265.019533) (xy 351.07749 -264.992884) (xy 351.127104 -264.973412)
			(xy 351.179066 -264.961552) (xy 351.232216 -264.957569) (xy 351.285366 -264.961552) (xy 351.337328 -264.973412)
			(xy 351.386942 -264.992884) (xy 351.4331 -265.019533) (xy 351.474771 -265.052764) (xy 351.511023 -265.091835)
			(xy 351.541047 -265.135872) (xy 351.564173 -265.183893) (xy 351.579883 -265.234823) (xy 351.587826 -265.287527)
			(xy 351.588324 -265.314176) (xy 351.587826 -265.340825) (xy 351.579883 -265.393529) (xy 351.564173 -265.444459)
			(xy 351.541047 -265.49248) (xy 351.511023 -265.536517) (xy 351.474771 -265.575588) (xy 351.4331 -265.608819)
			(xy 351.386942 -265.635468) (xy 351.337328 -265.65494) (xy 351.285366 -265.6668) (xy 351.232216 -265.670784)
			(xy 351.179066 -265.6668) (xy 351.127104 -265.65494) (xy 351.07749 -265.635468) (xy 351.031332 -265.608819)
			(xy 350.989661 -265.575588) (xy 350.953409 -265.536517) (xy 350.923385 -265.49248) (xy 350.900259 -265.444459)
			(xy 350.884549 -265.393529) (xy 350.876606 -265.340825) (xy 348.768426 -265.340825) (xy 348.760483 -265.393529)
			(xy 348.744773 -265.444459) (xy 348.721647 -265.49248) (xy 348.691623 -265.536517) (xy 348.655371 -265.575588)
			(xy 348.6137 -265.608819) (xy 348.567542 -265.635468) (xy 348.517928 -265.65494) (xy 348.465966 -265.6668)
			(xy 348.412816 -265.670784) (xy 348.359666 -265.6668) (xy 348.307704 -265.65494) (xy 348.25809 -265.635468)
			(xy 348.211932 -265.608819) (xy 348.170261 -265.575588) (xy 348.134009 -265.536517) (xy 348.103985 -265.49248)
			(xy 348.080859 -265.444459) (xy 348.065149 -265.393529) (xy 348.057206 -265.340825) (xy 347.828626 -265.340825)
			(xy 347.820683 -265.393529) (xy 347.804973 -265.444459) (xy 347.781847 -265.49248) (xy 347.751823 -265.536517)
			(xy 347.715571 -265.575588) (xy 347.6739 -265.608819) (xy 347.627742 -265.635468) (xy 347.578128 -265.65494)
			(xy 347.526166 -265.6668) (xy 347.473016 -265.670784) (xy 347.419866 -265.6668) (xy 347.367904 -265.65494)
			(xy 347.31829 -265.635468) (xy 347.272132 -265.608819) (xy 347.230461 -265.575588) (xy 347.194209 -265.536517)
			(xy 347.164185 -265.49248) (xy 347.141059 -265.444459) (xy 347.125349 -265.393529) (xy 347.117406 -265.340825)
			(xy 346.888572 -265.340825) (xy 346.880629 -265.393529) (xy 346.864919 -265.444459) (xy 346.841793 -265.49248)
			(xy 346.811769 -265.536517) (xy 346.775517 -265.575588) (xy 346.733846 -265.608819) (xy 346.687688 -265.635468)
			(xy 346.638074 -265.65494) (xy 346.586112 -265.6668) (xy 346.532962 -265.670784) (xy 346.479812 -265.6668)
			(xy 346.42785 -265.65494) (xy 346.378236 -265.635468) (xy 346.332078 -265.608819) (xy 346.290407 -265.575588)
			(xy 346.254155 -265.536517) (xy 346.224131 -265.49248) (xy 346.201005 -265.444459) (xy 346.185295 -265.393529)
			(xy 346.177352 -265.340825) (xy 345.949026 -265.340825) (xy 345.941083 -265.393529) (xy 345.925373 -265.444459)
			(xy 345.902247 -265.49248) (xy 345.872223 -265.536517) (xy 345.835971 -265.575588) (xy 345.7943 -265.608819)
			(xy 345.748142 -265.635468) (xy 345.698528 -265.65494) (xy 345.646566 -265.6668) (xy 345.593416 -265.670784)
			(xy 345.540266 -265.6668) (xy 345.488304 -265.65494) (xy 345.43869 -265.635468) (xy 345.392532 -265.608819)
			(xy 345.350861 -265.575588) (xy 345.314609 -265.536517) (xy 345.284585 -265.49248) (xy 345.261459 -265.444459)
			(xy 345.245749 -265.393529) (xy 345.237806 -265.340825) (xy 345.009226 -265.340825) (xy 345.001283 -265.393529)
			(xy 344.985573 -265.444459) (xy 344.962447 -265.49248) (xy 344.932423 -265.536517) (xy 344.896171 -265.575588)
			(xy 344.8545 -265.608819) (xy 344.808342 -265.635468) (xy 344.758728 -265.65494) (xy 344.706766 -265.6668)
			(xy 344.653616 -265.670784) (xy 344.600466 -265.6668) (xy 344.548504 -265.65494) (xy 344.49889 -265.635468)
			(xy 344.452732 -265.608819) (xy 344.411061 -265.575588) (xy 344.374809 -265.536517) (xy 344.344785 -265.49248)
			(xy 344.321659 -265.444459) (xy 344.305949 -265.393529) (xy 344.298006 -265.340825) (xy 344.069426 -265.340825)
			(xy 344.061483 -265.393529) (xy 344.045773 -265.444459) (xy 344.022647 -265.49248) (xy 343.992623 -265.536517)
			(xy 343.956371 -265.575588) (xy 343.9147 -265.608819) (xy 343.868542 -265.635468) (xy 343.818928 -265.65494)
			(xy 343.766966 -265.6668) (xy 343.713816 -265.670784) (xy 343.660666 -265.6668) (xy 343.608704 -265.65494)
			(xy 343.55909 -265.635468) (xy 343.512932 -265.608819) (xy 343.471261 -265.575588) (xy 343.435009 -265.536517)
			(xy 343.404985 -265.49248) (xy 343.381859 -265.444459) (xy 343.366149 -265.393529) (xy 343.358206 -265.340825)
			(xy 343.129626 -265.340825) (xy 343.121683 -265.393529) (xy 343.105973 -265.444459) (xy 343.082847 -265.49248)
			(xy 343.052823 -265.536517) (xy 343.016571 -265.575588) (xy 342.9749 -265.608819) (xy 342.928742 -265.635468)
			(xy 342.879128 -265.65494) (xy 342.827166 -265.6668) (xy 342.774016 -265.670784) (xy 342.720866 -265.6668)
			(xy 342.668904 -265.65494) (xy 342.61929 -265.635468) (xy 342.573132 -265.608819) (xy 342.531461 -265.575588)
			(xy 342.495209 -265.536517) (xy 342.465185 -265.49248) (xy 342.442059 -265.444459) (xy 342.426349 -265.393529)
			(xy 342.418406 -265.340825) (xy 342.189826 -265.340825) (xy 342.181883 -265.393529) (xy 342.166173 -265.444459)
			(xy 342.143047 -265.49248) (xy 342.113023 -265.536517) (xy 342.076771 -265.575588) (xy 342.0351 -265.608819)
			(xy 341.988942 -265.635468) (xy 341.939328 -265.65494) (xy 341.887366 -265.6668) (xy 341.834216 -265.670784)
			(xy 341.781066 -265.6668) (xy 341.729104 -265.65494) (xy 341.67949 -265.635468) (xy 341.633332 -265.608819)
			(xy 341.591661 -265.575588) (xy 341.555409 -265.536517) (xy 341.525385 -265.49248) (xy 341.502259 -265.444459)
			(xy 341.486549 -265.393529) (xy 341.478606 -265.340825) (xy 341.250026 -265.340825) (xy 341.242083 -265.393529)
			(xy 341.226373 -265.444459) (xy 341.203247 -265.49248) (xy 341.173223 -265.536517) (xy 341.136971 -265.575588)
			(xy 341.0953 -265.608819) (xy 341.049142 -265.635468) (xy 340.999528 -265.65494) (xy 340.947566 -265.6668)
			(xy 340.894416 -265.670784) (xy 340.841266 -265.6668) (xy 340.789304 -265.65494) (xy 340.73969 -265.635468)
			(xy 340.693532 -265.608819) (xy 340.651861 -265.575588) (xy 340.615609 -265.536517) (xy 340.585585 -265.49248)
			(xy 340.562459 -265.444459) (xy 340.546749 -265.393529) (xy 340.538806 -265.340825) (xy 340.309972 -265.340825)
			(xy 340.302029 -265.393529) (xy 340.286319 -265.444459) (xy 340.263193 -265.49248) (xy 340.233169 -265.536517)
			(xy 340.196917 -265.575588) (xy 340.155246 -265.608819) (xy 340.109088 -265.635468) (xy 340.059474 -265.65494)
			(xy 340.007512 -265.6668) (xy 339.954362 -265.670784) (xy 339.901212 -265.6668) (xy 339.84925 -265.65494)
			(xy 339.799636 -265.635468) (xy 339.753478 -265.608819) (xy 339.711807 -265.575588) (xy 339.675555 -265.536517)
			(xy 339.645531 -265.49248) (xy 339.622405 -265.444459) (xy 339.606695 -265.393529) (xy 339.598752 -265.340825)
			(xy 339.370426 -265.340825) (xy 339.362483 -265.393529) (xy 339.346773 -265.444459) (xy 339.323647 -265.49248)
			(xy 339.293623 -265.536517) (xy 339.257371 -265.575588) (xy 339.2157 -265.608819) (xy 339.169542 -265.635468)
			(xy 339.119928 -265.65494) (xy 339.067966 -265.6668) (xy 339.014816 -265.670784) (xy 338.961666 -265.6668)
			(xy 338.909704 -265.65494) (xy 338.86009 -265.635468) (xy 338.813932 -265.608819) (xy 338.772261 -265.575588)
			(xy 338.736009 -265.536517) (xy 338.705985 -265.49248) (xy 338.682859 -265.444459) (xy 338.667149 -265.393529)
			(xy 338.659206 -265.340825) (xy 338.430372 -265.340825) (xy 338.422429 -265.393529) (xy 338.406719 -265.444459)
			(xy 338.383593 -265.49248) (xy 338.353569 -265.536517) (xy 338.317317 -265.575588) (xy 338.275646 -265.608819)
			(xy 338.229488 -265.635468) (xy 338.179874 -265.65494) (xy 338.127912 -265.6668) (xy 338.074762 -265.670784)
			(xy 338.021612 -265.6668) (xy 337.96965 -265.65494) (xy 337.920036 -265.635468) (xy 337.873878 -265.608819)
			(xy 337.832207 -265.575588) (xy 337.795955 -265.536517) (xy 337.765931 -265.49248) (xy 337.742805 -265.444459)
			(xy 337.727095 -265.393529) (xy 337.719152 -265.340825) (xy 337.490234 -265.340825) (xy 337.484855 -265.382447)
			(xy 337.473204 -265.426705) (xy 337.464908 -265.448034) (xy 337.452208 -265.479276) (xy 337.810094 -265.837162)
			(xy 337.813396 -265.839702) (xy 337.836108 -265.856802) (xy 337.876305 -265.897) (xy 337.893406 -265.919712)
			(xy 337.895946 -265.923014) (xy 338.00288 -266.029948) (xy 338.200746 -266.029948)
		)
		(stroke
			(width 0)
			(type solid)
		)
		(fill yes)
		(layer "In13.Cu")
		(net "PVCCFA_EHV_CPU0")
	)
	(gr_poly
		(pts
			(xy 370.576602 -262.397748) (xy 370.590074 -262.397333) (xy 370.616079 -262.390286) (xy 370.639337 -262.376684)
			(xy 370.658228 -262.357472) (xy 370.671437 -262.333989) (xy 370.678046 -262.307868) (xy 370.677593 -262.280929)
			(xy 370.67011 -262.255045) (xy 370.66347 -262.243316) (xy 370.651214 -262.22235) (xy 370.631867 -262.177805)
			(xy 370.618745 -262.131047) (xy 370.612091 -262.08294) (xy 370.611654 -262.058658) (xy 370.612152 -262.032009)
			(xy 370.620095 -261.979305) (xy 370.635805 -261.928375) (xy 370.658931 -261.880354) (xy 370.688955 -261.836317)
			(xy 370.725207 -261.797246) (xy 370.766878 -261.764015) (xy 370.813036 -261.737366) (xy 370.86265 -261.717894)
			(xy 370.914612 -261.706034) (xy 370.967762 -261.702051) (xy 371.020912 -261.706034) (xy 371.072874 -261.717894)
			(xy 371.122488 -261.737366) (xy 371.168646 -261.764015) (xy 371.210317 -261.797246) (xy 371.246569 -261.836317)
			(xy 371.276593 -261.880354) (xy 371.299719 -261.928375) (xy 371.315429 -261.979305) (xy 371.323372 -262.032009)
			(xy 371.32387 -262.058658) (xy 371.323445 -262.082942) (xy 371.316813 -262.131055) (xy 371.303694 -262.177818)
			(xy 371.284331 -262.22236) (xy 371.272054 -262.243316) (xy 371.265407 -262.255039) (xy 371.257916 -262.280915)
			(xy 371.257458 -262.307851) (xy 371.264067 -262.333967) (xy 371.277281 -262.357442) (xy 371.296179 -262.376641)
			(xy 371.319443 -262.390224) (xy 371.345452 -262.397244) (xy 371.358922 -262.397748) (xy 371.516656 -262.397748)
			(xy 371.530122 -262.397327) (xy 371.556115 -262.390271) (xy 371.57936 -262.376666) (xy 371.598239 -262.357458)
			(xy 371.61144 -262.333982) (xy 371.618045 -262.307871) (xy 371.617595 -262.280941) (xy 371.61012 -262.255066)
			(xy 371.603524 -262.243316) (xy 371.591269 -262.222349) (xy 371.571925 -262.177804) (xy 371.558805 -262.131046)
			(xy 371.552152 -262.08294) (xy 371.551708 -262.058658) (xy 371.552206 -262.032009) (xy 371.560149 -261.979305)
			(xy 371.575859 -261.928375) (xy 371.598985 -261.880354) (xy 371.629009 -261.836317) (xy 371.665261 -261.797246)
			(xy 371.706932 -261.764015) (xy 371.75309 -261.737366) (xy 371.802704 -261.717894) (xy 371.854666 -261.706034)
			(xy 371.907816 -261.702051) (xy 371.960966 -261.706034) (xy 372.012928 -261.717894) (xy 372.062542 -261.737366)
			(xy 372.1087 -261.764015) (xy 372.150371 -261.797246) (xy 372.186623 -261.836317) (xy 372.216647 -261.880354)
			(xy 372.239773 -261.928375) (xy 372.255483 -261.979305) (xy 372.263426 -262.032009) (xy 372.263924 -262.058658)
			(xy 372.2635 -262.082942) (xy 372.256868 -262.131056) (xy 372.24375 -262.17782) (xy 372.22439 -262.222363)
			(xy 372.212108 -262.243316) (xy 372.205463 -262.255041) (xy 372.197975 -262.28092) (xy 372.197519 -262.307857)
			(xy 372.204128 -262.333975) (xy 372.21734 -262.357454) (xy 372.236236 -262.376657) (xy 372.259498 -262.390247)
			(xy 372.285505 -262.397277) (xy 372.298976 -262.397748) (xy 372.456456 -262.397748) (xy 372.469922 -262.397327)
			(xy 372.495915 -262.390271) (xy 372.51916 -262.376666) (xy 372.538039 -262.357458) (xy 372.55124 -262.333982)
			(xy 372.557845 -262.307871) (xy 372.557395 -262.280941) (xy 372.54992 -262.255066) (xy 372.543324 -262.243316)
			(xy 372.531069 -262.222349) (xy 372.511725 -262.177804) (xy 372.498605 -262.131046) (xy 372.491952 -262.08294)
			(xy 372.491508 -262.058658) (xy 372.492006 -262.032009) (xy 372.499949 -261.979305) (xy 372.515659 -261.928375)
			(xy 372.538785 -261.880354) (xy 372.568809 -261.836317) (xy 372.605061 -261.797246) (xy 372.646732 -261.764015)
			(xy 372.69289 -261.737366) (xy 372.742504 -261.717894) (xy 372.794466 -261.706034) (xy 372.847616 -261.702051)
			(xy 372.900766 -261.706034) (xy 372.952728 -261.717894) (xy 373.002342 -261.737366) (xy 373.0485 -261.764015)
			(xy 373.090171 -261.797246) (xy 373.126423 -261.836317) (xy 373.156447 -261.880354) (xy 373.179573 -261.928375)
			(xy 373.195283 -261.979305) (xy 373.203226 -262.032009) (xy 373.203724 -262.058658) (xy 373.2033 -262.082942)
			(xy 373.196668 -262.131056) (xy 373.18355 -262.17782) (xy 373.16419 -262.222363) (xy 373.151908 -262.243316)
			(xy 373.145263 -262.255041) (xy 373.137775 -262.28092) (xy 373.137319 -262.307857) (xy 373.143928 -262.333975)
			(xy 373.15714 -262.357454) (xy 373.176036 -262.376657) (xy 373.199298 -262.390247) (xy 373.225305 -262.397277)
			(xy 373.238776 -262.397748) (xy 373.396002 -262.397748) (xy 373.409474 -262.397333) (xy 373.435479 -262.390286)
			(xy 373.458737 -262.376684) (xy 373.477628 -262.357472) (xy 373.490837 -262.333989) (xy 373.497446 -262.307868)
			(xy 373.496993 -262.280929) (xy 373.48951 -262.255045) (xy 373.48287 -262.243316) (xy 373.470614 -262.22235)
			(xy 373.451267 -262.177805) (xy 373.438145 -262.131047) (xy 373.431491 -262.08294) (xy 373.431054 -262.058658)
			(xy 373.431552 -262.032009) (xy 373.439495 -261.979305) (xy 373.455205 -261.928375) (xy 373.478331 -261.880354)
			(xy 373.508355 -261.836317) (xy 373.544607 -261.797246) (xy 373.586278 -261.764015) (xy 373.632436 -261.737366)
			(xy 373.68205 -261.717894) (xy 373.734012 -261.706034) (xy 373.787162 -261.702051) (xy 373.840312 -261.706034)
			(xy 373.892274 -261.717894) (xy 373.941888 -261.737366) (xy 373.988046 -261.764015) (xy 374.029717 -261.797246)
			(xy 374.065969 -261.836317) (xy 374.095993 -261.880354) (xy 374.119119 -261.928375) (xy 374.134829 -261.979305)
			(xy 374.142772 -262.032009) (xy 374.14327 -262.058658) (xy 374.142845 -262.082942) (xy 374.136213 -262.131055)
			(xy 374.123094 -262.177818) (xy 374.103731 -262.22236) (xy 374.091454 -262.243316) (xy 374.084807 -262.255039)
			(xy 374.077316 -262.280915) (xy 374.076858 -262.307851) (xy 374.083467 -262.333967) (xy 374.096681 -262.357442)
			(xy 374.115579 -262.376641) (xy 374.138843 -262.390224) (xy 374.164852 -262.397244) (xy 374.178322 -262.397748)
			(xy 374.336056 -262.397748) (xy 374.349522 -262.397327) (xy 374.375515 -262.390271) (xy 374.39876 -262.376666)
			(xy 374.417639 -262.357458) (xy 374.43084 -262.333982) (xy 374.437445 -262.307871) (xy 374.436995 -262.280941)
			(xy 374.42952 -262.255066) (xy 374.422924 -262.243316) (xy 374.410669 -262.222349) (xy 374.391325 -262.177804)
			(xy 374.378205 -262.131046) (xy 374.371552 -262.08294) (xy 374.371108 -262.058658) (xy 374.371606 -262.032009)
			(xy 374.379549 -261.979305) (xy 374.395259 -261.928375) (xy 374.418385 -261.880354) (xy 374.448409 -261.836317)
			(xy 374.484661 -261.797246) (xy 374.526332 -261.764015) (xy 374.57249 -261.737366) (xy 374.622104 -261.717894)
			(xy 374.674066 -261.706034) (xy 374.727216 -261.702051) (xy 374.780366 -261.706034) (xy 374.832328 -261.717894)
			(xy 374.881942 -261.737366) (xy 374.9281 -261.764015) (xy 374.969771 -261.797246) (xy 375.006023 -261.836317)
			(xy 375.036047 -261.880354) (xy 375.059173 -261.928375) (xy 375.074883 -261.979305) (xy 375.082826 -262.032009)
			(xy 375.083324 -262.058658) (xy 375.0829 -262.082942) (xy 375.076268 -262.131056) (xy 375.06315 -262.17782)
			(xy 375.04379 -262.222363) (xy 375.031508 -262.243316) (xy 375.024863 -262.255041) (xy 375.017375 -262.28092)
			(xy 375.016919 -262.307857) (xy 375.023528 -262.333975) (xy 375.03674 -262.357454) (xy 375.055636 -262.376657)
			(xy 375.078898 -262.390247) (xy 375.104905 -262.397277) (xy 375.118376 -262.397748) (xy 375.275856 -262.397748)
			(xy 375.289322 -262.397327) (xy 375.315315 -262.390271) (xy 375.33856 -262.376666) (xy 375.357439 -262.357458)
			(xy 375.37064 -262.333982) (xy 375.377245 -262.307871) (xy 375.376795 -262.280941) (xy 375.36932 -262.255066)
			(xy 375.362724 -262.243316) (xy 375.350469 -262.222349) (xy 375.331125 -262.177804) (xy 375.318005 -262.131046)
			(xy 375.311352 -262.08294) (xy 375.310908 -262.058658) (xy 375.311406 -262.032009) (xy 375.319349 -261.979305)
			(xy 375.335059 -261.928375) (xy 375.358185 -261.880354) (xy 375.388209 -261.836317) (xy 375.424461 -261.797246)
			(xy 375.466132 -261.764015) (xy 375.51229 -261.737366) (xy 375.561904 -261.717894) (xy 375.613866 -261.706034)
			(xy 375.667016 -261.702051) (xy 375.720166 -261.706034) (xy 375.772128 -261.717894) (xy 375.821742 -261.737366)
			(xy 375.8679 -261.764015) (xy 375.909571 -261.797246) (xy 375.945823 -261.836317) (xy 375.975847 -261.880354)
			(xy 375.998973 -261.928375) (xy 376.014683 -261.979305) (xy 376.022626 -262.032009) (xy 376.023124 -262.058658)
			(xy 376.0227 -262.082942) (xy 376.016068 -262.131056) (xy 376.00295 -262.17782) (xy 375.98359 -262.222363)
			(xy 375.971308 -262.243316) (xy 375.964663 -262.255041) (xy 375.957175 -262.28092) (xy 375.956719 -262.307857)
			(xy 375.963328 -262.333975) (xy 375.97654 -262.357454) (xy 375.995436 -262.376657) (xy 376.018698 -262.390247)
			(xy 376.044705 -262.397277) (xy 376.058176 -262.397748) (xy 376.215656 -262.397748) (xy 376.229122 -262.397327)
			(xy 376.255115 -262.390271) (xy 376.27836 -262.376666) (xy 376.297239 -262.357458) (xy 376.31044 -262.333982)
			(xy 376.317045 -262.307871) (xy 376.316595 -262.280941) (xy 376.30912 -262.255066) (xy 376.302524 -262.243316)
			(xy 376.290269 -262.222349) (xy 376.270925 -262.177804) (xy 376.257805 -262.131046) (xy 376.251152 -262.08294)
			(xy 376.250708 -262.058658) (xy 376.251206 -262.032009) (xy 376.259149 -261.979305) (xy 376.274859 -261.928375)
			(xy 376.297985 -261.880354) (xy 376.328009 -261.836317) (xy 376.364261 -261.797246) (xy 376.405932 -261.764015)
			(xy 376.45209 -261.737366) (xy 376.501704 -261.717894) (xy 376.553666 -261.706034) (xy 376.606816 -261.702051)
			(xy 376.659966 -261.706034) (xy 376.711928 -261.717894) (xy 376.761542 -261.737366) (xy 376.8077 -261.764015)
			(xy 376.849371 -261.797246) (xy 376.885623 -261.836317) (xy 376.915647 -261.880354) (xy 376.938773 -261.928375)
			(xy 376.954483 -261.979305) (xy 376.962426 -262.032009) (xy 376.962924 -262.058658) (xy 376.9625 -262.082942)
			(xy 376.955868 -262.131056) (xy 376.94275 -262.17782) (xy 376.92339 -262.222363) (xy 376.911108 -262.243316)
			(xy 376.904463 -262.255041) (xy 376.896975 -262.28092) (xy 376.896519 -262.307857) (xy 376.903128 -262.333975)
			(xy 376.91634 -262.357454) (xy 376.935236 -262.376657) (xy 376.958498 -262.390247) (xy 376.984505 -262.397277)
			(xy 376.997976 -262.397748) (xy 377.155456 -262.397748) (xy 377.168922 -262.397327) (xy 377.194915 -262.390271)
			(xy 377.21816 -262.376666) (xy 377.237039 -262.357458) (xy 377.25024 -262.333982) (xy 377.256845 -262.307871)
			(xy 377.256395 -262.280941) (xy 377.24892 -262.255066) (xy 377.242324 -262.243316) (xy 377.230069 -262.222349)
			(xy 377.210725 -262.177804) (xy 377.197605 -262.131046) (xy 377.190952 -262.08294) (xy 377.190508 -262.058658)
			(xy 377.191006 -262.032009) (xy 377.198949 -261.979305) (xy 377.214659 -261.928375) (xy 377.237785 -261.880354)
			(xy 377.267809 -261.836317) (xy 377.304061 -261.797246) (xy 377.345732 -261.764015) (xy 377.39189 -261.737366)
			(xy 377.441504 -261.717894) (xy 377.493466 -261.706034) (xy 377.546616 -261.702051) (xy 377.599766 -261.706034)
			(xy 377.651728 -261.717894) (xy 377.701342 -261.737366) (xy 377.7475 -261.764015) (xy 377.789171 -261.797246)
			(xy 377.825423 -261.836317) (xy 377.855447 -261.880354) (xy 377.878573 -261.928375) (xy 377.894283 -261.979305)
			(xy 377.902226 -262.032009) (xy 377.902724 -262.058658) (xy 377.9023 -262.082942) (xy 377.895668 -262.131056)
			(xy 377.88255 -262.17782) (xy 377.86319 -262.222363) (xy 377.850908 -262.243316) (xy 377.844263 -262.255041)
			(xy 377.836775 -262.28092) (xy 377.836319 -262.307857) (xy 377.842928 -262.333975) (xy 377.85614 -262.357454)
			(xy 377.875036 -262.376657) (xy 377.898298 -262.390247) (xy 377.924305 -262.397277) (xy 377.937776 -262.397748)
			(xy 378.095256 -262.397748) (xy 378.108722 -262.397327) (xy 378.134715 -262.390271) (xy 378.15796 -262.376666)
			(xy 378.176839 -262.357458) (xy 378.19004 -262.333982) (xy 378.196645 -262.307871) (xy 378.196195 -262.280941)
			(xy 378.18872 -262.255066) (xy 378.182124 -262.243316) (xy 378.169869 -262.222349) (xy 378.150525 -262.177804)
			(xy 378.137405 -262.131046) (xy 378.130752 -262.08294) (xy 378.130308 -262.058658) (xy 378.130806 -262.032009)
			(xy 378.138749 -261.979305) (xy 378.154459 -261.928375) (xy 378.177585 -261.880354) (xy 378.207609 -261.836317)
			(xy 378.243861 -261.797246) (xy 378.285532 -261.764015) (xy 378.33169 -261.737366) (xy 378.381304 -261.717894)
			(xy 378.433266 -261.706034) (xy 378.486416 -261.702051) (xy 378.539566 -261.706034) (xy 378.591528 -261.717894)
			(xy 378.641142 -261.737366) (xy 378.6873 -261.764015) (xy 378.728971 -261.797246) (xy 378.765223 -261.836317)
			(xy 378.795247 -261.880354) (xy 378.818373 -261.928375) (xy 378.834083 -261.979305) (xy 378.842026 -262.032009)
			(xy 378.842524 -262.058658) (xy 378.8421 -262.082942) (xy 378.835468 -262.131056) (xy 378.82235 -262.17782)
			(xy 378.80299 -262.222363) (xy 378.790708 -262.243316) (xy 378.784063 -262.255041) (xy 378.776575 -262.28092)
			(xy 378.776119 -262.307857) (xy 378.782728 -262.333975) (xy 378.79594 -262.357454) (xy 378.814836 -262.376657)
			(xy 378.838098 -262.390247) (xy 378.864105 -262.397277) (xy 378.877576 -262.397748) (xy 379.035056 -262.397748)
			(xy 379.048522 -262.397327) (xy 379.074515 -262.390271) (xy 379.09776 -262.376666) (xy 379.116639 -262.357458)
			(xy 379.12984 -262.333982) (xy 379.136445 -262.307871) (xy 379.135995 -262.280941) (xy 379.12852 -262.255066)
			(xy 379.121924 -262.243316) (xy 379.109669 -262.222349) (xy 379.090325 -262.177804) (xy 379.077205 -262.131046)
			(xy 379.070552 -262.08294) (xy 379.070108 -262.058658) (xy 379.07066 -262.030678) (xy 379.07942 -261.975406)
			(xy 379.096719 -261.922186) (xy 379.122129 -261.872327) (xy 379.155027 -261.827056) (xy 379.1946 -261.787489)
			(xy 379.239876 -261.754599) (xy 379.28974 -261.729197) (xy 379.342963 -261.711907) (xy 379.398235 -261.703156)
			(xy 379.426216 -261.70255) (xy 379.453139 -261.703045) (xy 379.50637 -261.711155) (xy 379.557774 -261.727189)
			(xy 379.606177 -261.75078) (xy 379.650476 -261.78139) (xy 379.68966 -261.818322) (xy 379.722837 -261.860732)
			(xy 379.749249 -261.907655) (xy 379.768295 -261.95802) (xy 379.77445 -261.984236) (xy 379.777752 -261.997472)
			(xy 379.790353 -262.021655) (xy 379.808904 -262.041641) (xy 379.832083 -262.056004) (xy 379.858238 -262.063721)
			(xy 379.885502 -262.064242) (xy 379.911931 -262.057528) (xy 379.935641 -262.044059) (xy 379.945646 -262.034782)
			(xy 380.02464 -261.955788) (xy 380.02845 -261.944612) (xy 380.037681 -261.918942) (xy 380.062831 -261.870539)
			(xy 380.09507 -261.826537) (xy 380.133641 -261.787966) (xy 380.177643 -261.755729) (xy 380.226047 -261.730579)
			(xy 380.251716 -261.721346) (xy 380.262892 -261.717536) (xy 380.537466 -261.442962) (xy 380.520194 -261.409942)
			(xy 380.507428 -261.38431) (xy 380.48933 -261.329987) (xy 380.480135 -261.273471) (xy 380.479554 -261.244842)
			(xy 380.480071 -261.216853) (xy 380.488821 -261.161564) (xy 380.506113 -261.108325) (xy 380.53152 -261.058446)
			(xy 380.564418 -261.013156) (xy 380.603995 -260.97357) (xy 380.649278 -260.940662) (xy 380.699151 -260.915244)
			(xy 380.752386 -260.89794) (xy 380.807673 -260.889177) (xy 380.835662 -260.888734) (xy 380.864294 -260.889299)
			(xy 380.92082 -260.898462) (xy 380.975145 -260.916574) (xy 381.000762 -260.929374) (xy 381.033782 -260.946646)
			(xy 381.15748 -260.822948) (xy 381.15748 -260.754622) (xy 381.133029 -260.742879) (xy 381.087697 -260.713097)
			(xy 381.047405 -260.676786) (xy 381.013086 -260.634783) (xy 380.985534 -260.588062) (xy 380.965386 -260.537703)
			(xy 380.953109 -260.484871) (xy 380.948986 -260.430788) (xy 380.953112 -260.376706) (xy 380.965393 -260.323874)
			(xy 380.985544 -260.273517) (xy 381.013099 -260.226797) (xy 381.047421 -260.184797) (xy 381.087715 -260.148488)
			(xy 381.13305 -260.11871) (xy 381.15748 -260.106922) (xy 381.15748 -260.018276) (xy 381.156934 -260.003219)
			(xy 381.148146 -259.974414) (xy 381.131341 -259.949424) (xy 381.10798 -259.930419) (xy 381.080093 -259.919053)
			(xy 381.050103 -259.916311) (xy 381.020616 -259.922433) (xy 381.007112 -259.929122) (xy 380.980672 -259.942948)
			(xy 380.924321 -259.962545) (xy 380.865493 -259.972479) (xy 380.835662 -259.973064) (xy 380.809018 -259.972563)
			(xy 380.756325 -259.964616) (xy 380.705406 -259.948905) (xy 380.657397 -259.92578) (xy 380.61337 -259.895759)
			(xy 380.574308 -259.859511) (xy 380.541086 -259.817847) (xy 380.514443 -259.771697) (xy 380.494976 -259.722092)
			(xy 380.483119 -259.670139) (xy 380.479137 -259.617) (xy 380.483119 -259.563861) (xy 380.494976 -259.511908)
			(xy 380.514443 -259.462303) (xy 380.541086 -259.416153) (xy 380.574309 -259.374489) (xy 380.61337 -259.338241)
			(xy 380.657397 -259.30822) (xy 380.705406 -259.285095) (xy 380.756325 -259.269384) (xy 380.809018 -259.261437)
			(xy 380.835662 -259.260848) (xy 380.86549 -259.261456) (xy 380.924314 -259.271395) (xy 380.980663 -259.290986)
			(xy 381.007112 -259.30479) (xy 381.020587 -259.31155) (xy 381.050089 -259.317682) (xy 381.080095 -259.314941)
			(xy 381.107997 -259.303564) (xy 381.131365 -259.284541) (xy 381.148167 -259.259529) (xy 381.15694 -259.230702)
			(xy 381.15748 -259.215636) (xy 381.15748 -259.12699) (xy 381.133051 -259.115223) (xy 381.087765 -259.085406)
			(xy 381.047519 -259.049073) (xy 381.013241 -259.007062) (xy 380.985723 -258.960344) (xy 380.9656 -258.909996)
			(xy 380.953337 -258.85718) (xy 380.949215 -258.803117) (xy 380.953331 -258.749053) (xy 380.96559 -258.696236)
			(xy 380.985709 -258.645886) (xy 381.013222 -258.599165) (xy 381.047496 -258.557151) (xy 381.087739 -258.520814)
			(xy 381.133022 -258.490993) (xy 381.15748 -258.47929) (xy 381.15748 -258.39039) (xy 381.156936 -258.375331)
			(xy 381.14815 -258.346523) (xy 381.131346 -258.321529) (xy 381.107983 -258.302521) (xy 381.080093 -258.291153)
			(xy 381.0501 -258.288411) (xy 381.020611 -258.294535) (xy 381.007112 -258.301236) (xy 380.980672 -258.315061)
			(xy 380.924321 -258.334657) (xy 380.865493 -258.344591) (xy 380.835662 -258.345178) (xy 380.809017 -258.344677)
			(xy 380.756322 -258.33673) (xy 380.705401 -258.321018) (xy 380.65739 -258.297892) (xy 380.613361 -258.26787)
			(xy 380.574298 -258.231621) (xy 380.541074 -258.189955) (xy 380.514431 -258.143803) (xy 380.494963 -258.094196)
			(xy 380.483105 -258.042241) (xy 380.479123 -257.9891) (xy 380.483105 -257.935959) (xy 380.494963 -257.884004)
			(xy 380.514431 -257.834397) (xy 380.541074 -257.788245) (xy 380.574298 -257.746579) (xy 380.613361 -257.71033)
			(xy 380.65739 -257.680308) (xy 380.705401 -257.657182) (xy 380.756322 -257.64147) (xy 380.809017 -257.633523)
			(xy 380.835662 -257.632962) (xy 380.86549 -257.63357) (xy 380.924314 -257.64351) (xy 380.980662 -257.663101)
			(xy 381.007112 -257.676904) (xy 381.020588 -257.683663) (xy 381.05009 -257.689795) (xy 381.080098 -257.687053)
			(xy 381.108 -257.675676) (xy 381.13137 -257.656655) (xy 381.148174 -257.631643) (xy 381.15695 -257.602817)
			(xy 381.15748 -257.58775) (xy 381.15748 -257.499104) (xy 381.133058 -257.487337) (xy 381.087785 -257.457522)
			(xy 381.047551 -257.421193) (xy 381.013285 -257.379188) (xy 380.985778 -257.332477) (xy 380.965665 -257.282138)
			(xy 380.953409 -257.229333) (xy 380.949294 -257.175281) (xy 380.953415 -257.121229) (xy 380.965676 -257.068425)
			(xy 380.985795 -257.018089) (xy 381.013307 -256.971381) (xy 381.047578 -256.929379) (xy 381.087816 -256.893055)
			(xy 381.133092 -256.863244) (xy 381.15748 -256.851404) (xy 381.15748 -256.762758) (xy 381.156932 -256.747703)
			(xy 381.148141 -256.718903) (xy 381.131336 -256.693918) (xy 381.107976 -256.674917) (xy 381.080092 -256.663552)
			(xy 381.050106 -256.660811) (xy 381.020623 -256.666931) (xy 381.007112 -256.673604) (xy 380.980672 -256.68743)
			(xy 380.924321 -256.707028) (xy 380.865493 -256.716963) (xy 380.835662 -256.717546) (xy 380.809012 -256.717046)
			(xy 380.756307 -256.709096) (xy 380.705376 -256.693381) (xy 380.657355 -256.670251) (xy 380.613318 -256.640223)
			(xy 380.574248 -256.603967) (xy 380.541017 -256.562294) (xy 380.514369 -256.516133) (xy 380.494897 -256.466516)
			(xy 380.483037 -256.414552) (xy 380.479054 -256.3614) (xy 380.483037 -256.308248) (xy 380.494897 -256.256284)
			(xy 380.514369 -256.206667) (xy 380.541017 -256.160506) (xy 380.574248 -256.118833) (xy 380.613318 -256.082577)
			(xy 380.657355 -256.052549) (xy 380.705376 -256.029419) (xy 380.756307 -256.013704) (xy 380.809012 -256.005754)
			(xy 380.835662 -256.00533) (xy 380.865491 -256.005938) (xy 380.924314 -256.015877) (xy 380.980663 -256.035466)
			(xy 381.007112 -256.049272) (xy 381.020591 -256.056028) (xy 381.050098 -256.062155) (xy 381.080109 -256.059412)
			(xy 381.108015 -256.048037) (xy 381.131393 -256.029019) (xy 381.148208 -256.004011) (xy 381.157001 -255.975186)
			(xy 381.15748 -255.960118) (xy 381.15748 -255.871472) (xy 381.133025 -255.859728) (xy 381.087685 -255.829946)
			(xy 381.047386 -255.793632) (xy 381.013061 -255.751627) (xy 380.985502 -255.704901) (xy 380.965349 -255.654537)
			(xy 380.953067 -255.601699) (xy 380.94894 -255.547609) (xy 380.953064 -255.493519) (xy 380.965344 -255.440681)
			(xy 380.985494 -255.390315) (xy 381.01305 -255.343588) (xy 381.047374 -255.301581) (xy 381.087671 -255.265265)
			(xy 381.133009 -255.23548) (xy 381.15748 -255.223772) (xy 381.15748 -255.134872) (xy 381.156934 -255.119815)
			(xy 381.148145 -255.091012) (xy 381.13134 -255.066022) (xy 381.107979 -255.047019) (xy 381.080092 -255.035653)
			(xy 381.050103 -255.032911) (xy 381.020618 -255.039033) (xy 381.007112 -255.045718) (xy 380.980714 -255.059535)
			(xy 380.924449 -255.079125) (xy 380.865705 -255.08906) (xy 380.835916 -255.08966) (xy 380.809268 -255.089188)
			(xy 380.756566 -255.081247) (xy 380.705637 -255.065539) (xy 380.657617 -255.042416) (xy 380.613581 -255.012394)
			(xy 380.574511 -254.976144) (xy 380.54128 -254.934476) (xy 380.514631 -254.88832) (xy 380.495159 -254.838708)
			(xy 380.483299 -254.786748) (xy 380.479316 -254.7336) (xy 380.483299 -254.680452) (xy 380.495159 -254.628492)
			(xy 380.514631 -254.57888) (xy 380.54128 -254.532724) (xy 380.574511 -254.491056) (xy 380.613581 -254.454806)
			(xy 380.657617 -254.424784) (xy 380.705637 -254.401661) (xy 380.756566 -254.385953) (xy 380.809268 -254.378012)
			(xy 380.835916 -254.377444) (xy 380.865703 -254.378069) (xy 380.92444 -254.388017) (xy 380.98071 -254.407583)
			(xy 381.007112 -254.421386) (xy 381.020587 -254.428146) (xy 381.050088 -254.434279) (xy 381.080095 -254.431537)
			(xy 381.107996 -254.42016) (xy 381.131364 -254.401138) (xy 381.148165 -254.376125) (xy 381.156937 -254.347298)
			(xy 381.15748 -254.332232) (xy 381.15748 -254.243586) (xy 381.133052 -254.231819) (xy 381.087766 -254.202002)
			(xy 381.047521 -254.165669) (xy 381.013243 -254.123659) (xy 380.985726 -254.076941) (xy 380.965603 -254.026593)
			(xy 380.95334 -253.973778) (xy 380.949219 -253.919715) (xy 380.953335 -253.865652) (xy 380.965594 -253.812836)
			(xy 380.985713 -253.762486) (xy 381.013226 -253.715766) (xy 381.0475 -253.673753) (xy 381.087743 -253.637416)
			(xy 381.133025 -253.607595) (xy 381.15748 -253.595886) (xy 381.15748 -248.309384) (xy 381.156941 -248.294272)
			(xy 381.148113 -248.265368) (xy 381.131207 -248.240316) (xy 381.107705 -248.221315) (xy 381.079668 -248.210029)
			(xy 381.049556 -248.207451) (xy 381.020009 -248.213804) (xy 380.993618 -248.228533) (xy 380.982728 -248.239026)
			(xy 380.962418 -248.259297) (xy 380.916517 -248.293728) (xy 380.865694 -248.320362) (xy 380.811261 -248.338511)
			(xy 380.754623 -248.347707) (xy 380.725934 -248.348246) (xy 380.699278 -248.347775) (xy 380.646562 -248.339834)
			(xy 380.595618 -248.324124) (xy 380.547585 -248.300997) (xy 380.503535 -248.270968) (xy 380.464453 -248.234709)
			(xy 380.431213 -248.19303) (xy 380.404556 -248.146862) (xy 380.385078 -248.097237) (xy 380.373214 -248.045262)
			(xy 380.36923 -247.9921) (xy 380.373214 -247.938938) (xy 380.385078 -247.886963) (xy 380.404556 -247.837338)
			(xy 380.431213 -247.79117) (xy 380.464453 -247.749491) (xy 380.503535 -247.713232) (xy 380.547585 -247.683203)
			(xy 380.595618 -247.660076) (xy 380.646562 -247.644366) (xy 380.699278 -247.636425) (xy 380.725934 -247.63603)
			(xy 380.754629 -247.636548) (xy 380.811283 -247.645704) (xy 380.865732 -247.663837) (xy 380.916563 -247.690477)
			(xy 380.962458 -247.724933) (xy 380.982728 -247.74525) (xy 380.993598 -247.755748) (xy 381.019994 -247.770429)
			(xy 381.04953 -247.776749) (xy 381.079623 -247.774155) (xy 381.107641 -247.762874) (xy 381.131136 -247.743892)
			(xy 381.148052 -247.718869) (xy 381.156912 -247.689994) (xy 381.15748 -247.674892) (xy 381.15748 -247.534684)
			(xy 381.117856 -247.525794) (xy 381.091872 -247.519489) (xy 381.042025 -247.500145) (xy 380.995632 -247.473566)
			(xy 380.953733 -247.44035) (xy 380.917272 -247.401242) (xy 380.887068 -247.357123) (xy 380.863799 -247.308983)
			(xy 380.84799 -247.257906) (xy 380.839995 -247.205039) (xy 380.839995 -247.151571) (xy 380.847988 -247.098704)
			(xy 380.863796 -247.047626) (xy 380.887063 -246.999486) (xy 380.917266 -246.955365) (xy 380.953726 -246.916257)
			(xy 380.995624 -246.883039) (xy 381.042017 -246.856459) (xy 381.091862 -246.837114) (xy 381.117856 -246.83085)
			(xy 381.15748 -246.82196) (xy 381.15748 -246.681498) (xy 381.156928 -246.666364) (xy 381.148066 -246.637422)
			(xy 381.13112 -246.612342) (xy 381.107574 -246.593322) (xy 381.079492 -246.582028) (xy 381.049333 -246.57945)
			(xy 381.019742 -246.585814) (xy 380.993309 -246.600562) (xy 380.982474 -246.61114) (xy 380.962207 -246.631473)
			(xy 380.916327 -246.66598) (xy 380.865502 -246.69267) (xy 380.811049 -246.710851) (xy 380.754384 -246.720052)
			(xy 380.72568 -246.720614) (xy 380.699031 -246.720115) (xy 380.646329 -246.712169) (xy 380.5954 -246.696457)
			(xy 380.547382 -246.67333) (xy 380.503346 -246.643305) (xy 380.464277 -246.607052) (xy 380.431048 -246.565381)
			(xy 380.4044 -246.519224) (xy 380.384929 -246.46961) (xy 380.373069 -246.417649) (xy 380.369086 -246.3645)
			(xy 380.373069 -246.311351) (xy 380.384929 -246.25939) (xy 380.4044 -246.209776) (xy 380.431048 -246.163619)
			(xy 380.464277 -246.121948) (xy 380.503346 -246.085695) (xy 380.547382 -246.05567) (xy 380.5954 -246.032543)
			(xy 380.646329 -246.016831) (xy 380.699031 -246.008885) (xy 380.72568 -246.008398) (xy 380.754385 -246.008944)
			(xy 380.811052 -246.018153) (xy 380.865506 -246.036335) (xy 380.916337 -246.063021) (xy 380.962228 -246.097517)
			(xy 380.982474 -246.117872) (xy 380.993343 -246.128428) (xy 381.019772 -246.14321) (xy 381.049372 -246.1496)
			(xy 381.079546 -246.147035) (xy 381.107643 -246.135743) (xy 381.131199 -246.116713) (xy 381.148145 -246.091616)
			(xy 381.156993 -246.062655) (xy 381.15748 -246.047514) (xy 381.15748 -245.907052) (xy 381.117856 -245.898162)
			(xy 381.091885 -245.891845) (xy 381.042067 -245.872484) (xy 380.995702 -245.845894) (xy 380.953832 -245.812673)
			(xy 380.917397 -245.773568) (xy 380.887215 -245.729457) (xy 380.863965 -245.681331) (xy 380.848169 -245.63027)
			(xy 380.840182 -245.577422) (xy 380.840182 -245.523974) (xy 380.84817 -245.471126) (xy 380.863967 -245.420065)
			(xy 380.887218 -245.371939) (xy 380.9174 -245.327828) (xy 380.953835 -245.288724) (xy 380.995706 -245.255504)
			(xy 381.042071 -245.228915) (xy 381.091889 -245.209553) (xy 381.117856 -245.203218) (xy 381.15748 -245.194328)
			(xy 381.15748 -245.053612) (xy 381.156917 -245.038487) (xy 381.148041 -245.009569) (xy 381.131093 -244.984512)
			(xy 381.107556 -244.965511) (xy 381.079489 -244.954227) (xy 381.049349 -244.951649) (xy 381.019774 -244.958002)
			(xy 380.993351 -244.97273) (xy 380.982474 -244.983254) (xy 380.962207 -245.003587) (xy 380.916327 -245.038092)
			(xy 380.865501 -245.064781) (xy 380.811049 -245.082961) (xy 380.754384 -245.092161) (xy 380.72568 -245.092728)
			(xy 380.69903 -245.092229) (xy 380.646326 -245.084282) (xy 380.595395 -245.06857) (xy 380.547375 -245.045442)
			(xy 380.503337 -245.015415) (xy 380.464267 -244.979161) (xy 380.431036 -244.937489) (xy 380.404387 -244.89133)
			(xy 380.384915 -244.841714) (xy 380.373055 -244.789751) (xy 380.369072 -244.7366) (xy 380.373055 -244.683449)
			(xy 380.384915 -244.631486) (xy 380.404387 -244.58187) (xy 380.431036 -244.535711) (xy 380.464267 -244.494039)
			(xy 380.503337 -244.457785) (xy 380.547375 -244.427758) (xy 380.595395 -244.40463) (xy 380.646326 -244.388918)
			(xy 380.69903 -244.380971) (xy 380.72568 -244.380512) (xy 380.754385 -244.381058) (xy 380.811051 -244.390267)
			(xy 380.865505 -244.40845) (xy 380.916336 -244.435136) (xy 380.962225 -244.469633) (xy 380.982474 -244.489986)
			(xy 380.993344 -244.500541) (xy 381.019774 -244.515321) (xy 381.049374 -244.521709) (xy 381.079548 -244.519145)
			(xy 381.107645 -244.507853) (xy 381.131202 -244.488824) (xy 381.14815 -244.463729) (xy 381.157001 -244.434769)
			(xy 381.15748 -244.419628) (xy 381.15748 -244.279166) (xy 381.117856 -244.270276) (xy 381.091884 -244.263959)
			(xy 381.042064 -244.244597) (xy 380.995697 -244.218007) (xy 380.953825 -244.184785) (xy 380.917388 -244.145679)
			(xy 380.887205 -244.101567) (xy 380.863954 -244.053438) (xy 380.848157 -244.002376) (xy 380.840168 -243.949526)
			(xy 380.840168 -243.896076) (xy 380.848156 -243.843226) (xy 380.863953 -243.792163) (xy 380.887204 -243.744035)
			(xy 380.917387 -243.699922) (xy 380.953823 -243.660816) (xy 380.995695 -243.627594) (xy 381.042062 -243.601004)
			(xy 381.091882 -243.581641) (xy 381.117856 -243.575332) (xy 381.15748 -243.566442) (xy 381.15748 -243.426234)
			(xy 381.156934 -243.411128) (xy 381.148098 -243.382237) (xy 381.131191 -243.357199) (xy 381.107694 -243.338208)
			(xy 381.079667 -243.326929) (xy 381.049565 -243.32435) (xy 381.020028 -243.330697) (xy 380.993643 -243.345414)
			(xy 380.982728 -243.355876) (xy 380.962416 -243.376144) (xy 380.916514 -243.410571) (xy 380.865691 -243.437201)
			(xy 380.811259 -243.455348) (xy 380.754623 -243.464542) (xy 380.725934 -243.465096) (xy 380.699282 -243.464625)
			(xy 380.646573 -243.456685) (xy 380.595636 -243.440978) (xy 380.54761 -243.417853) (xy 380.503566 -243.387829)
			(xy 380.46449 -243.351575) (xy 380.431254 -243.309902) (xy 380.404601 -243.26374) (xy 380.385126 -243.214122)
			(xy 380.373264 -243.162155) (xy 380.36928 -243.109) (xy 380.373264 -243.055845) (xy 380.385126 -243.003878)
			(xy 380.404601 -242.95426) (xy 380.431254 -242.908098) (xy 380.46449 -242.866425) (xy 380.503566 -242.830171)
			(xy 380.54761 -242.800147) (xy 380.595636 -242.777022) (xy 380.646573 -242.761315) (xy 380.699282 -242.753375)
			(xy 380.725934 -242.75288) (xy 380.754629 -242.753398) (xy 380.811284 -242.762553) (xy 380.865735 -242.780684)
			(xy 380.916569 -242.807322) (xy 380.962467 -242.841774) (xy 380.982728 -242.8621) (xy 380.993601 -242.872595)
			(xy 381.020001 -242.887269) (xy 381.049537 -242.893585) (xy 381.07963 -242.89099) (xy 381.107649 -242.87971)
			(xy 381.131146 -242.860733) (xy 381.148069 -242.835715) (xy 381.15694 -242.806843) (xy 381.15748 -242.791742)
			(xy 381.15748 -242.65128) (xy 381.117856 -242.64239) (xy 381.091883 -242.636073) (xy 381.04206 -242.616711)
			(xy 380.995692 -242.59012) (xy 380.953818 -242.556897) (xy 380.917379 -242.51779) (xy 380.887195 -242.473676)
			(xy 380.863942 -242.425546) (xy 380.848144 -242.374482) (xy 380.840155 -242.32163) (xy 380.840154 -242.268178)
			(xy 380.848142 -242.215326) (xy 380.863939 -242.164261) (xy 380.887191 -242.116131) (xy 380.917374 -242.072016)
			(xy 380.953812 -242.032908) (xy 380.995685 -241.999685) (xy 381.042053 -241.973093) (xy 381.091875 -241.953729)
			(xy 381.117856 -241.947446) (xy 381.15748 -241.938556) (xy 381.15748 -241.798094) (xy 381.156928 -241.78296)
			(xy 381.148065 -241.754019) (xy 381.131119 -241.72894) (xy 381.107573 -241.709921) (xy 381.079492 -241.698628)
			(xy 381.049334 -241.69605) (xy 381.019743 -241.702414) (xy 380.993311 -241.717161) (xy 380.982474 -241.727736)
			(xy 380.962207 -241.74807) (xy 380.916328 -241.782576) (xy 380.865502 -241.809267) (xy 380.81105 -241.827448)
			(xy 380.754384 -241.836649) (xy 380.72568 -241.83721) (xy 380.699032 -241.836711) (xy 380.64633 -241.828765)
			(xy 380.595402 -241.813053) (xy 380.547384 -241.789926) (xy 380.503349 -241.759901) (xy 380.46428 -241.723649)
			(xy 380.431051 -241.681979) (xy 380.404403 -241.635822) (xy 380.384933 -241.586209) (xy 380.373073 -241.534248)
			(xy 380.36909 -241.4811) (xy 380.373073 -241.427952) (xy 380.384933 -241.375991) (xy 380.404403 -241.326378)
			(xy 380.431051 -241.280221) (xy 380.46428 -241.238551) (xy 380.503349 -241.202299) (xy 380.547384 -241.172274)
			(xy 380.595402 -241.149147) (xy 380.64633 -241.133435) (xy 380.699032 -241.125489) (xy 380.72568 -241.124994)
			(xy 380.754385 -241.12554) (xy 380.811052 -241.134749) (xy 380.865507 -241.152931) (xy 380.916338 -241.179616)
			(xy 380.962229 -241.214112) (xy 380.982474 -241.234468) (xy 380.993343 -241.245024) (xy 381.019771 -241.259807)
			(xy 381.049372 -241.266197) (xy 381.079545 -241.263633) (xy 381.107643 -241.25234) (xy 381.131198 -241.23331)
			(xy 381.148144 -241.208212) (xy 381.156991 -241.179252) (xy 381.15748 -241.16411) (xy 381.15748 -241.023648)
			(xy 381.117856 -241.014758) (xy 381.091885 -241.008441) (xy 381.042068 -240.98908) (xy 380.995703 -240.96249)
			(xy 380.953834 -240.92927) (xy 380.917399 -240.890165) (xy 380.887218 -240.846054) (xy 380.863969 -240.797928)
			(xy 380.848173 -240.746868) (xy 380.840185 -240.694021) (xy 380.840186 -240.640573) (xy 380.848174 -240.587726)
			(xy 380.863971 -240.536666) (xy 380.887221 -240.48854) (xy 380.917403 -240.44443) (xy 380.953838 -240.405326)
			(xy 380.995708 -240.372107) (xy 381.042073 -240.345518) (xy 381.091891 -240.326157) (xy 381.117856 -240.319814)
			(xy 381.15748 -240.310924) (xy 381.15748 -240.170208) (xy 381.156916 -240.155084) (xy 381.14804 -240.126166)
			(xy 381.131092 -240.101111) (xy 381.107555 -240.08211) (xy 381.079489 -240.070827) (xy 381.04935 -240.068249)
			(xy 381.019775 -240.074601) (xy 380.993353 -240.089328) (xy 380.982474 -240.09985) (xy 380.962207 -240.120183)
			(xy 380.916327 -240.154688) (xy 380.865501 -240.181378) (xy 380.811049 -240.199558) (xy 380.754384 -240.208758)
			(xy 380.72568 -240.209324) (xy 380.69903 -240.208825) (xy 380.646327 -240.200878) (xy 380.595397 -240.185166)
			(xy 380.547377 -240.162038) (xy 380.50334 -240.132012) (xy 380.46427 -240.095759) (xy 380.43104 -240.054087)
			(xy 380.404391 -240.007928) (xy 380.384919 -239.958313) (xy 380.373059 -239.90635) (xy 380.369076 -239.8532)
			(xy 380.373059 -239.80005) (xy 380.384919 -239.748087) (xy 380.404391 -239.698472) (xy 380.43104 -239.652313)
			(xy 380.46427 -239.610641) (xy 380.50334 -239.574388) (xy 380.547377 -239.544362) (xy 380.595397 -239.521234)
			(xy 380.646327 -239.505522) (xy 380.69903 -239.497575) (xy 380.72568 -239.497108) (xy 380.754385 -239.497654)
			(xy 380.811051 -239.506863) (xy 380.865506 -239.525046) (xy 380.916336 -239.551732) (xy 380.962226 -239.586229)
			(xy 380.982474 -239.606582) (xy 380.993344 -239.617137) (xy 381.019773 -239.631918) (xy 381.049374 -239.638307)
			(xy 381.079547 -239.635742) (xy 381.107645 -239.62445) (xy 381.131201 -239.605421) (xy 381.148148 -239.580325)
			(xy 381.156999 -239.551365) (xy 381.15748 -239.536224) (xy 381.15748 -239.395762) (xy 381.117856 -239.386872)
			(xy 381.091884 -239.380555) (xy 381.042064 -239.361193) (xy 380.995698 -239.334603) (xy 380.953827 -239.301382)
			(xy 380.917391 -239.262276) (xy 380.887208 -239.218164) (xy 380.863957 -239.170036) (xy 380.84816 -239.118974)
			(xy 380.840172 -239.066125) (xy 380.840172 -239.012675) (xy 380.84816 -238.959826) (xy 380.863957 -238.908764)
			(xy 380.887208 -238.860636) (xy 380.917391 -238.816524) (xy 380.953827 -238.777418) (xy 380.995698 -238.744197)
			(xy 381.042064 -238.717607) (xy 381.091884 -238.698245) (xy 381.117856 -238.691928) (xy 381.15748 -238.683038)
			(xy 381.15748 -238.54283) (xy 381.156933 -238.527724) (xy 381.148097 -238.498835) (xy 381.13119 -238.473798)
			(xy 381.107693 -238.454808) (xy 381.079667 -238.443529) (xy 381.049566 -238.44095) (xy 381.020029 -238.447297)
			(xy 380.993645 -238.462012) (xy 380.982728 -238.472472) (xy 380.962416 -238.492741) (xy 380.916514 -238.527167)
			(xy 380.865691 -238.553798) (xy 380.811259 -238.571945) (xy 380.754623 -238.58114) (xy 380.725934 -238.581692)
			(xy 380.699282 -238.581221) (xy 380.646574 -238.573281) (xy 380.595638 -238.557574) (xy 380.547612 -238.53445)
			(xy 380.503569 -238.504426) (xy 380.464493 -238.468172) (xy 380.431257 -238.4265) (xy 380.404604 -238.380339)
			(xy 380.385129 -238.330721) (xy 380.373268 -238.278754) (xy 380.369284 -238.2256) (xy 380.373268 -238.172446)
			(xy 380.385129 -238.120479) (xy 380.404604 -238.070861) (xy 380.431257 -238.0247) (xy 380.464493 -237.983028)
			(xy 380.503569 -237.946774) (xy 380.547612 -237.91675) (xy 380.595638 -237.893626) (xy 380.646574 -237.877919)
			(xy 380.699282 -237.869979) (xy 380.725934 -237.869476) (xy 380.75463 -237.869994) (xy 380.811285 -237.879149)
			(xy 380.865735 -237.89728) (xy 380.916569 -237.923917) (xy 380.962467 -237.958369) (xy 380.982728 -237.978696)
			(xy 380.993601 -237.989191) (xy 381.02 -238.003866) (xy 381.049537 -238.010182) (xy 381.079629 -238.007587)
			(xy 381.107648 -237.996308) (xy 381.131145 -237.97733) (xy 381.148068 -237.952312) (xy 381.156937 -237.923439)
			(xy 381.15748 -237.908338) (xy 381.15748 -237.767876) (xy 381.117856 -237.758986) (xy 381.091872 -237.752681)
			(xy 381.042027 -237.733338) (xy 380.995635 -237.706759) (xy 380.953737 -237.673543) (xy 380.917277 -237.634436)
			(xy 380.887074 -237.590317) (xy 380.863806 -237.542179) (xy 380.847997 -237.491102) (xy 380.840003 -237.438236)
			(xy 380.840003 -237.38477) (xy 380.847996 -237.331904) (xy 380.863804 -237.280827) (xy 380.887071 -237.232688)
			(xy 380.917273 -237.188569) (xy 380.953733 -237.149461) (xy 380.995629 -237.116244) (xy 381.042022 -237.089665)
			(xy 381.091866 -237.070321) (xy 381.117856 -237.064042) (xy 381.15748 -237.055152) (xy 381.15748 -236.914944)
			(xy 381.156921 -236.899816) (xy 381.148051 -236.870889) (xy 381.131103 -236.845823) (xy 381.107563 -236.826815)
			(xy 381.07949 -236.815528) (xy 381.049343 -236.81295) (xy 381.019762 -236.819307) (xy 380.993336 -236.834042)
			(xy 380.982474 -236.844586) (xy 380.962206 -236.864917) (xy 380.916325 -236.899419) (xy 380.865499 -236.926106)
			(xy 380.811047 -236.944284) (xy 380.754383 -236.953484) (xy 380.72568 -236.95406) (xy 380.699035 -236.953561)
			(xy 380.646341 -236.945616) (xy 380.59542 -236.929906) (xy 380.547409 -236.906782) (xy 380.50338 -236.876762)
			(xy 380.464317 -236.840515) (xy 380.431093 -236.798851) (xy 380.404449 -236.7527) (xy 380.384981 -236.703094)
			(xy 380.373123 -236.65114) (xy 380.369141 -236.598) (xy 380.373123 -236.54486) (xy 380.384981 -236.492906)
			(xy 380.404449 -236.4433) (xy 380.431093 -236.397149) (xy 380.464317 -236.355485) (xy 380.50338 -236.319238)
			(xy 380.547409 -236.289218) (xy 380.59542 -236.266094) (xy 380.646341 -236.250384) (xy 380.699035 -236.242439)
			(xy 380.72568 -236.241844) (xy 380.754385 -236.24239) (xy 380.81105 -236.2516) (xy 380.865504 -236.269784)
			(xy 380.916333 -236.296472) (xy 380.96222 -236.330971) (xy 380.982474 -236.351318) (xy 380.993346 -236.36187)
			(xy 381.019778 -236.376646) (xy 381.049379 -236.383032) (xy 381.079552 -236.380467) (xy 381.10765 -236.369176)
			(xy 381.131208 -236.35015) (xy 381.14816 -236.325058) (xy 381.157019 -236.296101) (xy 381.15748 -236.28096)
			(xy 381.15748 -236.140244) (xy 381.117856 -236.131354) (xy 381.091885 -236.125037) (xy 381.042069 -236.105676)
			(xy 380.995705 -236.079086) (xy 380.953836 -236.045866) (xy 380.917402 -236.006762) (xy 380.887221 -235.962652)
			(xy 380.863972 -235.914526) (xy 380.848176 -235.863466) (xy 380.840189 -235.81062) (xy 380.84019 -235.757173)
			(xy 380.848178 -235.704326) (xy 380.863975 -235.653267) (xy 380.887225 -235.605142) (xy 380.917407 -235.561032)
			(xy 380.953842 -235.521928) (xy 380.995711 -235.488709) (xy 381.042076 -235.462121) (xy 381.091893 -235.44276)
			(xy 381.117856 -235.43641) (xy 381.15748 -235.42752) (xy 381.15748 -235.287058) (xy 381.156923 -235.271928)
			(xy 381.148055 -235.242997) (xy 381.131108 -235.217928) (xy 381.107566 -235.198917) (xy 381.079491 -235.187628)
			(xy 381.049341 -235.18505) (xy 381.019757 -235.191409) (xy 380.993329 -235.206147) (xy 380.982474 -235.2167)
			(xy 380.962205 -235.23703) (xy 380.916324 -235.271531) (xy 380.865498 -235.298217) (xy 380.811047 -235.316395)
			(xy 380.754383 -235.325593) (xy 380.72568 -235.326174) (xy 380.699034 -235.325675) (xy 380.646338 -235.317729)
			(xy 380.595415 -235.302019) (xy 380.547402 -235.278895) (xy 380.503371 -235.248873) (xy 380.464307 -235.212624)
			(xy 380.431081 -235.170958) (xy 380.404436 -235.124806) (xy 380.384967 -235.075198) (xy 380.373109 -235.023243)
			(xy 380.369127 -234.9701) (xy 380.373109 -234.916957) (xy 380.384967 -234.865002) (xy 380.404436 -234.815394)
			(xy 380.431081 -234.769242) (xy 380.464307 -234.727576) (xy 380.503371 -234.691327) (xy 380.547402 -234.661305)
			(xy 380.595415 -234.638181) (xy 380.646338 -234.622471) (xy 380.699034 -234.614525) (xy 380.72568 -234.613958)
			(xy 380.754385 -234.614504) (xy 380.81105 -234.623714) (xy 380.865503 -234.641899) (xy 380.916331 -234.668588)
			(xy 380.962217 -234.703088) (xy 380.982474 -234.723432) (xy 380.993347 -234.733983) (xy 381.01978 -234.748757)
			(xy 381.049381 -234.755142) (xy 381.079553 -234.752576) (xy 381.107652 -234.741286) (xy 381.131211 -234.722261)
			(xy 381.148165 -234.697171) (xy 381.157026 -234.668215) (xy 381.15748 -234.653074) (xy 381.15748 -234.512612)
			(xy 381.117856 -234.503722) (xy 381.09188 -234.497405) (xy 381.042053 -234.478042) (xy 380.99568 -234.45145)
			(xy 380.953802 -234.418225) (xy 380.917359 -234.379115) (xy 380.887171 -234.334998) (xy 380.863916 -234.286864)
			(xy 380.848115 -234.235796) (xy 380.840124 -234.182939) (xy 380.840122 -234.129482) (xy 380.84811 -234.076626)
			(xy 380.863908 -234.025556) (xy 380.88716 -233.977421) (xy 380.917346 -233.933302) (xy 380.953786 -233.89419)
			(xy 380.995662 -233.860963) (xy 381.042034 -233.834367) (xy 381.091859 -233.815001) (xy 381.117856 -233.808778)
			(xy 381.15748 -233.799888) (xy 381.15748 -233.659426) (xy 381.156933 -233.644321) (xy 381.148096 -233.615432)
			(xy 381.131188 -233.590396) (xy 381.107692 -233.571407) (xy 381.079666 -233.560129) (xy 381.049567 -233.55755)
			(xy 381.020031 -233.563896) (xy 380.993647 -233.578611) (xy 380.982728 -233.589068) (xy 380.962416 -233.609337)
			(xy 380.916515 -233.643764) (xy 380.865691 -233.670395) (xy 380.811259 -233.688542) (xy 380.754623 -233.697737)
			(xy 380.725934 -233.698288) (xy 380.699283 -233.697817) (xy 380.646575 -233.689877) (xy 380.595639 -233.67417)
			(xy 380.547614 -233.651046) (xy 380.503571 -233.621023) (xy 380.464496 -233.58477) (xy 380.431261 -233.543097)
			(xy 380.404608 -233.496937) (xy 380.385133 -233.447319) (xy 380.373272 -233.395353) (xy 380.369288 -233.3422)
			(xy 380.373272 -233.289047) (xy 380.385133 -233.237081) (xy 380.404608 -233.187463) (xy 380.431261 -233.141303)
			(xy 380.464496 -233.09963) (xy 380.503571 -233.063377) (xy 380.547614 -233.033354) (xy 380.595639 -233.01023)
			(xy 380.646575 -232.994523) (xy 380.699283 -232.986583) (xy 380.725934 -232.986072) (xy 380.75463 -232.98659)
			(xy 380.811285 -232.995745) (xy 380.865735 -233.013876) (xy 380.916569 -233.040513) (xy 380.962468 -233.074964)
			(xy 380.982728 -233.095292) (xy 380.993601 -233.105788) (xy 381.02 -233.120463) (xy 381.049536 -233.126779)
			(xy 381.079628 -233.124184) (xy 381.107647 -233.112905) (xy 381.131145 -233.093927) (xy 381.148067 -233.068908)
			(xy 381.156935 -233.040035) (xy 381.15748 -233.024934) (xy 381.15748 -232.884726) (xy 381.117856 -232.875836)
			(xy 381.091876 -232.869531) (xy 381.042038 -232.850189) (xy 380.995653 -232.823613) (xy 380.953762 -232.7904)
			(xy 380.917308 -232.751297) (xy 380.88711 -232.707183) (xy 380.863847 -232.659051) (xy 380.848043 -232.607981)
			(xy 380.840051 -232.555122) (xy 380.840052 -232.501662) (xy 380.848046 -232.448804) (xy 380.863853 -232.397735)
			(xy 380.887118 -232.349603) (xy 380.917318 -232.305491) (xy 380.953774 -232.26639) (xy 380.995666 -232.233179)
			(xy 381.042053 -232.206604) (xy 381.091891 -232.187264) (xy 381.117856 -232.180892) (xy 381.15748 -232.172002)
			(xy 381.15748 -232.03154) (xy 381.15692 -232.016412) (xy 381.148049 -231.987486) (xy 381.131102 -231.962422)
			(xy 381.107562 -231.943414) (xy 381.07949 -231.932128) (xy 381.049344 -231.929549) (xy 381.019763 -231.935906)
			(xy 380.993338 -231.950641) (xy 380.982474 -231.961182) (xy 380.962206 -231.981513) (xy 380.916325 -232.016016)
			(xy 380.865499 -232.042703) (xy 380.811047 -232.060882) (xy 380.754383 -232.070081) (xy 380.72568 -232.070656)
			(xy 380.699028 -232.070157) (xy 380.64632 -232.06221) (xy 380.595385 -232.046496) (xy 380.547361 -232.023366)
			(xy 380.50332 -231.993337) (xy 380.464247 -231.95708) (xy 380.431013 -231.915405) (xy 380.404362 -231.869242)
			(xy 380.384889 -231.819622) (xy 380.373028 -231.767655) (xy 380.369044 -231.7145) (xy 380.373028 -231.661345)
			(xy 380.384889 -231.609378) (xy 380.404362 -231.559758) (xy 380.431013 -231.513595) (xy 380.464247 -231.47192)
			(xy 380.50332 -231.435663) (xy 380.547361 -231.405634) (xy 380.595385 -231.382504) (xy 380.64632 -231.36679)
			(xy 380.699028 -231.358843) (xy 380.72568 -231.35844) (xy 380.754385 -231.358986) (xy 380.81105 -231.368196)
			(xy 380.865504 -231.38638) (xy 380.916333 -231.413068) (xy 380.962221 -231.447566) (xy 380.982474 -231.467914)
			(xy 380.993346 -231.478467) (xy 381.019777 -231.493243) (xy 381.049378 -231.499629) (xy 381.079551 -231.497064)
			(xy 381.107649 -231.485773) (xy 381.131207 -231.466747) (xy 381.148159 -231.441654) (xy 381.157017 -231.412697)
			(xy 381.15748 -231.397556) (xy 381.15748 -231.25684) (xy 381.117856 -231.24795) (xy 381.091886 -231.241633)
			(xy 381.042069 -231.222272) (xy 380.995706 -231.195683) (xy 380.953838 -231.162463) (xy 380.917404 -231.123359)
			(xy 380.887224 -231.079249) (xy 380.863975 -231.031124) (xy 380.84818 -230.980065) (xy 380.840193 -230.927218)
			(xy 380.840194 -230.873772) (xy 380.848182 -230.820926) (xy 380.863979 -230.769867) (xy 380.887229 -230.721743)
			(xy 380.91741 -230.677634) (xy 380.953845 -230.638531) (xy 380.995714 -230.605312) (xy 381.042078 -230.578724)
			(xy 381.091895 -230.559364) (xy 381.117856 -230.553006) (xy 381.15748 -230.544116) (xy 381.15748 -230.403654)
			(xy 381.156922 -230.388525) (xy 381.148053 -230.359595) (xy 381.131106 -230.334527) (xy 381.107565 -230.315516)
			(xy 381.07949 -230.304228) (xy 381.049341 -230.30165) (xy 381.019758 -230.308008) (xy 380.993331 -230.322746)
			(xy 380.982474 -230.333296) (xy 380.962205 -230.353627) (xy 380.916324 -230.388128) (xy 380.865498 -230.414813)
			(xy 380.811047 -230.432992) (xy 380.754383 -230.44219) (xy 380.72568 -230.44277) (xy 380.699035 -230.442271)
			(xy 380.646339 -230.434325) (xy 380.595417 -230.418615) (xy 380.547404 -230.395491) (xy 380.503374 -230.36547)
			(xy 380.46431 -230.329222) (xy 380.431085 -230.287556) (xy 380.40444 -230.241404) (xy 380.384971 -230.191797)
			(xy 380.373113 -230.139842) (xy 380.369131 -230.0867) (xy 380.373113 -230.033558) (xy 380.384971 -229.981603)
			(xy 380.40444 -229.931996) (xy 380.431085 -229.885844) (xy 380.46431 -229.844178) (xy 380.503374 -229.80793)
			(xy 380.547404 -229.777909) (xy 380.595417 -229.754785) (xy 380.646339 -229.739075) (xy 380.699035 -229.731129)
			(xy 380.72568 -229.730554) (xy 380.754385 -229.7311) (xy 380.81105 -229.74031) (xy 380.865503 -229.758495)
			(xy 380.916331 -229.785183) (xy 380.962218 -229.819683) (xy 380.982474 -229.840028) (xy 380.993347 -229.85058)
			(xy 381.019779 -229.865354) (xy 381.04938 -229.871739) (xy 381.079553 -229.869174) (xy 381.107651 -229.857883)
			(xy 381.13121 -229.838858) (xy 381.148163 -229.813767) (xy 381.157024 -229.784811) (xy 381.15748 -229.76967)
			(xy 381.15748 -229.629208) (xy 381.117856 -229.620318) (xy 381.091881 -229.614001) (xy 381.042054 -229.594638)
			(xy 380.995681 -229.568046) (xy 380.953804 -229.534822) (xy 380.917362 -229.495712) (xy 380.887174 -229.451595)
			(xy 380.863919 -229.403462) (xy 380.848119 -229.352394) (xy 380.840128 -229.299538) (xy 380.840126 -229.246082)
			(xy 380.848114 -229.193226) (xy 380.863912 -229.142157) (xy 380.887164 -229.094022) (xy 380.917349 -229.049904)
			(xy 380.953789 -229.010792) (xy 380.995665 -228.977565) (xy 381.042036 -228.950971) (xy 381.091861 -228.931605)
			(xy 381.117856 -228.925374) (xy 381.15748 -228.916484) (xy 381.15748 -228.776276) (xy 381.156939 -228.761165)
			(xy 381.148111 -228.732263) (xy 381.131204 -228.707213) (xy 381.107703 -228.688214) (xy 381.079668 -228.676929)
			(xy 381.049558 -228.674351) (xy 381.020012 -228.680703) (xy 380.993622 -228.69543) (xy 380.982728 -228.705918)
			(xy 380.962418 -228.726189) (xy 380.916517 -228.760621) (xy 380.865694 -228.787256) (xy 380.811261 -228.805405)
			(xy 380.754624 -228.814602) (xy 380.725934 -228.815138) (xy 380.699279 -228.814667) (xy 380.646564 -228.806726)
			(xy 380.595621 -228.791017) (xy 380.547589 -228.76789) (xy 380.50354 -228.737862) (xy 380.464459 -228.701604)
			(xy 380.431219 -228.659926) (xy 380.404563 -228.613759) (xy 380.385085 -228.564134) (xy 380.373222 -228.512161)
			(xy 380.369238 -228.459) (xy 380.373222 -228.405839) (xy 380.385085 -228.353866) (xy 380.404563 -228.304241)
			(xy 380.431219 -228.258074) (xy 380.464459 -228.216396) (xy 380.50354 -228.180138) (xy 380.547589 -228.15011)
			(xy 380.595621 -228.126983) (xy 380.646564 -228.111274) (xy 380.699279 -228.103333) (xy 380.725934 -228.102922)
			(xy 380.754629 -228.10344) (xy 380.811283 -228.112596) (xy 380.865733 -228.130729) (xy 380.916564 -228.157368)
			(xy 380.962459 -228.191823) (xy 380.982728 -228.212142) (xy 380.993598 -228.222641) (xy 381.019993 -228.237323)
			(xy 381.049529 -228.243643) (xy 381.079622 -228.241049) (xy 381.10764 -228.229768) (xy 381.131134 -228.210786)
			(xy 381.14805 -228.185762) (xy 381.156907 -228.156886) (xy 381.15748 -228.141784) (xy 381.15748 -228.001322)
			(xy 381.117856 -227.992432) (xy 381.091887 -227.986115) (xy 381.042073 -227.966754) (xy 380.995713 -227.940166)
			(xy 380.953847 -227.906947) (xy 380.917416 -227.867845) (xy 380.887237 -227.823737) (xy 380.86399 -227.775614)
			(xy 380.848196 -227.724557) (xy 380.84021 -227.671713) (xy 380.840212 -227.618269) (xy 380.8482 -227.565426)
			(xy 380.863997 -227.51437) (xy 380.887246 -227.466248) (xy 380.917426 -227.422142) (xy 380.95386 -227.383041)
			(xy 380.995727 -227.349824) (xy 381.042089 -227.323238) (xy 381.091904 -227.303879) (xy 381.117856 -227.297488)
			(xy 381.15748 -227.288598) (xy 381.15748 -227.148136) (xy 381.15692 -227.133009) (xy 381.148048 -227.104084)
			(xy 381.131101 -227.079021) (xy 381.107561 -227.060014) (xy 381.07949 -227.048728) (xy 381.049345 -227.046149)
			(xy 381.019765 -227.052505) (xy 380.99334 -227.067239) (xy 380.982474 -227.077778) (xy 380.962206 -227.09811)
			(xy 380.916325 -227.132612) (xy 380.865499 -227.159299) (xy 380.811048 -227.177479) (xy 380.754383 -227.186678)
			(xy 380.72568 -227.187252) (xy 380.699028 -227.186753) (xy 380.646321 -227.178806) (xy 380.595386 -227.163092)
			(xy 380.547363 -227.139963) (xy 380.503322 -227.109934) (xy 380.464249 -227.073678) (xy 380.431016 -227.032003)
			(xy 380.404366 -226.98584) (xy 380.384892 -226.936221) (xy 380.373032 -226.884254) (xy 380.369048 -226.8311)
			(xy 380.373032 -226.777946) (xy 380.384892 -226.725979) (xy 380.404366 -226.67636) (xy 380.431016 -226.630197)
			(xy 380.464249 -226.588522) (xy 380.503322 -226.552266) (xy 380.547363 -226.522237) (xy 380.595386 -226.499108)
			(xy 380.646321 -226.483394) (xy 380.699028 -226.475447) (xy 380.72568 -226.475036) (xy 380.754385 -226.475582)
			(xy 380.811051 -226.484792) (xy 380.865504 -226.502976) (xy 380.916333 -226.529663) (xy 380.962221 -226.564162)
			(xy 380.982474 -226.58451) (xy 380.993345 -226.595063) (xy 381.019777 -226.60984) (xy 381.049378 -226.616226)
			(xy 381.079551 -226.613661) (xy 381.107649 -226.60237) (xy 381.131207 -226.583344) (xy 381.148157 -226.558251)
			(xy 381.157014 -226.529293) (xy 381.15748 -226.514152) (xy 381.15748 -226.37369) (xy 381.117856 -226.3648)
			(xy 381.091882 -226.358483) (xy 381.042058 -226.339121) (xy 380.995688 -226.312529) (xy 380.953813 -226.279306)
			(xy 380.917373 -226.240198) (xy 380.887187 -226.196083) (xy 380.863934 -226.147952) (xy 380.848135 -226.096886)
			(xy 380.840145 -226.044033) (xy 380.840144 -225.990579) (xy 380.848132 -225.937726) (xy 380.863929 -225.886659)
			(xy 380.887181 -225.838528) (xy 380.917365 -225.794412) (xy 380.953804 -225.755302) (xy 380.995678 -225.722078)
			(xy 381.042047 -225.695485) (xy 381.09187 -225.67612) (xy 381.117856 -225.669856) (xy 381.15748 -225.660966)
			(xy 381.15748 -225.52025) (xy 381.156922 -225.505121) (xy 381.148052 -225.476192) (xy 381.131105 -225.451125)
			(xy 381.107564 -225.432116) (xy 381.07949 -225.420828) (xy 381.049342 -225.41825) (xy 381.01976 -225.424607)
			(xy 380.993333 -225.439344) (xy 380.982474 -225.449892) (xy 380.962205 -225.470223) (xy 380.916324 -225.504724)
			(xy 380.865498 -225.53141) (xy 380.811047 -225.549589) (xy 380.754383 -225.558788) (xy 380.72568 -225.559366)
			(xy 380.697697 -225.558844) (xy 380.64242 -225.550085) (xy 380.589194 -225.532787) (xy 380.53933 -225.507375)
			(xy 380.494055 -225.474476) (xy 380.454484 -225.434898) (xy 380.421592 -225.389617) (xy 380.396189 -225.339748)
			(xy 380.3789 -225.286519) (xy 380.370151 -225.231241) (xy 380.369572 -225.203258) (xy 380.36995 -225.180014)
			(xy 380.376 -225.13392) (xy 380.387991 -225.089004) (xy 380.396496 -225.067368) (xy 380.406148 -225.044254)
			(xy 380.233682 -224.745804) (xy 380.209044 -224.742502) (xy 380.1837 -224.73868) (xy 380.134389 -224.724704)
			(xy 380.087592 -224.703802) (xy 380.044276 -224.676405) (xy 380.005337 -224.643079) (xy 379.971579 -224.604515)
			(xy 379.943699 -224.561507) (xy 379.922276 -224.514947) (xy 379.90775 -224.465795) (xy 379.900423 -224.415069)
			(xy 379.899926 -224.389442) (xy 379.900424 -224.362793) (xy 379.908367 -224.310089) (xy 379.924077 -224.259159)
			(xy 379.947203 -224.211138) (xy 379.977227 -224.167101) (xy 380.013479 -224.12803) (xy 380.05515 -224.094799)
			(xy 380.101308 -224.06815) (xy 380.150922 -224.048678) (xy 380.202884 -224.036818) (xy 380.256034 -224.032835)
			(xy 380.309184 -224.036818) (xy 380.361146 -224.048678) (xy 380.41076 -224.06815) (xy 380.456918 -224.094799)
			(xy 380.498589 -224.12803) (xy 380.534841 -224.167101) (xy 380.564865 -224.211138) (xy 380.587991 -224.259159)
			(xy 380.603701 -224.310089) (xy 380.611644 -224.362793) (xy 380.612142 -224.389442) (xy 380.611764 -224.412686)
			(xy 380.605714 -224.45878) (xy 380.593724 -224.503696) (xy 380.585218 -224.525332) (xy 380.575566 -224.548446)
			(xy 380.748032 -224.846896) (xy 380.77267 -224.850198) (xy 380.802312 -224.854786) (xy 380.85959 -224.872577)
			(xy 380.913082 -224.899704) (xy 380.961279 -224.9354) (xy 380.982474 -224.956624) (xy 380.993346 -224.967176)
			(xy 381.019779 -224.981951) (xy 381.04938 -224.988336) (xy 381.079552 -224.985771) (xy 381.107651 -224.97448)
			(xy 381.131209 -224.955455) (xy 381.148162 -224.930364) (xy 381.157022 -224.901407) (xy 381.15748 -224.886266)
			(xy 381.15748 -224.745804) (xy 381.117856 -224.736914) (xy 381.091886 -224.730597) (xy 381.042071 -224.711233)
			(xy 380.995709 -224.684642) (xy 380.953843 -224.65142) (xy 380.917413 -224.612313) (xy 380.887237 -224.5682)
			(xy 380.863993 -224.520073) (xy 380.848204 -224.469012) (xy 380.840224 -224.416165) (xy 380.839726 -224.389442)
			(xy 380.8402 -224.363465) (xy 380.847753 -224.312063) (xy 380.862689 -224.262302) (xy 380.873254 -224.238566)
			(xy 380.88824 -224.206308) (xy 380.584456 -223.902524) (xy 380.576328 -223.898714) (xy 380.553766 -223.887799)
			(xy 380.511686 -223.860575) (xy 380.473839 -223.827718) (xy 380.440973 -223.789878) (xy 380.413739 -223.747804)
			(xy 380.402846 -223.725232) (xy 380.399036 -223.717104) (xy 380.300738 -223.618806) (xy 380.289566 -223.608358)
			(xy 380.262522 -223.594093) (xy 380.232469 -223.588466) (xy 380.202097 -223.591981) (xy 380.174123 -223.604324)
			(xy 380.151053 -223.624389) (xy 380.134951 -223.65038) (xy 380.130558 -223.665034) (xy 380.123469 -223.690449)
			(xy 380.102829 -223.739007) (xy 380.075255 -223.783991) (xy 380.041351 -223.824418) (xy 380.001856 -223.859405)
			(xy 379.957635 -223.888186) (xy 379.909654 -223.910133) (xy 379.858962 -223.924766) (xy 379.83287 -223.928686)
			(xy 379.808232 -223.931988) (xy 379.635766 -224.230438) (xy 379.645418 -224.253552) (xy 379.653933 -224.275184)
			(xy 379.665916 -224.320102) (xy 379.671957 -224.366197) (xy 379.672342 -224.389442) (xy 379.671844 -224.416091)
			(xy 379.663901 -224.468795) (xy 379.648191 -224.519725) (xy 379.625065 -224.567746) (xy 379.595041 -224.611783)
			(xy 379.558789 -224.650854) (xy 379.517118 -224.684085) (xy 379.47096 -224.710734) (xy 379.421346 -224.730206)
			(xy 379.369384 -224.742066) (xy 379.316234 -224.74605) (xy 379.263084 -224.742066) (xy 379.211122 -224.730206)
			(xy 379.161508 -224.710734) (xy 379.11535 -224.684085) (xy 379.073679 -224.650854) (xy 379.037427 -224.611783)
			(xy 379.007403 -224.567746) (xy 378.984277 -224.519725) (xy 378.968567 -224.468795) (xy 378.960624 -224.416091)
			(xy 378.960126 -224.389442) (xy 378.960575 -224.363816) (xy 378.967928 -224.313094) (xy 378.982472 -224.263949)
			(xy 379.003909 -224.217395) (xy 379.031795 -224.174393) (xy 379.065555 -224.135831) (xy 379.104493 -224.102505)
			(xy 379.147804 -224.075102) (xy 379.194595 -224.054188) (xy 379.2439 -224.040194) (xy 379.269244 -224.036382)
			(xy 379.293882 -224.03308) (xy 379.466094 -223.734376) (xy 379.456696 -223.711262) (xy 379.448185 -223.689672)
			(xy 379.436199 -223.64484) (xy 379.430147 -223.598829) (xy 379.429772 -223.575626) (xy 379.430225 -223.549558)
			(xy 379.437825 -223.497979) (xy 379.452866 -223.44806) (xy 379.475026 -223.400868) (xy 379.503832 -223.357413)
			(xy 379.538667 -223.318623) (xy 379.578787 -223.285329) (xy 379.623334 -223.258242) (xy 379.671355 -223.237941)
			(xy 379.696472 -223.230948) (xy 379.711133 -223.226588) (xy 379.737111 -223.210468) (xy 379.757164 -223.187389)
			(xy 379.769499 -223.159414) (xy 379.773015 -223.129043) (xy 379.767397 -223.09899) (xy 379.753146 -223.07194)
			(xy 379.7427 -223.060768) (xy 379.70333 -223.021398) (xy 379.693789 -223.012418) (xy 379.671169 -222.999217)
			(xy 379.645928 -222.992225) (xy 379.619739 -222.991905) (xy 379.594336 -222.998278) (xy 379.571399 -223.010922)
			(xy 379.561598 -223.01962) (xy 379.541619 -223.03791) (xy 379.497162 -223.068848) (xy 379.448533 -223.0927)
			(xy 379.396854 -223.108914) (xy 379.343316 -223.117119) (xy 379.316234 -223.117664) (xy 379.289925 -223.117193)
			(xy 379.237878 -223.109452) (xy 379.187539 -223.094134) (xy 379.140003 -223.071572) (xy 379.096306 -223.042258)
			(xy 379.057401 -223.00683) (xy 379.024135 -222.966062) (xy 378.997232 -222.92084) (xy 378.986796 -222.896684)
			(xy 378.951816 -222.901487) (xy 378.881387 -222.906568) (xy 378.84608 -222.906844) (xy 378.8109 -222.906565)
			(xy 378.740724 -222.901482) (xy 378.705872 -222.896684) (xy 378.695449 -222.920843) (xy 378.668532 -222.966051)
			(xy 378.635257 -223.006807) (xy 378.596348 -223.042223) (xy 378.552651 -223.071529) (xy 378.505117 -223.094087)
			(xy 378.454782 -223.109406) (xy 378.402741 -223.117152) (xy 378.376434 -223.117664) (xy 378.35073 -223.117214)
			(xy 378.299856 -223.109824) (xy 378.250574 -223.095193) (xy 378.20391 -223.073624) (xy 378.160834 -223.045567)
			(xy 378.122241 -223.011605) (xy 378.088936 -222.972445) (xy 378.061609 -222.928902) (xy 378.050806 -222.905574)
			(xy 378.037344 -222.875348) (xy 377.775724 -222.875348) (xy 377.762262 -222.905574) (xy 377.751449 -222.928893)
			(xy 377.724107 -222.972419) (xy 377.690793 -223.011563) (xy 377.6522 -223.045513) (xy 377.609128 -223.073564)
			(xy 377.562471 -223.095133) (xy 377.513199 -223.109773) (xy 377.462334 -223.11718) (xy 377.436634 -223.117664)
			(xy 377.410325 -223.117193) (xy 377.358278 -223.109452) (xy 377.307939 -223.094134) (xy 377.260403 -223.071572)
			(xy 377.216706 -223.042258) (xy 377.177801 -223.00683) (xy 377.144535 -222.966062) (xy 377.117632 -222.92084)
			(xy 377.107196 -222.896684) (xy 377.072216 -222.901487) (xy 377.001787 -222.906568) (xy 376.96648 -222.906844)
			(xy 376.9313 -222.906565) (xy 376.861124 -222.901482) (xy 376.826272 -222.896684) (xy 376.815849 -222.920843)
			(xy 376.788932 -222.966051) (xy 376.755657 -223.006807) (xy 376.716748 -223.042223) (xy 376.673051 -223.071529)
			(xy 376.625517 -223.094087) (xy 376.575182 -223.109406) (xy 376.523141 -223.117152) (xy 376.496834 -223.117664)
			(xy 376.47113 -223.117214) (xy 376.420256 -223.109824) (xy 376.370974 -223.095193) (xy 376.32431 -223.073624)
			(xy 376.281234 -223.045567) (xy 376.242641 -223.011605) (xy 376.209336 -222.972445) (xy 376.182009 -222.928902)
			(xy 376.171206 -222.905574) (xy 376.157744 -222.875348) (xy 375.896124 -222.875348) (xy 375.882662 -222.905574)
			(xy 375.871849 -222.928893) (xy 375.844507 -222.972419) (xy 375.811193 -223.011563) (xy 375.7726 -223.045513)
			(xy 375.729528 -223.073564) (xy 375.682871 -223.095133) (xy 375.633599 -223.109773) (xy 375.582734 -223.11718)
			(xy 375.557034 -223.117664) (xy 375.530725 -223.117193) (xy 375.478678 -223.109452) (xy 375.428339 -223.094134)
			(xy 375.380803 -223.071572) (xy 375.337106 -223.042258) (xy 375.298201 -223.00683) (xy 375.264935 -222.966062)
			(xy 375.238032 -222.92084) (xy 375.227596 -222.896684) (xy 375.192616 -222.901487) (xy 375.122187 -222.906568)
			(xy 375.08688 -222.906844) (xy 375.0517 -222.906565) (xy 374.981524 -222.901482) (xy 374.946672 -222.896684)
			(xy 374.936249 -222.920843) (xy 374.909332 -222.966051) (xy 374.876057 -223.006807) (xy 374.837148 -223.042223)
			(xy 374.793451 -223.071529) (xy 374.745917 -223.094087) (xy 374.695582 -223.109406) (xy 374.643541 -223.117152)
			(xy 374.617234 -223.117664) (xy 374.59153 -223.117214) (xy 374.540656 -223.109824) (xy 374.491374 -223.095193)
			(xy 374.44471 -223.073624) (xy 374.401634 -223.045567) (xy 374.363041 -223.011605) (xy 374.329736 -222.972445)
			(xy 374.302409 -222.928902) (xy 374.291606 -222.905574) (xy 374.278144 -222.875348) (xy 374.016524 -222.875348)
			(xy 374.003062 -222.905574) (xy 373.992249 -222.928893) (xy 373.964907 -222.972419) (xy 373.931593 -223.011563)
			(xy 373.893 -223.045513) (xy 373.849928 -223.073564) (xy 373.803271 -223.095133) (xy 373.753999 -223.109773)
			(xy 373.703134 -223.11718) (xy 373.677434 -223.117664) (xy 373.651125 -223.117193) (xy 373.599078 -223.109452)
			(xy 373.548739 -223.094134) (xy 373.501203 -223.071572) (xy 373.457506 -223.042258) (xy 373.418601 -223.00683)
			(xy 373.385335 -222.966062) (xy 373.358432 -222.92084) (xy 373.347996 -222.896684) (xy 373.313016 -222.901487)
			(xy 373.242587 -222.906568) (xy 373.20728 -222.906844) (xy 373.1721 -222.906565) (xy 373.101924 -222.901482)
			(xy 373.067072 -222.896684) (xy 373.056649 -222.920843) (xy 373.029732 -222.966051) (xy 372.996457 -223.006807)
			(xy 372.957548 -223.042223) (xy 372.913851 -223.071529) (xy 372.866317 -223.094087) (xy 372.815982 -223.109406)
			(xy 372.763941 -223.117152) (xy 372.737634 -223.117664) (xy 372.71193 -223.117214) (xy 372.661056 -223.109824)
			(xy 372.611774 -223.095193) (xy 372.56511 -223.073624) (xy 372.522034 -223.045567) (xy 372.483441 -223.011605)
			(xy 372.450136 -222.972445) (xy 372.422809 -222.928902) (xy 372.412006 -222.905574) (xy 372.398544 -222.875348)
			(xy 372.136924 -222.875348) (xy 372.123462 -222.905574) (xy 372.112649 -222.928893) (xy 372.085307 -222.972419)
			(xy 372.051993 -223.011563) (xy 372.0134 -223.045513) (xy 371.970328 -223.073564) (xy 371.923671 -223.095133)
			(xy 371.874399 -223.109773) (xy 371.823534 -223.11718) (xy 371.797834 -223.117664) (xy 371.771525 -223.117193)
			(xy 371.719478 -223.109452) (xy 371.669139 -223.094134) (xy 371.621603 -223.071572) (xy 371.577906 -223.042258)
			(xy 371.539001 -223.00683) (xy 371.505735 -222.966062) (xy 371.478832 -222.92084) (xy 371.468396 -222.896684)
			(xy 371.433416 -222.901487) (xy 371.362987 -222.906568) (xy 371.32768 -222.906844) (xy 371.2925 -222.906565)
			(xy 371.222324 -222.901482) (xy 371.187472 -222.896684) (xy 371.177049 -222.920843) (xy 371.150132 -222.966051)
			(xy 371.116857 -223.006807) (xy 371.077948 -223.042223) (xy 371.034251 -223.071529) (xy 370.986717 -223.094087)
			(xy 370.936382 -223.109406) (xy 370.884341 -223.117152) (xy 370.858034 -223.117664) (xy 370.83233 -223.117214)
			(xy 370.781456 -223.109824) (xy 370.732174 -223.095193) (xy 370.68551 -223.073624) (xy 370.642434 -223.045567)
			(xy 370.603841 -223.011605) (xy 370.570536 -222.972445) (xy 370.543209 -222.928902) (xy 370.532406 -222.905574)
			(xy 370.518944 -222.875348) (xy 370.257324 -222.875348) (xy 370.243862 -222.905574) (xy 370.233049 -222.928893)
			(xy 370.205707 -222.972419) (xy 370.172393 -223.011563) (xy 370.1338 -223.045513) (xy 370.090728 -223.073564)
			(xy 370.044071 -223.095133) (xy 369.994799 -223.109773) (xy 369.943934 -223.11718) (xy 369.918234 -223.117664)
			(xy 369.891925 -223.117193) (xy 369.839878 -223.109452) (xy 369.789539 -223.094134) (xy 369.742003 -223.071572)
			(xy 369.698306 -223.042258) (xy 369.659401 -223.00683) (xy 369.626135 -222.966062) (xy 369.599232 -222.92084)
			(xy 369.588796 -222.896684) (xy 369.553816 -222.901487) (xy 369.483387 -222.906568) (xy 369.44808 -222.906844)
			(xy 369.4129 -222.906565) (xy 369.342724 -222.901482) (xy 369.307872 -222.896684) (xy 369.297449 -222.920843)
			(xy 369.270532 -222.966051) (xy 369.237257 -223.006807) (xy 369.198348 -223.042223) (xy 369.154651 -223.071529)
			(xy 369.107117 -223.094087) (xy 369.056782 -223.109406) (xy 369.004741 -223.117152) (xy 368.978434 -223.117664)
			(xy 368.950448 -223.117146) (xy 368.895165 -223.108394) (xy 368.841932 -223.091101) (xy 368.79206 -223.065692)
			(xy 368.746778 -223.032793) (xy 368.707201 -222.993214) (xy 368.674303 -222.947931) (xy 368.648895 -222.898059)
			(xy 368.631604 -222.844825) (xy 368.622853 -222.789542) (xy 368.622326 -222.761556) (xy 368.622435 -222.750028)
			(xy 368.623963 -222.727024) (xy 368.625374 -222.715582) (xy 368.628422 -222.69069) (xy 368.038888 -222.101156)
			(xy 368.029138 -222.091961) (xy 368.005929 -222.078577) (xy 367.980036 -222.071695) (xy 367.953244 -222.071791)
			(xy 367.927401 -222.078856) (xy 367.904288 -222.092405) (xy 367.885497 -222.111503) (xy 367.878614 -222.123)
			(xy 367.864973 -222.146163) (xy 367.831808 -222.188463) (xy 367.792656 -222.225293) (xy 367.748409 -222.255814)
			(xy 367.700075 -222.279332) (xy 367.648752 -222.29531) (xy 367.59561 -222.303387) (xy 367.568734 -222.303848)
			(xy 367.542078 -222.303377) (xy 367.489361 -222.295436) (xy 367.438417 -222.279726) (xy 367.390384 -222.256598)
			(xy 367.346334 -222.22657) (xy 367.307252 -222.19031) (xy 367.274011 -222.148631) (xy 367.247354 -222.102463)
			(xy 367.227876 -222.052837) (xy 367.216012 -222.000862) (xy 367.212028 -221.9477) (xy 367.216012 -221.894538)
			(xy 367.227876 -221.842563) (xy 367.247354 -221.792937) (xy 367.274011 -221.746769) (xy 367.307252 -221.70509)
			(xy 367.346334 -221.66883) (xy 367.390384 -221.638802) (xy 367.438417 -221.615674) (xy 367.489361 -221.599964)
			(xy 367.542078 -221.592023) (xy 367.568734 -221.591632) (xy 367.578598 -221.59173) (xy 367.598295 -221.592874)
			(xy 367.608104 -221.593918) (xy 367.622337 -221.595014) (xy 367.650459 -221.590186) (xy 367.676146 -221.577762)
			(xy 367.69739 -221.558712) (xy 367.712529 -221.534526) (xy 367.720381 -221.507094) (xy 367.72088 -221.492826)
			(xy 367.72088 -221.295468) (xy 367.716054 -221.285308) (xy 367.705381 -221.261514) (xy 367.690331 -221.211586)
			(xy 367.682723 -221.159996) (xy 367.682719 -221.107848) (xy 367.690321 -221.056257) (xy 367.705365 -221.006326)
			(xy 367.716054 -220.98254) (xy 367.72088 -220.97238) (xy 367.72088 -220.87459) (xy 367.677446 -220.799406)
			(xy 367.660112 -220.76874) (xy 367.629472 -220.705303) (xy 367.616232 -220.67266) (xy 367.604415 -220.674173)
			(xy 367.580647 -220.675824) (xy 367.568734 -220.675962) (xy 367.542085 -220.675491) (xy 367.489381 -220.667552)
			(xy 367.438449 -220.651846) (xy 367.390427 -220.628724) (xy 367.346387 -220.598702) (xy 367.307315 -220.562452)
			(xy 367.274082 -220.520783) (xy 367.247431 -220.474626) (xy 367.227958 -220.425012) (xy 367.216097 -220.37305)
			(xy 367.212114 -220.3199) (xy 367.216097 -220.26675) (xy 367.227958 -220.214788) (xy 367.247431 -220.165174)
			(xy 367.274082 -220.119017) (xy 367.307315 -220.077348) (xy 367.346387 -220.041098) (xy 367.390427 -220.011076)
			(xy 367.438449 -219.987954) (xy 367.489381 -219.972248) (xy 367.542085 -219.964309) (xy 367.568734 -219.963746)
			(xy 367.580647 -219.963866) (xy 367.604417 -219.965518) (xy 367.616232 -219.967048) (xy 367.635879 -219.919289)
			(xy 367.683991 -219.827905) (xy 367.712244 -219.784676) (xy 367.72088 -219.771722) (xy 367.72088 -219.667074)
			(xy 367.716054 -219.656914) (xy 367.705471 -219.633183) (xy 367.690524 -219.58342) (xy 367.682968 -219.532014)
			(xy 367.682963 -219.480055) (xy 367.690509 -219.428647) (xy 367.705446 -219.378881) (xy 367.716054 -219.355162)
			(xy 367.72088 -219.345002) (xy 367.72088 -219.147136) (xy 367.720395 -219.132874) (xy 367.712502 -219.105462)
			(xy 367.697347 -219.081296) (xy 367.676109 -219.062253) (xy 367.650438 -219.049815) (xy 367.622331 -219.044948)
			(xy 367.608104 -219.046044) (xy 367.598232 -219.047104) (xy 367.578408 -219.048249) (xy 367.56848 -219.04833)
			(xy 367.540497 -219.04778) (xy 367.485221 -219.039022) (xy 367.431995 -219.021726) (xy 367.38213 -218.996317)
			(xy 367.336854 -218.963421) (xy 367.29728 -218.923848) (xy 367.264384 -218.878571) (xy 367.238975 -218.828706)
			(xy 367.221678 -218.775481) (xy 367.212921 -218.720205) (xy 367.212372 -218.692222) (xy 367.212823 -218.666598)
			(xy 367.220178 -218.61588) (xy 367.234725 -218.56674) (xy 367.256163 -218.520191) (xy 367.284051 -218.477195)
			(xy 367.317813 -218.438639) (xy 367.356751 -218.405319) (xy 367.400062 -218.377923) (xy 367.446852 -218.357016)
			(xy 367.496155 -218.34303) (xy 367.52149 -218.339162) (xy 367.546128 -218.33586) (xy 367.718594 -218.036902)
			(xy 367.709196 -218.013788) (xy 367.700756 -217.992227) (xy 367.688882 -217.947472) (xy 367.682894 -217.901558)
			(xy 367.682526 -217.878406) (xy 367.682996 -217.852428) (xy 367.69054 -217.801023) (xy 367.705468 -217.751257)
			(xy 367.716054 -217.72753) (xy 367.72088 -217.71737) (xy 367.72088 -217.51925) (xy 367.720397 -217.504986)
			(xy 367.712506 -217.477572) (xy 367.697352 -217.453402) (xy 367.676113 -217.434356) (xy 367.650441 -217.421915)
			(xy 367.622331 -217.417048) (xy 367.608104 -217.418158) (xy 367.598295 -217.41921) (xy 367.578599 -217.420353)
			(xy 367.568734 -217.420444) (xy 367.542079 -217.419973) (xy 367.489362 -217.412032) (xy 367.438419 -217.396322)
			(xy 367.390386 -217.373195) (xy 367.346336 -217.343166) (xy 367.307255 -217.306908) (xy 367.274014 -217.265229)
			(xy 367.247357 -217.219061) (xy 367.22788 -217.169436) (xy 367.216016 -217.117462) (xy 367.212032 -217.0643)
			(xy 367.216016 -217.011138) (xy 367.22788 -216.959164) (xy 367.247357 -216.909539) (xy 367.274014 -216.863371)
			(xy 367.307255 -216.821692) (xy 367.346336 -216.785434) (xy 367.390386 -216.755405) (xy 367.438419 -216.732278)
			(xy 367.489362 -216.716568) (xy 367.542079 -216.708627) (xy 367.568734 -216.708228) (xy 367.578598 -216.708326)
			(xy 367.598295 -216.70947) (xy 367.608104 -216.710514) (xy 367.622337 -216.71161) (xy 367.650459 -216.706782)
			(xy 367.676145 -216.694358) (xy 367.697388 -216.675308) (xy 367.712527 -216.651122) (xy 367.720378 -216.62369)
			(xy 367.72088 -216.609422) (xy 367.72088 -216.411556) (xy 367.716054 -216.401396) (xy 367.705472 -216.377665)
			(xy 367.690528 -216.327903) (xy 367.682975 -216.276497) (xy 367.682972 -216.224539) (xy 367.69052 -216.173133)
			(xy 367.705459 -216.123369) (xy 367.716054 -216.099644) (xy 367.72088 -216.089484) (xy 367.72088 -214.187532)
			(xy 367.720395 -214.17327) (xy 367.712501 -214.14586) (xy 367.697346 -214.121694) (xy 367.676108 -214.102652)
			(xy 367.650438 -214.090214) (xy 367.622332 -214.085348) (xy 367.608104 -214.08644) (xy 367.598295 -214.087492)
			(xy 367.578599 -214.088635) (xy 367.568734 -214.088726) (xy 367.54208 -214.088255) (xy 367.489366 -214.080315)
			(xy 367.438425 -214.064606) (xy 367.390395 -214.041479) (xy 367.346348 -214.011452) (xy 367.307268 -213.975195)
			(xy 367.274029 -213.933519) (xy 367.247374 -213.887353) (xy 367.227897 -213.837731) (xy 367.216034 -213.785759)
			(xy 367.21205 -213.7326) (xy 367.216034 -213.679441) (xy 367.227897 -213.627469) (xy 367.247374 -213.577847)
			(xy 367.274029 -213.531681) (xy 367.307268 -213.490005) (xy 367.346348 -213.453748) (xy 367.390395 -213.423721)
			(xy 367.438425 -213.400594) (xy 367.489366 -213.384885) (xy 367.54208 -213.376945) (xy 367.568734 -213.37651)
			(xy 367.578598 -213.376608) (xy 367.598295 -213.377752) (xy 367.608104 -213.378796) (xy 367.622336 -213.379892)
			(xy 367.650456 -213.375064) (xy 367.67614 -213.362639) (xy 367.697381 -213.343589) (xy 367.712516 -213.319402)
			(xy 367.720362 -213.291971) (xy 367.72088 -213.277704) (xy 367.72088 -208.575148) (xy 379.7173 -196.578728)
			(xy 395.59484 -196.578728) (xy 396.42034 -195.753228) (xy 396.42034 -179.875688) (xy 398.58188 -177.714148)
			(xy 398.58188 -169.687748) (xy 399.802604 -168.467024) (xy 399.827011 -168.432167) (xy 399.88134 -168.366667)
			(xy 399.941516 -168.306495) (xy 400.00702 -168.252171) (xy 400.041872 -168.227756) (xy 401.93468 -166.334948)
			(xy 408.84348 -166.334948) (xy 409.52928 -165.649148) (xy 409.52928 -165.466014) (xy 409.50401 -165.453071)
			(xy 409.457274 -165.420837) (xy 409.415833 -165.382032) (xy 409.380601 -165.337512) (xy 409.352357 -165.288262)
			(xy 409.331726 -165.235369) (xy 409.319163 -165.180003) (xy 409.314946 -165.123386) (xy 409.319167 -165.066769)
			(xy 409.331734 -165.011404) (xy 409.352369 -164.958513) (xy 409.380616 -164.909265) (xy 409.415852 -164.864748)
			(xy 409.457296 -164.825945) (xy 409.504035 -164.793715) (xy 409.52928 -164.780722) (xy 409.52928 -159.438594)
			(xy 409.505577 -159.426482) (xy 409.461479 -159.396671) (xy 409.421952 -159.361021) (xy 409.387763 -159.320224)
			(xy 409.359575 -159.275071) (xy 409.337936 -159.226439) (xy 409.323265 -159.175272) (xy 409.315847 -159.122562)
			(xy 409.315412 -159.095948) (xy 409.315929 -159.067208) (xy 409.324546 -159.010376) (xy 409.341591 -158.955481)
			(xy 409.366679 -158.903765) (xy 409.399242 -158.856397) (xy 409.418536 -158.83509) (xy 409.428618 -158.823557)
			(xy 409.441978 -158.796007) (xy 409.446577 -158.765735) (xy 409.441999 -158.73546) (xy 409.428658 -158.707901)
			(xy 409.418536 -158.696406) (xy 409.399262 -158.67508) (xy 409.36669 -158.62772) (xy 409.341591 -158.576008)
			(xy 409.324533 -158.521117) (xy 409.315903 -158.464288) (xy 409.315412 -158.435548) (xy 409.315903 -158.40784)
			(xy 409.323931 -158.35301) (xy 409.331414 -158.326328) (xy 409.34005 -158.297118) (xy 408.91968 -157.876748)
			(xy 401.358608 -157.876748) (xy 401.344594 -157.87719) (xy 401.317619 -157.884804) (xy 401.293728 -157.899461)
			(xy 401.274719 -157.920059) (xy 401.262023 -157.945047) (xy 401.256593 -157.972545) (xy 401.25884 -158.000483)
			(xy 401.268595 -158.02676) (xy 401.276566 -158.038292) (xy 401.299818 -158.070909) (xy 401.341025 -158.139607)
			(xy 401.37589 -158.211731) (xy 401.404129 -158.286698) (xy 401.425514 -158.363899) (xy 401.439873 -158.442711)
			(xy 401.447088 -158.522494) (xy 401.447508 -158.562548) (xy 401.447031 -158.603649) (xy 401.439442 -158.6855)
			(xy 401.424334 -158.766302) (xy 401.401835 -158.845365) (xy 401.372137 -158.922015) (xy 401.335493 -158.995598)
			(xy 401.292217 -159.065486) (xy 401.242677 -159.131083) (xy 401.187296 -159.19183) (xy 401.126546 -159.247208)
			(xy 401.060947 -159.296744) (xy 400.991056 -159.340017) (xy 400.917471 -159.376656) (xy 400.84082 -159.40635)
			(xy 400.761755 -159.428845) (xy 400.680953 -159.443949) (xy 400.599101 -159.451533) (xy 400.558 -159.452056)
			(xy 400.514581 -159.451533) (xy 400.428155 -159.443071) (xy 400.342965 -159.426227) (xy 400.259822 -159.401163)
			(xy 400.179518 -159.368115) (xy 400.102815 -159.3274) (xy 400.030446 -159.279404) (xy 399.963097 -159.224584)
			(xy 399.901412 -159.163463) (xy 399.845975 -159.096621) (xy 399.797316 -159.024696) (xy 399.755898 -158.948371)
			(xy 399.722114 -158.868373) (xy 399.696286 -158.785464) (xy 399.67866 -158.700433) (xy 399.669404 -158.614089)
			(xy 399.668492 -158.570676) (xy 399.667858 -158.555731) (xy 399.65899 -158.527178) (xy 399.64223 -158.50242)
			(xy 399.619015 -158.48358) (xy 399.591336 -158.472276) (xy 399.561569 -158.469477) (xy 399.532269 -158.475423)
			(xy 399.505948 -158.489605) (xy 399.49501 -158.49981) (xy 395.209268 -162.785552) (xy 399.642589 -162.785552)
			(xy 399.646611 -162.699832) (xy 399.658642 -162.614864) (xy 399.678578 -162.531397) (xy 399.706241 -162.450163)
			(xy 399.74139 -162.371877) (xy 399.783716 -162.297226) (xy 399.832845 -162.226867) (xy 399.888348 -162.161417)
			(xy 399.949735 -162.101453) (xy 400.016468 -162.0475) (xy 400.08796 -162.000033) (xy 400.163582 -161.959469)
			(xy 400.242671 -161.926165) (xy 400.324531 -161.900413) (xy 400.408442 -161.88244) (xy 400.493668 -161.872404)
			(xy 400.57946 -161.870392) (xy 400.665062 -161.876423) (xy 400.749724 -161.890443) (xy 400.832701 -161.912329)
			(xy 400.913264 -161.94189) (xy 400.990704 -161.978864) (xy 401.064343 -162.022928) (xy 401.133531 -162.073694)
			(xy 401.197662 -162.130715) (xy 401.256171 -162.193491) (xy 401.308544 -162.261471) (xy 401.354322 -162.334056)
			(xy 401.393102 -162.410608) (xy 401.424543 -162.490456) (xy 401.448369 -162.572897) (xy 401.46437 -162.657207)
			(xy 401.472405 -162.742645) (xy 401.472908 -162.785552) (xy 401.472405 -162.828459) (xy 401.46437 -162.913897)
			(xy 401.448369 -162.998207) (xy 401.424543 -163.080648) (xy 401.393102 -163.160496) (xy 401.354322 -163.237048)
			(xy 401.308544 -163.309633) (xy 401.256171 -163.377613) (xy 401.197662 -163.440389) (xy 401.133531 -163.49741)
			(xy 401.064343 -163.548176) (xy 400.990704 -163.59224) (xy 400.913264 -163.629214) (xy 400.832701 -163.658775)
			(xy 400.749724 -163.680661) (xy 400.665062 -163.694681) (xy 400.57946 -163.700712) (xy 400.493668 -163.6987)
			(xy 400.408442 -163.688664) (xy 400.324531 -163.670691) (xy 400.242671 -163.644939) (xy 400.163582 -163.611635)
			(xy 400.08796 -163.571071) (xy 400.016468 -163.523604) (xy 399.949735 -163.469651) (xy 399.888348 -163.409687)
			(xy 399.832845 -163.344237) (xy 399.783716 -163.273878) (xy 399.74139 -163.199227) (xy 399.706241 -163.120941)
			(xy 399.678578 -163.039707) (xy 399.658642 -162.95624) (xy 399.646611 -162.871272) (xy 399.642589 -162.785552)
			(xy 395.209268 -162.785552) (xy 394.631672 -163.363148) (xy 386.99186 -163.363148) (xy 385.63042 -164.724588)
			(xy 396.0401 -164.724588) (xy 396.044171 -164.668966) (xy 396.056297 -164.614529) (xy 396.07622 -164.562438)
			(xy 396.103516 -164.513803) (xy 396.137602 -164.46966) (xy 396.177751 -164.430951) (xy 396.223109 -164.3985)
			(xy 396.272709 -164.372999) (xy 396.325493 -164.354992) (xy 396.380336 -164.344862) (xy 396.43607 -164.342825)
			(xy 396.491507 -164.348925) (xy 396.545464 -164.363031) (xy 396.596793 -164.384843) (xy 396.644399 -164.413897)
			(xy 396.687267 -164.449572) (xy 396.724484 -164.491109) (xy 396.755257 -164.537622) (xy 396.778929 -164.588119)
			(xy 396.794997 -164.641526) (xy 396.803117 -164.696702) (xy 396.803626 -164.724588) (xy 396.803117 -164.752474)
			(xy 396.794997 -164.80765) (xy 396.788906 -164.827896) (xy 399.668996 -164.827896) (xy 399.668996 -164.7432)
			(xy 399.677047 -164.658886) (xy 399.693076 -164.57572) (xy 399.716937 -164.494453) (xy 399.748416 -164.415823)
			(xy 399.787227 -164.340542) (xy 399.833017 -164.26929) (xy 399.885373 -164.202714) (xy 399.943821 -164.141416)
			(xy 400.007831 -164.085951) (xy 400.076823 -164.036822) (xy 400.150173 -163.994473) (xy 400.227216 -163.959289)
			(xy 400.307255 -163.931587) (xy 400.389564 -163.911619) (xy 400.473399 -163.899566) (xy 400.558 -163.895536)
			(xy 400.642601 -163.899566) (xy 400.726436 -163.911619) (xy 400.808745 -163.931587) (xy 400.888784 -163.959289)
			(xy 400.965827 -163.994473) (xy 401.039177 -164.036822) (xy 401.108169 -164.085951) (xy 401.172179 -164.141416)
			(xy 401.230627 -164.202714) (xy 401.282983 -164.26929) (xy 401.328773 -164.340542) (xy 401.367584 -164.415823)
			(xy 401.399063 -164.494453) (xy 401.422924 -164.57572) (xy 401.438953 -164.658886) (xy 401.447004 -164.7432)
			(xy 401.447508 -164.785548) (xy 401.447004 -164.827896) (xy 401.438953 -164.91221) (xy 401.422924 -164.995376)
			(xy 401.399063 -165.076643) (xy 401.367584 -165.155273) (xy 401.328773 -165.230554) (xy 401.282983 -165.301806)
			(xy 401.230627 -165.368382) (xy 401.172179 -165.42968) (xy 401.108169 -165.485145) (xy 401.039177 -165.534274)
			(xy 400.965827 -165.576623) (xy 400.888784 -165.611807) (xy 400.808745 -165.639509) (xy 400.726436 -165.659477)
			(xy 400.642601 -165.67153) (xy 400.558 -165.675561) (xy 400.473399 -165.67153) (xy 400.389564 -165.659477)
			(xy 400.307255 -165.639509) (xy 400.227216 -165.611807) (xy 400.150173 -165.576623) (xy 400.076823 -165.534274)
			(xy 400.007831 -165.485145) (xy 399.943821 -165.42968) (xy 399.885373 -165.368382) (xy 399.833017 -165.301806)
			(xy 399.787227 -165.230554) (xy 399.748416 -165.155273) (xy 399.716937 -165.076643) (xy 399.693076 -164.995376)
			(xy 399.677047 -164.91221) (xy 399.668996 -164.827896) (xy 396.788906 -164.827896) (xy 396.778929 -164.861057)
			(xy 396.755257 -164.911554) (xy 396.724484 -164.958067) (xy 396.687267 -164.999604) (xy 396.644399 -165.035279)
			(xy 396.596793 -165.064333) (xy 396.545464 -165.086145) (xy 396.491507 -165.100251) (xy 396.43607 -165.106351)
			(xy 396.380336 -165.104314) (xy 396.325493 -165.094184) (xy 396.272709 -165.076177) (xy 396.223109 -165.050676)
			(xy 396.177751 -165.018225) (xy 396.137602 -164.979516) (xy 396.103516 -164.935373) (xy 396.07622 -164.886738)
			(xy 396.056297 -164.834647) (xy 396.044171 -164.78021) (xy 396.0401 -164.724588) (xy 385.63042 -164.724588)
			(xy 382.939544 -167.415464) (xy 395.694408 -167.415464) (xy 395.694845 -167.389084) (xy 395.702103 -167.336826)
			(xy 395.716489 -167.286066) (xy 395.737728 -167.23777) (xy 395.765417 -167.192861) (xy 395.799027 -167.152192)
			(xy 395.837918 -167.11654) (xy 395.881349 -167.086585) (xy 395.90472 -167.074342) (xy 395.917115 -167.067697)
			(xy 395.937856 -167.048715) (xy 395.952625 -167.024791) (xy 395.9603 -166.997742) (xy 395.960295 -166.969626)
			(xy 395.952612 -166.94258) (xy 395.937836 -166.91866) (xy 395.917088 -166.899684) (xy 395.90472 -166.892986)
			(xy 395.881381 -166.880687) (xy 395.837957 -166.850734) (xy 395.79907 -166.815087) (xy 395.765461 -166.774426)
			(xy 395.73777 -166.729526) (xy 395.716525 -166.68124) (xy 395.702129 -166.63049) (xy 395.694858 -166.57824)
			(xy 395.694408 -166.551864) (xy 395.694894 -166.524613) (xy 395.70265 -166.470665) (xy 395.718005 -166.41837)
			(xy 395.740647 -166.368793) (xy 395.770113 -166.322943) (xy 395.805804 -166.281752) (xy 395.846995 -166.246061)
			(xy 395.892845 -166.216595) (xy 395.942422 -166.193953) (xy 395.994717 -166.178598) (xy 396.048665 -166.170842)
			(xy 396.103167 -166.170842) (xy 396.157115 -166.178598) (xy 396.20941 -166.193953) (xy 396.258987 -166.216595)
			(xy 396.304837 -166.246061) (xy 396.346028 -166.281752) (xy 396.381719 -166.322943) (xy 396.411185 -166.368793)
			(xy 396.433827 -166.41837) (xy 396.449182 -166.470665) (xy 396.456938 -166.524613) (xy 396.457424 -166.551864)
			(xy 396.456992 -166.578244) (xy 396.449732 -166.630501) (xy 396.435344 -166.681261) (xy 396.414102 -166.729556)
			(xy 396.386413 -166.774465) (xy 396.352803 -166.815133) (xy 396.313912 -166.850786) (xy 396.270483 -166.880743)
			(xy 396.247112 -166.892986) (xy 396.234787 -166.899743) (xy 396.214066 -166.918711) (xy 396.199309 -166.942614)
			(xy 396.191637 -166.969638) (xy 396.191633 -166.99773) (xy 396.199296 -167.024756) (xy 396.214046 -167.048664)
			(xy 396.23476 -167.067639) (xy 396.247112 -167.074342) (xy 396.27047 -167.086606) (xy 396.313893 -167.116565)
			(xy 396.352779 -167.152218) (xy 396.386386 -167.192884) (xy 396.414074 -167.237789) (xy 396.435316 -167.286079)
			(xy 396.449709 -167.336834) (xy 396.456976 -167.389086) (xy 396.457424 -167.415464) (xy 396.456938 -167.442715)
			(xy 396.449182 -167.496663) (xy 396.433827 -167.548958) (xy 396.411185 -167.598535) (xy 396.381719 -167.644385)
			(xy 396.346028 -167.685576) (xy 396.304837 -167.721267) (xy 396.258987 -167.750733) (xy 396.20941 -167.773375)
			(xy 396.157115 -167.78873) (xy 396.103167 -167.796486) (xy 396.048665 -167.796486) (xy 395.994717 -167.78873)
			(xy 395.942422 -167.773375) (xy 395.892845 -167.750733) (xy 395.846995 -167.721267) (xy 395.805804 -167.685576)
			(xy 395.770113 -167.644385) (xy 395.740647 -167.598535) (xy 395.718005 -167.548958) (xy 395.70265 -167.496663)
			(xy 395.694894 -167.442715) (xy 395.694408 -167.415464) (xy 382.939544 -167.415464) (xy 381.8763 -168.478708)
			(xy 397.049242 -168.478708) (xy 397.053313 -168.423086) (xy 397.065439 -168.368649) (xy 397.085362 -168.316558)
			(xy 397.112658 -168.267923) (xy 397.146744 -168.22378) (xy 397.186893 -168.185071) (xy 397.232251 -168.15262)
			(xy 397.281851 -168.127119) (xy 397.334635 -168.109112) (xy 397.389478 -168.098982) (xy 397.445212 -168.096945)
			(xy 397.500649 -168.103045) (xy 397.554606 -168.117151) (xy 397.605935 -168.138963) (xy 397.653541 -168.168017)
			(xy 397.696409 -168.203692) (xy 397.733626 -168.245229) (xy 397.764399 -168.291742) (xy 397.788071 -168.342239)
			(xy 397.804139 -168.395646) (xy 397.812259 -168.450822) (xy 397.812768 -168.478708) (xy 397.812259 -168.506594)
			(xy 397.804139 -168.56177) (xy 397.788071 -168.615177) (xy 397.764399 -168.665674) (xy 397.733626 -168.712187)
			(xy 397.696409 -168.753724) (xy 397.653541 -168.789399) (xy 397.605935 -168.818453) (xy 397.554606 -168.840265)
			(xy 397.500649 -168.854371) (xy 397.445212 -168.860471) (xy 397.389478 -168.858434) (xy 397.334635 -168.848304)
			(xy 397.281851 -168.830297) (xy 397.232251 -168.804796) (xy 397.186893 -168.772345) (xy 397.146744 -168.733636)
			(xy 397.112658 -168.689493) (xy 397.085362 -168.640858) (xy 397.065439 -168.588767) (xy 397.053313 -168.53433)
			(xy 397.049242 -168.478708) (xy 381.8763 -168.478708) (xy 378.385578 -171.96943) (xy 393.4239 -171.96943)
			(xy 393.427971 -171.913808) (xy 393.440097 -171.859371) (xy 393.46002 -171.80728) (xy 393.487316 -171.758645)
			(xy 393.521402 -171.714502) (xy 393.561551 -171.675793) (xy 393.606909 -171.643342) (xy 393.656509 -171.617841)
			(xy 393.709293 -171.599834) (xy 393.764136 -171.589704) (xy 393.81987 -171.587667) (xy 393.875307 -171.593767)
			(xy 393.929264 -171.607873) (xy 393.980593 -171.629685) (xy 394.028199 -171.658739) (xy 394.071067 -171.694414)
			(xy 394.108284 -171.735951) (xy 394.139057 -171.782464) (xy 394.162729 -171.832961) (xy 394.178797 -171.886368)
			(xy 394.186917 -171.941544) (xy 394.187426 -171.96943) (xy 394.186917 -171.997316) (xy 394.178797 -172.052492)
			(xy 394.162729 -172.105899) (xy 394.139057 -172.156396) (xy 394.108284 -172.202909) (xy 394.071067 -172.244446)
			(xy 394.028199 -172.280121) (xy 393.980593 -172.309175) (xy 393.929264 -172.330987) (xy 393.875307 -172.345093)
			(xy 393.81987 -172.351193) (xy 393.764136 -172.349156) (xy 393.709293 -172.339026) (xy 393.656509 -172.321019)
			(xy 393.606909 -172.295518) (xy 393.561551 -172.263067) (xy 393.521402 -172.224358) (xy 393.487316 -172.180215)
			(xy 393.46002 -172.13158) (xy 393.440097 -172.079489) (xy 393.427971 -172.025052) (xy 393.4239 -171.96943)
			(xy 378.385578 -171.96943) (xy 377.237498 -173.11751) (xy 393.44168 -173.11751) (xy 393.445751 -173.061888)
			(xy 393.457877 -173.007451) (xy 393.4778 -172.95536) (xy 393.505096 -172.906725) (xy 393.539182 -172.862582)
			(xy 393.579331 -172.823873) (xy 393.624689 -172.791422) (xy 393.674289 -172.765921) (xy 393.727073 -172.747914)
			(xy 393.781916 -172.737784) (xy 393.83765 -172.735747) (xy 393.893087 -172.741847) (xy 393.947044 -172.755953)
			(xy 393.998373 -172.777765) (xy 394.045979 -172.806819) (xy 394.088847 -172.842494) (xy 394.126064 -172.884031)
			(xy 394.156837 -172.930544) (xy 394.180509 -172.981041) (xy 394.196577 -173.034448) (xy 394.204697 -173.089624)
			(xy 394.205206 -173.11751) (xy 394.204697 -173.145396) (xy 394.196577 -173.200572) (xy 394.180509 -173.253979)
			(xy 394.156837 -173.304476) (xy 394.126064 -173.350989) (xy 394.088847 -173.392526) (xy 394.045979 -173.428201)
			(xy 393.998373 -173.457255) (xy 393.947044 -173.479067) (xy 393.893087 -173.493173) (xy 393.83765 -173.499273)
			(xy 393.781916 -173.497236) (xy 393.727073 -173.487106) (xy 393.674289 -173.469099) (xy 393.624689 -173.443598)
			(xy 393.579331 -173.411147) (xy 393.539182 -173.372438) (xy 393.505096 -173.328295) (xy 393.4778 -173.27966)
			(xy 393.457877 -173.227569) (xy 393.445751 -173.173132) (xy 393.44168 -173.11751) (xy 377.237498 -173.11751)
			(xy 376.88774 -173.467268) (xy 376.88774 -175.316388) (xy 376.058938 -176.14519) (xy 393.33297 -176.14519)
			(xy 393.333456 -176.117939) (xy 393.341212 -176.063991) (xy 393.356567 -176.011696) (xy 393.379209 -175.962119)
			(xy 393.408675 -175.916269) (xy 393.444366 -175.875078) (xy 393.485557 -175.839387) (xy 393.531407 -175.809921)
			(xy 393.580984 -175.787279) (xy 393.633279 -175.771924) (xy 393.687227 -175.764168) (xy 393.741729 -175.764168)
			(xy 393.795677 -175.771924) (xy 393.847972 -175.787279) (xy 393.897549 -175.809921) (xy 393.943399 -175.839387)
			(xy 393.98459 -175.875078) (xy 394.020281 -175.916269) (xy 394.049747 -175.962119) (xy 394.072389 -176.011696)
			(xy 394.087744 -176.063991) (xy 394.0955 -176.117939) (xy 394.095986 -176.14519) (xy 394.095519 -176.1726)
			(xy 394.087673 -176.226857) (xy 394.072143 -176.279431) (xy 394.049246 -176.329241) (xy 394.019456 -176.375261)
			(xy 393.983385 -176.416543) (xy 393.96289 -176.43475) (xy 393.952758 -176.444076) (xy 393.937417 -176.46693)
			(xy 393.928736 -176.49305) (xy 393.927348 -176.520541) (xy 393.933352 -176.547403) (xy 393.946312 -176.571686)
			(xy 393.965287 -176.591625) (xy 393.97686 -176.599088) (xy 394.000774 -176.613961) (xy 394.044353 -176.649629)
			(xy 394.082217 -176.691313) (xy 394.113543 -176.738111) (xy 394.137651 -176.789003) (xy 394.154018 -176.842887)
			(xy 394.162288 -176.898591) (xy 394.162788 -176.926748) (xy 394.162302 -176.953999) (xy 394.154546 -177.007947)
			(xy 394.139191 -177.060242) (xy 394.116549 -177.109819) (xy 394.087083 -177.155669) (xy 394.051392 -177.19686)
			(xy 394.010201 -177.232551) (xy 393.964351 -177.262017) (xy 393.914774 -177.284659) (xy 393.862479 -177.300014)
			(xy 393.808531 -177.30777) (xy 393.754029 -177.30777) (xy 393.700081 -177.300014) (xy 393.647786 -177.284659)
			(xy 393.598209 -177.262017) (xy 393.552359 -177.232551) (xy 393.511168 -177.19686) (xy 393.475477 -177.155669)
			(xy 393.446011 -177.109819) (xy 393.423369 -177.060242) (xy 393.408014 -177.007947) (xy 393.400258 -176.953999)
			(xy 393.399772 -176.926748) (xy 393.400245 -176.899338) (xy 393.408087 -176.845081) (xy 393.423615 -176.792506)
			(xy 393.44651 -176.742695) (xy 393.4763 -176.696675) (xy 393.512372 -176.655394) (xy 393.532868 -176.637188)
			(xy 393.542967 -176.627826) (xy 393.558316 -176.604983) (xy 393.567004 -176.57887) (xy 393.568399 -176.551384)
			(xy 393.5624 -176.524525) (xy 393.549443 -176.500245) (xy 393.530469 -176.48031) (xy 393.518898 -176.47285)
			(xy 393.494992 -176.457966) (xy 393.451415 -176.422298) (xy 393.413552 -176.380615) (xy 393.382226 -176.33382)
			(xy 393.358116 -176.282929) (xy 393.341747 -176.229048) (xy 393.333473 -176.173346) (xy 393.33297 -176.14519)
			(xy 376.058938 -176.14519) (xy 375.16308 -177.041048) (xy 370.99748 -177.041048) (xy 370.344682 -177.693846)
			(xy 372.866228 -177.693846) (xy 372.866228 -177.639354) (xy 372.873982 -177.585417) (xy 372.889333 -177.533133)
			(xy 372.911968 -177.483565) (xy 372.941427 -177.437723) (xy 372.977109 -177.396539) (xy 373.018289 -177.360852)
			(xy 373.064128 -177.331389) (xy 373.113693 -177.308748) (xy 373.165976 -177.293391) (xy 373.219912 -177.285631)
			(xy 373.247158 -177.285142) (xy 373.274024 -177.285603) (xy 373.327225 -177.293138) (xy 373.378843 -177.308064)
			(xy 373.427855 -177.330086) (xy 373.473291 -177.358768) (xy 373.514253 -177.393542) (xy 373.549929 -177.433721)
			(xy 373.579615 -177.478508) (xy 373.591582 -177.502566) (xy 373.598639 -177.516151) (xy 373.619382 -177.538647)
			(xy 373.645854 -177.553994) (xy 373.675682 -177.560817) (xy 373.706194 -177.558504) (xy 373.720614 -177.553366)
			(xy 373.750446 -177.542159) (xy 373.812202 -177.526422) (xy 373.875439 -177.518524) (xy 373.907304 -177.51806)
			(xy 373.907812 -177.51806) (xy 373.941031 -177.518606) (xy 374.006903 -177.527264) (xy 374.071088 -177.544419)
			(xy 374.132496 -177.569778) (xy 374.161558 -177.585878) (xy 375.08561 -178.119532) (xy 375.114227 -178.136663)
			(xy 375.167141 -178.177264) (xy 375.214298 -178.22443) (xy 375.25489 -178.277352) (xy 375.288221 -178.335122)
			(xy 375.313719 -178.396752) (xy 375.330949 -178.461184) (xy 375.3358 -178.494182) (xy 375.337563 -178.504112)
			(xy 375.347644 -178.521558) (xy 375.363672 -178.533767) (xy 375.383168 -178.538853) (xy 375.393204 -178.53787)
			(xy 375.406657 -178.536077) (xy 375.433734 -178.534171) (xy 375.447306 -178.53406) (xy 375.474555 -178.534611)
			(xy 375.528497 -178.542367) (xy 375.580787 -178.557721) (xy 375.630359 -178.580361) (xy 375.676205 -178.609825)
			(xy 375.717391 -178.645513) (xy 375.753079 -178.6867) (xy 375.782542 -178.732546) (xy 375.805181 -178.782119)
			(xy 375.820534 -178.834409) (xy 375.82829 -178.888351) (xy 375.82829 -178.942849) (xy 375.820534 -178.996791)
			(xy 375.805181 -179.049081) (xy 375.782542 -179.098654) (xy 375.753079 -179.1445) (xy 375.717391 -179.185687)
			(xy 375.676205 -179.221375) (xy 375.630359 -179.250839) (xy 375.580787 -179.273479) (xy 375.528497 -179.288833)
			(xy 375.474555 -179.296589) (xy 375.447306 -179.297076) (xy 375.418933 -179.296569) (xy 375.362813 -179.288152)
			(xy 375.30856 -179.271516) (xy 375.257368 -179.24703) (xy 375.210366 -179.215232) (xy 375.168592 -179.176824)
			(xy 375.132966 -179.132654) (xy 375.104275 -179.083695) (xy 375.09323 -179.057554) (xy 375.089063 -179.048357)
			(xy 375.07493 -179.033961) (xy 375.056331 -179.026146) (xy 375.036158 -179.026128) (xy 375.026682 -179.029614)
			(xy 374.995609 -179.041929) (xy 374.931047 -179.059239) (xy 374.864777 -179.06796) (xy 374.831356 -179.068476)
			(xy 374.830848 -179.068476) (xy 374.797629 -179.067942) (xy 374.731757 -179.05928) (xy 374.667571 -179.042122)
			(xy 374.606164 -179.016759) (xy 374.577102 -179.000658) (xy 373.65305 -178.467004) (xy 373.62649 -178.451169)
			(xy 373.57706 -178.414014) (xy 373.532505 -178.371135) (xy 373.493483 -178.323165) (xy 373.460571 -178.270814)
			(xy 373.434256 -178.214856) (xy 373.414926 -178.156118) (xy 373.408448 -178.125882) (xy 373.404945 -178.110999)
			(xy 373.390353 -178.084147) (xy 373.368471 -178.062812) (xy 373.341257 -178.048905) (xy 373.311147 -178.04367)
			(xy 373.295926 -178.04511) (xy 373.283785 -178.046545) (xy 373.259383 -178.048072) (xy 373.247158 -178.048158)
			(xy 373.219912 -178.047569) (xy 373.165976 -178.039809) (xy 373.113693 -178.024452) (xy 373.064128 -178.001811)
			(xy 373.018289 -177.972348) (xy 372.977109 -177.936661) (xy 372.941427 -177.895477) (xy 372.911968 -177.849635)
			(xy 372.889333 -177.800067) (xy 372.873982 -177.747783) (xy 372.866228 -177.693846) (xy 370.344682 -177.693846)
			(xy 368.587677 -179.450851) (xy 369.125746 -179.450851) (xy 369.125746 -179.396349) (xy 369.133502 -179.3424)
			(xy 369.148856 -179.290105) (xy 369.171495 -179.240527) (xy 369.20096 -179.194675) (xy 369.236649 -179.153482)
			(xy 369.277838 -179.117788) (xy 369.323686 -179.088318) (xy 369.373262 -179.065672) (xy 369.425555 -179.050311)
			(xy 369.479503 -179.042549) (xy 369.506754 -179.04206) (xy 369.520326 -179.042163) (xy 369.547403 -179.04407)
			(xy 369.560856 -179.04587) (xy 369.570892 -179.046782) (xy 369.59037 -179.041694) (xy 369.606397 -179.029511)
			(xy 369.616511 -179.012104) (xy 369.61826 -179.002182) (xy 369.623113 -178.969183) (xy 369.640328 -178.904744)
			(xy 369.665818 -178.843108) (xy 369.699145 -178.785332) (xy 369.739739 -178.732409) (xy 369.786902 -178.685245)
			(xy 369.839824 -178.64465) (xy 369.86845 -178.627532) (xy 370.792502 -178.093878) (xy 370.82156 -178.077769)
			(xy 370.882966 -178.0524) (xy 370.947153 -178.035245) (xy 371.013028 -178.026597) (xy 371.046248 -178.02606)
			(xy 371.046756 -178.02606) (xy 371.080179 -178.026555) (xy 371.146455 -178.035258) (xy 371.211015 -178.052587)
			(xy 371.242082 -178.064922) (xy 371.251563 -178.068338) (xy 371.271699 -178.068246) (xy 371.290265 -178.060452)
			(xy 371.304434 -178.046144) (xy 371.30863 -178.036982) (xy 371.319681 -178.010843) (xy 371.348365 -177.961879)
			(xy 371.383986 -177.917704) (xy 371.425758 -177.879294) (xy 371.47276 -177.847497) (xy 371.523955 -177.823014)
			(xy 371.578211 -177.806386) (xy 371.634332 -177.79798) (xy 371.662706 -177.79746) (xy 371.689955 -177.798011)
			(xy 371.743897 -177.805767) (xy 371.796187 -177.821121) (xy 371.845759 -177.843761) (xy 371.891605 -177.873225)
			(xy 371.932791 -177.908913) (xy 371.968479 -177.9501) (xy 371.997942 -177.995946) (xy 372.020581 -178.045519)
			(xy 372.035934 -178.097809) (xy 372.04369 -178.151751) (xy 372.04369 -178.206249) (xy 372.035934 -178.260191)
			(xy 372.020581 -178.312481) (xy 371.997942 -178.362054) (xy 371.968479 -178.4079) (xy 371.932791 -178.449087)
			(xy 371.891605 -178.484775) (xy 371.845759 -178.514239) (xy 371.796187 -178.536879) (xy 371.743897 -178.552233)
			(xy 371.689955 -178.559989) (xy 371.662706 -178.560476) (xy 371.649134 -178.560377) (xy 371.622057 -178.558468)
			(xy 371.608604 -178.556666) (xy 371.59857 -178.555685) (xy 371.57908 -178.560791) (xy 371.56305 -178.572995)
			(xy 371.552942 -178.590423) (xy 371.5512 -178.600354) (xy 371.546342 -178.633352) (xy 371.529125 -178.697789)
			(xy 371.503635 -178.759424) (xy 371.470307 -178.817199) (xy 371.429715 -178.870123) (xy 371.382554 -178.917287)
			(xy 371.329634 -178.957884) (xy 371.30101 -178.975004) (xy 370.610727 -179.373653) (xy 392.93263 -179.373653)
			(xy 392.93263 -179.319147) (xy 392.940386 -179.265195) (xy 392.955742 -179.212897) (xy 392.978383 -179.163316)
			(xy 393.00785 -179.117461) (xy 393.043542 -179.076266) (xy 393.084734 -179.04057) (xy 393.130586 -179.0111)
			(xy 393.180165 -178.988454) (xy 393.232462 -178.973094) (xy 393.286413 -178.965332) (xy 393.313666 -178.964844)
			(xy 393.340974 -178.9653) (xy 393.395033 -178.973077) (xy 393.421362 -178.980338) (xy 393.436348 -178.98414)
			(xy 393.467243 -178.983622) (xy 393.496574 -178.9739) (xy 393.521661 -178.955861) (xy 393.540216 -178.931153)
			(xy 393.550545 -178.902031) (xy 393.551664 -178.886612) (xy 393.553084 -178.860019) (xy 393.562379 -178.807582)
			(xy 393.578876 -178.756948) (xy 393.602256 -178.709101) (xy 393.632064 -178.66497) (xy 393.667719 -178.625415)
			(xy 393.708531 -178.591203) (xy 393.753703 -178.563) (xy 393.80236 -178.541354) (xy 393.853554 -178.526687)
			(xy 393.906291 -178.519282) (xy 393.932918 -178.51882) (xy 393.96017 -178.519251) (xy 394.01412 -178.52701)
			(xy 394.066417 -178.542368) (xy 394.115995 -178.565012) (xy 394.161847 -178.594481) (xy 394.203038 -178.630175)
			(xy 394.23873 -178.671368) (xy 394.268197 -178.717221) (xy 394.290838 -178.7668) (xy 394.306194 -178.819097)
			(xy 394.31395 -178.873048) (xy 394.31395 -178.927552) (xy 394.306194 -178.981503) (xy 394.290838 -179.0338)
			(xy 394.268197 -179.083379) (xy 394.23873 -179.129232) (xy 394.203038 -179.170425) (xy 394.161847 -179.206119)
			(xy 394.115995 -179.235588) (xy 394.066417 -179.258232) (xy 394.01412 -179.27359) (xy 393.96017 -179.281349)
			(xy 393.932918 -179.281836) (xy 393.90561 -179.281384) (xy 393.851551 -179.273605) (xy 393.825222 -179.266342)
			(xy 393.810237 -179.262541) (xy 393.779343 -179.263063) (xy 393.750015 -179.272787) (xy 393.724929 -179.290825)
			(xy 393.706373 -179.315531) (xy 393.696042 -179.34465) (xy 393.69492 -179.360068) (xy 393.693497 -179.386661)
			(xy 393.684205 -179.439099) (xy 393.667709 -179.489734) (xy 393.64433 -179.537582) (xy 393.614523 -179.581713)
			(xy 393.578868 -179.62127) (xy 393.538056 -179.655482) (xy 393.492883 -179.683684) (xy 393.444226 -179.705329)
			(xy 393.393031 -179.719996) (xy 393.340293 -179.727399) (xy 393.313666 -179.72786) (xy 393.286413 -179.727468)
			(xy 393.232462 -179.719706) (xy 393.180165 -179.704346) (xy 393.130586 -179.6817) (xy 393.084734 -179.65223)
			(xy 393.043542 -179.616534) (xy 393.00785 -179.575339) (xy 392.978383 -179.529484) (xy 392.955742 -179.479903)
			(xy 392.940386 -179.427605) (xy 392.93263 -179.373653) (xy 370.610727 -179.373653) (xy 370.376958 -179.508658)
			(xy 370.34791 -179.524786) (xy 370.2865 -179.55015) (xy 370.22231 -179.567299) (xy 370.156433 -179.575942)
			(xy 370.123212 -179.576476) (xy 370.122704 -179.576476) (xy 370.089281 -179.575991) (xy 370.023005 -179.567283)
			(xy 369.958445 -179.549951) (xy 369.927378 -179.537614) (xy 369.917888 -179.534261) (xy 369.897781 -179.534367)
			(xy 369.879243 -179.542152) (xy 369.86509 -179.556435) (xy 369.86083 -179.565554) (xy 369.84983 -179.591715)
			(xy 369.821138 -179.64068) (xy 369.785509 -179.684854) (xy 369.743729 -179.723262) (xy 369.69672 -179.755056)
			(xy 369.645519 -179.779535) (xy 369.591256 -179.796158) (xy 369.53513 -179.804559) (xy 369.506754 -179.805076)
			(xy 369.479503 -179.804651) (xy 369.425555 -179.796889) (xy 369.373262 -179.781528) (xy 369.323686 -179.758882)
			(xy 369.277838 -179.729412) (xy 369.236649 -179.693718) (xy 369.20096 -179.652525) (xy 369.171495 -179.606673)
			(xy 369.148856 -179.557095) (xy 369.133502 -179.5048) (xy 369.125746 -179.450851) (xy 368.587677 -179.450851)
			(xy 368.44478 -179.593748) (xy 368.44478 -180.31079) (xy 393.417042 -180.31079) (xy 393.421113 -180.255168)
			(xy 393.433239 -180.200731) (xy 393.453162 -180.14864) (xy 393.480458 -180.100005) (xy 393.514544 -180.055862)
			(xy 393.554693 -180.017153) (xy 393.600051 -179.984702) (xy 393.649651 -179.959201) (xy 393.702435 -179.941194)
			(xy 393.757278 -179.931064) (xy 393.813012 -179.929027) (xy 393.868449 -179.935127) (xy 393.922406 -179.949233)
			(xy 393.973735 -179.971045) (xy 394.021341 -180.000099) (xy 394.064209 -180.035774) (xy 394.101426 -180.077311)
			(xy 394.132199 -180.123824) (xy 394.155871 -180.174321) (xy 394.171939 -180.227728) (xy 394.180059 -180.282904)
			(xy 394.180568 -180.31079) (xy 394.180059 -180.338676) (xy 394.171939 -180.393852) (xy 394.155871 -180.447259)
			(xy 394.132199 -180.497756) (xy 394.101426 -180.544269) (xy 394.064209 -180.585806) (xy 394.021341 -180.621481)
			(xy 393.973735 -180.650535) (xy 393.922406 -180.672347) (xy 393.868449 -180.686453) (xy 393.813012 -180.692553)
			(xy 393.757278 -180.690516) (xy 393.702435 -180.680386) (xy 393.649651 -180.662379) (xy 393.600051 -180.636878)
			(xy 393.554693 -180.604427) (xy 393.514544 -180.565718) (xy 393.480458 -180.521575) (xy 393.453162 -180.47294)
			(xy 393.433239 -180.420849) (xy 393.421113 -180.366412) (xy 393.417042 -180.31079) (xy 368.44478 -180.31079)
			(xy 368.44478 -182.49115) (xy 369.046503 -182.49115) (xy 369.046503 -182.43665) (xy 369.054259 -182.382706)
			(xy 369.069614 -182.330414) (xy 369.092254 -182.28084) (xy 369.121719 -182.234992) (xy 369.157409 -182.193804)
			(xy 369.198597 -182.158115) (xy 369.244445 -182.128651) (xy 369.29402 -182.106012) (xy 369.346312 -182.090658)
			(xy 369.400256 -182.082903) (xy 369.427506 -182.08244) (xy 369.446949 -182.082669) (xy 369.485633 -182.086615)
			(xy 369.504722 -182.090314) (xy 369.51782 -182.092594) (xy 369.544354 -182.091052) (xy 369.569596 -182.082731)
			(xy 369.591845 -182.068192) (xy 369.6096 -182.048415) (xy 369.621666 -182.024734) (xy 369.624864 -182.011828)
			(xy 369.631576 -181.982009) (xy 369.651189 -181.924118) (xy 369.677596 -181.868994) (xy 369.710416 -181.81743)
			(xy 369.749177 -181.770169) (xy 369.79332 -181.727891) (xy 369.84221 -181.691206) (xy 369.86845 -181.675532)
			(xy 370.792502 -181.141878) (xy 370.82156 -181.125769) (xy 370.882966 -181.1004) (xy 370.947153 -181.083245)
			(xy 371.013028 -181.074597) (xy 371.046248 -181.07406) (xy 371.046756 -181.07406) (xy 371.080179 -181.074555)
			(xy 371.146455 -181.083258) (xy 371.211015 -181.100587) (xy 371.242082 -181.112922) (xy 371.251563 -181.116338)
			(xy 371.271699 -181.116246) (xy 371.290265 -181.108452) (xy 371.304434 -181.094144) (xy 371.30863 -181.084982)
			(xy 371.319681 -181.058843) (xy 371.348365 -181.009879) (xy 371.383986 -180.965704) (xy 371.425758 -180.927294)
			(xy 371.47276 -180.895497) (xy 371.523955 -180.871014) (xy 371.578211 -180.854386) (xy 371.634332 -180.84598)
			(xy 371.662706 -180.84546) (xy 371.689955 -180.846011) (xy 371.743897 -180.853767) (xy 371.796187 -180.869121)
			(xy 371.845759 -180.891761) (xy 371.891605 -180.921225) (xy 371.932791 -180.956913) (xy 371.968479 -180.9981)
			(xy 371.997942 -181.043946) (xy 372.020581 -181.093519) (xy 372.035934 -181.145809) (xy 372.04369 -181.199751)
			(xy 372.04369 -181.254249) (xy 372.035934 -181.308191) (xy 372.020581 -181.360481) (xy 372.011096 -181.381251)
			(xy 372.910346 -181.381251) (xy 372.910346 -181.326749) (xy 372.918102 -181.2728) (xy 372.933456 -181.220505)
			(xy 372.956095 -181.170927) (xy 372.98556 -181.125075) (xy 373.021249 -181.083882) (xy 373.062438 -181.048188)
			(xy 373.108286 -181.018718) (xy 373.157862 -180.996072) (xy 373.210155 -180.980711) (xy 373.264103 -180.972949)
			(xy 373.291354 -180.97246) (xy 373.319727 -180.972978) (xy 373.375847 -180.981391) (xy 373.430102 -180.998023)
			(xy 373.481295 -181.022507) (xy 373.528297 -181.054303) (xy 373.570071 -181.09271) (xy 373.605696 -181.136881)
			(xy 373.634386 -181.185841) (xy 373.64543 -181.211982) (xy 373.649555 -181.221205) (xy 373.663696 -181.235614)
			(xy 373.682312 -181.243426) (xy 373.7025 -181.243423) (xy 373.711978 -181.239922) (xy 373.743057 -181.227621)
			(xy 373.807615 -181.210305) (xy 373.873884 -181.201579) (xy 373.907304 -181.20106) (xy 373.907812 -181.20106)
			(xy 373.941031 -181.201606) (xy 374.006903 -181.210264) (xy 374.071088 -181.227419) (xy 374.132496 -181.252778)
			(xy 374.161558 -181.268878) (xy 375.08561 -181.802532) (xy 375.114227 -181.819663) (xy 375.167141 -181.860264)
			(xy 375.214298 -181.90743) (xy 375.25489 -181.960352) (xy 375.288221 -182.018122) (xy 375.313719 -182.079752)
			(xy 375.330949 -182.144184) (xy 375.3358 -182.177182) (xy 375.337563 -182.187112) (xy 375.347644 -182.204558)
			(xy 375.363672 -182.216767) (xy 375.383168 -182.221853) (xy 375.393204 -182.22087) (xy 375.406657 -182.219077)
			(xy 375.433734 -182.217171) (xy 375.447306 -182.21706) (xy 375.474555 -182.217611) (xy 375.528497 -182.225367)
			(xy 375.580787 -182.240721) (xy 375.630359 -182.263361) (xy 375.676205 -182.292825) (xy 375.717391 -182.328513)
			(xy 375.753079 -182.3697) (xy 375.782542 -182.415546) (xy 375.805181 -182.465119) (xy 375.820534 -182.517409)
			(xy 375.82829 -182.571351) (xy 375.82829 -182.625849) (xy 375.820534 -182.679791) (xy 375.805181 -182.732081)
			(xy 375.782542 -182.781654) (xy 375.753079 -182.8275) (xy 375.717391 -182.868687) (xy 375.676205 -182.904375)
			(xy 375.630359 -182.933839) (xy 375.580787 -182.956479) (xy 375.528497 -182.971833) (xy 375.474555 -182.979589)
			(xy 375.447306 -182.980076) (xy 375.418933 -182.979569) (xy 375.362813 -182.971152) (xy 375.30856 -182.954516)
			(xy 375.257368 -182.93003) (xy 375.210366 -182.898232) (xy 375.168592 -182.859824) (xy 375.132966 -182.815654)
			(xy 375.104275 -182.766695) (xy 375.09323 -182.740554) (xy 375.089063 -182.731357) (xy 375.07493 -182.716961)
			(xy 375.056331 -182.709146) (xy 375.036158 -182.709128) (xy 375.026682 -182.712614) (xy 374.995609 -182.724929)
			(xy 374.931047 -182.742239) (xy 374.864777 -182.75096) (xy 374.831356 -182.751476) (xy 374.830848 -182.751476)
			(xy 374.797629 -182.750942) (xy 374.731757 -182.74228) (xy 374.667571 -182.725122) (xy 374.606164 -182.699759)
			(xy 374.577102 -182.683658) (xy 373.65305 -182.150004) (xy 373.624423 -182.132889) (xy 373.571507 -182.092287)
			(xy 373.524348 -182.04512) (xy 373.483757 -181.992196) (xy 373.450428 -181.934422) (xy 373.424932 -181.872789)
			(xy 373.407708 -181.808353) (xy 373.40286 -181.775354) (xy 373.401115 -181.765418) (xy 373.391034 -181.747964)
			(xy 373.374999 -181.735753) (xy 373.355494 -181.730676) (xy 373.345456 -181.731666) (xy 373.332002 -181.733453)
			(xy 373.304926 -181.735363) (xy 373.291354 -181.735476) (xy 373.264103 -181.735051) (xy 373.210155 -181.727289)
			(xy 373.157862 -181.711928) (xy 373.108286 -181.689282) (xy 373.062438 -181.659812) (xy 373.021249 -181.624118)
			(xy 372.98556 -181.582925) (xy 372.956095 -181.537073) (xy 372.933456 -181.487495) (xy 372.918102 -181.4352)
			(xy 372.910346 -181.381251) (xy 372.011096 -181.381251) (xy 371.997942 -181.410054) (xy 371.968479 -181.4559)
			(xy 371.932791 -181.497087) (xy 371.891605 -181.532775) (xy 371.845759 -181.562239) (xy 371.796187 -181.584879)
			(xy 371.743897 -181.600233) (xy 371.689955 -181.607989) (xy 371.662706 -181.608476) (xy 371.649134 -181.608377)
			(xy 371.622057 -181.606468) (xy 371.608604 -181.604666) (xy 371.59857 -181.603685) (xy 371.57908 -181.608791)
			(xy 371.56305 -181.620995) (xy 371.552942 -181.638423) (xy 371.5512 -181.648354) (xy 371.546342 -181.681352)
			(xy 371.529125 -181.745789) (xy 371.503635 -181.807424) (xy 371.470307 -181.865199) (xy 371.429715 -181.918123)
			(xy 371.382554 -181.965287) (xy 371.329634 -182.005884) (xy 371.30101 -182.023004) (xy 370.376958 -182.556658)
			(xy 370.34791 -182.572786) (xy 370.2865 -182.59815) (xy 370.22231 -182.615299) (xy 370.156433 -182.623942)
			(xy 370.123212 -182.624476) (xy 370.122704 -182.624476) (xy 370.085716 -182.623822) (xy 370.012514 -182.613154)
			(xy 369.941633 -182.591985) (xy 369.90782 -182.576978) (xy 369.895566 -182.571811) (xy 369.869385 -182.567226)
			(xy 369.842906 -182.569549) (xy 369.817923 -182.578624) (xy 369.796126 -182.593837) (xy 369.778991 -182.614156)
			(xy 369.772946 -182.626) (xy 369.761066 -182.65026) (xy 369.731442 -182.695431) (xy 369.695744 -182.735974)
			(xy 369.654687 -182.771078) (xy 369.60909 -182.800042) (xy 369.559864 -182.822288) (xy 369.507994 -182.83737)
			(xy 369.454515 -182.844987) (xy 369.427506 -182.845456) (xy 369.400256 -182.844897) (xy 369.346312 -182.837142)
			(xy 369.29402 -182.821788) (xy 369.244445 -182.799149) (xy 369.198597 -182.769685) (xy 369.157409 -182.733996)
			(xy 369.121719 -182.692808) (xy 369.092254 -182.64696) (xy 369.069614 -182.597386) (xy 369.054259 -182.545094)
			(xy 369.046503 -182.49115) (xy 368.44478 -182.49115) (xy 368.44478 -183.076088) (xy 368.261646 -183.259222)
			(xy 373.211596 -183.259222) (xy 373.215667 -183.2036) (xy 373.227793 -183.149163) (xy 373.247716 -183.097072)
			(xy 373.275012 -183.048437) (xy 373.309098 -183.004294) (xy 373.349247 -182.965585) (xy 373.394605 -182.933134)
			(xy 373.444205 -182.907633) (xy 373.496989 -182.889626) (xy 373.551832 -182.879496) (xy 373.607566 -182.877459)
			(xy 373.663003 -182.883559) (xy 373.71696 -182.897665) (xy 373.768289 -182.919477) (xy 373.815895 -182.948531)
			(xy 373.858763 -182.984206) (xy 373.89598 -183.025743) (xy 373.926753 -183.072256) (xy 373.950425 -183.122753)
			(xy 373.966493 -183.17616) (xy 373.974613 -183.231336) (xy 373.975122 -183.259222) (xy 373.974613 -183.287108)
			(xy 373.966493 -183.342284) (xy 373.950425 -183.395691) (xy 373.926753 -183.446188) (xy 373.89598 -183.492701)
			(xy 373.858763 -183.534238) (xy 373.815895 -183.569913) (xy 373.768289 -183.598967) (xy 373.71696 -183.620779)
			(xy 373.663003 -183.634885) (xy 373.607566 -183.640985) (xy 373.551832 -183.638948) (xy 373.496989 -183.628818)
			(xy 373.444205 -183.610811) (xy 373.394605 -183.58531) (xy 373.349247 -183.552859) (xy 373.309098 -183.51415)
			(xy 373.275012 -183.470007) (xy 373.247716 -183.421372) (xy 373.227793 -183.369281) (xy 373.215667 -183.314844)
			(xy 373.211596 -183.259222) (xy 368.261646 -183.259222) (xy 366.876838 -184.64403) (xy 369.50218 -184.64403)
			(xy 369.506251 -184.588408) (xy 369.518377 -184.533971) (xy 369.5383 -184.48188) (xy 369.565596 -184.433245)
			(xy 369.599682 -184.389102) (xy 369.639831 -184.350393) (xy 369.685189 -184.317942) (xy 369.734789 -184.292441)
			(xy 369.787573 -184.274434) (xy 369.842416 -184.264304) (xy 369.89815 -184.262267) (xy 369.953587 -184.268367)
			(xy 370.007544 -184.282473) (xy 370.058873 -184.304285) (xy 370.106479 -184.333339) (xy 370.149347 -184.369014)
			(xy 370.186564 -184.410551) (xy 370.217337 -184.457064) (xy 370.241009 -184.507561) (xy 370.257077 -184.560968)
			(xy 370.265197 -184.616144) (xy 370.265706 -184.64403) (xy 370.265197 -184.671916) (xy 370.263529 -184.683251)
			(xy 372.097546 -184.683251) (xy 372.097546 -184.628749) (xy 372.105302 -184.5748) (xy 372.120656 -184.522505)
			(xy 372.143295 -184.472927) (xy 372.17276 -184.427075) (xy 372.208449 -184.385882) (xy 372.249638 -184.350188)
			(xy 372.295486 -184.320718) (xy 372.345062 -184.298072) (xy 372.397355 -184.282711) (xy 372.451303 -184.274949)
			(xy 372.478554 -184.27446) (xy 372.506927 -184.274978) (xy 372.563047 -184.283391) (xy 372.617302 -184.300023)
			(xy 372.668495 -184.324507) (xy 372.715497 -184.356303) (xy 372.757271 -184.39471) (xy 372.792896 -184.438881)
			(xy 372.821586 -184.487841) (xy 372.83263 -184.513982) (xy 372.836755 -184.523205) (xy 372.850896 -184.537614)
			(xy 372.869512 -184.545426) (xy 372.8897 -184.545423) (xy 372.899178 -184.541922) (xy 372.930257 -184.529621)
			(xy 372.994815 -184.512305) (xy 373.061084 -184.503579) (xy 373.094504 -184.50306) (xy 373.095012 -184.50306)
			(xy 373.128231 -184.503606) (xy 373.194103 -184.512264) (xy 373.258288 -184.529419) (xy 373.319696 -184.554778)
			(xy 373.348758 -184.570878) (xy 374.27281 -185.104532) (xy 374.301427 -185.121663) (xy 374.354341 -185.162264)
			(xy 374.401498 -185.20943) (xy 374.44209 -185.262352) (xy 374.475421 -185.320122) (xy 374.500919 -185.381752)
			(xy 374.518149 -185.446184) (xy 374.523 -185.479182) (xy 374.524763 -185.489112) (xy 374.534844 -185.506558)
			(xy 374.550872 -185.518767) (xy 374.570368 -185.523853) (xy 374.580404 -185.52287) (xy 374.593857 -185.521077)
			(xy 374.620934 -185.519171) (xy 374.634506 -185.51906) (xy 374.661755 -185.519611) (xy 374.715697 -185.527367)
			(xy 374.767987 -185.542721) (xy 374.817559 -185.565361) (xy 374.863405 -185.594825) (xy 374.904591 -185.630513)
			(xy 374.940279 -185.6717) (xy 374.969742 -185.717546) (xy 374.992381 -185.767119) (xy 375.007734 -185.819409)
			(xy 375.01549 -185.873351) (xy 375.01549 -185.927849) (xy 375.007734 -185.981791) (xy 374.992381 -186.034081)
			(xy 374.982596 -186.055508) (xy 380.051562 -186.055508) (xy 380.055633 -185.999886) (xy 380.067759 -185.945449)
			(xy 380.087682 -185.893358) (xy 380.114978 -185.844723) (xy 380.149064 -185.80058) (xy 380.189213 -185.761871)
			(xy 380.234571 -185.72942) (xy 380.284171 -185.703919) (xy 380.336955 -185.685912) (xy 380.391798 -185.675782)
			(xy 380.447532 -185.673745) (xy 380.502969 -185.679845) (xy 380.556926 -185.693951) (xy 380.608255 -185.715763)
			(xy 380.655861 -185.744817) (xy 380.698729 -185.780492) (xy 380.735946 -185.822029) (xy 380.766719 -185.868542)
			(xy 380.790391 -185.919039) (xy 380.806459 -185.972446) (xy 380.814579 -186.027622) (xy 380.815088 -186.055508)
			(xy 380.814579 -186.083394) (xy 380.806459 -186.13857) (xy 380.790391 -186.191977) (xy 380.766719 -186.242474)
			(xy 380.735946 -186.288987) (xy 380.698729 -186.330524) (xy 380.655861 -186.366199) (xy 380.608255 -186.395253)
			(xy 380.556926 -186.417065) (xy 380.502969 -186.431171) (xy 380.447532 -186.437271) (xy 380.391798 -186.435234)
			(xy 380.336955 -186.425104) (xy 380.284171 -186.407097) (xy 380.234571 -186.381596) (xy 380.189213 -186.349145)
			(xy 380.149064 -186.310436) (xy 380.114978 -186.266293) (xy 380.087682 -186.217658) (xy 380.067759 -186.165567)
			(xy 380.055633 -186.11113) (xy 380.051562 -186.055508) (xy 374.982596 -186.055508) (xy 374.969742 -186.083654)
			(xy 374.940279 -186.1295) (xy 374.904591 -186.170687) (xy 374.863405 -186.206375) (xy 374.817559 -186.235839)
			(xy 374.767987 -186.258479) (xy 374.715697 -186.273833) (xy 374.661755 -186.281589) (xy 374.634506 -186.282076)
			(xy 374.606133 -186.281569) (xy 374.550013 -186.273152) (xy 374.49576 -186.256516) (xy 374.444568 -186.23203)
			(xy 374.397566 -186.200232) (xy 374.355792 -186.161824) (xy 374.320166 -186.117654) (xy 374.291475 -186.068695)
			(xy 374.28043 -186.042554) (xy 374.276263 -186.033357) (xy 374.26213 -186.018961) (xy 374.243531 -186.011146)
			(xy 374.223358 -186.011128) (xy 374.213882 -186.014614) (xy 374.182809 -186.026929) (xy 374.118247 -186.044239)
			(xy 374.051977 -186.05296) (xy 374.018556 -186.053476) (xy 374.018048 -186.053476) (xy 373.984829 -186.052942)
			(xy 373.918957 -186.04428) (xy 373.854771 -186.027122) (xy 373.793364 -186.001759) (xy 373.764302 -185.985658)
			(xy 372.84025 -185.452004) (xy 372.811623 -185.434889) (xy 372.758707 -185.394287) (xy 372.711548 -185.34712)
			(xy 372.670957 -185.294196) (xy 372.637628 -185.236422) (xy 372.612132 -185.174789) (xy 372.594908 -185.110353)
			(xy 372.59006 -185.077354) (xy 372.588315 -185.067418) (xy 372.578234 -185.049964) (xy 372.562199 -185.037753)
			(xy 372.542694 -185.032676) (xy 372.532656 -185.033666) (xy 372.519202 -185.035453) (xy 372.492126 -185.037363)
			(xy 372.478554 -185.037476) (xy 372.451303 -185.037051) (xy 372.397355 -185.029289) (xy 372.345062 -185.013928)
			(xy 372.295486 -184.991282) (xy 372.249638 -184.961812) (xy 372.208449 -184.926118) (xy 372.17276 -184.884925)
			(xy 372.143295 -184.839073) (xy 372.120656 -184.789495) (xy 372.105302 -184.7372) (xy 372.097546 -184.683251)
			(xy 370.263529 -184.683251) (xy 370.257077 -184.727092) (xy 370.241009 -184.780499) (xy 370.217337 -184.830996)
			(xy 370.186564 -184.877509) (xy 370.149347 -184.919046) (xy 370.106479 -184.954721) (xy 370.058873 -184.983775)
			(xy 370.007544 -185.005587) (xy 369.953587 -185.019693) (xy 369.89815 -185.025793) (xy 369.842416 -185.023756)
			(xy 369.787573 -185.013626) (xy 369.734789 -184.995619) (xy 369.685189 -184.970118) (xy 369.639831 -184.937667)
			(xy 369.599682 -184.898958) (xy 369.565596 -184.854815) (xy 369.5383 -184.80618) (xy 369.518377 -184.754089)
			(xy 369.506251 -184.699652) (xy 369.50218 -184.64403) (xy 366.876838 -184.64403) (xy 366.150398 -185.37047)
			(xy 370.50548 -185.37047) (xy 370.509551 -185.314848) (xy 370.521677 -185.260411) (xy 370.5416 -185.20832)
			(xy 370.568896 -185.159685) (xy 370.602982 -185.115542) (xy 370.643131 -185.076833) (xy 370.688489 -185.044382)
			(xy 370.738089 -185.018881) (xy 370.790873 -185.000874) (xy 370.845716 -184.990744) (xy 370.90145 -184.988707)
			(xy 370.956887 -184.994807) (xy 371.010844 -185.008913) (xy 371.062173 -185.030725) (xy 371.109779 -185.059779)
			(xy 371.152647 -185.095454) (xy 371.189864 -185.136991) (xy 371.220637 -185.183504) (xy 371.244309 -185.234001)
			(xy 371.260377 -185.287408) (xy 371.268497 -185.342584) (xy 371.269006 -185.37047) (xy 371.268497 -185.398356)
			(xy 371.260377 -185.453532) (xy 371.244309 -185.506939) (xy 371.220637 -185.557436) (xy 371.189864 -185.603949)
			(xy 371.152647 -185.645486) (xy 371.109779 -185.681161) (xy 371.062173 -185.710215) (xy 371.010844 -185.732027)
			(xy 370.956887 -185.746133) (xy 370.90145 -185.752233) (xy 370.845716 -185.750196) (xy 370.790873 -185.740066)
			(xy 370.738089 -185.722059) (xy 370.688489 -185.696558) (xy 370.643131 -185.664107) (xy 370.602982 -185.625398)
			(xy 370.568896 -185.581255) (xy 370.5416 -185.53262) (xy 370.521677 -185.480529) (xy 370.509551 -185.426092)
			(xy 370.50548 -185.37047) (xy 366.150398 -185.37047) (xy 365.745014 -185.775854) (xy 369.36375 -185.775854)
			(xy 369.367821 -185.720232) (xy 369.379947 -185.665795) (xy 369.39987 -185.613704) (xy 369.427166 -185.565069)
			(xy 369.461252 -185.520926) (xy 369.501401 -185.482217) (xy 369.546759 -185.449766) (xy 369.596359 -185.424265)
			(xy 369.649143 -185.406258) (xy 369.703986 -185.396128) (xy 369.75972 -185.394091) (xy 369.815157 -185.400191)
			(xy 369.869114 -185.414297) (xy 369.920443 -185.436109) (xy 369.968049 -185.465163) (xy 370.010917 -185.500838)
			(xy 370.048134 -185.542375) (xy 370.078907 -185.588888) (xy 370.102579 -185.639385) (xy 370.118647 -185.692792)
			(xy 370.126767 -185.747968) (xy 370.127276 -185.775854) (xy 370.126767 -185.80374) (xy 370.118647 -185.858916)
			(xy 370.102579 -185.912323) (xy 370.078907 -185.96282) (xy 370.048134 -186.009333) (xy 370.010917 -186.05087)
			(xy 369.968049 -186.086545) (xy 369.920443 -186.115599) (xy 369.869114 -186.137411) (xy 369.815157 -186.151517)
			(xy 369.75972 -186.157617) (xy 369.703986 -186.15558) (xy 369.649143 -186.14545) (xy 369.596359 -186.127443)
			(xy 369.546759 -186.101942) (xy 369.501401 -186.069491) (xy 369.461252 -186.030782) (xy 369.427166 -185.986639)
			(xy 369.39987 -185.938004) (xy 369.379947 -185.885913) (xy 369.367821 -185.831476) (xy 369.36375 -185.775854)
			(xy 365.745014 -185.775854) (xy 363.805978 -187.71489) (xy 369.84813 -187.71489) (xy 369.848588 -187.687829)
			(xy 369.856255 -187.634252) (xy 369.871419 -187.582297) (xy 369.893775 -187.533008) (xy 369.922876 -187.487374)
			(xy 369.958135 -187.446312) (xy 369.978178 -187.428124) (xy 369.988628 -187.418318) (xy 370.004113 -187.394223)
			(xy 370.012298 -187.366775) (xy 370.01254 -187.338134) (xy 370.00482 -187.310552) (xy 369.989744 -187.286198)
			(xy 369.979448 -187.276232) (xy 369.960047 -187.258099) (xy 369.925991 -187.217353) (xy 369.897921 -187.172273)
			(xy 369.876382 -187.123734) (xy 369.861789 -187.072674) (xy 369.854427 -187.020082) (xy 369.853972 -186.99353)
			(xy 369.854486 -186.966592) (xy 369.862063 -186.913251) (xy 369.877068 -186.861507) (xy 369.899205 -186.812389)
			(xy 369.928033 -186.766874) (xy 369.962978 -186.725867) (xy 370.003345 -186.690186) (xy 370.04833 -186.660539)
			(xy 370.09704 -186.637517) (xy 370.148504 -186.621576) (xy 370.175028 -186.616848) (xy 370.188069 -186.614283)
			(xy 370.212312 -186.603417) (xy 370.232929 -186.586664) (xy 370.248525 -186.565157) (xy 370.258042 -186.540354)
			(xy 370.260837 -186.513936) (xy 370.256719 -186.487691) (xy 370.251736 -186.47537) (xy 370.241367 -186.450871)
			(xy 370.226766 -186.399716) (xy 370.219412 -186.347029) (xy 370.21897 -186.32043) (xy 370.219456 -186.293179)
			(xy 370.227212 -186.239231) (xy 370.242567 -186.186936) (xy 370.265209 -186.137359) (xy 370.294675 -186.091509)
			(xy 370.330366 -186.050318) (xy 370.371557 -186.014627) (xy 370.417407 -185.985161) (xy 370.466984 -185.962519)
			(xy 370.519279 -185.947164) (xy 370.573227 -185.939408) (xy 370.627729 -185.939408) (xy 370.681677 -185.947164)
			(xy 370.733972 -185.962519) (xy 370.783549 -185.985161) (xy 370.829399 -186.014627) (xy 370.87059 -186.050318)
			(xy 370.906281 -186.091509) (xy 370.935747 -186.137359) (xy 370.958389 -186.186936) (xy 370.973744 -186.239231)
			(xy 370.9815 -186.293179) (xy 370.981986 -186.32043) (xy 370.981562 -186.347371) (xy 370.973977 -186.400718)
			(xy 370.958961 -186.452466) (xy 370.936814 -186.501587) (xy 370.907976 -186.547103) (xy 370.873021 -186.588109)
			(xy 370.832644 -186.623789) (xy 370.787649 -186.653433) (xy 370.73893 -186.676452) (xy 370.687458 -186.692387)
			(xy 370.66093 -186.697112) (xy 370.647897 -186.699704) (xy 370.623663 -186.710572) (xy 370.603052 -186.727323)
			(xy 370.58746 -186.748824) (xy 370.577941 -186.773619) (xy 370.57514 -186.80003) (xy 370.579246 -186.82627)
			(xy 370.584222 -186.83859) (xy 370.592486 -186.858148) (xy 374.039382 -186.858148) (xy 374.043453 -186.802526)
			(xy 374.055579 -186.748089) (xy 374.075502 -186.695998) (xy 374.102798 -186.647363) (xy 374.136884 -186.60322)
			(xy 374.177033 -186.564511) (xy 374.222391 -186.53206) (xy 374.271991 -186.506559) (xy 374.324775 -186.488552)
			(xy 374.379618 -186.478422) (xy 374.435352 -186.476385) (xy 374.490789 -186.482485) (xy 374.544746 -186.496591)
			(xy 374.596075 -186.518403) (xy 374.643681 -186.547457) (xy 374.686549 -186.583132) (xy 374.723766 -186.624669)
			(xy 374.754539 -186.671182) (xy 374.778211 -186.721679) (xy 374.794279 -186.775086) (xy 374.802399 -186.830262)
			(xy 374.802908 -186.858148) (xy 374.802399 -186.886034) (xy 374.794279 -186.94121) (xy 374.778211 -186.994617)
			(xy 374.754539 -187.045114) (xy 374.723766 -187.091627) (xy 374.686549 -187.133164) (xy 374.643681 -187.168839)
			(xy 374.596075 -187.197893) (xy 374.544746 -187.219705) (xy 374.490789 -187.233811) (xy 374.435352 -187.239911)
			(xy 374.379618 -187.237874) (xy 374.324775 -187.227744) (xy 374.271991 -187.209737) (xy 374.222391 -187.184236)
			(xy 374.177033 -187.151785) (xy 374.136884 -187.113076) (xy 374.102798 -187.068933) (xy 374.075502 -187.020298)
			(xy 374.055579 -186.968207) (xy 374.043453 -186.91377) (xy 374.039382 -186.858148) (xy 370.592486 -186.858148)
			(xy 370.594576 -186.863095) (xy 370.609184 -186.914246) (xy 370.616543 -186.966931) (xy 370.616988 -186.99353)
			(xy 370.61647 -187.020589) (xy 370.608814 -187.074163) (xy 370.593662 -187.126117) (xy 370.571317 -187.175406)
			(xy 370.542227 -187.221041) (xy 370.506978 -187.262106) (xy 370.48694 -187.280296) (xy 370.476476 -187.290085)
			(xy 370.461005 -187.314188) (xy 370.452829 -187.341638) (xy 370.45259 -187.370279) (xy 370.460309 -187.397861)
			(xy 370.475378 -187.422218) (xy 370.48567 -187.432188) (xy 370.505035 -187.450357) (xy 370.539094 -187.491096)
			(xy 370.567168 -187.536168) (xy 370.588714 -187.584701) (xy 370.603314 -187.635754) (xy 370.610686 -187.68834)
			(xy 370.611146 -187.71489) (xy 370.610691 -187.741754) (xy 370.603143 -187.79495) (xy 370.588209 -187.846561)
			(xy 370.566184 -187.895568) (xy 370.537503 -187.941001) (xy 370.520468 -187.961778) (xy 370.511027 -187.973755)
			(xy 370.499095 -188.001807) (xy 370.495953 -188.032128) (xy 370.50188 -188.06203) (xy 370.51635 -188.088861)
			(xy 370.526818 -188.099954) (xy 370.548014 -188.121619) (xy 370.583974 -188.170406) (xy 370.611767 -188.224264)
			(xy 370.630695 -188.28184) (xy 370.632644 -188.29401) (xy 382.993392 -188.29401) (xy 382.993945 -188.265472)
			(xy 383.002435 -188.209031) (xy 383.019241 -188.154486) (xy 383.043988 -188.103055) (xy 383.076123 -188.055885)
			(xy 383.11493 -188.014032) (xy 383.136902 -187.995814) (xy 383.147143 -187.98716) (xy 383.163017 -187.965562)
			(xy 383.172726 -187.940577) (xy 383.175599 -187.913927) (xy 383.171439 -187.887447) (xy 383.160532 -187.862962)
			(xy 383.152396 -187.852304) (xy 383.136247 -187.83179) (xy 383.109068 -187.787213) (xy 383.088225 -187.739345)
			(xy 383.074106 -187.689082) (xy 383.066976 -187.637362) (xy 383.066544 -187.611258) (xy 383.06703 -187.584007)
			(xy 383.074786 -187.530059) (xy 383.090141 -187.477764) (xy 383.112783 -187.428187) (xy 383.142249 -187.382337)
			(xy 383.17794 -187.341146) (xy 383.219131 -187.305455) (xy 383.264981 -187.275989) (xy 383.314558 -187.253347)
			(xy 383.366853 -187.237992) (xy 383.420801 -187.230236) (xy 383.475303 -187.230236) (xy 383.529251 -187.237992)
			(xy 383.581546 -187.253347) (xy 383.631123 -187.275989) (xy 383.676973 -187.305455) (xy 383.718164 -187.341146)
			(xy 383.753855 -187.382337) (xy 383.783321 -187.428187) (xy 383.805963 -187.477764) (xy 383.821318 -187.530059)
			(xy 383.829074 -187.584007) (xy 383.82956 -187.611258) (xy 383.829036 -187.639797) (xy 383.820538 -187.696238)
			(xy 383.803725 -187.750783) (xy 383.778972 -187.802214) (xy 383.746833 -187.849383) (xy 383.708024 -187.891236)
			(xy 383.68605 -187.909454) (xy 383.675837 -187.918136) (xy 383.659968 -187.939729) (xy 383.650261 -187.964706)
			(xy 383.647384 -187.991348) (xy 383.651534 -188.017822) (xy 383.662427 -188.042305) (xy 383.670556 -188.052964)
			(xy 383.686744 -188.073449) (xy 383.713915 -188.118034) (xy 383.73475 -188.16591) (xy 383.74886 -188.216179)
			(xy 383.755981 -188.267904) (xy 383.756408 -188.29401) (xy 383.755922 -188.321261) (xy 383.748166 -188.375209)
			(xy 383.732811 -188.427504) (xy 383.710169 -188.477081) (xy 383.680703 -188.522931) (xy 383.645012 -188.564122)
			(xy 383.603821 -188.599813) (xy 383.557971 -188.629279) (xy 383.508394 -188.651921) (xy 383.456099 -188.667276)
			(xy 383.402151 -188.675032) (xy 383.347649 -188.675032) (xy 383.293701 -188.667276) (xy 383.241406 -188.651921)
			(xy 383.191829 -188.629279) (xy 383.145979 -188.599813) (xy 383.104788 -188.564122) (xy 383.069097 -188.522931)
			(xy 383.039631 -188.477081) (xy 383.016989 -188.427504) (xy 383.001634 -188.375209) (xy 382.993878 -188.321261)
			(xy 382.993392 -188.29401) (xy 370.632644 -188.29401) (xy 370.64028 -188.341684) (xy 370.640864 -188.371988)
			(xy 370.640378 -188.399239) (xy 370.632622 -188.453187) (xy 370.617267 -188.505482) (xy 370.594625 -188.555059)
			(xy 370.565159 -188.600909) (xy 370.529468 -188.6421) (xy 370.488277 -188.677791) (xy 370.442427 -188.707257)
			(xy 370.39285 -188.729899) (xy 370.340555 -188.745254) (xy 370.286607 -188.75301) (xy 370.232105 -188.75301)
			(xy 370.178157 -188.745254) (xy 370.125862 -188.729899) (xy 370.076285 -188.707257) (xy 370.030435 -188.677791)
			(xy 369.989244 -188.6421) (xy 369.953553 -188.600909) (xy 369.924087 -188.555059) (xy 369.901445 -188.505482)
			(xy 369.88609 -188.453187) (xy 369.878334 -188.399239) (xy 369.877848 -188.371988) (xy 369.878292 -188.345124)
			(xy 369.885843 -188.291927) (xy 369.90078 -188.240316) (xy 369.922807 -188.19131) (xy 369.95149 -188.145877)
			(xy 369.968526 -188.1251) (xy 369.977889 -188.113066) (xy 369.989832 -188.085036) (xy 369.99299 -188.054732)
			(xy 369.987082 -188.024842) (xy 369.972633 -187.998017) (xy 369.962176 -187.986924) (xy 369.940968 -187.96527)
			(xy 369.90501 -187.91648) (xy 369.877219 -187.862619) (xy 369.858294 -187.805041) (xy 369.848712 -187.745194)
			(xy 369.84813 -187.71489) (xy 363.805978 -187.71489) (xy 361.708446 -189.812422) (xy 381.82372 -189.812422)
			(xy 381.827791 -189.7568) (xy 381.839917 -189.702363) (xy 381.85984 -189.650272) (xy 381.887136 -189.601637)
			(xy 381.921222 -189.557494) (xy 381.961371 -189.518785) (xy 382.006729 -189.486334) (xy 382.056329 -189.460833)
			(xy 382.109113 -189.442826) (xy 382.163956 -189.432696) (xy 382.21969 -189.430659) (xy 382.275127 -189.436759)
			(xy 382.329084 -189.450865) (xy 382.380413 -189.472677) (xy 382.428019 -189.501731) (xy 382.470887 -189.537406)
			(xy 382.508104 -189.578943) (xy 382.538877 -189.625456) (xy 382.562549 -189.675953) (xy 382.578617 -189.72936)
			(xy 382.586737 -189.784536) (xy 382.587246 -189.812422) (xy 382.586737 -189.840308) (xy 382.578617 -189.895484)
			(xy 382.562549 -189.948891) (xy 382.538877 -189.999388) (xy 382.508104 -190.045901) (xy 382.470887 -190.087438)
			(xy 382.428019 -190.123113) (xy 382.380413 -190.152167) (xy 382.329084 -190.173979) (xy 382.275127 -190.188085)
			(xy 382.21969 -190.194185) (xy 382.163956 -190.192148) (xy 382.109113 -190.182018) (xy 382.056329 -190.164011)
			(xy 382.006729 -190.13851) (xy 381.961371 -190.106059) (xy 381.921222 -190.06735) (xy 381.887136 -190.023207)
			(xy 381.85984 -189.974572) (xy 381.839917 -189.922481) (xy 381.827791 -189.868044) (xy 381.82372 -189.812422)
			(xy 361.708446 -189.812422) (xy 361.29722 -190.223648) (xy 386.842252 -190.223648) (xy 386.846323 -190.168026)
			(xy 386.858449 -190.113589) (xy 386.878372 -190.061498) (xy 386.905668 -190.012863) (xy 386.939754 -189.96872)
			(xy 386.979903 -189.930011) (xy 387.025261 -189.89756) (xy 387.074861 -189.872059) (xy 387.127645 -189.854052)
			(xy 387.182488 -189.843922) (xy 387.238222 -189.841885) (xy 387.293659 -189.847985) (xy 387.347616 -189.862091)
			(xy 387.398945 -189.883903) (xy 387.446551 -189.912957) (xy 387.489419 -189.948632) (xy 387.526636 -189.990169)
			(xy 387.557409 -190.036682) (xy 387.581081 -190.087179) (xy 387.597149 -190.140586) (xy 387.605269 -190.195762)
			(xy 387.605778 -190.223648) (xy 387.605269 -190.251534) (xy 387.597149 -190.30671) (xy 387.581081 -190.360117)
			(xy 387.557409 -190.410614) (xy 387.526636 -190.457127) (xy 387.489419 -190.498664) (xy 387.446551 -190.534339)
			(xy 387.398945 -190.563393) (xy 387.347616 -190.585205) (xy 387.293659 -190.599311) (xy 387.238222 -190.605411)
			(xy 387.182488 -190.603374) (xy 387.127645 -190.593244) (xy 387.074861 -190.575237) (xy 387.025261 -190.549736)
			(xy 386.979903 -190.517285) (xy 386.939754 -190.478576) (xy 386.905668 -190.434433) (xy 386.878372 -190.385798)
			(xy 386.858449 -190.333707) (xy 386.846323 -190.27927) (xy 386.842252 -190.223648) (xy 361.29722 -190.223648)
			(xy 359.918254 -191.602614) (xy 359.918254 -213.759267) (xy 363.453924 -213.759267) (xy 363.453924 -213.705969)
			(xy 363.461867 -213.653265) (xy 363.477577 -213.602335) (xy 363.500703 -213.554314) (xy 363.530727 -213.510277)
			(xy 363.566979 -213.471206) (xy 363.60865 -213.437975) (xy 363.654808 -213.411326) (xy 363.704422 -213.391854)
			(xy 363.756384 -213.379994) (xy 363.809534 -213.376011) (xy 363.862684 -213.379994) (xy 363.914646 -213.391854)
			(xy 363.96426 -213.411326) (xy 364.010418 -213.437975) (xy 364.052089 -213.471206) (xy 364.088341 -213.510277)
			(xy 364.118365 -213.554314) (xy 364.141491 -213.602335) (xy 364.157201 -213.653265) (xy 364.165144 -213.705969)
			(xy 364.165642 -213.732618) (xy 364.165144 -213.759267) (xy 365.333524 -213.759267) (xy 365.333524 -213.705969)
			(xy 365.341467 -213.653265) (xy 365.357177 -213.602335) (xy 365.380303 -213.554314) (xy 365.410327 -213.510277)
			(xy 365.446579 -213.471206) (xy 365.48825 -213.437975) (xy 365.534408 -213.411326) (xy 365.584022 -213.391854)
			(xy 365.635984 -213.379994) (xy 365.689134 -213.376011) (xy 365.742284 -213.379994) (xy 365.794246 -213.391854)
			(xy 365.84386 -213.411326) (xy 365.890018 -213.437975) (xy 365.931689 -213.471206) (xy 365.967941 -213.510277)
			(xy 365.997965 -213.554314) (xy 366.021091 -213.602335) (xy 366.036801 -213.653265) (xy 366.044744 -213.705969)
			(xy 366.045242 -213.732618) (xy 366.044744 -213.759267) (xy 366.036801 -213.811971) (xy 366.021091 -213.862901)
			(xy 365.997965 -213.910922) (xy 365.967941 -213.954959) (xy 365.931689 -213.99403) (xy 365.890018 -214.027261)
			(xy 365.84386 -214.05391) (xy 365.794246 -214.073382) (xy 365.742284 -214.085242) (xy 365.689134 -214.089226)
			(xy 365.635984 -214.085242) (xy 365.584022 -214.073382) (xy 365.534408 -214.05391) (xy 365.48825 -214.027261)
			(xy 365.446579 -213.99403) (xy 365.410327 -213.954959) (xy 365.380303 -213.910922) (xy 365.357177 -213.862901)
			(xy 365.341467 -213.811971) (xy 365.333524 -213.759267) (xy 364.165144 -213.759267) (xy 364.157201 -213.811971)
			(xy 364.141491 -213.862901) (xy 364.118365 -213.910922) (xy 364.088341 -213.954959) (xy 364.052089 -213.99403)
			(xy 364.010418 -214.027261) (xy 363.96426 -214.05391) (xy 363.914646 -214.073382) (xy 363.862684 -214.085242)
			(xy 363.809534 -214.089226) (xy 363.756384 -214.085242) (xy 363.704422 -214.073382) (xy 363.654808 -214.05391)
			(xy 363.60865 -214.027261) (xy 363.566979 -213.99403) (xy 363.530727 -213.954959) (xy 363.500703 -213.910922)
			(xy 363.477577 -213.862901) (xy 363.461867 -213.811971) (xy 363.453924 -213.759267) (xy 359.918254 -213.759267)
			(xy 359.918254 -214.511382) (xy 359.92054 -214.518494) (xy 359.927789 -214.543916) (xy 359.935567 -214.596203)
			(xy 359.936034 -214.622634) (xy 359.935571 -214.649066) (xy 359.927792 -214.701353) (xy 359.92054 -214.726774)
			(xy 359.918254 -214.733886) (xy 359.918254 -214.980012) (xy 359.918725 -214.99388) (xy 359.926199 -215.020591)
			(xy 359.940591 -215.044302) (xy 359.960838 -215.06326) (xy 359.985443 -215.076064) (xy 360.012587 -215.081768)
			(xy 360.026458 -215.081358) (xy 360.05008 -215.080596) (xy 360.076732 -215.081068) (xy 360.12944 -215.08901)
			(xy 360.180377 -215.104719) (xy 360.228402 -215.127844) (xy 360.272445 -215.15787) (xy 360.31152 -215.194124)
			(xy 360.344756 -215.235798) (xy 360.371408 -215.28196) (xy 360.390883 -215.331578) (xy 360.402744 -215.383545)
			(xy 360.406728 -215.4367) (xy 360.40473 -215.463353) (xy 360.63427 -215.463353) (xy 360.63427 -215.410055)
			(xy 360.642213 -215.357351) (xy 360.657923 -215.306421) (xy 360.681049 -215.2584) (xy 360.711073 -215.214363)
			(xy 360.747325 -215.175292) (xy 360.788996 -215.142061) (xy 360.835154 -215.115412) (xy 360.884768 -215.09594)
			(xy 360.93673 -215.08408) (xy 360.98988 -215.080097) (xy 361.04303 -215.08408) (xy 361.094992 -215.09594)
			(xy 361.144606 -215.115412) (xy 361.190764 -215.142061) (xy 361.232435 -215.175292) (xy 361.268687 -215.214363)
			(xy 361.298711 -215.2584) (xy 361.321837 -215.306421) (xy 361.337547 -215.357351) (xy 361.34549 -215.410055)
			(xy 361.345988 -215.436704) (xy 361.34549 -215.463353) (xy 362.51387 -215.463353) (xy 362.51387 -215.410055)
			(xy 362.521813 -215.357351) (xy 362.537523 -215.306421) (xy 362.560649 -215.2584) (xy 362.590673 -215.214363)
			(xy 362.626925 -215.175292) (xy 362.668596 -215.142061) (xy 362.714754 -215.115412) (xy 362.764368 -215.09594)
			(xy 362.81633 -215.08408) (xy 362.86948 -215.080097) (xy 362.92263 -215.08408) (xy 362.974592 -215.09594)
			(xy 363.024206 -215.115412) (xy 363.070364 -215.142061) (xy 363.112035 -215.175292) (xy 363.148287 -215.214363)
			(xy 363.178311 -215.2584) (xy 363.201437 -215.306421) (xy 363.217147 -215.357351) (xy 363.22509 -215.410055)
			(xy 363.225588 -215.436704) (xy 363.22509 -215.463353) (xy 364.39347 -215.463353) (xy 364.39347 -215.410055)
			(xy 364.401413 -215.357351) (xy 364.417123 -215.306421) (xy 364.440249 -215.2584) (xy 364.470273 -215.214363)
			(xy 364.506525 -215.175292) (xy 364.548196 -215.142061) (xy 364.594354 -215.115412) (xy 364.643968 -215.09594)
			(xy 364.69593 -215.08408) (xy 364.74908 -215.080097) (xy 364.80223 -215.08408) (xy 364.854192 -215.09594)
			(xy 364.903806 -215.115412) (xy 364.949964 -215.142061) (xy 364.991635 -215.175292) (xy 365.027887 -215.214363)
			(xy 365.057911 -215.2584) (xy 365.081037 -215.306421) (xy 365.096747 -215.357351) (xy 365.10469 -215.410055)
			(xy 365.105188 -215.436704) (xy 365.10469 -215.463353) (xy 366.27307 -215.463353) (xy 366.27307 -215.410055)
			(xy 366.281013 -215.357351) (xy 366.296723 -215.306421) (xy 366.319849 -215.2584) (xy 366.349873 -215.214363)
			(xy 366.386125 -215.175292) (xy 366.427796 -215.142061) (xy 366.473954 -215.115412) (xy 366.523568 -215.09594)
			(xy 366.57553 -215.08408) (xy 366.62868 -215.080097) (xy 366.68183 -215.08408) (xy 366.733792 -215.09594)
			(xy 366.783406 -215.115412) (xy 366.829564 -215.142061) (xy 366.871235 -215.175292) (xy 366.907487 -215.214363)
			(xy 366.937511 -215.2584) (xy 366.960637 -215.306421) (xy 366.976347 -215.357351) (xy 366.98429 -215.410055)
			(xy 366.984788 -215.436704) (xy 366.98429 -215.463353) (xy 366.976347 -215.516057) (xy 366.960637 -215.566987)
			(xy 366.937511 -215.615008) (xy 366.907487 -215.659045) (xy 366.871235 -215.698116) (xy 366.829564 -215.731347)
			(xy 366.783406 -215.757996) (xy 366.733792 -215.777468) (xy 366.68183 -215.789328) (xy 366.62868 -215.793312)
			(xy 366.57553 -215.789328) (xy 366.523568 -215.777468) (xy 366.473954 -215.757996) (xy 366.427796 -215.731347)
			(xy 366.386125 -215.698116) (xy 366.349873 -215.659045) (xy 366.319849 -215.615008) (xy 366.296723 -215.566987)
			(xy 366.281013 -215.516057) (xy 366.27307 -215.463353) (xy 365.10469 -215.463353) (xy 365.096747 -215.516057)
			(xy 365.081037 -215.566987) (xy 365.057911 -215.615008) (xy 365.027887 -215.659045) (xy 364.991635 -215.698116)
			(xy 364.949964 -215.731347) (xy 364.903806 -215.757996) (xy 364.854192 -215.777468) (xy 364.80223 -215.789328)
			(xy 364.74908 -215.793312) (xy 364.69593 -215.789328) (xy 364.643968 -215.777468) (xy 364.594354 -215.757996)
			(xy 364.548196 -215.731347) (xy 364.506525 -215.698116) (xy 364.470273 -215.659045) (xy 364.440249 -215.615008)
			(xy 364.417123 -215.566987) (xy 364.401413 -215.516057) (xy 364.39347 -215.463353) (xy 363.22509 -215.463353)
			(xy 363.217147 -215.516057) (xy 363.201437 -215.566987) (xy 363.178311 -215.615008) (xy 363.148287 -215.659045)
			(xy 363.112035 -215.698116) (xy 363.070364 -215.731347) (xy 363.024206 -215.757996) (xy 362.974592 -215.777468)
			(xy 362.92263 -215.789328) (xy 362.86948 -215.793312) (xy 362.81633 -215.789328) (xy 362.764368 -215.777468)
			(xy 362.714754 -215.757996) (xy 362.668596 -215.731347) (xy 362.626925 -215.698116) (xy 362.590673 -215.659045)
			(xy 362.560649 -215.615008) (xy 362.537523 -215.566987) (xy 362.521813 -215.516057) (xy 362.51387 -215.463353)
			(xy 361.34549 -215.463353) (xy 361.337547 -215.516057) (xy 361.321837 -215.566987) (xy 361.298711 -215.615008)
			(xy 361.268687 -215.659045) (xy 361.232435 -215.698116) (xy 361.190764 -215.731347) (xy 361.144606 -215.757996)
			(xy 361.094992 -215.777468) (xy 361.04303 -215.789328) (xy 360.98988 -215.793312) (xy 360.93673 -215.789328)
			(xy 360.884768 -215.777468) (xy 360.835154 -215.757996) (xy 360.788996 -215.731347) (xy 360.747325 -215.698116)
			(xy 360.711073 -215.659045) (xy 360.681049 -215.615008) (xy 360.657923 -215.566987) (xy 360.642213 -215.516057)
			(xy 360.63427 -215.463353) (xy 360.40473 -215.463353) (xy 360.402744 -215.489855) (xy 360.390883 -215.541822)
			(xy 360.371408 -215.59144) (xy 360.344756 -215.637602) (xy 360.31152 -215.679276) (xy 360.272445 -215.71553)
			(xy 360.228402 -215.745556) (xy 360.180377 -215.768681) (xy 360.12944 -215.78439) (xy 360.076732 -215.792332)
			(xy 360.05008 -215.792812) (xy 360.026458 -215.79205) (xy 360.012589 -215.791622) (xy 359.98545 -215.797345)
			(xy 359.960852 -215.810159) (xy 359.940607 -215.829117) (xy 359.926209 -215.852823) (xy 359.91872 -215.879529)
			(xy 359.918254 -215.893396) (xy 359.918254 -216.13749) (xy 359.92054 -216.144856) (xy 359.92804 -216.170625)
			(xy 359.936078 -216.223686) (xy 359.936542 -216.25052) (xy 359.936055 -216.277169) (xy 360.16437 -216.277169)
			(xy 360.16437 -216.223871) (xy 360.172313 -216.171167) (xy 360.188023 -216.120237) (xy 360.211149 -216.072216)
			(xy 360.241173 -216.028179) (xy 360.277425 -215.989108) (xy 360.319096 -215.955877) (xy 360.365254 -215.929228)
			(xy 360.414868 -215.909756) (xy 360.46683 -215.897896) (xy 360.51998 -215.893913) (xy 360.57313 -215.897896)
			(xy 360.625092 -215.909756) (xy 360.674706 -215.929228) (xy 360.720864 -215.955877) (xy 360.762535 -215.989108)
			(xy 360.798787 -216.028179) (xy 360.828811 -216.072216) (xy 360.851937 -216.120237) (xy 360.867647 -216.171167)
			(xy 360.87559 -216.223871) (xy 360.876088 -216.25052) (xy 360.87559 -216.277169) (xy 361.10417 -216.277169)
			(xy 361.10417 -216.223871) (xy 361.112113 -216.171167) (xy 361.127823 -216.120237) (xy 361.150949 -216.072216)
			(xy 361.180973 -216.028179) (xy 361.217225 -215.989108) (xy 361.258896 -215.955877) (xy 361.305054 -215.929228)
			(xy 361.354668 -215.909756) (xy 361.40663 -215.897896) (xy 361.45978 -215.893913) (xy 361.51293 -215.897896)
			(xy 361.564892 -215.909756) (xy 361.614506 -215.929228) (xy 361.660664 -215.955877) (xy 361.702335 -215.989108)
			(xy 361.738587 -216.028179) (xy 361.768611 -216.072216) (xy 361.791737 -216.120237) (xy 361.807447 -216.171167)
			(xy 361.81539 -216.223871) (xy 361.815888 -216.25052) (xy 361.81539 -216.277169) (xy 362.044224 -216.277169)
			(xy 362.044224 -216.223871) (xy 362.052167 -216.171167) (xy 362.067877 -216.120237) (xy 362.091003 -216.072216)
			(xy 362.121027 -216.028179) (xy 362.157279 -215.989108) (xy 362.19895 -215.955877) (xy 362.245108 -215.929228)
			(xy 362.294722 -215.909756) (xy 362.346684 -215.897896) (xy 362.399834 -215.893913) (xy 362.452984 -215.897896)
			(xy 362.504946 -215.909756) (xy 362.55456 -215.929228) (xy 362.600718 -215.955877) (xy 362.642389 -215.989108)
			(xy 362.678641 -216.028179) (xy 362.708665 -216.072216) (xy 362.731791 -216.120237) (xy 362.747501 -216.171167)
			(xy 362.755444 -216.223871) (xy 362.755942 -216.25052) (xy 362.755444 -216.277169) (xy 362.98377 -216.277169)
			(xy 362.98377 -216.223871) (xy 362.991713 -216.171167) (xy 363.007423 -216.120237) (xy 363.030549 -216.072216)
			(xy 363.060573 -216.028179) (xy 363.096825 -215.989108) (xy 363.138496 -215.955877) (xy 363.184654 -215.929228)
			(xy 363.234268 -215.909756) (xy 363.28623 -215.897896) (xy 363.33938 -215.893913) (xy 363.39253 -215.897896)
			(xy 363.444492 -215.909756) (xy 363.494106 -215.929228) (xy 363.540264 -215.955877) (xy 363.581935 -215.989108)
			(xy 363.618187 -216.028179) (xy 363.648211 -216.072216) (xy 363.671337 -216.120237) (xy 363.687047 -216.171167)
			(xy 363.69499 -216.223871) (xy 363.695488 -216.25052) (xy 363.69499 -216.277169) (xy 363.923824 -216.277169)
			(xy 363.923824 -216.223871) (xy 363.931767 -216.171167) (xy 363.947477 -216.120237) (xy 363.970603 -216.072216)
			(xy 364.000627 -216.028179) (xy 364.036879 -215.989108) (xy 364.07855 -215.955877) (xy 364.124708 -215.929228)
			(xy 364.174322 -215.909756) (xy 364.226284 -215.897896) (xy 364.279434 -215.893913) (xy 364.332584 -215.897896)
			(xy 364.384546 -215.909756) (xy 364.43416 -215.929228) (xy 364.480318 -215.955877) (xy 364.521989 -215.989108)
			(xy 364.558241 -216.028179) (xy 364.588265 -216.072216) (xy 364.611391 -216.120237) (xy 364.627101 -216.171167)
			(xy 364.635044 -216.223871) (xy 364.635542 -216.25052) (xy 364.635044 -216.277169) (xy 364.863624 -216.277169)
			(xy 364.863624 -216.223871) (xy 364.871567 -216.171167) (xy 364.887277 -216.120237) (xy 364.910403 -216.072216)
			(xy 364.940427 -216.028179) (xy 364.976679 -215.989108) (xy 365.01835 -215.955877) (xy 365.064508 -215.929228)
			(xy 365.114122 -215.909756) (xy 365.166084 -215.897896) (xy 365.219234 -215.893913) (xy 365.272384 -215.897896)
			(xy 365.324346 -215.909756) (xy 365.37396 -215.929228) (xy 365.420118 -215.955877) (xy 365.461789 -215.989108)
			(xy 365.498041 -216.028179) (xy 365.528065 -216.072216) (xy 365.551191 -216.120237) (xy 365.566901 -216.171167)
			(xy 365.574844 -216.223871) (xy 365.575342 -216.25052) (xy 365.574844 -216.277169) (xy 365.803424 -216.277169)
			(xy 365.803424 -216.223871) (xy 365.811367 -216.171167) (xy 365.827077 -216.120237) (xy 365.850203 -216.072216)
			(xy 365.880227 -216.028179) (xy 365.916479 -215.989108) (xy 365.95815 -215.955877) (xy 366.004308 -215.929228)
			(xy 366.053922 -215.909756) (xy 366.105884 -215.897896) (xy 366.159034 -215.893913) (xy 366.212184 -215.897896)
			(xy 366.264146 -215.909756) (xy 366.31376 -215.929228) (xy 366.359918 -215.955877) (xy 366.401589 -215.989108)
			(xy 366.437841 -216.028179) (xy 366.467865 -216.072216) (xy 366.490991 -216.120237) (xy 366.506701 -216.171167)
			(xy 366.514644 -216.223871) (xy 366.515142 -216.25052) (xy 366.514644 -216.277169) (xy 366.743224 -216.277169)
			(xy 366.743224 -216.223871) (xy 366.751167 -216.171167) (xy 366.766877 -216.120237) (xy 366.790003 -216.072216)
			(xy 366.820027 -216.028179) (xy 366.856279 -215.989108) (xy 366.89795 -215.955877) (xy 366.944108 -215.929228)
			(xy 366.993722 -215.909756) (xy 367.045684 -215.897896) (xy 367.098834 -215.893913) (xy 367.151984 -215.897896)
			(xy 367.203946 -215.909756) (xy 367.25356 -215.929228) (xy 367.299718 -215.955877) (xy 367.341389 -215.989108)
			(xy 367.377641 -216.028179) (xy 367.407665 -216.072216) (xy 367.430791 -216.120237) (xy 367.446501 -216.171167)
			(xy 367.454444 -216.223871) (xy 367.454942 -216.25052) (xy 367.454444 -216.277169) (xy 367.446501 -216.329873)
			(xy 367.430791 -216.380803) (xy 367.407665 -216.428824) (xy 367.377641 -216.472861) (xy 367.341389 -216.511932)
			(xy 367.299718 -216.545163) (xy 367.25356 -216.571812) (xy 367.203946 -216.591284) (xy 367.151984 -216.603144)
			(xy 367.098834 -216.607128) (xy 367.045684 -216.603144) (xy 366.993722 -216.591284) (xy 366.944108 -216.571812)
			(xy 366.89795 -216.545163) (xy 366.856279 -216.511932) (xy 366.820027 -216.472861) (xy 366.790003 -216.428824)
			(xy 366.766877 -216.380803) (xy 366.751167 -216.329873) (xy 366.743224 -216.277169) (xy 366.514644 -216.277169)
			(xy 366.506701 -216.329873) (xy 366.490991 -216.380803) (xy 366.467865 -216.428824) (xy 366.437841 -216.472861)
			(xy 366.401589 -216.511932) (xy 366.359918 -216.545163) (xy 366.31376 -216.571812) (xy 366.264146 -216.591284)
			(xy 366.212184 -216.603144) (xy 366.159034 -216.607128) (xy 366.105884 -216.603144) (xy 366.053922 -216.591284)
			(xy 366.004308 -216.571812) (xy 365.95815 -216.545163) (xy 365.916479 -216.511932) (xy 365.880227 -216.472861)
			(xy 365.850203 -216.428824) (xy 365.827077 -216.380803) (xy 365.811367 -216.329873) (xy 365.803424 -216.277169)
			(xy 365.574844 -216.277169) (xy 365.566901 -216.329873) (xy 365.551191 -216.380803) (xy 365.528065 -216.428824)
			(xy 365.498041 -216.472861) (xy 365.461789 -216.511932) (xy 365.420118 -216.545163) (xy 365.37396 -216.571812)
			(xy 365.324346 -216.591284) (xy 365.272384 -216.603144) (xy 365.219234 -216.607128) (xy 365.166084 -216.603144)
			(xy 365.114122 -216.591284) (xy 365.064508 -216.571812) (xy 365.01835 -216.545163) (xy 364.976679 -216.511932)
			(xy 364.940427 -216.472861) (xy 364.910403 -216.428824) (xy 364.887277 -216.380803) (xy 364.871567 -216.329873)
			(xy 364.863624 -216.277169) (xy 364.635044 -216.277169) (xy 364.627101 -216.329873) (xy 364.611391 -216.380803)
			(xy 364.588265 -216.428824) (xy 364.558241 -216.472861) (xy 364.521989 -216.511932) (xy 364.480318 -216.545163)
			(xy 364.43416 -216.571812) (xy 364.384546 -216.591284) (xy 364.332584 -216.603144) (xy 364.279434 -216.607128)
			(xy 364.226284 -216.603144) (xy 364.174322 -216.591284) (xy 364.124708 -216.571812) (xy 364.07855 -216.545163)
			(xy 364.036879 -216.511932) (xy 364.000627 -216.472861) (xy 363.970603 -216.428824) (xy 363.947477 -216.380803)
			(xy 363.931767 -216.329873) (xy 363.923824 -216.277169) (xy 363.69499 -216.277169) (xy 363.687047 -216.329873)
			(xy 363.671337 -216.380803) (xy 363.648211 -216.428824) (xy 363.618187 -216.472861) (xy 363.581935 -216.511932)
			(xy 363.540264 -216.545163) (xy 363.494106 -216.571812) (xy 363.444492 -216.591284) (xy 363.39253 -216.603144)
			(xy 363.33938 -216.607128) (xy 363.28623 -216.603144) (xy 363.234268 -216.591284) (xy 363.184654 -216.571812)
			(xy 363.138496 -216.545163) (xy 363.096825 -216.511932) (xy 363.060573 -216.472861) (xy 363.030549 -216.428824)
			(xy 363.007423 -216.380803) (xy 362.991713 -216.329873) (xy 362.98377 -216.277169) (xy 362.755444 -216.277169)
			(xy 362.747501 -216.329873) (xy 362.731791 -216.380803) (xy 362.708665 -216.428824) (xy 362.678641 -216.472861)
			(xy 362.642389 -216.511932) (xy 362.600718 -216.545163) (xy 362.55456 -216.571812) (xy 362.504946 -216.591284)
			(xy 362.452984 -216.603144) (xy 362.399834 -216.607128) (xy 362.346684 -216.603144) (xy 362.294722 -216.591284)
			(xy 362.245108 -216.571812) (xy 362.19895 -216.545163) (xy 362.157279 -216.511932) (xy 362.121027 -216.472861)
			(xy 362.091003 -216.428824) (xy 362.067877 -216.380803) (xy 362.052167 -216.329873) (xy 362.044224 -216.277169)
			(xy 361.81539 -216.277169) (xy 361.807447 -216.329873) (xy 361.791737 -216.380803) (xy 361.768611 -216.428824)
			(xy 361.738587 -216.472861) (xy 361.702335 -216.511932) (xy 361.660664 -216.545163) (xy 361.614506 -216.571812)
			(xy 361.564892 -216.591284) (xy 361.51293 -216.603144) (xy 361.45978 -216.607128) (xy 361.40663 -216.603144)
			(xy 361.354668 -216.591284) (xy 361.305054 -216.571812) (xy 361.258896 -216.545163) (xy 361.217225 -216.511932)
			(xy 361.180973 -216.472861) (xy 361.150949 -216.428824) (xy 361.127823 -216.380803) (xy 361.112113 -216.329873)
			(xy 361.10417 -216.277169) (xy 360.87559 -216.277169) (xy 360.867647 -216.329873) (xy 360.851937 -216.380803)
			(xy 360.828811 -216.428824) (xy 360.798787 -216.472861) (xy 360.762535 -216.511932) (xy 360.720864 -216.545163)
			(xy 360.674706 -216.571812) (xy 360.625092 -216.591284) (xy 360.57313 -216.603144) (xy 360.51998 -216.607128)
			(xy 360.46683 -216.603144) (xy 360.414868 -216.591284) (xy 360.365254 -216.571812) (xy 360.319096 -216.545163)
			(xy 360.277425 -216.511932) (xy 360.241173 -216.472861) (xy 360.211149 -216.428824) (xy 360.188023 -216.380803)
			(xy 360.172313 -216.329873) (xy 360.16437 -216.277169) (xy 359.936055 -216.277169) (xy 359.936052 -216.277352)
			(xy 359.928015 -216.33041) (xy 359.92054 -216.356184) (xy 359.918254 -216.36355) (xy 359.918254 -216.607644)
			(xy 359.918675 -216.621546) (xy 359.926164 -216.648322) (xy 359.9406 -216.672083) (xy 359.960912 -216.691067)
			(xy 359.985595 -216.703866) (xy 360.012815 -216.709529) (xy 360.026712 -216.70899) (xy 360.050334 -216.708228)
			(xy 360.076979 -216.708728) (xy 360.129673 -216.716675) (xy 360.180594 -216.732387) (xy 360.228605 -216.755512)
			(xy 360.272634 -216.785534) (xy 360.311696 -216.821782) (xy 360.34492 -216.863447) (xy 360.371564 -216.909598)
			(xy 360.391031 -216.959205) (xy 360.402889 -217.011159) (xy 360.406871 -217.0643) (xy 360.406868 -217.064336)
			(xy 360.633772 -217.064336) (xy 360.63427 -217.037687) (xy 360.642213 -216.984983) (xy 360.657923 -216.934053)
			(xy 360.681049 -216.886032) (xy 360.711073 -216.841995) (xy 360.747325 -216.802924) (xy 360.788996 -216.769693)
			(xy 360.835154 -216.743044) (xy 360.884768 -216.723572) (xy 360.93673 -216.711712) (xy 360.98988 -216.707729)
			(xy 361.04303 -216.711712) (xy 361.094992 -216.723572) (xy 361.144606 -216.743044) (xy 361.190764 -216.769693)
			(xy 361.232435 -216.802924) (xy 361.268687 -216.841995) (xy 361.298711 -216.886032) (xy 361.321837 -216.934053)
			(xy 361.337547 -216.984983) (xy 361.34549 -217.037687) (xy 361.345988 -217.064336) (xy 361.345619 -217.08754)
			(xy 361.345166 -217.090985) (xy 361.574324 -217.090985) (xy 361.574324 -217.037687) (xy 361.582267 -216.984983)
			(xy 361.597977 -216.934053) (xy 361.621103 -216.886032) (xy 361.651127 -216.841995) (xy 361.687379 -216.802924)
			(xy 361.72905 -216.769693) (xy 361.775208 -216.743044) (xy 361.824822 -216.723572) (xy 361.876784 -216.711712)
			(xy 361.929934 -216.707729) (xy 361.983084 -216.711712) (xy 362.035046 -216.723572) (xy 362.08466 -216.743044)
			(xy 362.130818 -216.769693) (xy 362.172489 -216.802924) (xy 362.208741 -216.841995) (xy 362.238765 -216.886032)
			(xy 362.261891 -216.934053) (xy 362.277601 -216.984983) (xy 362.285544 -217.037687) (xy 362.286042 -217.064336)
			(xy 362.513372 -217.064336) (xy 362.51387 -217.037687) (xy 362.521813 -216.984983) (xy 362.537523 -216.934053)
			(xy 362.560649 -216.886032) (xy 362.590673 -216.841995) (xy 362.626925 -216.802924) (xy 362.668596 -216.769693)
			(xy 362.714754 -216.743044) (xy 362.764368 -216.723572) (xy 362.81633 -216.711712) (xy 362.86948 -216.707729)
			(xy 362.92263 -216.711712) (xy 362.974592 -216.723572) (xy 363.024206 -216.743044) (xy 363.070364 -216.769693)
			(xy 363.112035 -216.802924) (xy 363.148287 -216.841995) (xy 363.178311 -216.886032) (xy 363.201437 -216.934053)
			(xy 363.217147 -216.984983) (xy 363.22509 -217.037687) (xy 363.225588 -217.064336) (xy 363.225219 -217.08754)
			(xy 363.224766 -217.090985) (xy 363.453924 -217.090985) (xy 363.453924 -217.037687) (xy 363.461867 -216.984983)
			(xy 363.477577 -216.934053) (xy 363.500703 -216.886032) (xy 363.530727 -216.841995) (xy 363.566979 -216.802924)
			(xy 363.60865 -216.769693) (xy 363.654808 -216.743044) (xy 363.704422 -216.723572) (xy 363.756384 -216.711712)
			(xy 363.809534 -216.707729) (xy 363.862684 -216.711712) (xy 363.914646 -216.723572) (xy 363.96426 -216.743044)
			(xy 364.010418 -216.769693) (xy 364.052089 -216.802924) (xy 364.088341 -216.841995) (xy 364.118365 -216.886032)
			(xy 364.141491 -216.934053) (xy 364.157201 -216.984983) (xy 364.165144 -217.037687) (xy 364.165642 -217.064336)
			(xy 364.392972 -217.064336) (xy 364.39347 -217.037687) (xy 364.401413 -216.984983) (xy 364.417123 -216.934053)
			(xy 364.440249 -216.886032) (xy 364.470273 -216.841995) (xy 364.506525 -216.802924) (xy 364.548196 -216.769693)
			(xy 364.594354 -216.743044) (xy 364.643968 -216.723572) (xy 364.69593 -216.711712) (xy 364.74908 -216.707729)
			(xy 364.80223 -216.711712) (xy 364.854192 -216.723572) (xy 364.903806 -216.743044) (xy 364.949964 -216.769693)
			(xy 364.991635 -216.802924) (xy 365.027887 -216.841995) (xy 365.057911 -216.886032) (xy 365.081037 -216.934053)
			(xy 365.096747 -216.984983) (xy 365.10469 -217.037687) (xy 365.105188 -217.064336) (xy 365.104819 -217.08754)
			(xy 365.104366 -217.090985) (xy 365.333524 -217.090985) (xy 365.333524 -217.037687) (xy 365.341467 -216.984983)
			(xy 365.357177 -216.934053) (xy 365.380303 -216.886032) (xy 365.410327 -216.841995) (xy 365.446579 -216.802924)
			(xy 365.48825 -216.769693) (xy 365.534408 -216.743044) (xy 365.584022 -216.723572) (xy 365.635984 -216.711712)
			(xy 365.689134 -216.707729) (xy 365.742284 -216.711712) (xy 365.794246 -216.723572) (xy 365.84386 -216.743044)
			(xy 365.890018 -216.769693) (xy 365.931689 -216.802924) (xy 365.967941 -216.841995) (xy 365.997965 -216.886032)
			(xy 366.021091 -216.934053) (xy 366.036801 -216.984983) (xy 366.044744 -217.037687) (xy 366.045242 -217.064336)
			(xy 366.272572 -217.064336) (xy 366.27307 -217.037687) (xy 366.281013 -216.984983) (xy 366.296723 -216.934053)
			(xy 366.319849 -216.886032) (xy 366.349873 -216.841995) (xy 366.386125 -216.802924) (xy 366.427796 -216.769693)
			(xy 366.473954 -216.743044) (xy 366.523568 -216.723572) (xy 366.57553 -216.711712) (xy 366.62868 -216.707729)
			(xy 366.68183 -216.711712) (xy 366.733792 -216.723572) (xy 366.783406 -216.743044) (xy 366.829564 -216.769693)
			(xy 366.871235 -216.802924) (xy 366.907487 -216.841995) (xy 366.937511 -216.886032) (xy 366.960637 -216.934053)
			(xy 366.976347 -216.984983) (xy 366.98429 -217.037687) (xy 366.984788 -217.064336) (xy 366.984419 -217.08754)
			(xy 366.978365 -217.13355) (xy 366.966376 -217.178383) (xy 366.957864 -217.199972) (xy 366.948466 -217.223086)
			(xy 367.121186 -217.522044) (xy 367.145824 -217.525346) (xy 367.171158 -217.529218) (xy 367.22046 -217.543205)
			(xy 367.267249 -217.564113) (xy 367.310559 -217.591509) (xy 367.349497 -217.624829) (xy 367.383258 -217.663384)
			(xy 367.411146 -217.706379) (xy 367.432585 -217.752926) (xy 367.447133 -217.802065) (xy 367.45449 -217.852782)
			(xy 367.454942 -217.878406) (xy 367.454444 -217.905055) (xy 367.446501 -217.957759) (xy 367.430791 -218.008689)
			(xy 367.407665 -218.05671) (xy 367.377641 -218.100747) (xy 367.341389 -218.139818) (xy 367.299718 -218.173049)
			(xy 367.25356 -218.199698) (xy 367.203946 -218.21917) (xy 367.151984 -218.23103) (xy 367.098834 -218.235014)
			(xy 367.045684 -218.23103) (xy 366.993722 -218.21917) (xy 366.944108 -218.199698) (xy 366.89795 -218.173049)
			(xy 366.856279 -218.139818) (xy 366.820027 -218.100747) (xy 366.790003 -218.05671) (xy 366.766877 -218.008689)
			(xy 366.751167 -217.957759) (xy 366.743224 -217.905055) (xy 366.742726 -217.878406) (xy 366.743095 -217.855161)
			(xy 366.749142 -217.809065) (xy 366.761132 -217.764148) (xy 366.76965 -217.742516) (xy 366.779302 -217.719402)
			(xy 366.606836 -217.420698) (xy 366.581944 -217.417396) (xy 366.556595 -217.413539) (xy 366.507256 -217.399588)
			(xy 366.460428 -217.378707) (xy 366.417079 -217.351325) (xy 366.378105 -217.31801) (xy 366.344311 -217.27945)
			(xy 366.316396 -217.236443) (xy 366.294938 -217.189877) (xy 366.280379 -217.140714) (xy 366.273021 -217.089972)
			(xy 366.272572 -217.064336) (xy 366.045242 -217.064336) (xy 366.044744 -217.090985) (xy 366.036801 -217.143689)
			(xy 366.021091 -217.194619) (xy 365.997965 -217.24264) (xy 365.967941 -217.286677) (xy 365.931689 -217.325748)
			(xy 365.890018 -217.358979) (xy 365.84386 -217.385628) (xy 365.794246 -217.4051) (xy 365.742284 -217.41696)
			(xy 365.689134 -217.420944) (xy 365.635984 -217.41696) (xy 365.584022 -217.4051) (xy 365.534408 -217.385628)
			(xy 365.48825 -217.358979) (xy 365.446579 -217.325748) (xy 365.410327 -217.286677) (xy 365.380303 -217.24264)
			(xy 365.357177 -217.194619) (xy 365.341467 -217.143689) (xy 365.333524 -217.090985) (xy 365.104366 -217.090985)
			(xy 365.098765 -217.13355) (xy 365.086776 -217.178383) (xy 365.078264 -217.199972) (xy 365.068866 -217.223086)
			(xy 365.241586 -217.522044) (xy 365.266224 -217.525346) (xy 365.291558 -217.529218) (xy 365.34086 -217.543205)
			(xy 365.387649 -217.564113) (xy 365.430959 -217.591509) (xy 365.469897 -217.624829) (xy 365.503658 -217.663384)
			(xy 365.531546 -217.706379) (xy 365.552985 -217.752926) (xy 365.567533 -217.802065) (xy 365.57489 -217.852782)
			(xy 365.575342 -217.878406) (xy 365.574844 -217.905055) (xy 365.566901 -217.957759) (xy 365.551191 -218.008689)
			(xy 365.528065 -218.05671) (xy 365.498041 -218.100747) (xy 365.461789 -218.139818) (xy 365.420118 -218.173049)
			(xy 365.37396 -218.199698) (xy 365.324346 -218.21917) (xy 365.272384 -218.23103) (xy 365.219234 -218.235014)
			(xy 365.166084 -218.23103) (xy 365.114122 -218.21917) (xy 365.064508 -218.199698) (xy 365.01835 -218.173049)
			(xy 364.976679 -218.139818) (xy 364.940427 -218.100747) (xy 364.910403 -218.05671) (xy 364.887277 -218.008689)
			(xy 364.871567 -217.957759) (xy 364.863624 -217.905055) (xy 364.863126 -217.878406) (xy 364.863495 -217.855161)
			(xy 364.869542 -217.809065) (xy 364.881532 -217.764148) (xy 364.89005 -217.742516) (xy 364.899702 -217.719402)
			(xy 364.727236 -217.420698) (xy 364.702344 -217.417396) (xy 364.676995 -217.413539) (xy 364.627656 -217.399588)
			(xy 364.580828 -217.378707) (xy 364.537479 -217.351325) (xy 364.498505 -217.31801) (xy 364.464711 -217.27945)
			(xy 364.436796 -217.236443) (xy 364.415338 -217.189877) (xy 364.400779 -217.140714) (xy 364.393421 -217.089972)
			(xy 364.392972 -217.064336) (xy 364.165642 -217.064336) (xy 364.165144 -217.090985) (xy 364.157201 -217.143689)
			(xy 364.141491 -217.194619) (xy 364.118365 -217.24264) (xy 364.088341 -217.286677) (xy 364.052089 -217.325748)
			(xy 364.010418 -217.358979) (xy 363.96426 -217.385628) (xy 363.914646 -217.4051) (xy 363.862684 -217.41696)
			(xy 363.809534 -217.420944) (xy 363.756384 -217.41696) (xy 363.704422 -217.4051) (xy 363.654808 -217.385628)
			(xy 363.60865 -217.358979) (xy 363.566979 -217.325748) (xy 363.530727 -217.286677) (xy 363.500703 -217.24264)
			(xy 363.477577 -217.194619) (xy 363.461867 -217.143689) (xy 363.453924 -217.090985) (xy 363.224766 -217.090985)
			(xy 363.219165 -217.13355) (xy 363.207176 -217.178383) (xy 363.198664 -217.199972) (xy 363.189266 -217.223086)
			(xy 363.361986 -217.522044) (xy 363.386624 -217.525346) (xy 363.411958 -217.529218) (xy 363.46126 -217.543205)
			(xy 363.508049 -217.564113) (xy 363.551359 -217.591509) (xy 363.590297 -217.624829) (xy 363.624058 -217.663384)
			(xy 363.651946 -217.706379) (xy 363.673385 -217.752926) (xy 363.687933 -217.802065) (xy 363.69529 -217.852782)
			(xy 363.695742 -217.878406) (xy 363.695244 -217.905055) (xy 363.687301 -217.957759) (xy 363.671591 -218.008689)
			(xy 363.648465 -218.05671) (xy 363.618441 -218.100747) (xy 363.582189 -218.139818) (xy 363.540518 -218.173049)
			(xy 363.49436 -218.199698) (xy 363.444746 -218.21917) (xy 363.392784 -218.23103) (xy 363.339634 -218.235014)
			(xy 363.286484 -218.23103) (xy 363.234522 -218.21917) (xy 363.184908 -218.199698) (xy 363.13875 -218.173049)
			(xy 363.097079 -218.139818) (xy 363.060827 -218.100747) (xy 363.030803 -218.05671) (xy 363.007677 -218.008689)
			(xy 362.991967 -217.957759) (xy 362.984024 -217.905055) (xy 362.983526 -217.878406) (xy 362.983895 -217.855161)
			(xy 362.989942 -217.809065) (xy 363.001932 -217.764148) (xy 363.01045 -217.742516) (xy 363.020102 -217.719402)
			(xy 362.847636 -217.420698) (xy 362.822744 -217.417396) (xy 362.797395 -217.413539) (xy 362.748056 -217.399588)
			(xy 362.701228 -217.378707) (xy 362.657879 -217.351325) (xy 362.618905 -217.31801) (xy 362.585111 -217.27945)
			(xy 362.557196 -217.236443) (xy 362.535738 -217.189877) (xy 362.521179 -217.140714) (xy 362.513821 -217.089972)
			(xy 362.513372 -217.064336) (xy 362.286042 -217.064336) (xy 362.285544 -217.090985) (xy 362.277601 -217.143689)
			(xy 362.261891 -217.194619) (xy 362.238765 -217.24264) (xy 362.208741 -217.286677) (xy 362.172489 -217.325748)
			(xy 362.130818 -217.358979) (xy 362.08466 -217.385628) (xy 362.035046 -217.4051) (xy 361.983084 -217.41696)
			(xy 361.929934 -217.420944) (xy 361.876784 -217.41696) (xy 361.824822 -217.4051) (xy 361.775208 -217.385628)
			(xy 361.72905 -217.358979) (xy 361.687379 -217.325748) (xy 361.651127 -217.286677) (xy 361.621103 -217.24264)
			(xy 361.597977 -217.194619) (xy 361.582267 -217.143689) (xy 361.574324 -217.090985) (xy 361.345166 -217.090985)
			(xy 361.339565 -217.13355) (xy 361.327576 -217.178383) (xy 361.319064 -217.199972) (xy 361.309666 -217.223086)
			(xy 361.482386 -217.522044) (xy 361.507024 -217.525346) (xy 361.532358 -217.529218) (xy 361.58166 -217.543205)
			(xy 361.628449 -217.564113) (xy 361.671759 -217.591509) (xy 361.710697 -217.624829) (xy 361.744458 -217.663384)
			(xy 361.772346 -217.706379) (xy 361.793785 -217.752926) (xy 361.808333 -217.802065) (xy 361.81569 -217.852782)
			(xy 361.816142 -217.878406) (xy 361.815644 -217.905055) (xy 361.807701 -217.957759) (xy 361.791991 -218.008689)
			(xy 361.768865 -218.05671) (xy 361.738841 -218.100747) (xy 361.702589 -218.139818) (xy 361.660918 -218.173049)
			(xy 361.61476 -218.199698) (xy 361.565146 -218.21917) (xy 361.513184 -218.23103) (xy 361.460034 -218.235014)
			(xy 361.406884 -218.23103) (xy 361.354922 -218.21917) (xy 361.305308 -218.199698) (xy 361.25915 -218.173049)
			(xy 361.217479 -218.139818) (xy 361.181227 -218.100747) (xy 361.151203 -218.05671) (xy 361.128077 -218.008689)
			(xy 361.112367 -217.957759) (xy 361.104424 -217.905055) (xy 361.103926 -217.878406) (xy 361.104295 -217.855161)
			(xy 361.110342 -217.809065) (xy 361.122332 -217.764148) (xy 361.13085 -217.742516) (xy 361.140502 -217.719402)
			(xy 360.968036 -217.420698) (xy 360.943144 -217.417396) (xy 360.917795 -217.413539) (xy 360.868456 -217.399588)
			(xy 360.821628 -217.378707) (xy 360.778279 -217.351325) (xy 360.739305 -217.31801) (xy 360.705511 -217.27945)
			(xy 360.677596 -217.236443) (xy 360.656138 -217.189877) (xy 360.641579 -217.140714) (xy 360.634221 -217.089972)
			(xy 360.633772 -217.064336) (xy 360.406868 -217.064336) (xy 360.402889 -217.117441) (xy 360.391031 -217.169395)
			(xy 360.371564 -217.219002) (xy 360.34492 -217.265153) (xy 360.311696 -217.306818) (xy 360.272634 -217.343066)
			(xy 360.228605 -217.373088) (xy 360.180594 -217.396213) (xy 360.129673 -217.411925) (xy 360.076979 -217.419872)
			(xy 360.050334 -217.420444) (xy 360.026712 -217.419682) (xy 360.012822 -217.419221) (xy 359.985629 -217.424898)
			(xy 359.960972 -217.437692) (xy 359.940674 -217.456658) (xy 359.926239 -217.480392) (xy 359.918734 -217.507139)
			(xy 359.918254 -217.521028) (xy 359.918254 -217.765376) (xy 359.92054 -217.772742) (xy 359.928041 -217.798511)
			(xy 359.936081 -217.851572) (xy 359.936542 -217.878406) (xy 359.936053 -217.905238) (xy 359.928018 -217.958297)
			(xy 359.92054 -217.98407) (xy 359.918254 -217.991436) (xy 359.918254 -218.344242) (xy 359.974134 -218.344242)
			(xy 359.979214 -218.343226) (xy 360.00309 -218.339162) (xy 360.027728 -218.33586) (xy 360.200194 -218.036902)
			(xy 360.190796 -218.013788) (xy 360.182356 -217.992227) (xy 360.170482 -217.947472) (xy 360.164494 -217.901558)
			(xy 360.164126 -217.878406) (xy 360.164624 -217.851757) (xy 360.172567 -217.799053) (xy 360.188277 -217.748123)
			(xy 360.211403 -217.700102) (xy 360.241427 -217.656065) (xy 360.277679 -217.616994) (xy 360.31935 -217.583763)
			(xy 360.365508 -217.557114) (xy 360.415122 -217.537642) (xy 360.467084 -217.525782) (xy 360.520234 -217.521799)
			(xy 360.573384 -217.525782) (xy 360.625346 -217.537642) (xy 360.67496 -217.557114) (xy 360.721118 -217.583763)
			(xy 360.762789 -217.616994) (xy 360.799041 -217.656065) (xy 360.829065 -217.700102) (xy 360.852191 -217.748123)
			(xy 360.867901 -217.799053) (xy 360.875844 -217.851757) (xy 360.876342 -217.878406) (xy 360.875894 -217.904057)
			(xy 360.868533 -217.954827) (xy 360.853963 -218.004015) (xy 360.832486 -218.050604) (xy 360.804546 -218.09363)
			(xy 360.770723 -218.132201) (xy 360.731715 -218.165521) (xy 360.68833 -218.192898) (xy 360.641465 -218.213768)
			(xy 360.592092 -218.227697) (xy 360.566716 -218.231466) (xy 360.541824 -218.234768) (xy 360.369612 -218.533218)
			(xy 360.379264 -218.556332) (xy 360.38778 -218.577964) (xy 360.399769 -218.622882) (xy 360.405813 -218.668977)
			(xy 360.406188 -218.692222) (xy 361.573826 -218.692222) (xy 361.57429 -218.666594) (xy 361.581622 -218.615866)
			(xy 361.596152 -218.566714) (xy 361.61758 -218.520153) (xy 361.645463 -218.477146) (xy 361.679225 -218.438582)
			(xy 361.718168 -218.405257) (xy 361.761487 -218.377861) (xy 361.808286 -218.356959) (xy 361.857599 -218.342984)
			(xy 361.882944 -218.339162) (xy 361.907582 -218.33586) (xy 362.080048 -218.037156) (xy 362.07065 -218.014042)
			(xy 362.062149 -217.99245) (xy 362.050176 -217.947616) (xy 362.044118 -217.901608) (xy 362.043726 -217.878406)
			(xy 362.044224 -217.851757) (xy 362.052167 -217.799053) (xy 362.067877 -217.748123) (xy 362.091003 -217.700102)
			(xy 362.121027 -217.656065) (xy 362.157279 -217.616994) (xy 362.19895 -217.583763) (xy 362.245108 -217.557114)
			(xy 362.294722 -217.537642) (xy 362.346684 -217.525782) (xy 362.399834 -217.521799) (xy 362.452984 -217.525782)
			(xy 362.504946 -217.537642) (xy 362.55456 -217.557114) (xy 362.600718 -217.583763) (xy 362.642389 -217.616994)
			(xy 362.678641 -217.656065) (xy 362.708665 -217.700102) (xy 362.731791 -217.748123) (xy 362.747501 -217.799053)
			(xy 362.755444 -217.851757) (xy 362.755942 -217.878406) (xy 362.755498 -217.904046) (xy 362.748154 -217.954797)
			(xy 362.733606 -218.003969) (xy 362.712154 -218.050546) (xy 362.684241 -218.093563) (xy 362.650446 -218.132131)
			(xy 362.611468 -218.165452) (xy 362.568112 -218.192836) (xy 362.521277 -218.213716) (xy 362.47193 -218.227662)
			(xy 362.44657 -218.231466) (xy 362.421678 -218.234768) (xy 362.249466 -218.533218) (xy 362.259118 -218.556332)
			(xy 362.267643 -218.577961) (xy 362.279626 -218.62288) (xy 362.285668 -218.668977) (xy 362.286042 -218.692222)
			(xy 363.453172 -218.692222) (xy 363.453596 -218.666593) (xy 363.460929 -218.615861) (xy 363.475462 -218.566706)
			(xy 363.496893 -218.520142) (xy 363.524781 -218.477134) (xy 363.558547 -218.438569) (xy 363.597495 -218.405244)
			(xy 363.64082 -218.37785) (xy 363.687625 -218.356952) (xy 363.736943 -218.342981) (xy 363.76229 -218.339162)
			(xy 363.786928 -218.33586) (xy 363.959394 -218.036902) (xy 363.949996 -218.013788) (xy 363.941551 -217.992227)
			(xy 363.929658 -217.947476) (xy 363.92368 -217.901559) (xy 363.923326 -217.878406) (xy 363.923824 -217.851757)
			(xy 363.931767 -217.799053) (xy 363.947477 -217.748123) (xy 363.970603 -217.700102) (xy 364.000627 -217.656065)
			(xy 364.036879 -217.616994) (xy 364.07855 -217.583763) (xy 364.124708 -217.557114) (xy 364.174322 -217.537642)
			(xy 364.226284 -217.525782) (xy 364.279434 -217.521799) (xy 364.332584 -217.525782) (xy 364.384546 -217.537642)
			(xy 364.43416 -217.557114) (xy 364.480318 -217.583763) (xy 364.521989 -217.616994) (xy 364.558241 -217.656065)
			(xy 364.588265 -217.700102) (xy 364.611391 -217.748123) (xy 364.627101 -217.799053) (xy 364.635044 -217.851757)
			(xy 364.635542 -217.878406) (xy 364.635069 -217.904055) (xy 364.627708 -217.954821) (xy 364.613139 -218.004006)
			(xy 364.591664 -218.050592) (xy 364.563727 -218.093615) (xy 364.529905 -218.132183) (xy 364.4909 -218.1655)
			(xy 364.447518 -218.192876) (xy 364.400657 -218.213744) (xy 364.351287 -218.227672) (xy 364.325916 -218.231466)
			(xy 364.301024 -218.234768) (xy 364.128812 -218.533218) (xy 364.138464 -218.556332) (xy 364.146986 -218.577962)
			(xy 364.158971 -218.622881) (xy 364.165014 -218.668977) (xy 364.165388 -218.692222) (xy 364.16489 -218.718871)
			(xy 364.39347 -218.718871) (xy 364.39347 -218.665573) (xy 364.401413 -218.612869) (xy 364.417123 -218.561939)
			(xy 364.440249 -218.513918) (xy 364.470273 -218.469881) (xy 364.506525 -218.43081) (xy 364.548196 -218.397579)
			(xy 364.594354 -218.37093) (xy 364.643968 -218.351458) (xy 364.69593 -218.339598) (xy 364.74908 -218.335615)
			(xy 364.80223 -218.339598) (xy 364.854192 -218.351458) (xy 364.903806 -218.37093) (xy 364.949964 -218.397579)
			(xy 364.991635 -218.43081) (xy 365.027887 -218.469881) (xy 365.057911 -218.513918) (xy 365.081037 -218.561939)
			(xy 365.096747 -218.612869) (xy 365.10469 -218.665573) (xy 365.105188 -218.692222) (xy 365.332772 -218.692222)
			(xy 365.333196 -218.666593) (xy 365.340529 -218.615861) (xy 365.355062 -218.566706) (xy 365.376493 -218.520142)
			(xy 365.404381 -218.477134) (xy 365.438147 -218.438569) (xy 365.477095 -218.405244) (xy 365.52042 -218.37785)
			(xy 365.567225 -218.356952) (xy 365.616543 -218.342981) (xy 365.64189 -218.339162) (xy 365.666528 -218.33586)
			(xy 365.838994 -218.036902) (xy 365.829596 -218.013788) (xy 365.821151 -217.992227) (xy 365.809258 -217.947476)
			(xy 365.80328 -217.901559) (xy 365.802926 -217.878406) (xy 365.803424 -217.851757) (xy 365.811367 -217.799053)
			(xy 365.827077 -217.748123) (xy 365.850203 -217.700102) (xy 365.880227 -217.656065) (xy 365.916479 -217.616994)
			(xy 365.95815 -217.583763) (xy 366.004308 -217.557114) (xy 366.053922 -217.537642) (xy 366.105884 -217.525782)
			(xy 366.159034 -217.521799) (xy 366.212184 -217.525782) (xy 366.264146 -217.537642) (xy 366.31376 -217.557114)
			(xy 366.359918 -217.583763) (xy 366.401589 -217.616994) (xy 366.437841 -217.656065) (xy 366.467865 -217.700102)
			(xy 366.490991 -217.748123) (xy 366.506701 -217.799053) (xy 366.514644 -217.851757) (xy 366.515142 -217.878406)
			(xy 366.514669 -217.904055) (xy 366.507308 -217.954821) (xy 366.492739 -218.004006) (xy 366.471264 -218.050592)
			(xy 366.443327 -218.093615) (xy 366.409505 -218.132183) (xy 366.3705 -218.1655) (xy 366.327118 -218.192876)
			(xy 366.280257 -218.213744) (xy 366.230887 -218.227672) (xy 366.205516 -218.231466) (xy 366.180624 -218.234768)
			(xy 366.008412 -218.533218) (xy 366.018064 -218.556332) (xy 366.026586 -218.577962) (xy 366.038571 -218.622881)
			(xy 366.044614 -218.668977) (xy 366.044988 -218.692222) (xy 366.04449 -218.718871) (xy 366.27307 -218.718871)
			(xy 366.27307 -218.665573) (xy 366.281013 -218.612869) (xy 366.296723 -218.561939) (xy 366.319849 -218.513918)
			(xy 366.349873 -218.469881) (xy 366.386125 -218.43081) (xy 366.427796 -218.397579) (xy 366.473954 -218.37093)
			(xy 366.523568 -218.351458) (xy 366.57553 -218.339598) (xy 366.62868 -218.335615) (xy 366.68183 -218.339598)
			(xy 366.733792 -218.351458) (xy 366.783406 -218.37093) (xy 366.829564 -218.397579) (xy 366.871235 -218.43081)
			(xy 366.907487 -218.469881) (xy 366.937511 -218.513918) (xy 366.960637 -218.561939) (xy 366.976347 -218.612869)
			(xy 366.98429 -218.665573) (xy 366.984788 -218.692222) (xy 366.98429 -218.718871) (xy 366.976347 -218.771575)
			(xy 366.960637 -218.822505) (xy 366.937511 -218.870526) (xy 366.907487 -218.914563) (xy 366.871235 -218.953634)
			(xy 366.829564 -218.986865) (xy 366.783406 -219.013514) (xy 366.733792 -219.032986) (xy 366.68183 -219.044846)
			(xy 366.62868 -219.04883) (xy 366.57553 -219.044846) (xy 366.523568 -219.032986) (xy 366.473954 -219.013514)
			(xy 366.427796 -218.986865) (xy 366.386125 -218.953634) (xy 366.349873 -218.914563) (xy 366.319849 -218.870526)
			(xy 366.296723 -218.822505) (xy 366.281013 -218.771575) (xy 366.27307 -218.718871) (xy 366.04449 -218.718871)
			(xy 366.036547 -218.771575) (xy 366.020837 -218.822505) (xy 365.997711 -218.870526) (xy 365.967687 -218.914563)
			(xy 365.931435 -218.953634) (xy 365.889764 -218.986865) (xy 365.843606 -219.013514) (xy 365.793992 -219.032986)
			(xy 365.74203 -219.044846) (xy 365.68888 -219.04883) (xy 365.63573 -219.044846) (xy 365.583768 -219.032986)
			(xy 365.534154 -219.013514) (xy 365.487996 -218.986865) (xy 365.446325 -218.953634) (xy 365.410073 -218.914563)
			(xy 365.380049 -218.870526) (xy 365.356923 -218.822505) (xy 365.341213 -218.771575) (xy 365.33327 -218.718871)
			(xy 365.332772 -218.692222) (xy 365.105188 -218.692222) (xy 365.10469 -218.718871) (xy 365.096747 -218.771575)
			(xy 365.081037 -218.822505) (xy 365.057911 -218.870526) (xy 365.027887 -218.914563) (xy 364.991635 -218.953634)
			(xy 364.949964 -218.986865) (xy 364.903806 -219.013514) (xy 364.854192 -219.032986) (xy 364.80223 -219.044846)
			(xy 364.74908 -219.04883) (xy 364.69593 -219.044846) (xy 364.643968 -219.032986) (xy 364.594354 -219.013514)
			(xy 364.548196 -218.986865) (xy 364.506525 -218.953634) (xy 364.470273 -218.914563) (xy 364.440249 -218.870526)
			(xy 364.417123 -218.822505) (xy 364.401413 -218.771575) (xy 364.39347 -218.718871) (xy 364.16489 -218.718871)
			(xy 364.156947 -218.771575) (xy 364.141237 -218.822505) (xy 364.118111 -218.870526) (xy 364.088087 -218.914563)
			(xy 364.051835 -218.953634) (xy 364.010164 -218.986865) (xy 363.964006 -219.013514) (xy 363.914392 -219.032986)
			(xy 363.86243 -219.044846) (xy 363.80928 -219.04883) (xy 363.75613 -219.044846) (xy 363.704168 -219.032986)
			(xy 363.654554 -219.013514) (xy 363.608396 -218.986865) (xy 363.566725 -218.953634) (xy 363.530473 -218.914563)
			(xy 363.500449 -218.870526) (xy 363.477323 -218.822505) (xy 363.461613 -218.771575) (xy 363.45367 -218.718871)
			(xy 363.453172 -218.692222) (xy 362.286042 -218.692222) (xy 362.285544 -218.718871) (xy 362.277601 -218.771575)
			(xy 362.261891 -218.822505) (xy 362.238765 -218.870526) (xy 362.208741 -218.914563) (xy 362.172489 -218.953634)
			(xy 362.130818 -218.986865) (xy 362.08466 -219.013514) (xy 362.035046 -219.032986) (xy 361.983084 -219.044846)
			(xy 361.929934 -219.04883) (xy 361.876784 -219.044846) (xy 361.824822 -219.032986) (xy 361.775208 -219.013514)
			(xy 361.72905 -218.986865) (xy 361.687379 -218.953634) (xy 361.651127 -218.914563) (xy 361.621103 -218.870526)
			(xy 361.597977 -218.822505) (xy 361.582267 -218.771575) (xy 361.574324 -218.718871) (xy 361.573826 -218.692222)
			(xy 360.406188 -218.692222) (xy 360.405637 -218.720203) (xy 360.396879 -218.775477) (xy 360.379583 -218.8287)
			(xy 360.354173 -218.878561) (xy 360.321276 -218.923834) (xy 360.281702 -218.963404) (xy 360.236425 -218.996295)
			(xy 360.186561 -219.021699) (xy 360.133336 -219.038989) (xy 360.078061 -219.047741) (xy 360.05008 -219.04833)
			(xy 360.026458 -219.047568) (xy 360.01259 -219.04714) (xy 359.985453 -219.052863) (xy 359.960856 -219.065677)
			(xy 359.940615 -219.084636) (xy 359.926221 -219.108343) (xy 359.918736 -219.135047) (xy 359.918254 -219.148914)
			(xy 359.918254 -219.393008) (xy 359.92054 -219.400374) (xy 359.928038 -219.426143) (xy 359.936074 -219.479204)
			(xy 359.936542 -219.506038) (xy 359.936054 -219.532687) (xy 360.164624 -219.532687) (xy 360.164624 -219.479389)
			(xy 360.172567 -219.426685) (xy 360.188277 -219.375755) (xy 360.211403 -219.327734) (xy 360.241427 -219.283697)
			(xy 360.277679 -219.244626) (xy 360.31935 -219.211395) (xy 360.365508 -219.184746) (xy 360.415122 -219.165274)
			(xy 360.467084 -219.153414) (xy 360.520234 -219.149431) (xy 360.573384 -219.153414) (xy 360.625346 -219.165274)
			(xy 360.67496 -219.184746) (xy 360.721118 -219.211395) (xy 360.762789 -219.244626) (xy 360.799041 -219.283697)
			(xy 360.829065 -219.327734) (xy 360.852191 -219.375755) (xy 360.867901 -219.426685) (xy 360.875844 -219.479389)
			(xy 360.876342 -219.506038) (xy 360.875844 -219.532687) (xy 361.104424 -219.532687) (xy 361.104424 -219.479389)
			(xy 361.112367 -219.426685) (xy 361.128077 -219.375755) (xy 361.151203 -219.327734) (xy 361.181227 -219.283697)
			(xy 361.217479 -219.244626) (xy 361.25915 -219.211395) (xy 361.305308 -219.184746) (xy 361.354922 -219.165274)
			(xy 361.406884 -219.153414) (xy 361.460034 -219.149431) (xy 361.513184 -219.153414) (xy 361.565146 -219.165274)
			(xy 361.61476 -219.184746) (xy 361.660918 -219.211395) (xy 361.702589 -219.244626) (xy 361.738841 -219.283697)
			(xy 361.768865 -219.327734) (xy 361.791991 -219.375755) (xy 361.807701 -219.426685) (xy 361.815644 -219.479389)
			(xy 361.816142 -219.506038) (xy 361.815644 -219.532687) (xy 362.044224 -219.532687) (xy 362.044224 -219.479389)
			(xy 362.052167 -219.426685) (xy 362.067877 -219.375755) (xy 362.091003 -219.327734) (xy 362.121027 -219.283697)
			(xy 362.157279 -219.244626) (xy 362.19895 -219.211395) (xy 362.245108 -219.184746) (xy 362.294722 -219.165274)
			(xy 362.346684 -219.153414) (xy 362.399834 -219.149431) (xy 362.452984 -219.153414) (xy 362.504946 -219.165274)
			(xy 362.55456 -219.184746) (xy 362.600718 -219.211395) (xy 362.642389 -219.244626) (xy 362.678641 -219.283697)
			(xy 362.708665 -219.327734) (xy 362.731791 -219.375755) (xy 362.747501 -219.426685) (xy 362.755444 -219.479389)
			(xy 362.755942 -219.506038) (xy 362.755444 -219.532687) (xy 362.984024 -219.532687) (xy 362.984024 -219.479389)
			(xy 362.991967 -219.426685) (xy 363.007677 -219.375755) (xy 363.030803 -219.327734) (xy 363.060827 -219.283697)
			(xy 363.097079 -219.244626) (xy 363.13875 -219.211395) (xy 363.184908 -219.184746) (xy 363.234522 -219.165274)
			(xy 363.286484 -219.153414) (xy 363.339634 -219.149431) (xy 363.392784 -219.153414) (xy 363.444746 -219.165274)
			(xy 363.49436 -219.184746) (xy 363.540518 -219.211395) (xy 363.582189 -219.244626) (xy 363.618441 -219.283697)
			(xy 363.648465 -219.327734) (xy 363.671591 -219.375755) (xy 363.687301 -219.426685) (xy 363.695244 -219.479389)
			(xy 363.695742 -219.506038) (xy 363.695244 -219.532687) (xy 363.923824 -219.532687) (xy 363.923824 -219.479389)
			(xy 363.931767 -219.426685) (xy 363.947477 -219.375755) (xy 363.970603 -219.327734) (xy 364.000627 -219.283697)
			(xy 364.036879 -219.244626) (xy 364.07855 -219.211395) (xy 364.124708 -219.184746) (xy 364.174322 -219.165274)
			(xy 364.226284 -219.153414) (xy 364.279434 -219.149431) (xy 364.332584 -219.153414) (xy 364.384546 -219.165274)
			(xy 364.43416 -219.184746) (xy 364.480318 -219.211395) (xy 364.521989 -219.244626) (xy 364.558241 -219.283697)
			(xy 364.588265 -219.327734) (xy 364.611391 -219.375755) (xy 364.627101 -219.426685) (xy 364.635044 -219.479389)
			(xy 364.635542 -219.506038) (xy 364.635044 -219.532687) (xy 364.863624 -219.532687) (xy 364.863624 -219.479389)
			(xy 364.871567 -219.426685) (xy 364.887277 -219.375755) (xy 364.910403 -219.327734) (xy 364.940427 -219.283697)
			(xy 364.976679 -219.244626) (xy 365.01835 -219.211395) (xy 365.064508 -219.184746) (xy 365.114122 -219.165274)
			(xy 365.166084 -219.153414) (xy 365.219234 -219.149431) (xy 365.272384 -219.153414) (xy 365.324346 -219.165274)
			(xy 365.37396 -219.184746) (xy 365.420118 -219.211395) (xy 365.461789 -219.244626) (xy 365.498041 -219.283697)
			(xy 365.528065 -219.327734) (xy 365.551191 -219.375755) (xy 365.566901 -219.426685) (xy 365.574844 -219.479389)
			(xy 365.575342 -219.506038) (xy 365.574844 -219.532687) (xy 365.803424 -219.532687) (xy 365.803424 -219.479389)
			(xy 365.811367 -219.426685) (xy 365.827077 -219.375755) (xy 365.850203 -219.327734) (xy 365.880227 -219.283697)
			(xy 365.916479 -219.244626) (xy 365.95815 -219.211395) (xy 366.004308 -219.184746) (xy 366.053922 -219.165274)
			(xy 366.105884 -219.153414) (xy 366.159034 -219.149431) (xy 366.212184 -219.153414) (xy 366.264146 -219.165274)
			(xy 366.31376 -219.184746) (xy 366.359918 -219.211395) (xy 366.401589 -219.244626) (xy 366.437841 -219.283697)
			(xy 366.467865 -219.327734) (xy 366.490991 -219.375755) (xy 366.506701 -219.426685) (xy 366.514644 -219.479389)
			(xy 366.515142 -219.506038) (xy 366.514644 -219.532687) (xy 366.743224 -219.532687) (xy 366.743224 -219.479389)
			(xy 366.751167 -219.426685) (xy 366.766877 -219.375755) (xy 366.790003 -219.327734) (xy 366.820027 -219.283697)
			(xy 366.856279 -219.244626) (xy 366.89795 -219.211395) (xy 366.944108 -219.184746) (xy 366.993722 -219.165274)
			(xy 367.045684 -219.153414) (xy 367.098834 -219.149431) (xy 367.151984 -219.153414) (xy 367.203946 -219.165274)
			(xy 367.25356 -219.184746) (xy 367.299718 -219.211395) (xy 367.341389 -219.244626) (xy 367.377641 -219.283697)
			(xy 367.407665 -219.327734) (xy 367.430791 -219.375755) (xy 367.446501 -219.426685) (xy 367.454444 -219.479389)
			(xy 367.454942 -219.506038) (xy 367.454444 -219.532687) (xy 367.446501 -219.585391) (xy 367.430791 -219.636321)
			(xy 367.407665 -219.684342) (xy 367.377641 -219.728379) (xy 367.341389 -219.76745) (xy 367.299718 -219.800681)
			(xy 367.25356 -219.82733) (xy 367.203946 -219.846802) (xy 367.151984 -219.858662) (xy 367.098834 -219.862646)
			(xy 367.045684 -219.858662) (xy 366.993722 -219.846802) (xy 366.944108 -219.82733) (xy 366.89795 -219.800681)
			(xy 366.856279 -219.76745) (xy 366.820027 -219.728379) (xy 366.790003 -219.684342) (xy 366.766877 -219.636321)
			(xy 366.751167 -219.585391) (xy 366.743224 -219.532687) (xy 366.514644 -219.532687) (xy 366.506701 -219.585391)
			(xy 366.490991 -219.636321) (xy 366.467865 -219.684342) (xy 366.437841 -219.728379) (xy 366.401589 -219.76745)
			(xy 366.359918 -219.800681) (xy 366.31376 -219.82733) (xy 366.264146 -219.846802) (xy 366.212184 -219.858662)
			(xy 366.159034 -219.862646) (xy 366.105884 -219.858662) (xy 366.053922 -219.846802) (xy 366.004308 -219.82733)
			(xy 365.95815 -219.800681) (xy 365.916479 -219.76745) (xy 365.880227 -219.728379) (xy 365.850203 -219.684342)
			(xy 365.827077 -219.636321) (xy 365.811367 -219.585391) (xy 365.803424 -219.532687) (xy 365.574844 -219.532687)
			(xy 365.566901 -219.585391) (xy 365.551191 -219.636321) (xy 365.528065 -219.684342) (xy 365.498041 -219.728379)
			(xy 365.461789 -219.76745) (xy 365.420118 -219.800681) (xy 365.37396 -219.82733) (xy 365.324346 -219.846802)
			(xy 365.272384 -219.858662) (xy 365.219234 -219.862646) (xy 365.166084 -219.858662) (xy 365.114122 -219.846802)
			(xy 365.064508 -219.82733) (xy 365.01835 -219.800681) (xy 364.976679 -219.76745) (xy 364.940427 -219.728379)
			(xy 364.910403 -219.684342) (xy 364.887277 -219.636321) (xy 364.871567 -219.585391) (xy 364.863624 -219.532687)
			(xy 364.635044 -219.532687) (xy 364.627101 -219.585391) (xy 364.611391 -219.636321) (xy 364.588265 -219.684342)
			(xy 364.558241 -219.728379) (xy 364.521989 -219.76745) (xy 364.480318 -219.800681) (xy 364.43416 -219.82733)
			(xy 364.384546 -219.846802) (xy 364.332584 -219.858662) (xy 364.279434 -219.862646) (xy 364.226284 -219.858662)
			(xy 364.174322 -219.846802) (xy 364.124708 -219.82733) (xy 364.07855 -219.800681) (xy 364.036879 -219.76745)
			(xy 364.000627 -219.728379) (xy 363.970603 -219.684342) (xy 363.947477 -219.636321) (xy 363.931767 -219.585391)
			(xy 363.923824 -219.532687) (xy 363.695244 -219.532687) (xy 363.687301 -219.585391) (xy 363.671591 -219.636321)
			(xy 363.648465 -219.684342) (xy 363.618441 -219.728379) (xy 363.582189 -219.76745) (xy 363.540518 -219.800681)
			(xy 363.49436 -219.82733) (xy 363.444746 -219.846802) (xy 363.392784 -219.858662) (xy 363.339634 -219.862646)
			(xy 363.286484 -219.858662) (xy 363.234522 -219.846802) (xy 363.184908 -219.82733) (xy 363.13875 -219.800681)
			(xy 363.097079 -219.76745) (xy 363.060827 -219.728379) (xy 363.030803 -219.684342) (xy 363.007677 -219.636321)
			(xy 362.991967 -219.585391) (xy 362.984024 -219.532687) (xy 362.755444 -219.532687) (xy 362.747501 -219.585391)
			(xy 362.731791 -219.636321) (xy 362.708665 -219.684342) (xy 362.678641 -219.728379) (xy 362.642389 -219.76745)
			(xy 362.600718 -219.800681) (xy 362.55456 -219.82733) (xy 362.504946 -219.846802) (xy 362.452984 -219.858662)
			(xy 362.399834 -219.862646) (xy 362.346684 -219.858662) (xy 362.294722 -219.846802) (xy 362.245108 -219.82733)
			(xy 362.19895 -219.800681) (xy 362.157279 -219.76745) (xy 362.121027 -219.728379) (xy 362.091003 -219.684342)
			(xy 362.067877 -219.636321) (xy 362.052167 -219.585391) (xy 362.044224 -219.532687) (xy 361.815644 -219.532687)
			(xy 361.807701 -219.585391) (xy 361.791991 -219.636321) (xy 361.768865 -219.684342) (xy 361.738841 -219.728379)
			(xy 361.702589 -219.76745) (xy 361.660918 -219.800681) (xy 361.61476 -219.82733) (xy 361.565146 -219.846802)
			(xy 361.513184 -219.858662) (xy 361.460034 -219.862646) (xy 361.406884 -219.858662) (xy 361.354922 -219.846802)
			(xy 361.305308 -219.82733) (xy 361.25915 -219.800681) (xy 361.217479 -219.76745) (xy 361.181227 -219.728379)
			(xy 361.151203 -219.684342) (xy 361.128077 -219.636321) (xy 361.112367 -219.585391) (xy 361.104424 -219.532687)
			(xy 360.875844 -219.532687) (xy 360.867901 -219.585391) (xy 360.852191 -219.636321) (xy 360.829065 -219.684342)
			(xy 360.799041 -219.728379) (xy 360.762789 -219.76745) (xy 360.721118 -219.800681) (xy 360.67496 -219.82733)
			(xy 360.625346 -219.846802) (xy 360.573384 -219.858662) (xy 360.520234 -219.862646) (xy 360.467084 -219.858662)
			(xy 360.415122 -219.846802) (xy 360.365508 -219.82733) (xy 360.31935 -219.800681) (xy 360.277679 -219.76745)
			(xy 360.241427 -219.728379) (xy 360.211403 -219.684342) (xy 360.188277 -219.636321) (xy 360.172567 -219.585391)
			(xy 360.164624 -219.532687) (xy 359.936054 -219.532687) (xy 359.936051 -219.532869) (xy 359.928011 -219.585927)
			(xy 359.92054 -219.611702) (xy 359.918254 -219.619068) (xy 359.918254 -219.863162) (xy 359.918678 -219.877062)
			(xy 359.926169 -219.903834) (xy 359.940606 -219.927591) (xy 359.960918 -219.946571) (xy 359.985598 -219.959367)
			(xy 360.012815 -219.965029) (xy 360.026712 -219.964508) (xy 360.050334 -219.963746) (xy 360.076985 -219.964246)
			(xy 360.129691 -219.972195) (xy 360.180624 -219.98791) (xy 360.228646 -220.01104) (xy 360.272685 -220.041069)
			(xy 360.311757 -220.077326) (xy 360.344988 -220.119001) (xy 360.371638 -220.165163) (xy 360.39111 -220.214781)
			(xy 360.40297 -220.266747) (xy 360.406951 -220.319854) (xy 360.633772 -220.319854) (xy 360.63427 -220.293205)
			(xy 360.642213 -220.240501) (xy 360.657923 -220.189571) (xy 360.681049 -220.14155) (xy 360.711073 -220.097513)
			(xy 360.747325 -220.058442) (xy 360.788996 -220.025211) (xy 360.835154 -219.998562) (xy 360.884768 -219.97909)
			(xy 360.93673 -219.96723) (xy 360.98988 -219.963247) (xy 361.04303 -219.96723) (xy 361.094992 -219.97909)
			(xy 361.144606 -219.998562) (xy 361.190764 -220.025211) (xy 361.232435 -220.058442) (xy 361.268687 -220.097513)
			(xy 361.298711 -220.14155) (xy 361.321837 -220.189571) (xy 361.337547 -220.240501) (xy 361.34549 -220.293205)
			(xy 361.345988 -220.319854) (xy 361.345593 -220.343057) (xy 361.34514 -220.346503) (xy 361.574324 -220.346503)
			(xy 361.574324 -220.293205) (xy 361.582267 -220.240501) (xy 361.597977 -220.189571) (xy 361.621103 -220.14155)
			(xy 361.651127 -220.097513) (xy 361.687379 -220.058442) (xy 361.72905 -220.025211) (xy 361.775208 -219.998562)
			(xy 361.824822 -219.97909) (xy 361.876784 -219.96723) (xy 361.929934 -219.963247) (xy 361.983084 -219.96723)
			(xy 362.035046 -219.97909) (xy 362.08466 -219.998562) (xy 362.130818 -220.025211) (xy 362.172489 -220.058442)
			(xy 362.208741 -220.097513) (xy 362.238765 -220.14155) (xy 362.261891 -220.189571) (xy 362.277601 -220.240501)
			(xy 362.285544 -220.293205) (xy 362.286042 -220.319854) (xy 362.513372 -220.319854) (xy 362.51387 -220.293205)
			(xy 362.521813 -220.240501) (xy 362.537523 -220.189571) (xy 362.560649 -220.14155) (xy 362.590673 -220.097513)
			(xy 362.626925 -220.058442) (xy 362.668596 -220.025211) (xy 362.714754 -219.998562) (xy 362.764368 -219.97909)
			(xy 362.81633 -219.96723) (xy 362.86948 -219.963247) (xy 362.92263 -219.96723) (xy 362.974592 -219.97909)
			(xy 363.024206 -219.998562) (xy 363.070364 -220.025211) (xy 363.112035 -220.058442) (xy 363.148287 -220.097513)
			(xy 363.178311 -220.14155) (xy 363.201437 -220.189571) (xy 363.217147 -220.240501) (xy 363.22509 -220.293205)
			(xy 363.225588 -220.319854) (xy 363.225193 -220.343057) (xy 363.22474 -220.346503) (xy 363.453924 -220.346503)
			(xy 363.453924 -220.293205) (xy 363.461867 -220.240501) (xy 363.477577 -220.189571) (xy 363.500703 -220.14155)
			(xy 363.530727 -220.097513) (xy 363.566979 -220.058442) (xy 363.60865 -220.025211) (xy 363.654808 -219.998562)
			(xy 363.704422 -219.97909) (xy 363.756384 -219.96723) (xy 363.809534 -219.963247) (xy 363.862684 -219.96723)
			(xy 363.914646 -219.97909) (xy 363.96426 -219.998562) (xy 364.010418 -220.025211) (xy 364.052089 -220.058442)
			(xy 364.088341 -220.097513) (xy 364.118365 -220.14155) (xy 364.141491 -220.189571) (xy 364.157201 -220.240501)
			(xy 364.165144 -220.293205) (xy 364.165642 -220.319854) (xy 364.392972 -220.319854) (xy 364.39347 -220.293205)
			(xy 364.401413 -220.240501) (xy 364.417123 -220.189571) (xy 364.440249 -220.14155) (xy 364.470273 -220.097513)
			(xy 364.506525 -220.058442) (xy 364.548196 -220.025211) (xy 364.594354 -219.998562) (xy 364.643968 -219.97909)
			(xy 364.69593 -219.96723) (xy 364.74908 -219.963247) (xy 364.80223 -219.96723) (xy 364.854192 -219.97909)
			(xy 364.903806 -219.998562) (xy 364.949964 -220.025211) (xy 364.991635 -220.058442) (xy 365.027887 -220.097513)
			(xy 365.057911 -220.14155) (xy 365.081037 -220.189571) (xy 365.096747 -220.240501) (xy 365.10469 -220.293205)
			(xy 365.105188 -220.319854) (xy 365.104793 -220.343057) (xy 365.10434 -220.346503) (xy 365.333524 -220.346503)
			(xy 365.333524 -220.293205) (xy 365.341467 -220.240501) (xy 365.357177 -220.189571) (xy 365.380303 -220.14155)
			(xy 365.410327 -220.097513) (xy 365.446579 -220.058442) (xy 365.48825 -220.025211) (xy 365.534408 -219.998562)
			(xy 365.584022 -219.97909) (xy 365.635984 -219.96723) (xy 365.689134 -219.963247) (xy 365.742284 -219.96723)
			(xy 365.794246 -219.97909) (xy 365.84386 -219.998562) (xy 365.890018 -220.025211) (xy 365.931689 -220.058442)
			(xy 365.967941 -220.097513) (xy 365.997965 -220.14155) (xy 366.021091 -220.189571) (xy 366.036801 -220.240501)
			(xy 366.044744 -220.293205) (xy 366.045242 -220.319854) (xy 366.272572 -220.319854) (xy 366.27307 -220.293205)
			(xy 366.281013 -220.240501) (xy 366.296723 -220.189571) (xy 366.319849 -220.14155) (xy 366.349873 -220.097513)
			(xy 366.386125 -220.058442) (xy 366.427796 -220.025211) (xy 366.473954 -219.998562) (xy 366.523568 -219.97909)
			(xy 366.57553 -219.96723) (xy 366.62868 -219.963247) (xy 366.68183 -219.96723) (xy 366.733792 -219.97909)
			(xy 366.783406 -219.998562) (xy 366.829564 -220.025211) (xy 366.871235 -220.058442) (xy 366.907487 -220.097513)
			(xy 366.937511 -220.14155) (xy 366.960637 -220.189571) (xy 366.976347 -220.240501) (xy 366.98429 -220.293205)
			(xy 366.984788 -220.319854) (xy 366.984393 -220.343057) (xy 366.978349 -220.389067) (xy 366.966371 -220.4339)
			(xy 366.957864 -220.45549) (xy 366.948466 -220.478604) (xy 367.121186 -220.777562) (xy 367.145824 -220.780864)
			(xy 367.171161 -220.784719) (xy 367.220465 -220.798707) (xy 367.267255 -220.819616) (xy 367.310565 -220.847014)
			(xy 367.349503 -220.880335) (xy 367.383264 -220.918892) (xy 367.411152 -220.96189) (xy 367.43259 -221.008439)
			(xy 367.447137 -221.057581) (xy 367.454491 -221.1083) (xy 367.454942 -221.133924) (xy 367.454444 -221.160573)
			(xy 367.446501 -221.213277) (xy 367.430791 -221.264207) (xy 367.407665 -221.312228) (xy 367.377641 -221.356265)
			(xy 367.341389 -221.395336) (xy 367.299718 -221.428567) (xy 367.25356 -221.455216) (xy 367.203946 -221.474688)
			(xy 367.151984 -221.486548) (xy 367.098834 -221.490532) (xy 367.045684 -221.486548) (xy 366.993722 -221.474688)
			(xy 366.944108 -221.455216) (xy 366.89795 -221.428567) (xy 366.856279 -221.395336) (xy 366.820027 -221.356265)
			(xy 366.790003 -221.312228) (xy 366.766877 -221.264207) (xy 366.751167 -221.213277) (xy 366.743224 -221.160573)
			(xy 366.742726 -221.133924) (xy 366.743101 -221.110679) (xy 366.749145 -221.064584) (xy 366.761133 -221.019666)
			(xy 366.76965 -220.998034) (xy 366.779302 -220.97492) (xy 366.606836 -220.676216) (xy 366.581944 -220.672914)
			(xy 366.556598 -220.669039) (xy 366.507261 -220.65509) (xy 366.460434 -220.634209) (xy 366.417086 -220.60683)
			(xy 366.378112 -220.573517) (xy 366.344318 -220.534959) (xy 366.316402 -220.491954) (xy 366.294943 -220.44539)
			(xy 366.280382 -220.39623) (xy 366.273022 -220.345489) (xy 366.272572 -220.319854) (xy 366.045242 -220.319854)
			(xy 366.044744 -220.346503) (xy 366.036801 -220.399207) (xy 366.021091 -220.450137) (xy 365.997965 -220.498158)
			(xy 365.967941 -220.542195) (xy 365.931689 -220.581266) (xy 365.890018 -220.614497) (xy 365.84386 -220.641146)
			(xy 365.794246 -220.660618) (xy 365.742284 -220.672478) (xy 365.689134 -220.676462) (xy 365.635984 -220.672478)
			(xy 365.584022 -220.660618) (xy 365.534408 -220.641146) (xy 365.48825 -220.614497) (xy 365.446579 -220.581266)
			(xy 365.410327 -220.542195) (xy 365.380303 -220.498158) (xy 365.357177 -220.450137) (xy 365.341467 -220.399207)
			(xy 365.333524 -220.346503) (xy 365.10434 -220.346503) (xy 365.098749 -220.389067) (xy 365.086771 -220.4339)
			(xy 365.078264 -220.45549) (xy 365.068866 -220.478604) (xy 365.241586 -220.777562) (xy 365.266224 -220.780864)
			(xy 365.291561 -220.784719) (xy 365.340865 -220.798707) (xy 365.387655 -220.819616) (xy 365.430965 -220.847014)
			(xy 365.469903 -220.880335) (xy 365.503664 -220.918892) (xy 365.531552 -220.96189) (xy 365.55299 -221.008439)
			(xy 365.567537 -221.057581) (xy 365.574891 -221.1083) (xy 365.575342 -221.133924) (xy 365.574844 -221.160573)
			(xy 365.566901 -221.213277) (xy 365.551191 -221.264207) (xy 365.528065 -221.312228) (xy 365.498041 -221.356265)
			(xy 365.461789 -221.395336) (xy 365.420118 -221.428567) (xy 365.37396 -221.455216) (xy 365.324346 -221.474688)
			(xy 365.272384 -221.486548) (xy 365.219234 -221.490532) (xy 365.166084 -221.486548) (xy 365.114122 -221.474688)
			(xy 365.064508 -221.455216) (xy 365.01835 -221.428567) (xy 364.976679 -221.395336) (xy 364.940427 -221.356265)
			(xy 364.910403 -221.312228) (xy 364.887277 -221.264207) (xy 364.871567 -221.213277) (xy 364.863624 -221.160573)
			(xy 364.863126 -221.133924) (xy 364.863501 -221.110679) (xy 364.869545 -221.064584) (xy 364.881533 -221.019666)
			(xy 364.89005 -220.998034) (xy 364.899702 -220.97492) (xy 364.727236 -220.676216) (xy 364.702344 -220.672914)
			(xy 364.676998 -220.669039) (xy 364.627661 -220.65509) (xy 364.580834 -220.634209) (xy 364.537486 -220.60683)
			(xy 364.498512 -220.573517) (xy 364.464718 -220.534959) (xy 364.436802 -220.491954) (xy 364.415343 -220.44539)
			(xy 364.400782 -220.39623) (xy 364.393422 -220.345489) (xy 364.392972 -220.319854) (xy 364.165642 -220.319854)
			(xy 364.165144 -220.346503) (xy 364.157201 -220.399207) (xy 364.141491 -220.450137) (xy 364.118365 -220.498158)
			(xy 364.088341 -220.542195) (xy 364.052089 -220.581266) (xy 364.010418 -220.614497) (xy 363.96426 -220.641146)
			(xy 363.914646 -220.660618) (xy 363.862684 -220.672478) (xy 363.809534 -220.676462) (xy 363.756384 -220.672478)
			(xy 363.704422 -220.660618) (xy 363.654808 -220.641146) (xy 363.60865 -220.614497) (xy 363.566979 -220.581266)
			(xy 363.530727 -220.542195) (xy 363.500703 -220.498158) (xy 363.477577 -220.450137) (xy 363.461867 -220.399207)
			(xy 363.453924 -220.346503) (xy 363.22474 -220.346503) (xy 363.219149 -220.389067) (xy 363.207171 -220.4339)
			(xy 363.198664 -220.45549) (xy 363.189266 -220.478604) (xy 363.361986 -220.777562) (xy 363.386624 -220.780864)
			(xy 363.411961 -220.784719) (xy 363.461265 -220.798707) (xy 363.508055 -220.819616) (xy 363.551365 -220.847014)
			(xy 363.590303 -220.880335) (xy 363.624064 -220.918892) (xy 363.651952 -220.96189) (xy 363.67339 -221.008439)
			(xy 363.687937 -221.057581) (xy 363.695291 -221.1083) (xy 363.695742 -221.133924) (xy 363.695244 -221.160573)
			(xy 363.687301 -221.213277) (xy 363.671591 -221.264207) (xy 363.648465 -221.312228) (xy 363.618441 -221.356265)
			(xy 363.582189 -221.395336) (xy 363.540518 -221.428567) (xy 363.49436 -221.455216) (xy 363.444746 -221.474688)
			(xy 363.392784 -221.486548) (xy 363.339634 -221.490532) (xy 363.286484 -221.486548) (xy 363.234522 -221.474688)
			(xy 363.184908 -221.455216) (xy 363.13875 -221.428567) (xy 363.097079 -221.395336) (xy 363.060827 -221.356265)
			(xy 363.030803 -221.312228) (xy 363.007677 -221.264207) (xy 362.991967 -221.213277) (xy 362.984024 -221.160573)
			(xy 362.983526 -221.133924) (xy 362.983901 -221.110679) (xy 362.989945 -221.064584) (xy 363.001933 -221.019666)
			(xy 363.01045 -220.998034) (xy 363.020102 -220.97492) (xy 362.847636 -220.676216) (xy 362.822744 -220.672914)
			(xy 362.797398 -220.669039) (xy 362.748061 -220.65509) (xy 362.701234 -220.634209) (xy 362.657886 -220.60683)
			(xy 362.618912 -220.573517) (xy 362.585118 -220.534959) (xy 362.557202 -220.491954) (xy 362.535743 -220.44539)
			(xy 362.521182 -220.39623) (xy 362.513822 -220.345489) (xy 362.513372 -220.319854) (xy 362.286042 -220.319854)
			(xy 362.285544 -220.346503) (xy 362.277601 -220.399207) (xy 362.261891 -220.450137) (xy 362.238765 -220.498158)
			(xy 362.208741 -220.542195) (xy 362.172489 -220.581266) (xy 362.130818 -220.614497) (xy 362.08466 -220.641146)
			(xy 362.035046 -220.660618) (xy 361.983084 -220.672478) (xy 361.929934 -220.676462) (xy 361.876784 -220.672478)
			(xy 361.824822 -220.660618) (xy 361.775208 -220.641146) (xy 361.72905 -220.614497) (xy 361.687379 -220.581266)
			(xy 361.651127 -220.542195) (xy 361.621103 -220.498158) (xy 361.597977 -220.450137) (xy 361.582267 -220.399207)
			(xy 361.574324 -220.346503) (xy 361.34514 -220.346503) (xy 361.339549 -220.389067) (xy 361.327571 -220.4339)
			(xy 361.319064 -220.45549) (xy 361.309666 -220.478604) (xy 361.482386 -220.777562) (xy 361.507024 -220.780864)
			(xy 361.532361 -220.784719) (xy 361.581665 -220.798707) (xy 361.628455 -220.819616) (xy 361.671765 -220.847014)
			(xy 361.710703 -220.880335) (xy 361.744464 -220.918892) (xy 361.772352 -220.96189) (xy 361.79379 -221.008439)
			(xy 361.808337 -221.057581) (xy 361.815691 -221.1083) (xy 361.816142 -221.133924) (xy 361.815644 -221.160573)
			(xy 361.807701 -221.213277) (xy 361.791991 -221.264207) (xy 361.768865 -221.312228) (xy 361.738841 -221.356265)
			(xy 361.702589 -221.395336) (xy 361.660918 -221.428567) (xy 361.61476 -221.455216) (xy 361.565146 -221.474688)
			(xy 361.513184 -221.486548) (xy 361.460034 -221.490532) (xy 361.406884 -221.486548) (xy 361.354922 -221.474688)
			(xy 361.305308 -221.455216) (xy 361.25915 -221.428567) (xy 361.217479 -221.395336) (xy 361.181227 -221.356265)
			(xy 361.151203 -221.312228) (xy 361.128077 -221.264207) (xy 361.112367 -221.213277) (xy 361.104424 -221.160573)
			(xy 361.103926 -221.133924) (xy 361.104301 -221.110679) (xy 361.110345 -221.064584) (xy 361.122333 -221.019666)
			(xy 361.13085 -220.998034) (xy 361.140502 -220.97492) (xy 360.968036 -220.676216) (xy 360.943144 -220.672914)
			(xy 360.917798 -220.669039) (xy 360.868461 -220.65509) (xy 360.821634 -220.634209) (xy 360.778286 -220.60683)
			(xy 360.739312 -220.573517) (xy 360.705518 -220.534959) (xy 360.677602 -220.491954) (xy 360.656143 -220.44539)
			(xy 360.641582 -220.39623) (xy 360.634222 -220.345489) (xy 360.633772 -220.319854) (xy 360.406951 -220.319854)
			(xy 360.406954 -220.3199) (xy 360.40297 -220.373053) (xy 360.39111 -220.425019) (xy 360.371638 -220.474637)
			(xy 360.344988 -220.520799) (xy 360.311757 -220.562474) (xy 360.272685 -220.598731) (xy 360.228646 -220.62876)
			(xy 360.180624 -220.65189) (xy 360.129691 -220.667605) (xy 360.076985 -220.675554) (xy 360.050334 -220.675962)
			(xy 360.026712 -220.6752) (xy 360.012823 -220.674739) (xy 359.985632 -220.680416) (xy 359.960977 -220.693211)
			(xy 359.940682 -220.712178) (xy 359.926251 -220.735912) (xy 359.91875 -220.762658) (xy 359.918254 -220.776546)
			(xy 359.918254 -221.020894) (xy 359.92054 -221.02826) (xy 359.928039 -221.054029) (xy 359.936077 -221.10709)
			(xy 359.936542 -221.133924) (xy 359.936052 -221.160756) (xy 359.928014 -221.213814) (xy 359.92054 -221.239588)
			(xy 359.918254 -221.246954) (xy 359.918254 -221.59976) (xy 359.974134 -221.59976) (xy 359.979214 -221.598744)
			(xy 360.00309 -221.59468) (xy 360.027728 -221.591378) (xy 360.200194 -221.29242) (xy 360.190796 -221.269306)
			(xy 360.182355 -221.247745) (xy 360.170478 -221.20299) (xy 360.164488 -221.157076) (xy 360.164126 -221.133924)
			(xy 360.164624 -221.107275) (xy 360.172567 -221.054571) (xy 360.188277 -221.003641) (xy 360.211403 -220.95562)
			(xy 360.241427 -220.911583) (xy 360.277679 -220.872512) (xy 360.31935 -220.839281) (xy 360.365508 -220.812632)
			(xy 360.415122 -220.79316) (xy 360.467084 -220.7813) (xy 360.520234 -220.777317) (xy 360.573384 -220.7813)
			(xy 360.625346 -220.79316) (xy 360.67496 -220.812632) (xy 360.721118 -220.839281) (xy 360.762789 -220.872512)
			(xy 360.799041 -220.911583) (xy 360.829065 -220.95562) (xy 360.852191 -221.003641) (xy 360.867901 -221.054571)
			(xy 360.875844 -221.107275) (xy 360.876342 -221.133924) (xy 360.875893 -221.159574) (xy 360.868529 -221.210342)
			(xy 360.853958 -221.259528) (xy 360.83248 -221.306115) (xy 360.80454 -221.349138) (xy 360.770716 -221.387708)
			(xy 360.731709 -221.421025) (xy 360.688324 -221.448401) (xy 360.641461 -221.469269) (xy 360.592089 -221.483198)
			(xy 360.566716 -221.486984) (xy 360.541824 -221.490286) (xy 360.369612 -221.788736) (xy 360.379264 -221.81185)
			(xy 360.387779 -221.833482) (xy 360.399765 -221.8784) (xy 360.405807 -221.924495) (xy 360.406188 -221.94774)
			(xy 360.405662 -221.974389) (xy 360.63427 -221.974389) (xy 360.63427 -221.921091) (xy 360.642213 -221.868387)
			(xy 360.657923 -221.817457) (xy 360.681049 -221.769436) (xy 360.711073 -221.725399) (xy 360.747325 -221.686328)
			(xy 360.788996 -221.653097) (xy 360.835154 -221.626448) (xy 360.884768 -221.606976) (xy 360.93673 -221.595116)
			(xy 360.98988 -221.591133) (xy 361.04303 -221.595116) (xy 361.094992 -221.606976) (xy 361.144606 -221.626448)
			(xy 361.190764 -221.653097) (xy 361.232435 -221.686328) (xy 361.268687 -221.725399) (xy 361.298711 -221.769436)
			(xy 361.321837 -221.817457) (xy 361.337547 -221.868387) (xy 361.34549 -221.921091) (xy 361.345988 -221.94774)
			(xy 361.573826 -221.94774) (xy 361.574306 -221.922113) (xy 361.581636 -221.871386) (xy 361.596164 -221.822234)
			(xy 361.61759 -221.775673) (xy 361.645471 -221.732666) (xy 361.679231 -221.694101) (xy 361.718172 -221.660776)
			(xy 361.76149 -221.63338) (xy 361.808288 -221.612478) (xy 361.8576 -221.598502) (xy 361.882944 -221.59468)
			(xy 361.907582 -221.591378) (xy 362.080048 -221.292674) (xy 362.07065 -221.26956) (xy 362.062155 -221.247966)
			(xy 362.050179 -221.203133) (xy 362.044119 -221.157126) (xy 362.043726 -221.133924) (xy 362.044224 -221.107275)
			(xy 362.052167 -221.054571) (xy 362.067877 -221.003641) (xy 362.091003 -220.95562) (xy 362.121027 -220.911583)
			(xy 362.157279 -220.872512) (xy 362.19895 -220.839281) (xy 362.245108 -220.812632) (xy 362.294722 -220.79316)
			(xy 362.346684 -220.7813) (xy 362.399834 -220.777317) (xy 362.452984 -220.7813) (xy 362.504946 -220.79316)
			(xy 362.55456 -220.812632) (xy 362.600718 -220.839281) (xy 362.642389 -220.872512) (xy 362.678641 -220.911583)
			(xy 362.708665 -220.95562) (xy 362.731791 -221.003641) (xy 362.747501 -221.054571) (xy 362.755444 -221.107275)
			(xy 362.755942 -221.133924) (xy 362.755514 -221.159564) (xy 362.748168 -221.210316) (xy 362.733618 -221.259489)
			(xy 362.712163 -221.306066) (xy 362.684249 -221.349083) (xy 362.650452 -221.38765) (xy 362.611472 -221.420971)
			(xy 362.568115 -221.448354) (xy 362.521278 -221.469235) (xy 362.47193 -221.48318) (xy 362.44657 -221.486984)
			(xy 362.421678 -221.490286) (xy 362.249466 -221.788736) (xy 362.259118 -221.81185) (xy 362.267648 -221.833477)
			(xy 362.27963 -221.878397) (xy 362.285669 -221.924494) (xy 362.286042 -221.94774) (xy 362.285544 -221.974389)
			(xy 362.514124 -221.974389) (xy 362.514124 -221.921091) (xy 362.522067 -221.868387) (xy 362.537777 -221.817457)
			(xy 362.560903 -221.769436) (xy 362.590927 -221.725399) (xy 362.627179 -221.686328) (xy 362.66885 -221.653097)
			(xy 362.715008 -221.626448) (xy 362.764622 -221.606976) (xy 362.816584 -221.595116) (xy 362.869734 -221.591133)
			(xy 362.922884 -221.595116) (xy 362.974846 -221.606976) (xy 363.02446 -221.626448) (xy 363.070618 -221.653097)
			(xy 363.112289 -221.686328) (xy 363.148541 -221.725399) (xy 363.178565 -221.769436) (xy 363.201691 -221.817457)
			(xy 363.217401 -221.868387) (xy 363.225344 -221.921091) (xy 363.225842 -221.94774) (xy 363.453172 -221.94774)
			(xy 363.453612 -221.922111) (xy 363.460943 -221.87138) (xy 363.475473 -221.822225) (xy 363.496903 -221.775662)
			(xy 363.524788 -221.732653) (xy 363.558553 -221.694088) (xy 363.5975 -221.660763) (xy 363.640823 -221.633369)
			(xy 363.687626 -221.61247) (xy 363.736943 -221.598499) (xy 363.76229 -221.59468) (xy 363.786928 -221.591378)
			(xy 363.959394 -221.29242) (xy 363.949996 -221.269306) (xy 363.941526 -221.247754) (xy 363.929643 -221.202998)
			(xy 363.923675 -221.157078) (xy 363.923326 -221.133924) (xy 363.923824 -221.107275) (xy 363.931767 -221.054571)
			(xy 363.947477 -221.003641) (xy 363.970603 -220.95562) (xy 364.000627 -220.911583) (xy 364.036879 -220.872512)
			(xy 364.07855 -220.839281) (xy 364.124708 -220.812632) (xy 364.174322 -220.79316) (xy 364.226284 -220.7813)
			(xy 364.279434 -220.777317) (xy 364.332584 -220.7813) (xy 364.384546 -220.79316) (xy 364.43416 -220.812632)
			(xy 364.480318 -220.839281) (xy 364.521989 -220.872512) (xy 364.558241 -220.911583) (xy 364.588265 -220.95562)
			(xy 364.611391 -221.003641) (xy 364.627101 -221.054571) (xy 364.635044 -221.107275) (xy 364.635542 -221.133924)
			(xy 364.635086 -221.159573) (xy 364.627722 -221.21034) (xy 364.613151 -221.259526) (xy 364.591674 -221.306112)
			(xy 364.563734 -221.349134) (xy 364.529911 -221.387703) (xy 364.490904 -221.421019) (xy 364.447521 -221.448395)
			(xy 364.400659 -221.469263) (xy 364.351287 -221.483191) (xy 364.325916 -221.486984) (xy 364.301024 -221.490286)
			(xy 364.128812 -221.788736) (xy 364.138464 -221.81185) (xy 364.146992 -221.833478) (xy 364.158975 -221.878398)
			(xy 364.165015 -221.924495) (xy 364.165388 -221.94774) (xy 364.16489 -221.974389) (xy 364.39347 -221.974389)
			(xy 364.39347 -221.921091) (xy 364.401413 -221.868387) (xy 364.417123 -221.817457) (xy 364.440249 -221.769436)
			(xy 364.470273 -221.725399) (xy 364.506525 -221.686328) (xy 364.548196 -221.653097) (xy 364.594354 -221.626448)
			(xy 364.643968 -221.606976) (xy 364.69593 -221.595116) (xy 364.74908 -221.591133) (xy 364.80223 -221.595116)
			(xy 364.854192 -221.606976) (xy 364.903806 -221.626448) (xy 364.949964 -221.653097) (xy 364.991635 -221.686328)
			(xy 365.027887 -221.725399) (xy 365.057911 -221.769436) (xy 365.081037 -221.817457) (xy 365.096747 -221.868387)
			(xy 365.10469 -221.921091) (xy 365.105188 -221.94774) (xy 365.332772 -221.94774) (xy 365.333212 -221.922111)
			(xy 365.340543 -221.87138) (xy 365.355073 -221.822225) (xy 365.376503 -221.775662) (xy 365.404388 -221.732653)
			(xy 365.438153 -221.694088) (xy 365.4771 -221.660763) (xy 365.520423 -221.633369) (xy 365.567226 -221.61247)
			(xy 365.616543 -221.598499) (xy 365.64189 -221.59468) (xy 365.666528 -221.591378) (xy 365.838994 -221.29242)
			(xy 365.829596 -221.269306) (xy 365.821126 -221.247754) (xy 365.809243 -221.202998) (xy 365.803275 -221.157078)
			(xy 365.802926 -221.133924) (xy 365.803424 -221.107275) (xy 365.811367 -221.054571) (xy 365.827077 -221.003641)
			(xy 365.850203 -220.95562) (xy 365.880227 -220.911583) (xy 365.916479 -220.872512) (xy 365.95815 -220.839281)
			(xy 366.004308 -220.812632) (xy 366.053922 -220.79316) (xy 366.105884 -220.7813) (xy 366.159034 -220.777317)
			(xy 366.212184 -220.7813) (xy 366.264146 -220.79316) (xy 366.31376 -220.812632) (xy 366.359918 -220.839281)
			(xy 366.401589 -220.872512) (xy 366.437841 -220.911583) (xy 366.467865 -220.95562) (xy 366.490991 -221.003641)
			(xy 366.506701 -221.054571) (xy 366.514644 -221.107275) (xy 366.515142 -221.133924) (xy 366.514686 -221.159573)
			(xy 366.507322 -221.21034) (xy 366.492751 -221.259526) (xy 366.471274 -221.306112) (xy 366.443334 -221.349134)
			(xy 366.409511 -221.387703) (xy 366.370504 -221.421019) (xy 366.327121 -221.448395) (xy 366.280259 -221.469263)
			(xy 366.230887 -221.483191) (xy 366.205516 -221.486984) (xy 366.180624 -221.490286) (xy 366.008412 -221.788736)
			(xy 366.018064 -221.81185) (xy 366.026592 -221.833478) (xy 366.038575 -221.878398) (xy 366.044615 -221.924495)
			(xy 366.044988 -221.94774) (xy 366.04449 -221.974389) (xy 366.27307 -221.974389) (xy 366.27307 -221.921091)
			(xy 366.281013 -221.868387) (xy 366.296723 -221.817457) (xy 366.319849 -221.769436) (xy 366.349873 -221.725399)
			(xy 366.386125 -221.686328) (xy 366.427796 -221.653097) (xy 366.473954 -221.626448) (xy 366.523568 -221.606976)
			(xy 366.57553 -221.595116) (xy 366.62868 -221.591133) (xy 366.68183 -221.595116) (xy 366.733792 -221.606976)
			(xy 366.783406 -221.626448) (xy 366.829564 -221.653097) (xy 366.871235 -221.686328) (xy 366.907487 -221.725399)
			(xy 366.937511 -221.769436) (xy 366.960637 -221.817457) (xy 366.976347 -221.868387) (xy 366.98429 -221.921091)
			(xy 366.984788 -221.94774) (xy 366.98429 -221.974389) (xy 366.976347 -222.027093) (xy 366.960637 -222.078023)
			(xy 366.937511 -222.126044) (xy 366.907487 -222.170081) (xy 366.871235 -222.209152) (xy 366.829564 -222.242383)
			(xy 366.783406 -222.269032) (xy 366.733792 -222.288504) (xy 366.68183 -222.300364) (xy 366.62868 -222.304348)
			(xy 366.57553 -222.300364) (xy 366.523568 -222.288504) (xy 366.473954 -222.269032) (xy 366.427796 -222.242383)
			(xy 366.386125 -222.209152) (xy 366.349873 -222.170081) (xy 366.319849 -222.126044) (xy 366.296723 -222.078023)
			(xy 366.281013 -222.027093) (xy 366.27307 -221.974389) (xy 366.04449 -221.974389) (xy 366.036547 -222.027093)
			(xy 366.020837 -222.078023) (xy 365.997711 -222.126044) (xy 365.967687 -222.170081) (xy 365.931435 -222.209152)
			(xy 365.889764 -222.242383) (xy 365.843606 -222.269032) (xy 365.793992 -222.288504) (xy 365.74203 -222.300364)
			(xy 365.68888 -222.304348) (xy 365.63573 -222.300364) (xy 365.583768 -222.288504) (xy 365.534154 -222.269032)
			(xy 365.487996 -222.242383) (xy 365.446325 -222.209152) (xy 365.410073 -222.170081) (xy 365.380049 -222.126044)
			(xy 365.356923 -222.078023) (xy 365.341213 -222.027093) (xy 365.33327 -221.974389) (xy 365.332772 -221.94774)
			(xy 365.105188 -221.94774) (xy 365.10469 -221.974389) (xy 365.096747 -222.027093) (xy 365.081037 -222.078023)
			(xy 365.057911 -222.126044) (xy 365.027887 -222.170081) (xy 364.991635 -222.209152) (xy 364.949964 -222.242383)
			(xy 364.903806 -222.269032) (xy 364.854192 -222.288504) (xy 364.80223 -222.300364) (xy 364.74908 -222.304348)
			(xy 364.69593 -222.300364) (xy 364.643968 -222.288504) (xy 364.594354 -222.269032) (xy 364.548196 -222.242383)
			(xy 364.506525 -222.209152) (xy 364.470273 -222.170081) (xy 364.440249 -222.126044) (xy 364.417123 -222.078023)
			(xy 364.401413 -222.027093) (xy 364.39347 -221.974389) (xy 364.16489 -221.974389) (xy 364.156947 -222.027093)
			(xy 364.141237 -222.078023) (xy 364.118111 -222.126044) (xy 364.088087 -222.170081) (xy 364.051835 -222.209152)
			(xy 364.010164 -222.242383) (xy 363.964006 -222.269032) (xy 363.914392 -222.288504) (xy 363.86243 -222.300364)
			(xy 363.80928 -222.304348) (xy 363.75613 -222.300364) (xy 363.704168 -222.288504) (xy 363.654554 -222.269032)
			(xy 363.608396 -222.242383) (xy 363.566725 -222.209152) (xy 363.530473 -222.170081) (xy 363.500449 -222.126044)
			(xy 363.477323 -222.078023) (xy 363.461613 -222.027093) (xy 363.45367 -221.974389) (xy 363.453172 -221.94774)
			(xy 363.225842 -221.94774) (xy 363.225344 -221.974389) (xy 363.217401 -222.027093) (xy 363.201691 -222.078023)
			(xy 363.178565 -222.126044) (xy 363.148541 -222.170081) (xy 363.112289 -222.209152) (xy 363.070618 -222.242383)
			(xy 363.02446 -222.269032) (xy 362.974846 -222.288504) (xy 362.922884 -222.300364) (xy 362.869734 -222.304348)
			(xy 362.816584 -222.300364) (xy 362.764622 -222.288504) (xy 362.715008 -222.269032) (xy 362.66885 -222.242383)
			(xy 362.627179 -222.209152) (xy 362.590927 -222.170081) (xy 362.560903 -222.126044) (xy 362.537777 -222.078023)
			(xy 362.522067 -222.027093) (xy 362.514124 -221.974389) (xy 362.285544 -221.974389) (xy 362.277601 -222.027093)
			(xy 362.261891 -222.078023) (xy 362.238765 -222.126044) (xy 362.208741 -222.170081) (xy 362.172489 -222.209152)
			(xy 362.130818 -222.242383) (xy 362.08466 -222.269032) (xy 362.035046 -222.288504) (xy 361.983084 -222.300364)
			(xy 361.929934 -222.304348) (xy 361.876784 -222.300364) (xy 361.824822 -222.288504) (xy 361.775208 -222.269032)
			(xy 361.72905 -222.242383) (xy 361.687379 -222.209152) (xy 361.651127 -222.170081) (xy 361.621103 -222.126044)
			(xy 361.597977 -222.078023) (xy 361.582267 -222.027093) (xy 361.574324 -221.974389) (xy 361.573826 -221.94774)
			(xy 361.345988 -221.94774) (xy 361.34549 -221.974389) (xy 361.337547 -222.027093) (xy 361.321837 -222.078023)
			(xy 361.298711 -222.126044) (xy 361.268687 -222.170081) (xy 361.232435 -222.209152) (xy 361.190764 -222.242383)
			(xy 361.144606 -222.269032) (xy 361.094992 -222.288504) (xy 361.04303 -222.300364) (xy 360.98988 -222.304348)
			(xy 360.93673 -222.300364) (xy 360.884768 -222.288504) (xy 360.835154 -222.269032) (xy 360.788996 -222.242383)
			(xy 360.747325 -222.209152) (xy 360.711073 -222.170081) (xy 360.681049 -222.126044) (xy 360.657923 -222.078023)
			(xy 360.642213 -222.027093) (xy 360.63427 -221.974389) (xy 360.405662 -221.974389) (xy 360.405636 -221.97572)
			(xy 360.396876 -222.030992) (xy 360.379578 -222.084212) (xy 360.354167 -222.134071) (xy 360.32127 -222.179342)
			(xy 360.281696 -222.218909) (xy 360.23642 -222.251798) (xy 360.186557 -222.277201) (xy 360.133333 -222.29449)
			(xy 360.078061 -222.303241) (xy 360.05008 -222.303848) (xy 360.026458 -222.303086) (xy 360.012591 -222.302659)
			(xy 359.985455 -222.308382) (xy 359.960861 -222.321196) (xy 359.940623 -222.340156) (xy 359.926232 -222.363862)
			(xy 359.918752 -222.390566) (xy 359.918254 -222.404432) (xy 359.918254 -222.648526) (xy 359.92054 -222.655892)
			(xy 359.928037 -222.681661) (xy 359.93607 -222.734723) (xy 359.936542 -222.761556) (xy 359.936053 -222.788205)
			(xy 360.164624 -222.788205) (xy 360.164624 -222.734907) (xy 360.172567 -222.682203) (xy 360.188277 -222.631273)
			(xy 360.211403 -222.583252) (xy 360.241427 -222.539215) (xy 360.277679 -222.500144) (xy 360.31935 -222.466913)
			(xy 360.365508 -222.440264) (xy 360.415122 -222.420792) (xy 360.467084 -222.408932) (xy 360.520234 -222.404949)
			(xy 360.573384 -222.408932) (xy 360.625346 -222.420792) (xy 360.67496 -222.440264) (xy 360.721118 -222.466913)
			(xy 360.762789 -222.500144) (xy 360.799041 -222.539215) (xy 360.829065 -222.583252) (xy 360.852191 -222.631273)
			(xy 360.867901 -222.682203) (xy 360.875844 -222.734907) (xy 360.876342 -222.761556) (xy 360.875844 -222.788205)
			(xy 361.104424 -222.788205) (xy 361.104424 -222.734907) (xy 361.112367 -222.682203) (xy 361.128077 -222.631273)
			(xy 361.151203 -222.583252) (xy 361.181227 -222.539215) (xy 361.217479 -222.500144) (xy 361.25915 -222.466913)
			(xy 361.305308 -222.440264) (xy 361.354922 -222.420792) (xy 361.406884 -222.408932) (xy 361.460034 -222.404949)
			(xy 361.513184 -222.408932) (xy 361.565146 -222.420792) (xy 361.61476 -222.440264) (xy 361.660918 -222.466913)
			(xy 361.702589 -222.500144) (xy 361.738841 -222.539215) (xy 361.768865 -222.583252) (xy 361.791991 -222.631273)
			(xy 361.807701 -222.682203) (xy 361.815644 -222.734907) (xy 361.816142 -222.761556) (xy 361.815644 -222.788205)
			(xy 362.044224 -222.788205) (xy 362.044224 -222.734907) (xy 362.052167 -222.682203) (xy 362.067877 -222.631273)
			(xy 362.091003 -222.583252) (xy 362.121027 -222.539215) (xy 362.157279 -222.500144) (xy 362.19895 -222.466913)
			(xy 362.245108 -222.440264) (xy 362.294722 -222.420792) (xy 362.346684 -222.408932) (xy 362.399834 -222.404949)
			(xy 362.452984 -222.408932) (xy 362.504946 -222.420792) (xy 362.55456 -222.440264) (xy 362.600718 -222.466913)
			(xy 362.642389 -222.500144) (xy 362.678641 -222.539215) (xy 362.708665 -222.583252) (xy 362.731791 -222.631273)
			(xy 362.747501 -222.682203) (xy 362.755444 -222.734907) (xy 362.755942 -222.761556) (xy 362.755444 -222.788205)
			(xy 362.984024 -222.788205) (xy 362.984024 -222.734907) (xy 362.991967 -222.682203) (xy 363.007677 -222.631273)
			(xy 363.030803 -222.583252) (xy 363.060827 -222.539215) (xy 363.097079 -222.500144) (xy 363.13875 -222.466913)
			(xy 363.184908 -222.440264) (xy 363.234522 -222.420792) (xy 363.286484 -222.408932) (xy 363.339634 -222.404949)
			(xy 363.392784 -222.408932) (xy 363.444746 -222.420792) (xy 363.49436 -222.440264) (xy 363.540518 -222.466913)
			(xy 363.582189 -222.500144) (xy 363.618441 -222.539215) (xy 363.648465 -222.583252) (xy 363.671591 -222.631273)
			(xy 363.687301 -222.682203) (xy 363.695244 -222.734907) (xy 363.695742 -222.761556) (xy 363.695244 -222.788205)
			(xy 363.923824 -222.788205) (xy 363.923824 -222.734907) (xy 363.931767 -222.682203) (xy 363.947477 -222.631273)
			(xy 363.970603 -222.583252) (xy 364.000627 -222.539215) (xy 364.036879 -222.500144) (xy 364.07855 -222.466913)
			(xy 364.124708 -222.440264) (xy 364.174322 -222.420792) (xy 364.226284 -222.408932) (xy 364.279434 -222.404949)
			(xy 364.332584 -222.408932) (xy 364.384546 -222.420792) (xy 364.43416 -222.440264) (xy 364.480318 -222.466913)
			(xy 364.521989 -222.500144) (xy 364.558241 -222.539215) (xy 364.588265 -222.583252) (xy 364.611391 -222.631273)
			(xy 364.627101 -222.682203) (xy 364.635044 -222.734907) (xy 364.635542 -222.761556) (xy 364.635044 -222.788205)
			(xy 364.863624 -222.788205) (xy 364.863624 -222.734907) (xy 364.871567 -222.682203) (xy 364.887277 -222.631273)
			(xy 364.910403 -222.583252) (xy 364.940427 -222.539215) (xy 364.976679 -222.500144) (xy 365.01835 -222.466913)
			(xy 365.064508 -222.440264) (xy 365.114122 -222.420792) (xy 365.166084 -222.408932) (xy 365.219234 -222.404949)
			(xy 365.272384 -222.408932) (xy 365.324346 -222.420792) (xy 365.37396 -222.440264) (xy 365.420118 -222.466913)
			(xy 365.461789 -222.500144) (xy 365.498041 -222.539215) (xy 365.528065 -222.583252) (xy 365.551191 -222.631273)
			(xy 365.566901 -222.682203) (xy 365.574844 -222.734907) (xy 365.575342 -222.761556) (xy 365.574844 -222.788205)
			(xy 365.803424 -222.788205) (xy 365.803424 -222.734907) (xy 365.811367 -222.682203) (xy 365.827077 -222.631273)
			(xy 365.850203 -222.583252) (xy 365.880227 -222.539215) (xy 365.916479 -222.500144) (xy 365.95815 -222.466913)
			(xy 366.004308 -222.440264) (xy 366.053922 -222.420792) (xy 366.105884 -222.408932) (xy 366.159034 -222.404949)
			(xy 366.212184 -222.408932) (xy 366.264146 -222.420792) (xy 366.31376 -222.440264) (xy 366.359918 -222.466913)
			(xy 366.401589 -222.500144) (xy 366.437841 -222.539215) (xy 366.467865 -222.583252) (xy 366.490991 -222.631273)
			(xy 366.506701 -222.682203) (xy 366.514644 -222.734907) (xy 366.515142 -222.761556) (xy 366.514644 -222.788205)
			(xy 366.743224 -222.788205) (xy 366.743224 -222.734907) (xy 366.751167 -222.682203) (xy 366.766877 -222.631273)
			(xy 366.790003 -222.583252) (xy 366.820027 -222.539215) (xy 366.856279 -222.500144) (xy 366.89795 -222.466913)
			(xy 366.944108 -222.440264) (xy 366.993722 -222.420792) (xy 367.045684 -222.408932) (xy 367.098834 -222.404949)
			(xy 367.151984 -222.408932) (xy 367.203946 -222.420792) (xy 367.25356 -222.440264) (xy 367.299718 -222.466913)
			(xy 367.341389 -222.500144) (xy 367.377641 -222.539215) (xy 367.407665 -222.583252) (xy 367.430791 -222.631273)
			(xy 367.446501 -222.682203) (xy 367.454444 -222.734907) (xy 367.454942 -222.761556) (xy 367.454444 -222.788205)
			(xy 367.683024 -222.788205) (xy 367.683024 -222.734907) (xy 367.690967 -222.682203) (xy 367.706677 -222.631273)
			(xy 367.729803 -222.583252) (xy 367.759827 -222.539215) (xy 367.796079 -222.500144) (xy 367.83775 -222.466913)
			(xy 367.883908 -222.440264) (xy 367.933522 -222.420792) (xy 367.985484 -222.408932) (xy 368.038634 -222.404949)
			(xy 368.091784 -222.408932) (xy 368.143746 -222.420792) (xy 368.19336 -222.440264) (xy 368.239518 -222.466913)
			(xy 368.281189 -222.500144) (xy 368.317441 -222.539215) (xy 368.347465 -222.583252) (xy 368.370591 -222.631273)
			(xy 368.386301 -222.682203) (xy 368.394244 -222.734907) (xy 368.394742 -222.761556) (xy 368.394244 -222.788205)
			(xy 368.386301 -222.840909) (xy 368.370591 -222.891839) (xy 368.347465 -222.93986) (xy 368.317441 -222.983897)
			(xy 368.281189 -223.022968) (xy 368.239518 -223.056199) (xy 368.19336 -223.082848) (xy 368.143746 -223.10232)
			(xy 368.091784 -223.11418) (xy 368.038634 -223.118164) (xy 367.985484 -223.11418) (xy 367.933522 -223.10232)
			(xy 367.883908 -223.082848) (xy 367.83775 -223.056199) (xy 367.796079 -223.022968) (xy 367.759827 -222.983897)
			(xy 367.729803 -222.93986) (xy 367.706677 -222.891839) (xy 367.690967 -222.840909) (xy 367.683024 -222.788205)
			(xy 367.454444 -222.788205) (xy 367.446501 -222.840909) (xy 367.430791 -222.891839) (xy 367.407665 -222.93986)
			(xy 367.377641 -222.983897) (xy 367.341389 -223.022968) (xy 367.299718 -223.056199) (xy 367.25356 -223.082848)
			(xy 367.203946 -223.10232) (xy 367.151984 -223.11418) (xy 367.098834 -223.118164) (xy 367.045684 -223.11418)
			(xy 366.993722 -223.10232) (xy 366.944108 -223.082848) (xy 366.89795 -223.056199) (xy 366.856279 -223.022968)
			(xy 366.820027 -222.983897) (xy 366.790003 -222.93986) (xy 366.766877 -222.891839) (xy 366.751167 -222.840909)
			(xy 366.743224 -222.788205) (xy 366.514644 -222.788205) (xy 366.506701 -222.840909) (xy 366.490991 -222.891839)
			(xy 366.467865 -222.93986) (xy 366.437841 -222.983897) (xy 366.401589 -223.022968) (xy 366.359918 -223.056199)
			(xy 366.31376 -223.082848) (xy 366.264146 -223.10232) (xy 366.212184 -223.11418) (xy 366.159034 -223.118164)
			(xy 366.105884 -223.11418) (xy 366.053922 -223.10232) (xy 366.004308 -223.082848) (xy 365.95815 -223.056199)
			(xy 365.916479 -223.022968) (xy 365.880227 -222.983897) (xy 365.850203 -222.93986) (xy 365.827077 -222.891839)
			(xy 365.811367 -222.840909) (xy 365.803424 -222.788205) (xy 365.574844 -222.788205) (xy 365.566901 -222.840909)
			(xy 365.551191 -222.891839) (xy 365.528065 -222.93986) (xy 365.498041 -222.983897) (xy 365.461789 -223.022968)
			(xy 365.420118 -223.056199) (xy 365.37396 -223.082848) (xy 365.324346 -223.10232) (xy 365.272384 -223.11418)
			(xy 365.219234 -223.118164) (xy 365.166084 -223.11418) (xy 365.114122 -223.10232) (xy 365.064508 -223.082848)
			(xy 365.01835 -223.056199) (xy 364.976679 -223.022968) (xy 364.940427 -222.983897) (xy 364.910403 -222.93986)
			(xy 364.887277 -222.891839) (xy 364.871567 -222.840909) (xy 364.863624 -222.788205) (xy 364.635044 -222.788205)
			(xy 364.627101 -222.840909) (xy 364.611391 -222.891839) (xy 364.588265 -222.93986) (xy 364.558241 -222.983897)
			(xy 364.521989 -223.022968) (xy 364.480318 -223.056199) (xy 364.43416 -223.082848) (xy 364.384546 -223.10232)
			(xy 364.332584 -223.11418) (xy 364.279434 -223.118164) (xy 364.226284 -223.11418) (xy 364.174322 -223.10232)
			(xy 364.124708 -223.082848) (xy 364.07855 -223.056199) (xy 364.036879 -223.022968) (xy 364.000627 -222.983897)
			(xy 363.970603 -222.93986) (xy 363.947477 -222.891839) (xy 363.931767 -222.840909) (xy 363.923824 -222.788205)
			(xy 363.695244 -222.788205) (xy 363.687301 -222.840909) (xy 363.671591 -222.891839) (xy 363.648465 -222.93986)
			(xy 363.618441 -222.983897) (xy 363.582189 -223.022968) (xy 363.540518 -223.056199) (xy 363.49436 -223.082848)
			(xy 363.444746 -223.10232) (xy 363.392784 -223.11418) (xy 363.339634 -223.118164) (xy 363.286484 -223.11418)
			(xy 363.234522 -223.10232) (xy 363.184908 -223.082848) (xy 363.13875 -223.056199) (xy 363.097079 -223.022968)
			(xy 363.060827 -222.983897) (xy 363.030803 -222.93986) (xy 363.007677 -222.891839) (xy 362.991967 -222.840909)
			(xy 362.984024 -222.788205) (xy 362.755444 -222.788205) (xy 362.747501 -222.840909) (xy 362.731791 -222.891839)
			(xy 362.708665 -222.93986) (xy 362.678641 -222.983897) (xy 362.642389 -223.022968) (xy 362.600718 -223.056199)
			(xy 362.55456 -223.082848) (xy 362.504946 -223.10232) (xy 362.452984 -223.11418) (xy 362.399834 -223.118164)
			(xy 362.346684 -223.11418) (xy 362.294722 -223.10232) (xy 362.245108 -223.082848) (xy 362.19895 -223.056199)
			(xy 362.157279 -223.022968) (xy 362.121027 -222.983897) (xy 362.091003 -222.93986) (xy 362.067877 -222.891839)
			(xy 362.052167 -222.840909) (xy 362.044224 -222.788205) (xy 361.815644 -222.788205) (xy 361.807701 -222.840909)
			(xy 361.791991 -222.891839) (xy 361.768865 -222.93986) (xy 361.738841 -222.983897) (xy 361.702589 -223.022968)
			(xy 361.660918 -223.056199) (xy 361.61476 -223.082848) (xy 361.565146 -223.10232) (xy 361.513184 -223.11418)
			(xy 361.460034 -223.118164) (xy 361.406884 -223.11418) (xy 361.354922 -223.10232) (xy 361.305308 -223.082848)
			(xy 361.25915 -223.056199) (xy 361.217479 -223.022968) (xy 361.181227 -222.983897) (xy 361.151203 -222.93986)
			(xy 361.128077 -222.891839) (xy 361.112367 -222.840909) (xy 361.104424 -222.788205) (xy 360.875844 -222.788205)
			(xy 360.867901 -222.840909) (xy 360.852191 -222.891839) (xy 360.829065 -222.93986) (xy 360.799041 -222.983897)
			(xy 360.762789 -223.022968) (xy 360.721118 -223.056199) (xy 360.67496 -223.082848) (xy 360.625346 -223.10232)
			(xy 360.573384 -223.11418) (xy 360.520234 -223.118164) (xy 360.467084 -223.11418) (xy 360.415122 -223.10232)
			(xy 360.365508 -223.082848) (xy 360.31935 -223.056199) (xy 360.277679 -223.022968) (xy 360.241427 -222.983897)
			(xy 360.211403 -222.93986) (xy 360.188277 -222.891839) (xy 360.172567 -222.840909) (xy 360.164624 -222.788205)
			(xy 359.936053 -222.788205) (xy 359.93605 -222.788387) (xy 359.928007 -222.841444) (xy 359.92054 -222.86722)
			(xy 359.918254 -222.874586) (xy 359.918254 -223.118934) (xy 359.918731 -223.132821) (xy 359.926231 -223.159565)
			(xy 359.940666 -223.183294) (xy 359.960966 -223.202251) (xy 359.985626 -223.21503) (xy 360.01282 -223.220684)
			(xy 360.026712 -223.22028) (xy 360.050334 -223.219518) (xy 360.07698 -223.220018) (xy 360.129675 -223.227966)
			(xy 360.180598 -223.243678) (xy 360.22861 -223.266803) (xy 360.27264 -223.296826) (xy 360.311703 -223.333075)
			(xy 360.344928 -223.374741) (xy 360.371573 -223.420894) (xy 360.391041 -223.470502) (xy 360.402899 -223.522458)
			(xy 360.406881 -223.5756) (xy 360.402899 -223.628742) (xy 360.391041 -223.680698) (xy 360.371573 -223.730306)
			(xy 360.344928 -223.776459) (xy 360.311703 -223.818125) (xy 360.27264 -223.854374) (xy 360.22861 -223.884397)
			(xy 360.180598 -223.907522) (xy 360.129675 -223.923234) (xy 360.07698 -223.931182) (xy 360.050334 -223.931734)
			(xy 360.026712 -223.930972) (xy 360.012822 -223.930511) (xy 359.985628 -223.936187) (xy 359.960969 -223.948982)
			(xy 359.94067 -223.967948) (xy 359.926233 -223.991682) (xy 359.918726 -224.018428) (xy 359.918254 -224.032318)
			(xy 359.918254 -224.276412) (xy 359.92054 -224.283778) (xy 359.928038 -224.309547) (xy 359.936073 -224.362608)
			(xy 359.936542 -224.389442) (xy 360.164126 -224.389442) (xy 360.164608 -224.363815) (xy 360.171937 -224.313088)
			(xy 360.186465 -224.263936) (xy 360.207891 -224.217375) (xy 360.235772 -224.174368) (xy 360.269532 -224.135803)
			(xy 360.308473 -224.102478) (xy 360.35179 -224.075082) (xy 360.398588 -224.05418) (xy 360.4479 -224.040204)
			(xy 360.473244 -224.036382) (xy 360.497882 -224.03308) (xy 360.670094 -223.734376) (xy 360.660696 -223.711516)
			(xy 360.652186 -223.689882) (xy 360.640197 -223.644965) (xy 360.634149 -223.598871) (xy 360.633772 -223.575626)
			(xy 360.63427 -223.548977) (xy 360.642213 -223.496273) (xy 360.657923 -223.445343) (xy 360.681049 -223.397322)
			(xy 360.711073 -223.353285) (xy 360.747325 -223.314214) (xy 360.788996 -223.280983) (xy 360.835154 -223.254334)
			(xy 360.884768 -223.234862) (xy 360.93673 -223.223002) (xy 360.98988 -223.219019) (xy 361.04303 -223.223002)
			(xy 361.094992 -223.234862) (xy 361.144606 -223.254334) (xy 361.190764 -223.280983) (xy 361.232435 -223.314214)
			(xy 361.268687 -223.353285) (xy 361.298711 -223.397322) (xy 361.321837 -223.445343) (xy 361.337547 -223.496273)
			(xy 361.34549 -223.548977) (xy 361.345988 -223.575626) (xy 361.345557 -223.601254) (xy 361.345409 -223.602275)
			(xy 361.574324 -223.602275) (xy 361.574324 -223.548977) (xy 361.582267 -223.496273) (xy 361.597977 -223.445343)
			(xy 361.621103 -223.397322) (xy 361.651127 -223.353285) (xy 361.687379 -223.314214) (xy 361.72905 -223.280983)
			(xy 361.775208 -223.254334) (xy 361.824822 -223.234862) (xy 361.876784 -223.223002) (xy 361.929934 -223.219019)
			(xy 361.983084 -223.223002) (xy 362.035046 -223.234862) (xy 362.08466 -223.254334) (xy 362.130818 -223.280983)
			(xy 362.172489 -223.314214) (xy 362.208741 -223.353285) (xy 362.238765 -223.397322) (xy 362.261891 -223.445343)
			(xy 362.277601 -223.496273) (xy 362.285544 -223.548977) (xy 362.286042 -223.575626) (xy 362.285544 -223.602275)
			(xy 362.277601 -223.654979) (xy 362.261891 -223.705909) (xy 362.238765 -223.75393) (xy 362.208741 -223.797967)
			(xy 362.172489 -223.837038) (xy 362.130818 -223.870269) (xy 362.08466 -223.896918) (xy 362.035046 -223.91639)
			(xy 361.983084 -223.92825) (xy 361.929934 -223.932234) (xy 361.876784 -223.92825) (xy 361.824822 -223.91639)
			(xy 361.775208 -223.896918) (xy 361.72905 -223.870269) (xy 361.687379 -223.837038) (xy 361.651127 -223.797967)
			(xy 361.621103 -223.75393) (xy 361.597977 -223.705909) (xy 361.582267 -223.654979) (xy 361.574324 -223.602275)
			(xy 361.345409 -223.602275) (xy 361.338219 -223.651983) (xy 361.323683 -223.701135) (xy 361.30225 -223.747696)
			(xy 361.274363 -223.790702) (xy 361.240598 -223.829266) (xy 361.201652 -223.86259) (xy 361.158331 -223.889986)
			(xy 361.11153 -223.910888) (xy 361.062216 -223.924864) (xy 361.03687 -223.928686) (xy 361.011978 -223.931988)
			(xy 360.839766 -224.230438) (xy 360.849418 -224.253552) (xy 360.857949 -224.275178) (xy 360.86993 -224.320099)
			(xy 360.875969 -224.366196) (xy 360.876342 -224.389442) (xy 361.103926 -224.389442) (xy 361.104424 -224.362793)
			(xy 361.112367 -224.310089) (xy 361.128077 -224.259159) (xy 361.151203 -224.211138) (xy 361.181227 -224.167101)
			(xy 361.217479 -224.12803) (xy 361.25915 -224.094799) (xy 361.305308 -224.06815) (xy 361.354922 -224.048678)
			(xy 361.406884 -224.036818) (xy 361.460034 -224.032835) (xy 361.513184 -224.036818) (xy 361.565146 -224.048678)
			(xy 361.61476 -224.06815) (xy 361.660918 -224.094799) (xy 361.702589 -224.12803) (xy 361.738841 -224.167101)
			(xy 361.768865 -224.211138) (xy 361.791991 -224.259159) (xy 361.807701 -224.310089) (xy 361.815644 -224.362793)
			(xy 361.816142 -224.389442) (xy 362.043726 -224.389442) (xy 362.044208 -224.363815) (xy 362.051537 -224.313088)
			(xy 362.066065 -224.263936) (xy 362.087491 -224.217375) (xy 362.115372 -224.174368) (xy 362.149132 -224.135803)
			(xy 362.188073 -224.102478) (xy 362.23139 -224.075082) (xy 362.278188 -224.05418) (xy 362.3275 -224.040204)
			(xy 362.352844 -224.036382) (xy 362.377482 -224.03308) (xy 362.549948 -223.734376) (xy 362.54055 -223.711262)
			(xy 362.532055 -223.689667) (xy 362.52008 -223.644835) (xy 362.514019 -223.598828) (xy 362.513626 -223.575626)
			(xy 362.514124 -223.548977) (xy 362.522067 -223.496273) (xy 362.537777 -223.445343) (xy 362.560903 -223.397322)
			(xy 362.590927 -223.353285) (xy 362.627179 -223.314214) (xy 362.66885 -223.280983) (xy 362.715008 -223.254334)
			(xy 362.764622 -223.234862) (xy 362.816584 -223.223002) (xy 362.869734 -223.219019) (xy 362.922884 -223.223002)
			(xy 362.974846 -223.234862) (xy 363.02446 -223.254334) (xy 363.070618 -223.280983) (xy 363.112289 -223.314214)
			(xy 363.148541 -223.353285) (xy 363.178565 -223.397322) (xy 363.201691 -223.445343) (xy 363.217401 -223.496273)
			(xy 363.225344 -223.548977) (xy 363.225842 -223.575626) (xy 363.225416 -223.601266) (xy 363.22527 -223.602275)
			(xy 363.453924 -223.602275) (xy 363.453924 -223.548977) (xy 363.461867 -223.496273) (xy 363.477577 -223.445343)
			(xy 363.500703 -223.397322) (xy 363.530727 -223.353285) (xy 363.566979 -223.314214) (xy 363.60865 -223.280983)
			(xy 363.654808 -223.254334) (xy 363.704422 -223.234862) (xy 363.756384 -223.223002) (xy 363.809534 -223.219019)
			(xy 363.862684 -223.223002) (xy 363.914646 -223.234862) (xy 363.96426 -223.254334) (xy 364.010418 -223.280983)
			(xy 364.052089 -223.314214) (xy 364.088341 -223.353285) (xy 364.118365 -223.397322) (xy 364.141491 -223.445343)
			(xy 364.157201 -223.496273) (xy 364.165144 -223.548977) (xy 364.165642 -223.575626) (xy 364.165144 -223.602275)
			(xy 364.157201 -223.654979) (xy 364.141491 -223.705909) (xy 364.118365 -223.75393) (xy 364.088341 -223.797967)
			(xy 364.052089 -223.837038) (xy 364.010418 -223.870269) (xy 363.96426 -223.896918) (xy 363.914646 -223.91639)
			(xy 363.862684 -223.92825) (xy 363.809534 -223.932234) (xy 363.756384 -223.92825) (xy 363.704422 -223.91639)
			(xy 363.654808 -223.896918) (xy 363.60865 -223.870269) (xy 363.566979 -223.837038) (xy 363.530727 -223.797967)
			(xy 363.500703 -223.75393) (xy 363.477577 -223.705909) (xy 363.461867 -223.654979) (xy 363.453924 -223.602275)
			(xy 363.22527 -223.602275) (xy 363.21807 -223.652018) (xy 363.203519 -223.701191) (xy 363.182064 -223.747768)
			(xy 363.15415 -223.790785) (xy 363.120353 -223.829353) (xy 363.081373 -223.862673) (xy 363.038016 -223.890056)
			(xy 362.991179 -223.910937) (xy 362.94183 -223.924882) (xy 362.91647 -223.928686) (xy 362.891578 -223.931988)
			(xy 362.719366 -224.230438) (xy 362.729018 -224.253552) (xy 362.737549 -224.275178) (xy 362.74953 -224.320099)
			(xy 362.755569 -224.366196) (xy 362.755942 -224.389442) (xy 362.983526 -224.389442) (xy 362.984024 -224.362793)
			(xy 362.991967 -224.310089) (xy 363.007677 -224.259159) (xy 363.030803 -224.211138) (xy 363.060827 -224.167101)
			(xy 363.097079 -224.12803) (xy 363.13875 -224.094799) (xy 363.184908 -224.06815) (xy 363.234522 -224.048678)
			(xy 363.286484 -224.036818) (xy 363.339634 -224.032835) (xy 363.392784 -224.036818) (xy 363.444746 -224.048678)
			(xy 363.49436 -224.06815) (xy 363.540518 -224.094799) (xy 363.582189 -224.12803) (xy 363.618441 -224.167101)
			(xy 363.648465 -224.211138) (xy 363.671591 -224.259159) (xy 363.687301 -224.310089) (xy 363.695244 -224.362793)
			(xy 363.695742 -224.389442) (xy 363.923326 -224.389442) (xy 363.923808 -224.363815) (xy 363.931137 -224.313088)
			(xy 363.945665 -224.263936) (xy 363.967091 -224.217375) (xy 363.994972 -224.174368) (xy 364.028732 -224.135803)
			(xy 364.067673 -224.102478) (xy 364.11099 -224.075082) (xy 364.157788 -224.05418) (xy 364.2071 -224.040204)
			(xy 364.232444 -224.036382) (xy 364.257082 -224.03308) (xy 364.429294 -223.734376) (xy 364.419896 -223.711516)
			(xy 364.411386 -223.689882) (xy 364.399397 -223.644965) (xy 364.393349 -223.598871) (xy 364.392972 -223.575626)
			(xy 364.39347 -223.548977) (xy 364.401413 -223.496273) (xy 364.417123 -223.445343) (xy 364.440249 -223.397322)
			(xy 364.470273 -223.353285) (xy 364.506525 -223.314214) (xy 364.548196 -223.280983) (xy 364.594354 -223.254334)
			(xy 364.643968 -223.234862) (xy 364.69593 -223.223002) (xy 364.74908 -223.219019) (xy 364.80223 -223.223002)
			(xy 364.854192 -223.234862) (xy 364.903806 -223.254334) (xy 364.949964 -223.280983) (xy 364.991635 -223.314214)
			(xy 365.027887 -223.353285) (xy 365.057911 -223.397322) (xy 365.081037 -223.445343) (xy 365.096747 -223.496273)
			(xy 365.10469 -223.548977) (xy 365.105188 -223.575626) (xy 365.104757 -223.601254) (xy 365.104609 -223.602275)
			(xy 365.333524 -223.602275) (xy 365.333524 -223.548977) (xy 365.341467 -223.496273) (xy 365.357177 -223.445343)
			(xy 365.380303 -223.397322) (xy 365.410327 -223.353285) (xy 365.446579 -223.314214) (xy 365.48825 -223.280983)
			(xy 365.534408 -223.254334) (xy 365.584022 -223.234862) (xy 365.635984 -223.223002) (xy 365.689134 -223.219019)
			(xy 365.742284 -223.223002) (xy 365.794246 -223.234862) (xy 365.84386 -223.254334) (xy 365.890018 -223.280983)
			(xy 365.931689 -223.314214) (xy 365.967941 -223.353285) (xy 365.997965 -223.397322) (xy 366.021091 -223.445343)
			(xy 366.036801 -223.496273) (xy 366.044744 -223.548977) (xy 366.045242 -223.575626) (xy 366.044744 -223.602275)
			(xy 366.036801 -223.654979) (xy 366.021091 -223.705909) (xy 365.997965 -223.75393) (xy 365.967941 -223.797967)
			(xy 365.931689 -223.837038) (xy 365.890018 -223.870269) (xy 365.84386 -223.896918) (xy 365.794246 -223.91639)
			(xy 365.742284 -223.92825) (xy 365.689134 -223.932234) (xy 365.635984 -223.92825) (xy 365.584022 -223.91639)
			(xy 365.534408 -223.896918) (xy 365.48825 -223.870269) (xy 365.446579 -223.837038) (xy 365.410327 -223.797967)
			(xy 365.380303 -223.75393) (xy 365.357177 -223.705909) (xy 365.341467 -223.654979) (xy 365.333524 -223.602275)
			(xy 365.104609 -223.602275) (xy 365.097419 -223.651983) (xy 365.082883 -223.701135) (xy 365.06145 -223.747696)
			(xy 365.033563 -223.790702) (xy 364.999798 -223.829266) (xy 364.960852 -223.86259) (xy 364.917531 -223.889986)
			(xy 364.87073 -223.910888) (xy 364.821416 -223.924864) (xy 364.79607 -223.928686) (xy 364.771178 -223.931988)
			(xy 364.598966 -224.230438) (xy 364.608618 -224.253552) (xy 364.617149 -224.275178) (xy 364.62913 -224.320099)
			(xy 364.635169 -224.366196) (xy 364.635542 -224.389442) (xy 364.863126 -224.389442) (xy 364.863624 -224.362793)
			(xy 364.871567 -224.310089) (xy 364.887277 -224.259159) (xy 364.910403 -224.211138) (xy 364.940427 -224.167101)
			(xy 364.976679 -224.12803) (xy 365.01835 -224.094799) (xy 365.064508 -224.06815) (xy 365.114122 -224.048678)
			(xy 365.166084 -224.036818) (xy 365.219234 -224.032835) (xy 365.272384 -224.036818) (xy 365.324346 -224.048678)
			(xy 365.37396 -224.06815) (xy 365.420118 -224.094799) (xy 365.461789 -224.12803) (xy 365.498041 -224.167101)
			(xy 365.528065 -224.211138) (xy 365.551191 -224.259159) (xy 365.566901 -224.310089) (xy 365.574844 -224.362793)
			(xy 365.575342 -224.389442) (xy 365.802926 -224.389442) (xy 365.803408 -224.363815) (xy 365.810737 -224.313088)
			(xy 365.825265 -224.263936) (xy 365.846691 -224.217375) (xy 365.874572 -224.174368) (xy 365.908332 -224.135803)
			(xy 365.947273 -224.102478) (xy 365.99059 -224.075082) (xy 366.037388 -224.05418) (xy 366.0867 -224.040204)
			(xy 366.112044 -224.036382) (xy 366.136682 -224.03308) (xy 366.308894 -223.734376) (xy 366.299496 -223.711516)
			(xy 366.290986 -223.689882) (xy 366.278997 -223.644965) (xy 366.272949 -223.598871) (xy 366.272572 -223.575626)
			(xy 366.27307 -223.548977) (xy 366.281013 -223.496273) (xy 366.296723 -223.445343) (xy 366.319849 -223.397322)
			(xy 366.349873 -223.353285) (xy 366.386125 -223.314214) (xy 366.427796 -223.280983) (xy 366.473954 -223.254334)
			(xy 366.523568 -223.234862) (xy 366.57553 -223.223002) (xy 366.62868 -223.219019) (xy 366.68183 -223.223002)
			(xy 366.733792 -223.234862) (xy 366.783406 -223.254334) (xy 366.829564 -223.280983) (xy 366.871235 -223.314214)
			(xy 366.907487 -223.353285) (xy 366.937511 -223.397322) (xy 366.960637 -223.445343) (xy 366.976347 -223.496273)
			(xy 366.98429 -223.548977) (xy 366.984788 -223.575626) (xy 366.984357 -223.601254) (xy 366.984209 -223.602275)
			(xy 367.213124 -223.602275) (xy 367.213124 -223.548977) (xy 367.221067 -223.496273) (xy 367.236777 -223.445343)
			(xy 367.259903 -223.397322) (xy 367.289927 -223.353285) (xy 367.326179 -223.314214) (xy 367.36785 -223.280983)
			(xy 367.414008 -223.254334) (xy 367.463622 -223.234862) (xy 367.515584 -223.223002) (xy 367.568734 -223.219019)
			(xy 367.621884 -223.223002) (xy 367.673846 -223.234862) (xy 367.72346 -223.254334) (xy 367.769618 -223.280983)
			(xy 367.811289 -223.314214) (xy 367.847541 -223.353285) (xy 367.877565 -223.397322) (xy 367.900691 -223.445343)
			(xy 367.916401 -223.496273) (xy 367.924344 -223.548977) (xy 367.924842 -223.575626) (xy 367.924344 -223.602275)
			(xy 367.916401 -223.654979) (xy 367.900691 -223.705909) (xy 367.877565 -223.75393) (xy 367.847541 -223.797967)
			(xy 367.811289 -223.837038) (xy 367.769618 -223.870269) (xy 367.72346 -223.896918) (xy 367.673846 -223.91639)
			(xy 367.621884 -223.92825) (xy 367.568734 -223.932234) (xy 367.515584 -223.92825) (xy 367.463622 -223.91639)
			(xy 367.414008 -223.896918) (xy 367.36785 -223.870269) (xy 367.326179 -223.837038) (xy 367.289927 -223.797967)
			(xy 367.259903 -223.75393) (xy 367.236777 -223.705909) (xy 367.221067 -223.654979) (xy 367.213124 -223.602275)
			(xy 366.984209 -223.602275) (xy 366.977019 -223.651983) (xy 366.962483 -223.701135) (xy 366.94105 -223.747696)
			(xy 366.913163 -223.790702) (xy 366.879398 -223.829266) (xy 366.840452 -223.86259) (xy 366.797131 -223.889986)
			(xy 366.75033 -223.910888) (xy 366.701016 -223.924864) (xy 366.67567 -223.928686) (xy 366.650778 -223.931988)
			(xy 366.478566 -224.230438) (xy 366.488218 -224.253552) (xy 366.496749 -224.275178) (xy 366.50873 -224.320099)
			(xy 366.514769 -224.366196) (xy 366.515142 -224.389442) (xy 366.742726 -224.389442) (xy 366.743224 -224.362793)
			(xy 366.751167 -224.310089) (xy 366.766877 -224.259159) (xy 366.790003 -224.211138) (xy 366.820027 -224.167101)
			(xy 366.856279 -224.12803) (xy 366.89795 -224.094799) (xy 366.944108 -224.06815) (xy 366.993722 -224.048678)
			(xy 367.045684 -224.036818) (xy 367.098834 -224.032835) (xy 367.151984 -224.036818) (xy 367.203946 -224.048678)
			(xy 367.25356 -224.06815) (xy 367.299718 -224.094799) (xy 367.341389 -224.12803) (xy 367.377641 -224.167101)
			(xy 367.407665 -224.211138) (xy 367.430791 -224.259159) (xy 367.446501 -224.310089) (xy 367.454444 -224.362793)
			(xy 367.454942 -224.389442) (xy 367.682526 -224.389442) (xy 367.683008 -224.363815) (xy 367.690337 -224.313088)
			(xy 367.704865 -224.263936) (xy 367.726291 -224.217375) (xy 367.754172 -224.174368) (xy 367.787932 -224.135803)
			(xy 367.826873 -224.102478) (xy 367.87019 -224.075082) (xy 367.916988 -224.05418) (xy 367.9663 -224.040204)
			(xy 367.991644 -224.036382) (xy 368.016282 -224.03308) (xy 368.188494 -223.734376) (xy 368.179096 -223.711516)
			(xy 368.170586 -223.689882) (xy 368.158597 -223.644965) (xy 368.152549 -223.598871) (xy 368.152172 -223.575626)
			(xy 368.15267 -223.548977) (xy 368.160613 -223.496273) (xy 368.176323 -223.445343) (xy 368.199449 -223.397322)
			(xy 368.229473 -223.353285) (xy 368.265725 -223.314214) (xy 368.307396 -223.280983) (xy 368.353554 -223.254334)
			(xy 368.403168 -223.234862) (xy 368.45513 -223.223002) (xy 368.50828 -223.219019) (xy 368.56143 -223.223002)
			(xy 368.613392 -223.234862) (xy 368.663006 -223.254334) (xy 368.709164 -223.280983) (xy 368.750835 -223.314214)
			(xy 368.787087 -223.353285) (xy 368.817111 -223.397322) (xy 368.840237 -223.445343) (xy 368.855947 -223.496273)
			(xy 368.86389 -223.548977) (xy 368.864388 -223.575626) (xy 368.863957 -223.601254) (xy 368.863809 -223.602275)
			(xy 369.092724 -223.602275) (xy 369.092724 -223.548977) (xy 369.100667 -223.496273) (xy 369.116377 -223.445343)
			(xy 369.139503 -223.397322) (xy 369.169527 -223.353285) (xy 369.205779 -223.314214) (xy 369.24745 -223.280983)
			(xy 369.293608 -223.254334) (xy 369.343222 -223.234862) (xy 369.395184 -223.223002) (xy 369.448334 -223.219019)
			(xy 369.501484 -223.223002) (xy 369.553446 -223.234862) (xy 369.60306 -223.254334) (xy 369.649218 -223.280983)
			(xy 369.690889 -223.314214) (xy 369.727141 -223.353285) (xy 369.757165 -223.397322) (xy 369.780291 -223.445343)
			(xy 369.796001 -223.496273) (xy 369.803944 -223.548977) (xy 369.804442 -223.575626) (xy 369.803944 -223.602275)
			(xy 369.796001 -223.654979) (xy 369.780291 -223.705909) (xy 369.757165 -223.75393) (xy 369.727141 -223.797967)
			(xy 369.690889 -223.837038) (xy 369.649218 -223.870269) (xy 369.60306 -223.896918) (xy 369.553446 -223.91639)
			(xy 369.501484 -223.92825) (xy 369.448334 -223.932234) (xy 369.395184 -223.92825) (xy 369.343222 -223.91639)
			(xy 369.293608 -223.896918) (xy 369.24745 -223.870269) (xy 369.205779 -223.837038) (xy 369.169527 -223.797967)
			(xy 369.139503 -223.75393) (xy 369.116377 -223.705909) (xy 369.100667 -223.654979) (xy 369.092724 -223.602275)
			(xy 368.863809 -223.602275) (xy 368.856619 -223.651983) (xy 368.842083 -223.701135) (xy 368.82065 -223.747696)
			(xy 368.792763 -223.790702) (xy 368.758998 -223.829266) (xy 368.720052 -223.86259) (xy 368.676731 -223.889986)
			(xy 368.62993 -223.910888) (xy 368.580616 -223.924864) (xy 368.55527 -223.928686) (xy 368.530378 -223.931988)
			(xy 368.358166 -224.230438) (xy 368.367818 -224.253552) (xy 368.376349 -224.275178) (xy 368.38833 -224.320099)
			(xy 368.394369 -224.366196) (xy 368.394742 -224.389442) (xy 368.622326 -224.389442) (xy 368.622824 -224.362793)
			(xy 368.630767 -224.310089) (xy 368.646477 -224.259159) (xy 368.669603 -224.211138) (xy 368.699627 -224.167101)
			(xy 368.735879 -224.12803) (xy 368.77755 -224.094799) (xy 368.823708 -224.06815) (xy 368.873322 -224.048678)
			(xy 368.925284 -224.036818) (xy 368.978434 -224.032835) (xy 369.031584 -224.036818) (xy 369.083546 -224.048678)
			(xy 369.13316 -224.06815) (xy 369.179318 -224.094799) (xy 369.220989 -224.12803) (xy 369.257241 -224.167101)
			(xy 369.287265 -224.211138) (xy 369.310391 -224.259159) (xy 369.326101 -224.310089) (xy 369.334044 -224.362793)
			(xy 369.334542 -224.389442) (xy 369.562126 -224.389442) (xy 369.562608 -224.363815) (xy 369.569937 -224.313088)
			(xy 369.584465 -224.263936) (xy 369.605891 -224.217375) (xy 369.633772 -224.174368) (xy 369.667532 -224.135803)
			(xy 369.706473 -224.102478) (xy 369.74979 -224.075082) (xy 369.796588 -224.05418) (xy 369.8459 -224.040204)
			(xy 369.871244 -224.036382) (xy 369.895882 -224.03308) (xy 370.068094 -223.734376) (xy 370.058696 -223.711516)
			(xy 370.050186 -223.689882) (xy 370.038197 -223.644965) (xy 370.032149 -223.598871) (xy 370.031772 -223.575626)
			(xy 370.03227 -223.548977) (xy 370.040213 -223.496273) (xy 370.055923 -223.445343) (xy 370.079049 -223.397322)
			(xy 370.109073 -223.353285) (xy 370.145325 -223.314214) (xy 370.186996 -223.280983) (xy 370.233154 -223.254334)
			(xy 370.282768 -223.234862) (xy 370.33473 -223.223002) (xy 370.38788 -223.219019) (xy 370.44103 -223.223002)
			(xy 370.492992 -223.234862) (xy 370.542606 -223.254334) (xy 370.588764 -223.280983) (xy 370.630435 -223.314214)
			(xy 370.666687 -223.353285) (xy 370.696711 -223.397322) (xy 370.719837 -223.445343) (xy 370.735547 -223.496273)
			(xy 370.74349 -223.548977) (xy 370.743988 -223.575626) (xy 370.743557 -223.601254) (xy 370.743409 -223.602275)
			(xy 370.972324 -223.602275) (xy 370.972324 -223.548977) (xy 370.980267 -223.496273) (xy 370.995977 -223.445343)
			(xy 371.019103 -223.397322) (xy 371.049127 -223.353285) (xy 371.085379 -223.314214) (xy 371.12705 -223.280983)
			(xy 371.173208 -223.254334) (xy 371.222822 -223.234862) (xy 371.274784 -223.223002) (xy 371.327934 -223.219019)
			(xy 371.381084 -223.223002) (xy 371.433046 -223.234862) (xy 371.48266 -223.254334) (xy 371.528818 -223.280983)
			(xy 371.570489 -223.314214) (xy 371.606741 -223.353285) (xy 371.636765 -223.397322) (xy 371.659891 -223.445343)
			(xy 371.675601 -223.496273) (xy 371.683544 -223.548977) (xy 371.684042 -223.575626) (xy 371.683544 -223.602275)
			(xy 371.675601 -223.654979) (xy 371.659891 -223.705909) (xy 371.636765 -223.75393) (xy 371.606741 -223.797967)
			(xy 371.570489 -223.837038) (xy 371.528818 -223.870269) (xy 371.48266 -223.896918) (xy 371.433046 -223.91639)
			(xy 371.381084 -223.92825) (xy 371.327934 -223.932234) (xy 371.274784 -223.92825) (xy 371.222822 -223.91639)
			(xy 371.173208 -223.896918) (xy 371.12705 -223.870269) (xy 371.085379 -223.837038) (xy 371.049127 -223.797967)
			(xy 371.019103 -223.75393) (xy 370.995977 -223.705909) (xy 370.980267 -223.654979) (xy 370.972324 -223.602275)
			(xy 370.743409 -223.602275) (xy 370.736219 -223.651983) (xy 370.721683 -223.701135) (xy 370.70025 -223.747696)
			(xy 370.672363 -223.790702) (xy 370.638598 -223.829266) (xy 370.599652 -223.86259) (xy 370.556331 -223.889986)
			(xy 370.50953 -223.910888) (xy 370.460216 -223.924864) (xy 370.43487 -223.928686) (xy 370.409978 -223.931988)
			(xy 370.237766 -224.230438) (xy 370.247418 -224.253552) (xy 370.255949 -224.275178) (xy 370.26793 -224.320099)
			(xy 370.273969 -224.366196) (xy 370.274342 -224.389442) (xy 370.501926 -224.389442) (xy 370.502424 -224.362793)
			(xy 370.510367 -224.310089) (xy 370.526077 -224.259159) (xy 370.549203 -224.211138) (xy 370.579227 -224.167101)
			(xy 370.615479 -224.12803) (xy 370.65715 -224.094799) (xy 370.703308 -224.06815) (xy 370.752922 -224.048678)
			(xy 370.804884 -224.036818) (xy 370.858034 -224.032835) (xy 370.911184 -224.036818) (xy 370.963146 -224.048678)
			(xy 371.01276 -224.06815) (xy 371.058918 -224.094799) (xy 371.100589 -224.12803) (xy 371.136841 -224.167101)
			(xy 371.166865 -224.211138) (xy 371.189991 -224.259159) (xy 371.205701 -224.310089) (xy 371.213644 -224.362793)
			(xy 371.214142 -224.389442) (xy 371.441726 -224.389442) (xy 371.442208 -224.363815) (xy 371.449537 -224.313088)
			(xy 371.464065 -224.263936) (xy 371.485491 -224.217375) (xy 371.513372 -224.174368) (xy 371.547132 -224.135803)
			(xy 371.586073 -224.102478) (xy 371.62939 -224.075082) (xy 371.676188 -224.05418) (xy 371.7255 -224.040204)
			(xy 371.750844 -224.036382) (xy 371.775482 -224.03308) (xy 371.947694 -223.734376) (xy 371.938296 -223.711516)
			(xy 371.929786 -223.689882) (xy 371.917797 -223.644965) (xy 371.911749 -223.598871) (xy 371.911372 -223.575626)
			(xy 371.91187 -223.548977) (xy 371.919813 -223.496273) (xy 371.935523 -223.445343) (xy 371.958649 -223.397322)
			(xy 371.988673 -223.353285) (xy 372.024925 -223.314214) (xy 372.066596 -223.280983) (xy 372.112754 -223.254334)
			(xy 372.162368 -223.234862) (xy 372.21433 -223.223002) (xy 372.26748 -223.219019) (xy 372.32063 -223.223002)
			(xy 372.372592 -223.234862) (xy 372.422206 -223.254334) (xy 372.468364 -223.280983) (xy 372.510035 -223.314214)
			(xy 372.546287 -223.353285) (xy 372.576311 -223.397322) (xy 372.599437 -223.445343) (xy 372.615147 -223.496273)
			(xy 372.62309 -223.548977) (xy 372.623588 -223.575626) (xy 372.623157 -223.601254) (xy 372.623009 -223.602275)
			(xy 372.851924 -223.602275) (xy 372.851924 -223.548977) (xy 372.859867 -223.496273) (xy 372.875577 -223.445343)
			(xy 372.898703 -223.397322) (xy 372.928727 -223.353285) (xy 372.964979 -223.314214) (xy 373.00665 -223.280983)
			(xy 373.052808 -223.254334) (xy 373.102422 -223.234862) (xy 373.154384 -223.223002) (xy 373.207534 -223.219019)
			(xy 373.260684 -223.223002) (xy 373.312646 -223.234862) (xy 373.36226 -223.254334) (xy 373.408418 -223.280983)
			(xy 373.450089 -223.314214) (xy 373.486341 -223.353285) (xy 373.516365 -223.397322) (xy 373.539491 -223.445343)
			(xy 373.555201 -223.496273) (xy 373.563144 -223.548977) (xy 373.563642 -223.575626) (xy 373.563144 -223.602275)
			(xy 373.555201 -223.654979) (xy 373.539491 -223.705909) (xy 373.516365 -223.75393) (xy 373.486341 -223.797967)
			(xy 373.450089 -223.837038) (xy 373.408418 -223.870269) (xy 373.36226 -223.896918) (xy 373.312646 -223.91639)
			(xy 373.260684 -223.92825) (xy 373.207534 -223.932234) (xy 373.154384 -223.92825) (xy 373.102422 -223.91639)
			(xy 373.052808 -223.896918) (xy 373.00665 -223.870269) (xy 372.964979 -223.837038) (xy 372.928727 -223.797967)
			(xy 372.898703 -223.75393) (xy 372.875577 -223.705909) (xy 372.859867 -223.654979) (xy 372.851924 -223.602275)
			(xy 372.623009 -223.602275) (xy 372.615819 -223.651983) (xy 372.601283 -223.701135) (xy 372.57985 -223.747696)
			(xy 372.551963 -223.790702) (xy 372.518198 -223.829266) (xy 372.479252 -223.86259) (xy 372.435931 -223.889986)
			(xy 372.38913 -223.910888) (xy 372.339816 -223.924864) (xy 372.31447 -223.928686) (xy 372.289578 -223.931988)
			(xy 372.117366 -224.230438) (xy 372.127018 -224.253552) (xy 372.135549 -224.275178) (xy 372.14753 -224.320099)
			(xy 372.153569 -224.366196) (xy 372.153942 -224.389442) (xy 372.381526 -224.389442) (xy 372.382024 -224.362793)
			(xy 372.389967 -224.310089) (xy 372.405677 -224.259159) (xy 372.428803 -224.211138) (xy 372.458827 -224.167101)
			(xy 372.495079 -224.12803) (xy 372.53675 -224.094799) (xy 372.582908 -224.06815) (xy 372.632522 -224.048678)
			(xy 372.684484 -224.036818) (xy 372.737634 -224.032835) (xy 372.790784 -224.036818) (xy 372.842746 -224.048678)
			(xy 372.89236 -224.06815) (xy 372.938518 -224.094799) (xy 372.980189 -224.12803) (xy 373.016441 -224.167101)
			(xy 373.046465 -224.211138) (xy 373.069591 -224.259159) (xy 373.085301 -224.310089) (xy 373.093244 -224.362793)
			(xy 373.093742 -224.389442) (xy 373.321326 -224.389442) (xy 373.321808 -224.363815) (xy 373.329137 -224.313088)
			(xy 373.343665 -224.263936) (xy 373.365091 -224.217375) (xy 373.392972 -224.174368) (xy 373.426732 -224.135803)
			(xy 373.465673 -224.102478) (xy 373.50899 -224.075082) (xy 373.555788 -224.05418) (xy 373.6051 -224.040204)
			(xy 373.630444 -224.036382) (xy 373.655082 -224.03308) (xy 373.827294 -223.734376) (xy 373.817896 -223.711516)
			(xy 373.809386 -223.689882) (xy 373.797397 -223.644965) (xy 373.791349 -223.598871) (xy 373.790972 -223.575626)
			(xy 373.79147 -223.548977) (xy 373.799413 -223.496273) (xy 373.815123 -223.445343) (xy 373.838249 -223.397322)
			(xy 373.868273 -223.353285) (xy 373.904525 -223.314214) (xy 373.946196 -223.280983) (xy 373.992354 -223.254334)
			(xy 374.041968 -223.234862) (xy 374.09393 -223.223002) (xy 374.14708 -223.219019) (xy 374.20023 -223.223002)
			(xy 374.252192 -223.234862) (xy 374.301806 -223.254334) (xy 374.347964 -223.280983) (xy 374.389635 -223.314214)
			(xy 374.425887 -223.353285) (xy 374.455911 -223.397322) (xy 374.479037 -223.445343) (xy 374.494747 -223.496273)
			(xy 374.50269 -223.548977) (xy 374.503188 -223.575626) (xy 374.502757 -223.601254) (xy 374.502609 -223.602275)
			(xy 374.731524 -223.602275) (xy 374.731524 -223.548977) (xy 374.739467 -223.496273) (xy 374.755177 -223.445343)
			(xy 374.778303 -223.397322) (xy 374.808327 -223.353285) (xy 374.844579 -223.314214) (xy 374.88625 -223.280983)
			(xy 374.932408 -223.254334) (xy 374.982022 -223.234862) (xy 375.033984 -223.223002) (xy 375.087134 -223.219019)
			(xy 375.140284 -223.223002) (xy 375.192246 -223.234862) (xy 375.24186 -223.254334) (xy 375.288018 -223.280983)
			(xy 375.329689 -223.314214) (xy 375.365941 -223.353285) (xy 375.395965 -223.397322) (xy 375.419091 -223.445343)
			(xy 375.434801 -223.496273) (xy 375.442744 -223.548977) (xy 375.443242 -223.575626) (xy 375.442744 -223.602275)
			(xy 375.434801 -223.654979) (xy 375.419091 -223.705909) (xy 375.395965 -223.75393) (xy 375.365941 -223.797967)
			(xy 375.329689 -223.837038) (xy 375.288018 -223.870269) (xy 375.24186 -223.896918) (xy 375.192246 -223.91639)
			(xy 375.140284 -223.92825) (xy 375.087134 -223.932234) (xy 375.033984 -223.92825) (xy 374.982022 -223.91639)
			(xy 374.932408 -223.896918) (xy 374.88625 -223.870269) (xy 374.844579 -223.837038) (xy 374.808327 -223.797967)
			(xy 374.778303 -223.75393) (xy 374.755177 -223.705909) (xy 374.739467 -223.654979) (xy 374.731524 -223.602275)
			(xy 374.502609 -223.602275) (xy 374.495419 -223.651983) (xy 374.480883 -223.701135) (xy 374.45945 -223.747696)
			(xy 374.431563 -223.790702) (xy 374.397798 -223.829266) (xy 374.358852 -223.86259) (xy 374.315531 -223.889986)
			(xy 374.26873 -223.910888) (xy 374.219416 -223.924864) (xy 374.19407 -223.928686) (xy 374.169178 -223.931988)
			(xy 373.996966 -224.230438) (xy 374.006618 -224.253552) (xy 374.015149 -224.275178) (xy 374.02713 -224.320099)
			(xy 374.033169 -224.366196) (xy 374.033542 -224.389442) (xy 374.261126 -224.389442) (xy 374.261624 -224.362793)
			(xy 374.269567 -224.310089) (xy 374.285277 -224.259159) (xy 374.308403 -224.211138) (xy 374.338427 -224.167101)
			(xy 374.374679 -224.12803) (xy 374.41635 -224.094799) (xy 374.462508 -224.06815) (xy 374.512122 -224.048678)
			(xy 374.564084 -224.036818) (xy 374.617234 -224.032835) (xy 374.670384 -224.036818) (xy 374.722346 -224.048678)
			(xy 374.77196 -224.06815) (xy 374.818118 -224.094799) (xy 374.859789 -224.12803) (xy 374.896041 -224.167101)
			(xy 374.926065 -224.211138) (xy 374.949191 -224.259159) (xy 374.964901 -224.310089) (xy 374.972844 -224.362793)
			(xy 374.973342 -224.389442) (xy 375.200926 -224.389442) (xy 375.201408 -224.363815) (xy 375.208737 -224.313088)
			(xy 375.223265 -224.263936) (xy 375.244691 -224.217375) (xy 375.272572 -224.174368) (xy 375.306332 -224.135803)
			(xy 375.345273 -224.102478) (xy 375.38859 -224.075082) (xy 375.435388 -224.05418) (xy 375.4847 -224.040204)
			(xy 375.510044 -224.036382) (xy 375.534682 -224.03308) (xy 375.706894 -223.734376) (xy 375.697496 -223.711516)
			(xy 375.688986 -223.689882) (xy 375.676997 -223.644965) (xy 375.670949 -223.598871) (xy 375.670572 -223.575626)
			(xy 375.67107 -223.548977) (xy 375.679013 -223.496273) (xy 375.694723 -223.445343) (xy 375.717849 -223.397322)
			(xy 375.747873 -223.353285) (xy 375.784125 -223.314214) (xy 375.825796 -223.280983) (xy 375.871954 -223.254334)
			(xy 375.921568 -223.234862) (xy 375.97353 -223.223002) (xy 376.02668 -223.219019) (xy 376.07983 -223.223002)
			(xy 376.131792 -223.234862) (xy 376.181406 -223.254334) (xy 376.227564 -223.280983) (xy 376.269235 -223.314214)
			(xy 376.305487 -223.353285) (xy 376.335511 -223.397322) (xy 376.358637 -223.445343) (xy 376.374347 -223.496273)
			(xy 376.38229 -223.548977) (xy 376.382788 -223.575626) (xy 376.382357 -223.601254) (xy 376.382209 -223.602275)
			(xy 376.611124 -223.602275) (xy 376.611124 -223.548977) (xy 376.619067 -223.496273) (xy 376.634777 -223.445343)
			(xy 376.657903 -223.397322) (xy 376.687927 -223.353285) (xy 376.724179 -223.314214) (xy 376.76585 -223.280983)
			(xy 376.812008 -223.254334) (xy 376.861622 -223.234862) (xy 376.913584 -223.223002) (xy 376.966734 -223.219019)
			(xy 377.019884 -223.223002) (xy 377.071846 -223.234862) (xy 377.12146 -223.254334) (xy 377.167618 -223.280983)
			(xy 377.209289 -223.314214) (xy 377.245541 -223.353285) (xy 377.275565 -223.397322) (xy 377.298691 -223.445343)
			(xy 377.314401 -223.496273) (xy 377.322344 -223.548977) (xy 377.322842 -223.575626) (xy 377.322344 -223.602275)
			(xy 377.314401 -223.654979) (xy 377.298691 -223.705909) (xy 377.275565 -223.75393) (xy 377.245541 -223.797967)
			(xy 377.209289 -223.837038) (xy 377.167618 -223.870269) (xy 377.12146 -223.896918) (xy 377.071846 -223.91639)
			(xy 377.019884 -223.92825) (xy 376.966734 -223.932234) (xy 376.913584 -223.92825) (xy 376.861622 -223.91639)
			(xy 376.812008 -223.896918) (xy 376.76585 -223.870269) (xy 376.724179 -223.837038) (xy 376.687927 -223.797967)
			(xy 376.657903 -223.75393) (xy 376.634777 -223.705909) (xy 376.619067 -223.654979) (xy 376.611124 -223.602275)
			(xy 376.382209 -223.602275) (xy 376.375019 -223.651983) (xy 376.360483 -223.701135) (xy 376.33905 -223.747696)
			(xy 376.311163 -223.790702) (xy 376.277398 -223.829266) (xy 376.238452 -223.86259) (xy 376.195131 -223.889986)
			(xy 376.14833 -223.910888) (xy 376.099016 -223.924864) (xy 376.07367 -223.928686) (xy 376.048778 -223.931988)
			(xy 375.876566 -224.230438) (xy 375.886218 -224.253552) (xy 375.894749 -224.275178) (xy 375.90673 -224.320099)
			(xy 375.912769 -224.366196) (xy 375.913142 -224.389442) (xy 376.140726 -224.389442) (xy 376.141224 -224.362793)
			(xy 376.149167 -224.310089) (xy 376.164877 -224.259159) (xy 376.188003 -224.211138) (xy 376.218027 -224.167101)
			(xy 376.254279 -224.12803) (xy 376.29595 -224.094799) (xy 376.342108 -224.06815) (xy 376.391722 -224.048678)
			(xy 376.443684 -224.036818) (xy 376.496834 -224.032835) (xy 376.549984 -224.036818) (xy 376.601946 -224.048678)
			(xy 376.65156 -224.06815) (xy 376.697718 -224.094799) (xy 376.739389 -224.12803) (xy 376.775641 -224.167101)
			(xy 376.805665 -224.211138) (xy 376.828791 -224.259159) (xy 376.844501 -224.310089) (xy 376.852444 -224.362793)
			(xy 376.852942 -224.389442) (xy 377.080526 -224.389442) (xy 377.081008 -224.363815) (xy 377.088337 -224.313088)
			(xy 377.102865 -224.263936) (xy 377.124291 -224.217375) (xy 377.152172 -224.174368) (xy 377.185932 -224.135803)
			(xy 377.224873 -224.102478) (xy 377.26819 -224.075082) (xy 377.314988 -224.05418) (xy 377.3643 -224.040204)
			(xy 377.389644 -224.036382) (xy 377.414282 -224.03308) (xy 377.586494 -223.734376) (xy 377.577096 -223.711516)
			(xy 377.568586 -223.689882) (xy 377.556597 -223.644965) (xy 377.550549 -223.598871) (xy 377.550172 -223.575626)
			(xy 377.55067 -223.548977) (xy 377.558613 -223.496273) (xy 377.574323 -223.445343) (xy 377.597449 -223.397322)
			(xy 377.627473 -223.353285) (xy 377.663725 -223.314214) (xy 377.705396 -223.280983) (xy 377.751554 -223.254334)
			(xy 377.801168 -223.234862) (xy 377.85313 -223.223002) (xy 377.90628 -223.219019) (xy 377.95943 -223.223002)
			(xy 378.011392 -223.234862) (xy 378.061006 -223.254334) (xy 378.107164 -223.280983) (xy 378.148835 -223.314214)
			(xy 378.185087 -223.353285) (xy 378.215111 -223.397322) (xy 378.238237 -223.445343) (xy 378.253947 -223.496273)
			(xy 378.26189 -223.548977) (xy 378.262388 -223.575626) (xy 378.261957 -223.601254) (xy 378.261809 -223.602275)
			(xy 378.490724 -223.602275) (xy 378.490724 -223.548977) (xy 378.498667 -223.496273) (xy 378.514377 -223.445343)
			(xy 378.537503 -223.397322) (xy 378.567527 -223.353285) (xy 378.603779 -223.314214) (xy 378.64545 -223.280983)
			(xy 378.691608 -223.254334) (xy 378.741222 -223.234862) (xy 378.793184 -223.223002) (xy 378.846334 -223.219019)
			(xy 378.899484 -223.223002) (xy 378.951446 -223.234862) (xy 379.00106 -223.254334) (xy 379.047218 -223.280983)
			(xy 379.088889 -223.314214) (xy 379.125141 -223.353285) (xy 379.155165 -223.397322) (xy 379.178291 -223.445343)
			(xy 379.194001 -223.496273) (xy 379.201944 -223.548977) (xy 379.202442 -223.575626) (xy 379.201944 -223.602275)
			(xy 379.194001 -223.654979) (xy 379.178291 -223.705909) (xy 379.155165 -223.75393) (xy 379.125141 -223.797967)
			(xy 379.088889 -223.837038) (xy 379.047218 -223.870269) (xy 379.00106 -223.896918) (xy 378.951446 -223.91639)
			(xy 378.899484 -223.92825) (xy 378.846334 -223.932234) (xy 378.793184 -223.92825) (xy 378.741222 -223.91639)
			(xy 378.691608 -223.896918) (xy 378.64545 -223.870269) (xy 378.603779 -223.837038) (xy 378.567527 -223.797967)
			(xy 378.537503 -223.75393) (xy 378.514377 -223.705909) (xy 378.498667 -223.654979) (xy 378.490724 -223.602275)
			(xy 378.261809 -223.602275) (xy 378.254619 -223.651983) (xy 378.240083 -223.701135) (xy 378.21865 -223.747696)
			(xy 378.190763 -223.790702) (xy 378.156998 -223.829266) (xy 378.118052 -223.86259) (xy 378.074731 -223.889986)
			(xy 378.02793 -223.910888) (xy 377.978616 -223.924864) (xy 377.95327 -223.928686) (xy 377.928378 -223.931988)
			(xy 377.756166 -224.230438) (xy 377.765818 -224.253552) (xy 377.774349 -224.275178) (xy 377.78633 -224.320099)
			(xy 377.792369 -224.366196) (xy 377.792742 -224.389442) (xy 378.020326 -224.389442) (xy 378.020824 -224.362793)
			(xy 378.028767 -224.310089) (xy 378.044477 -224.259159) (xy 378.067603 -224.211138) (xy 378.097627 -224.167101)
			(xy 378.133879 -224.12803) (xy 378.17555 -224.094799) (xy 378.221708 -224.06815) (xy 378.271322 -224.048678)
			(xy 378.323284 -224.036818) (xy 378.376434 -224.032835) (xy 378.429584 -224.036818) (xy 378.481546 -224.048678)
			(xy 378.53116 -224.06815) (xy 378.577318 -224.094799) (xy 378.618989 -224.12803) (xy 378.655241 -224.167101)
			(xy 378.685265 -224.211138) (xy 378.708391 -224.259159) (xy 378.724101 -224.310089) (xy 378.732044 -224.362793)
			(xy 378.732542 -224.389442) (xy 378.732152 -224.412686) (xy 378.726113 -224.458781) (xy 378.714132 -224.5037)
			(xy 378.705618 -224.525332) (xy 378.695966 -224.548446) (xy 378.868432 -224.846896) (xy 378.89307 -224.850198)
			(xy 378.918419 -224.853984) (xy 378.967725 -224.86798) (xy 379.014517 -224.888897) (xy 379.057829 -224.916303)
			(xy 379.096766 -224.949633) (xy 379.130526 -224.988198) (xy 379.158411 -225.031202) (xy 379.179847 -225.077759)
			(xy 379.19439 -225.126907) (xy 379.20174 -225.177631) (xy 379.202188 -225.203258) (xy 379.20169 -225.229907)
			(xy 379.43027 -225.229907) (xy 379.43027 -225.176609) (xy 379.438213 -225.123905) (xy 379.453923 -225.072975)
			(xy 379.477049 -225.024954) (xy 379.507073 -224.980917) (xy 379.543325 -224.941846) (xy 379.584996 -224.908615)
			(xy 379.631154 -224.881966) (xy 379.680768 -224.862494) (xy 379.73273 -224.850634) (xy 379.78588 -224.846651)
			(xy 379.83903 -224.850634) (xy 379.890992 -224.862494) (xy 379.940606 -224.881966) (xy 379.986764 -224.908615)
			(xy 380.028435 -224.941846) (xy 380.064687 -224.980917) (xy 380.094711 -225.024954) (xy 380.117837 -225.072975)
			(xy 380.133547 -225.123905) (xy 380.14149 -225.176609) (xy 380.141988 -225.203258) (xy 380.14149 -225.229907)
			(xy 380.133547 -225.282611) (xy 380.117837 -225.333541) (xy 380.094711 -225.381562) (xy 380.064687 -225.425599)
			(xy 380.028435 -225.46467) (xy 379.986764 -225.497901) (xy 379.940606 -225.52455) (xy 379.890992 -225.544022)
			(xy 379.83903 -225.555882) (xy 379.78588 -225.559866) (xy 379.73273 -225.555882) (xy 379.680768 -225.544022)
			(xy 379.631154 -225.52455) (xy 379.584996 -225.497901) (xy 379.543325 -225.46467) (xy 379.507073 -225.425599)
			(xy 379.477049 -225.381562) (xy 379.453923 -225.333541) (xy 379.438213 -225.282611) (xy 379.43027 -225.229907)
			(xy 379.20169 -225.229907) (xy 379.193747 -225.282611) (xy 379.178037 -225.333541) (xy 379.154911 -225.381562)
			(xy 379.124887 -225.425599) (xy 379.088635 -225.46467) (xy 379.046964 -225.497901) (xy 379.000806 -225.52455)
			(xy 378.951192 -225.544022) (xy 378.89923 -225.555882) (xy 378.84608 -225.559866) (xy 378.79293 -225.555882)
			(xy 378.740968 -225.544022) (xy 378.691354 -225.52455) (xy 378.645196 -225.497901) (xy 378.603525 -225.46467)
			(xy 378.567273 -225.425599) (xy 378.537249 -225.381562) (xy 378.514123 -225.333541) (xy 378.498413 -225.282611)
			(xy 378.49047 -225.229907) (xy 378.489972 -225.203258) (xy 378.490361 -225.180014) (xy 378.4964 -225.133918)
			(xy 378.508382 -225.089) (xy 378.516896 -225.067368) (xy 378.526548 -225.044254) (xy 378.354082 -224.745804)
			(xy 378.329444 -224.742502) (xy 378.304097 -224.738705) (xy 378.254791 -224.724711) (xy 378.207999 -224.703796)
			(xy 378.164687 -224.676391) (xy 378.125749 -224.643063) (xy 378.091989 -224.604499) (xy 378.064103 -224.561495)
			(xy 378.042668 -224.514939) (xy 378.028125 -224.465792) (xy 378.020774 -224.415069) (xy 378.020326 -224.389442)
			(xy 377.792742 -224.389442) (xy 377.792244 -224.416091) (xy 377.784301 -224.468795) (xy 377.768591 -224.519725)
			(xy 377.745465 -224.567746) (xy 377.715441 -224.611783) (xy 377.679189 -224.650854) (xy 377.637518 -224.684085)
			(xy 377.59136 -224.710734) (xy 377.541746 -224.730206) (xy 377.489784 -224.742066) (xy 377.436634 -224.74605)
			(xy 377.383484 -224.742066) (xy 377.331522 -224.730206) (xy 377.281908 -224.710734) (xy 377.23575 -224.684085)
			(xy 377.194079 -224.650854) (xy 377.157827 -224.611783) (xy 377.127803 -224.567746) (xy 377.104677 -224.519725)
			(xy 377.088967 -224.468795) (xy 377.081024 -224.416091) (xy 377.080526 -224.389442) (xy 376.852942 -224.389442)
			(xy 376.852552 -224.412686) (xy 376.846513 -224.458781) (xy 376.834532 -224.5037) (xy 376.826018 -224.525332)
			(xy 376.816366 -224.548446) (xy 376.988832 -224.846896) (xy 377.01347 -224.850198) (xy 377.038819 -224.853984)
			(xy 377.088125 -224.86798) (xy 377.134917 -224.888897) (xy 377.178229 -224.916303) (xy 377.217166 -224.949633)
			(xy 377.250926 -224.988198) (xy 377.278811 -225.031202) (xy 377.300247 -225.077759) (xy 377.31479 -225.126907)
			(xy 377.32214 -225.177631) (xy 377.322588 -225.203258) (xy 377.32209 -225.229907) (xy 377.55067 -225.229907)
			(xy 377.55067 -225.176609) (xy 377.558613 -225.123905) (xy 377.574323 -225.072975) (xy 377.597449 -225.024954)
			(xy 377.627473 -224.980917) (xy 377.663725 -224.941846) (xy 377.705396 -224.908615) (xy 377.751554 -224.881966)
			(xy 377.801168 -224.862494) (xy 377.85313 -224.850634) (xy 377.90628 -224.846651) (xy 377.95943 -224.850634)
			(xy 378.011392 -224.862494) (xy 378.061006 -224.881966) (xy 378.107164 -224.908615) (xy 378.148835 -224.941846)
			(xy 378.185087 -224.980917) (xy 378.215111 -225.024954) (xy 378.238237 -225.072975) (xy 378.253947 -225.123905)
			(xy 378.26189 -225.176609) (xy 378.262388 -225.203258) (xy 378.26189 -225.229907) (xy 378.253947 -225.282611)
			(xy 378.238237 -225.333541) (xy 378.215111 -225.381562) (xy 378.185087 -225.425599) (xy 378.148835 -225.46467)
			(xy 378.107164 -225.497901) (xy 378.061006 -225.52455) (xy 378.011392 -225.544022) (xy 377.95943 -225.555882)
			(xy 377.90628 -225.559866) (xy 377.85313 -225.555882) (xy 377.801168 -225.544022) (xy 377.751554 -225.52455)
			(xy 377.705396 -225.497901) (xy 377.663725 -225.46467) (xy 377.627473 -225.425599) (xy 377.597449 -225.381562)
			(xy 377.574323 -225.333541) (xy 377.558613 -225.282611) (xy 377.55067 -225.229907) (xy 377.32209 -225.229907)
			(xy 377.314147 -225.282611) (xy 377.298437 -225.333541) (xy 377.275311 -225.381562) (xy 377.245287 -225.425599)
			(xy 377.209035 -225.46467) (xy 377.167364 -225.497901) (xy 377.121206 -225.52455) (xy 377.071592 -225.544022)
			(xy 377.01963 -225.555882) (xy 376.96648 -225.559866) (xy 376.91333 -225.555882) (xy 376.861368 -225.544022)
			(xy 376.811754 -225.52455) (xy 376.765596 -225.497901) (xy 376.723925 -225.46467) (xy 376.687673 -225.425599)
			(xy 376.657649 -225.381562) (xy 376.634523 -225.333541) (xy 376.618813 -225.282611) (xy 376.61087 -225.229907)
			(xy 376.610372 -225.203258) (xy 376.610761 -225.180014) (xy 376.6168 -225.133918) (xy 376.628782 -225.089)
			(xy 376.637296 -225.067368) (xy 376.646948 -225.044254) (xy 376.474482 -224.745804) (xy 376.449844 -224.742502)
			(xy 376.424497 -224.738705) (xy 376.375191 -224.724711) (xy 376.328399 -224.703796) (xy 376.285087 -224.676391)
			(xy 376.246149 -224.643063) (xy 376.212389 -224.604499) (xy 376.184503 -224.561495) (xy 376.163068 -224.514939)
			(xy 376.148525 -224.465792) (xy 376.141174 -224.415069) (xy 376.140726 -224.389442) (xy 375.913142 -224.389442)
			(xy 375.912644 -224.416091) (xy 375.904701 -224.468795) (xy 375.888991 -224.519725) (xy 375.865865 -224.567746)
			(xy 375.835841 -224.611783) (xy 375.799589 -224.650854) (xy 375.757918 -224.684085) (xy 375.71176 -224.710734)
			(xy 375.662146 -224.730206) (xy 375.610184 -224.742066) (xy 375.557034 -224.74605) (xy 375.503884 -224.742066)
			(xy 375.451922 -224.730206) (xy 375.402308 -224.710734) (xy 375.35615 -224.684085) (xy 375.314479 -224.650854)
			(xy 375.278227 -224.611783) (xy 375.248203 -224.567746) (xy 375.225077 -224.519725) (xy 375.209367 -224.468795)
			(xy 375.201424 -224.416091) (xy 375.200926 -224.389442) (xy 374.973342 -224.389442) (xy 374.972952 -224.412686)
			(xy 374.966913 -224.458781) (xy 374.954932 -224.5037) (xy 374.946418 -224.525332) (xy 374.936766 -224.548446)
			(xy 375.109232 -224.846896) (xy 375.13387 -224.850198) (xy 375.159219 -224.853984) (xy 375.208525 -224.86798)
			(xy 375.255317 -224.888897) (xy 375.298629 -224.916303) (xy 375.337566 -224.949633) (xy 375.371326 -224.988198)
			(xy 375.399211 -225.031202) (xy 375.420647 -225.077759) (xy 375.43519 -225.126907) (xy 375.44254 -225.177631)
			(xy 375.442988 -225.203258) (xy 375.44249 -225.229907) (xy 375.67107 -225.229907) (xy 375.67107 -225.176609)
			(xy 375.679013 -225.123905) (xy 375.694723 -225.072975) (xy 375.717849 -225.024954) (xy 375.747873 -224.980917)
			(xy 375.784125 -224.941846) (xy 375.825796 -224.908615) (xy 375.871954 -224.881966) (xy 375.921568 -224.862494)
			(xy 375.97353 -224.850634) (xy 376.02668 -224.846651) (xy 376.07983 -224.850634) (xy 376.131792 -224.862494)
			(xy 376.181406 -224.881966) (xy 376.227564 -224.908615) (xy 376.269235 -224.941846) (xy 376.305487 -224.980917)
			(xy 376.335511 -225.024954) (xy 376.358637 -225.072975) (xy 376.374347 -225.123905) (xy 376.38229 -225.176609)
			(xy 376.382788 -225.203258) (xy 376.38229 -225.229907) (xy 376.374347 -225.282611) (xy 376.358637 -225.333541)
			(xy 376.335511 -225.381562) (xy 376.305487 -225.425599) (xy 376.269235 -225.46467) (xy 376.227564 -225.497901)
			(xy 376.181406 -225.52455) (xy 376.131792 -225.544022) (xy 376.07983 -225.555882) (xy 376.02668 -225.559866)
			(xy 375.97353 -225.555882) (xy 375.921568 -225.544022) (xy 375.871954 -225.52455) (xy 375.825796 -225.497901)
			(xy 375.784125 -225.46467) (xy 375.747873 -225.425599) (xy 375.717849 -225.381562) (xy 375.694723 -225.333541)
			(xy 375.679013 -225.282611) (xy 375.67107 -225.229907) (xy 375.44249 -225.229907) (xy 375.434547 -225.282611)
			(xy 375.418837 -225.333541) (xy 375.395711 -225.381562) (xy 375.365687 -225.425599) (xy 375.329435 -225.46467)
			(xy 375.287764 -225.497901) (xy 375.241606 -225.52455) (xy 375.191992 -225.544022) (xy 375.14003 -225.555882)
			(xy 375.08688 -225.559866) (xy 375.03373 -225.555882) (xy 374.981768 -225.544022) (xy 374.932154 -225.52455)
			(xy 374.885996 -225.497901) (xy 374.844325 -225.46467) (xy 374.808073 -225.425599) (xy 374.778049 -225.381562)
			(xy 374.754923 -225.333541) (xy 374.739213 -225.282611) (xy 374.73127 -225.229907) (xy 374.730772 -225.203258)
			(xy 374.731161 -225.180014) (xy 374.7372 -225.133918) (xy 374.749182 -225.089) (xy 374.757696 -225.067368)
			(xy 374.767348 -225.044254) (xy 374.594882 -224.745804) (xy 374.570244 -224.742502) (xy 374.544897 -224.738705)
			(xy 374.495591 -224.724711) (xy 374.448799 -224.703796) (xy 374.405487 -224.676391) (xy 374.366549 -224.643063)
			(xy 374.332789 -224.604499) (xy 374.304903 -224.561495) (xy 374.283468 -224.514939) (xy 374.268925 -224.465792)
			(xy 374.261574 -224.415069) (xy 374.261126 -224.389442) (xy 374.033542 -224.389442) (xy 374.033044 -224.416091)
			(xy 374.025101 -224.468795) (xy 374.009391 -224.519725) (xy 373.986265 -224.567746) (xy 373.956241 -224.611783)
			(xy 373.919989 -224.650854) (xy 373.878318 -224.684085) (xy 373.83216 -224.710734) (xy 373.782546 -224.730206)
			(xy 373.730584 -224.742066) (xy 373.677434 -224.74605) (xy 373.624284 -224.742066) (xy 373.572322 -224.730206)
			(xy 373.522708 -224.710734) (xy 373.47655 -224.684085) (xy 373.434879 -224.650854) (xy 373.398627 -224.611783)
			(xy 373.368603 -224.567746) (xy 373.345477 -224.519725) (xy 373.329767 -224.468795) (xy 373.321824 -224.416091)
			(xy 373.321326 -224.389442) (xy 373.093742 -224.389442) (xy 373.093352 -224.412686) (xy 373.087313 -224.458781)
			(xy 373.075332 -224.5037) (xy 373.066818 -224.525332) (xy 373.057166 -224.548446) (xy 373.229632 -224.846896)
			(xy 373.25427 -224.850198) (xy 373.279619 -224.853984) (xy 373.328925 -224.86798) (xy 373.375717 -224.888897)
			(xy 373.419029 -224.916303) (xy 373.457966 -224.949633) (xy 373.491726 -224.988198) (xy 373.519611 -225.031202)
			(xy 373.541047 -225.077759) (xy 373.55559 -225.126907) (xy 373.56294 -225.177631) (xy 373.563388 -225.203258)
			(xy 373.56289 -225.229907) (xy 373.79147 -225.229907) (xy 373.79147 -225.176609) (xy 373.799413 -225.123905)
			(xy 373.815123 -225.072975) (xy 373.838249 -225.024954) (xy 373.868273 -224.980917) (xy 373.904525 -224.941846)
			(xy 373.946196 -224.908615) (xy 373.992354 -224.881966) (xy 374.041968 -224.862494) (xy 374.09393 -224.850634)
			(xy 374.14708 -224.846651) (xy 374.20023 -224.850634) (xy 374.252192 -224.862494) (xy 374.301806 -224.881966)
			(xy 374.347964 -224.908615) (xy 374.389635 -224.941846) (xy 374.425887 -224.980917) (xy 374.455911 -225.024954)
			(xy 374.479037 -225.072975) (xy 374.494747 -225.123905) (xy 374.50269 -225.176609) (xy 374.503188 -225.203258)
			(xy 374.50269 -225.229907) (xy 374.494747 -225.282611) (xy 374.479037 -225.333541) (xy 374.455911 -225.381562)
			(xy 374.425887 -225.425599) (xy 374.389635 -225.46467) (xy 374.347964 -225.497901) (xy 374.301806 -225.52455)
			(xy 374.252192 -225.544022) (xy 374.20023 -225.555882) (xy 374.14708 -225.559866) (xy 374.09393 -225.555882)
			(xy 374.041968 -225.544022) (xy 373.992354 -225.52455) (xy 373.946196 -225.497901) (xy 373.904525 -225.46467)
			(xy 373.868273 -225.425599) (xy 373.838249 -225.381562) (xy 373.815123 -225.333541) (xy 373.799413 -225.282611)
			(xy 373.79147 -225.229907) (xy 373.56289 -225.229907) (xy 373.554947 -225.282611) (xy 373.539237 -225.333541)
			(xy 373.516111 -225.381562) (xy 373.486087 -225.425599) (xy 373.449835 -225.46467) (xy 373.408164 -225.497901)
			(xy 373.362006 -225.52455) (xy 373.312392 -225.544022) (xy 373.26043 -225.555882) (xy 373.20728 -225.559866)
			(xy 373.15413 -225.555882) (xy 373.102168 -225.544022) (xy 373.052554 -225.52455) (xy 373.006396 -225.497901)
			(xy 372.964725 -225.46467) (xy 372.928473 -225.425599) (xy 372.898449 -225.381562) (xy 372.875323 -225.333541)
			(xy 372.859613 -225.282611) (xy 372.85167 -225.229907) (xy 372.851172 -225.203258) (xy 372.851561 -225.180014)
			(xy 372.8576 -225.133918) (xy 372.869582 -225.089) (xy 372.878096 -225.067368) (xy 372.887748 -225.044254)
			(xy 372.715282 -224.745804) (xy 372.690644 -224.742502) (xy 372.665297 -224.738705) (xy 372.615991 -224.724711)
			(xy 372.569199 -224.703796) (xy 372.525887 -224.676391) (xy 372.486949 -224.643063) (xy 372.453189 -224.604499)
			(xy 372.425303 -224.561495) (xy 372.403868 -224.514939) (xy 372.389325 -224.465792) (xy 372.381974 -224.415069)
			(xy 372.381526 -224.389442) (xy 372.153942 -224.389442) (xy 372.153444 -224.416091) (xy 372.145501 -224.468795)
			(xy 372.129791 -224.519725) (xy 372.106665 -224.567746) (xy 372.076641 -224.611783) (xy 372.040389 -224.650854)
			(xy 371.998718 -224.684085) (xy 371.95256 -224.710734) (xy 371.902946 -224.730206) (xy 371.850984 -224.742066)
			(xy 371.797834 -224.74605) (xy 371.744684 -224.742066) (xy 371.692722 -224.730206) (xy 371.643108 -224.710734)
			(xy 371.59695 -224.684085) (xy 371.555279 -224.650854) (xy 371.519027 -224.611783) (xy 371.489003 -224.567746)
			(xy 371.465877 -224.519725) (xy 371.450167 -224.468795) (xy 371.442224 -224.416091) (xy 371.441726 -224.389442)
			(xy 371.214142 -224.389442) (xy 371.213752 -224.412686) (xy 371.207713 -224.458781) (xy 371.195732 -224.5037)
			(xy 371.187218 -224.525332) (xy 371.177566 -224.548446) (xy 371.350032 -224.846896) (xy 371.37467 -224.850198)
			(xy 371.400019 -224.853984) (xy 371.449325 -224.86798) (xy 371.496117 -224.888897) (xy 371.539429 -224.916303)
			(xy 371.578366 -224.949633) (xy 371.612126 -224.988198) (xy 371.640011 -225.031202) (xy 371.661447 -225.077759)
			(xy 371.67599 -225.126907) (xy 371.68334 -225.177631) (xy 371.683788 -225.203258) (xy 371.68329 -225.229907)
			(xy 371.91187 -225.229907) (xy 371.91187 -225.176609) (xy 371.919813 -225.123905) (xy 371.935523 -225.072975)
			(xy 371.958649 -225.024954) (xy 371.988673 -224.980917) (xy 372.024925 -224.941846) (xy 372.066596 -224.908615)
			(xy 372.112754 -224.881966) (xy 372.162368 -224.862494) (xy 372.21433 -224.850634) (xy 372.26748 -224.846651)
			(xy 372.32063 -224.850634) (xy 372.372592 -224.862494) (xy 372.422206 -224.881966) (xy 372.468364 -224.908615)
			(xy 372.510035 -224.941846) (xy 372.546287 -224.980917) (xy 372.576311 -225.024954) (xy 372.599437 -225.072975)
			(xy 372.615147 -225.123905) (xy 372.62309 -225.176609) (xy 372.623588 -225.203258) (xy 372.62309 -225.229907)
			(xy 372.615147 -225.282611) (xy 372.599437 -225.333541) (xy 372.576311 -225.381562) (xy 372.546287 -225.425599)
			(xy 372.510035 -225.46467) (xy 372.468364 -225.497901) (xy 372.422206 -225.52455) (xy 372.372592 -225.544022)
			(xy 372.32063 -225.555882) (xy 372.26748 -225.559866) (xy 372.21433 -225.555882) (xy 372.162368 -225.544022)
			(xy 372.112754 -225.52455) (xy 372.066596 -225.497901) (xy 372.024925 -225.46467) (xy 371.988673 -225.425599)
			(xy 371.958649 -225.381562) (xy 371.935523 -225.333541) (xy 371.919813 -225.282611) (xy 371.91187 -225.229907)
			(xy 371.68329 -225.229907) (xy 371.675347 -225.282611) (xy 371.659637 -225.333541) (xy 371.636511 -225.381562)
			(xy 371.606487 -225.425599) (xy 371.570235 -225.46467) (xy 371.528564 -225.497901) (xy 371.482406 -225.52455)
			(xy 371.432792 -225.544022) (xy 371.38083 -225.555882) (xy 371.32768 -225.559866) (xy 371.27453 -225.555882)
			(xy 371.222568 -225.544022) (xy 371.172954 -225.52455) (xy 371.126796 -225.497901) (xy 371.085125 -225.46467)
			(xy 371.048873 -225.425599) (xy 371.018849 -225.381562) (xy 370.995723 -225.333541) (xy 370.980013 -225.282611)
			(xy 370.97207 -225.229907) (xy 370.971572 -225.203258) (xy 370.971961 -225.180014) (xy 370.978 -225.133918)
			(xy 370.989982 -225.089) (xy 370.998496 -225.067368) (xy 371.008148 -225.044254) (xy 370.835682 -224.745804)
			(xy 370.811044 -224.742502) (xy 370.785697 -224.738705) (xy 370.736391 -224.724711) (xy 370.689599 -224.703796)
			(xy 370.646287 -224.676391) (xy 370.607349 -224.643063) (xy 370.573589 -224.604499) (xy 370.545703 -224.561495)
			(xy 370.524268 -224.514939) (xy 370.509725 -224.465792) (xy 370.502374 -224.415069) (xy 370.501926 -224.389442)
			(xy 370.274342 -224.389442) (xy 370.273844 -224.416091) (xy 370.265901 -224.468795) (xy 370.250191 -224.519725)
			(xy 370.227065 -224.567746) (xy 370.197041 -224.611783) (xy 370.160789 -224.650854) (xy 370.119118 -224.684085)
			(xy 370.07296 -224.710734) (xy 370.023346 -224.730206) (xy 369.971384 -224.742066) (xy 369.918234 -224.74605)
			(xy 369.865084 -224.742066) (xy 369.813122 -224.730206) (xy 369.763508 -224.710734) (xy 369.71735 -224.684085)
			(xy 369.675679 -224.650854) (xy 369.639427 -224.611783) (xy 369.609403 -224.567746) (xy 369.586277 -224.519725)
			(xy 369.570567 -224.468795) (xy 369.562624 -224.416091) (xy 369.562126 -224.389442) (xy 369.334542 -224.389442)
			(xy 369.334152 -224.412686) (xy 369.328113 -224.458781) (xy 369.316132 -224.5037) (xy 369.307618 -224.525332)
			(xy 369.297966 -224.548446) (xy 369.470432 -224.846896) (xy 369.49507 -224.850198) (xy 369.520419 -224.853984)
			(xy 369.569725 -224.86798) (xy 369.616517 -224.888897) (xy 369.659829 -224.916303) (xy 369.698766 -224.949633)
			(xy 369.732526 -224.988198) (xy 369.760411 -225.031202) (xy 369.781847 -225.077759) (xy 369.79639 -225.126907)
			(xy 369.80374 -225.177631) (xy 369.804188 -225.203258) (xy 369.80369 -225.229907) (xy 370.03227 -225.229907)
			(xy 370.03227 -225.176609) (xy 370.040213 -225.123905) (xy 370.055923 -225.072975) (xy 370.079049 -225.024954)
			(xy 370.109073 -224.980917) (xy 370.145325 -224.941846) (xy 370.186996 -224.908615) (xy 370.233154 -224.881966)
			(xy 370.282768 -224.862494) (xy 370.33473 -224.850634) (xy 370.38788 -224.846651) (xy 370.44103 -224.850634)
			(xy 370.492992 -224.862494) (xy 370.542606 -224.881966) (xy 370.588764 -224.908615) (xy 370.630435 -224.941846)
			(xy 370.666687 -224.980917) (xy 370.696711 -225.024954) (xy 370.719837 -225.072975) (xy 370.735547 -225.123905)
			(xy 370.74349 -225.176609) (xy 370.743988 -225.203258) (xy 370.74349 -225.229907) (xy 370.735547 -225.282611)
			(xy 370.719837 -225.333541) (xy 370.696711 -225.381562) (xy 370.666687 -225.425599) (xy 370.630435 -225.46467)
			(xy 370.588764 -225.497901) (xy 370.542606 -225.52455) (xy 370.492992 -225.544022) (xy 370.44103 -225.555882)
			(xy 370.38788 -225.559866) (xy 370.33473 -225.555882) (xy 370.282768 -225.544022) (xy 370.233154 -225.52455)
			(xy 370.186996 -225.497901) (xy 370.145325 -225.46467) (xy 370.109073 -225.425599) (xy 370.079049 -225.381562)
			(xy 370.055923 -225.333541) (xy 370.040213 -225.282611) (xy 370.03227 -225.229907) (xy 369.80369 -225.229907)
			(xy 369.795747 -225.282611) (xy 369.780037 -225.333541) (xy 369.756911 -225.381562) (xy 369.726887 -225.425599)
			(xy 369.690635 -225.46467) (xy 369.648964 -225.497901) (xy 369.602806 -225.52455) (xy 369.553192 -225.544022)
			(xy 369.50123 -225.555882) (xy 369.44808 -225.559866) (xy 369.39493 -225.555882) (xy 369.342968 -225.544022)
			(xy 369.293354 -225.52455) (xy 369.247196 -225.497901) (xy 369.205525 -225.46467) (xy 369.169273 -225.425599)
			(xy 369.139249 -225.381562) (xy 369.116123 -225.333541) (xy 369.100413 -225.282611) (xy 369.09247 -225.229907)
			(xy 369.091972 -225.203258) (xy 369.092361 -225.180014) (xy 369.0984 -225.133918) (xy 369.110382 -225.089)
			(xy 369.118896 -225.067368) (xy 369.128548 -225.044254) (xy 368.956082 -224.745804) (xy 368.931444 -224.742502)
			(xy 368.906097 -224.738705) (xy 368.856791 -224.724711) (xy 368.809999 -224.703796) (xy 368.766687 -224.676391)
			(xy 368.727749 -224.643063) (xy 368.693989 -224.604499) (xy 368.666103 -224.561495) (xy 368.644668 -224.514939)
			(xy 368.630125 -224.465792) (xy 368.622774 -224.415069) (xy 368.622326 -224.389442) (xy 368.394742 -224.389442)
			(xy 368.394244 -224.416091) (xy 368.386301 -224.468795) (xy 368.370591 -224.519725) (xy 368.347465 -224.567746)
			(xy 368.317441 -224.611783) (xy 368.281189 -224.650854) (xy 368.239518 -224.684085) (xy 368.19336 -224.710734)
			(xy 368.143746 -224.730206) (xy 368.091784 -224.742066) (xy 368.038634 -224.74605) (xy 367.985484 -224.742066)
			(xy 367.933522 -224.730206) (xy 367.883908 -224.710734) (xy 367.83775 -224.684085) (xy 367.796079 -224.650854)
			(xy 367.759827 -224.611783) (xy 367.729803 -224.567746) (xy 367.706677 -224.519725) (xy 367.690967 -224.468795)
			(xy 367.683024 -224.416091) (xy 367.682526 -224.389442) (xy 367.454942 -224.389442) (xy 367.454552 -224.412686)
			(xy 367.448513 -224.458781) (xy 367.436532 -224.5037) (xy 367.428018 -224.525332) (xy 367.418366 -224.548446)
			(xy 367.590832 -224.846896) (xy 367.61547 -224.850198) (xy 367.640819 -224.853984) (xy 367.690125 -224.86798)
			(xy 367.736917 -224.888897) (xy 367.780229 -224.916303) (xy 367.819166 -224.949633) (xy 367.852926 -224.988198)
			(xy 367.880811 -225.031202) (xy 367.902247 -225.077759) (xy 367.91679 -225.126907) (xy 367.92414 -225.177631)
			(xy 367.924588 -225.203258) (xy 367.92409 -225.229907) (xy 368.15267 -225.229907) (xy 368.15267 -225.176609)
			(xy 368.160613 -225.123905) (xy 368.176323 -225.072975) (xy 368.199449 -225.024954) (xy 368.229473 -224.980917)
			(xy 368.265725 -224.941846) (xy 368.307396 -224.908615) (xy 368.353554 -224.881966) (xy 368.403168 -224.862494)
			(xy 368.45513 -224.850634) (xy 368.50828 -224.846651) (xy 368.56143 -224.850634) (xy 368.613392 -224.862494)
			(xy 368.663006 -224.881966) (xy 368.709164 -224.908615) (xy 368.750835 -224.941846) (xy 368.787087 -224.980917)
			(xy 368.817111 -225.024954) (xy 368.840237 -225.072975) (xy 368.855947 -225.123905) (xy 368.86389 -225.176609)
			(xy 368.864388 -225.203258) (xy 368.86389 -225.229907) (xy 368.855947 -225.282611) (xy 368.840237 -225.333541)
			(xy 368.817111 -225.381562) (xy 368.787087 -225.425599) (xy 368.750835 -225.46467) (xy 368.709164 -225.497901)
			(xy 368.663006 -225.52455) (xy 368.613392 -225.544022) (xy 368.56143 -225.555882) (xy 368.50828 -225.559866)
			(xy 368.45513 -225.555882) (xy 368.403168 -225.544022) (xy 368.353554 -225.52455) (xy 368.307396 -225.497901)
			(xy 368.265725 -225.46467) (xy 368.229473 -225.425599) (xy 368.199449 -225.381562) (xy 368.176323 -225.333541)
			(xy 368.160613 -225.282611) (xy 368.15267 -225.229907) (xy 367.92409 -225.229907) (xy 367.916147 -225.282611)
			(xy 367.900437 -225.333541) (xy 367.877311 -225.381562) (xy 367.847287 -225.425599) (xy 367.811035 -225.46467)
			(xy 367.769364 -225.497901) (xy 367.723206 -225.52455) (xy 367.673592 -225.544022) (xy 367.62163 -225.555882)
			(xy 367.56848 -225.559866) (xy 367.51533 -225.555882) (xy 367.463368 -225.544022) (xy 367.413754 -225.52455)
			(xy 367.367596 -225.497901) (xy 367.325925 -225.46467) (xy 367.289673 -225.425599) (xy 367.259649 -225.381562)
			(xy 367.236523 -225.333541) (xy 367.220813 -225.282611) (xy 367.21287 -225.229907) (xy 367.212372 -225.203258)
			(xy 367.212761 -225.180014) (xy 367.2188 -225.133918) (xy 367.230782 -225.089) (xy 367.239296 -225.067368)
			(xy 367.248948 -225.044254) (xy 367.076482 -224.745804) (xy 367.051844 -224.742502) (xy 367.026497 -224.738705)
			(xy 366.977191 -224.724711) (xy 366.930399 -224.703796) (xy 366.887087 -224.676391) (xy 366.848149 -224.643063)
			(xy 366.814389 -224.604499) (xy 366.786503 -224.561495) (xy 366.765068 -224.514939) (xy 366.750525 -224.465792)
			(xy 366.743174 -224.415069) (xy 366.742726 -224.389442) (xy 366.515142 -224.389442) (xy 366.514644 -224.416091)
			(xy 366.506701 -224.468795) (xy 366.490991 -224.519725) (xy 366.467865 -224.567746) (xy 366.437841 -224.611783)
			(xy 366.401589 -224.650854) (xy 366.359918 -224.684085) (xy 366.31376 -224.710734) (xy 366.264146 -224.730206)
			(xy 366.212184 -224.742066) (xy 366.159034 -224.74605) (xy 366.105884 -224.742066) (xy 366.053922 -224.730206)
			(xy 366.004308 -224.710734) (xy 365.95815 -224.684085) (xy 365.916479 -224.650854) (xy 365.880227 -224.611783)
			(xy 365.850203 -224.567746) (xy 365.827077 -224.519725) (xy 365.811367 -224.468795) (xy 365.803424 -224.416091)
			(xy 365.802926 -224.389442) (xy 365.575342 -224.389442) (xy 365.574952 -224.412686) (xy 365.568913 -224.458781)
			(xy 365.556932 -224.5037) (xy 365.548418 -224.525332) (xy 365.538766 -224.548446) (xy 365.711232 -224.846896)
			(xy 365.73587 -224.850198) (xy 365.761219 -224.853984) (xy 365.810525 -224.86798) (xy 365.857317 -224.888897)
			(xy 365.900629 -224.916303) (xy 365.939566 -224.949633) (xy 365.973326 -224.988198) (xy 366.001211 -225.031202)
			(xy 366.022647 -225.077759) (xy 366.03719 -225.126907) (xy 366.04454 -225.177631) (xy 366.044988 -225.203258)
			(xy 366.04449 -225.229907) (xy 366.27307 -225.229907) (xy 366.27307 -225.176609) (xy 366.281013 -225.123905)
			(xy 366.296723 -225.072975) (xy 366.319849 -225.024954) (xy 366.349873 -224.980917) (xy 366.386125 -224.941846)
			(xy 366.427796 -224.908615) (xy 366.473954 -224.881966) (xy 366.523568 -224.862494) (xy 366.57553 -224.850634)
			(xy 366.62868 -224.846651) (xy 366.68183 -224.850634) (xy 366.733792 -224.862494) (xy 366.783406 -224.881966)
			(xy 366.829564 -224.908615) (xy 366.871235 -224.941846) (xy 366.907487 -224.980917) (xy 366.937511 -225.024954)
			(xy 366.960637 -225.072975) (xy 366.976347 -225.123905) (xy 366.98429 -225.176609) (xy 366.984788 -225.203258)
			(xy 366.98429 -225.229907) (xy 366.976347 -225.282611) (xy 366.960637 -225.333541) (xy 366.937511 -225.381562)
			(xy 366.907487 -225.425599) (xy 366.871235 -225.46467) (xy 366.829564 -225.497901) (xy 366.783406 -225.52455)
			(xy 366.733792 -225.544022) (xy 366.68183 -225.555882) (xy 366.62868 -225.559866) (xy 366.57553 -225.555882)
			(xy 366.523568 -225.544022) (xy 366.473954 -225.52455) (xy 366.427796 -225.497901) (xy 366.386125 -225.46467)
			(xy 366.349873 -225.425599) (xy 366.319849 -225.381562) (xy 366.296723 -225.333541) (xy 366.281013 -225.282611)
			(xy 366.27307 -225.229907) (xy 366.04449 -225.229907) (xy 366.036547 -225.282611) (xy 366.020837 -225.333541)
			(xy 365.997711 -225.381562) (xy 365.967687 -225.425599) (xy 365.931435 -225.46467) (xy 365.889764 -225.497901)
			(xy 365.843606 -225.52455) (xy 365.793992 -225.544022) (xy 365.74203 -225.555882) (xy 365.68888 -225.559866)
			(xy 365.63573 -225.555882) (xy 365.583768 -225.544022) (xy 365.534154 -225.52455) (xy 365.487996 -225.497901)
			(xy 365.446325 -225.46467) (xy 365.410073 -225.425599) (xy 365.380049 -225.381562) (xy 365.356923 -225.333541)
			(xy 365.341213 -225.282611) (xy 365.33327 -225.229907) (xy 365.332772 -225.203258) (xy 365.333161 -225.180014)
			(xy 365.3392 -225.133918) (xy 365.351182 -225.089) (xy 365.359696 -225.067368) (xy 365.369348 -225.044254)
			(xy 365.196882 -224.745804) (xy 365.172244 -224.742502) (xy 365.146897 -224.738705) (xy 365.097591 -224.724711)
			(xy 365.050799 -224.703796) (xy 365.007487 -224.676391) (xy 364.968549 -224.643063) (xy 364.934789 -224.604499)
			(xy 364.906903 -224.561495) (xy 364.885468 -224.514939) (xy 364.870925 -224.465792) (xy 364.863574 -224.415069)
			(xy 364.863126 -224.389442) (xy 364.635542 -224.389442) (xy 364.635044 -224.416091) (xy 364.627101 -224.468795)
			(xy 364.611391 -224.519725) (xy 364.588265 -224.567746) (xy 364.558241 -224.611783) (xy 364.521989 -224.650854)
			(xy 364.480318 -224.684085) (xy 364.43416 -224.710734) (xy 364.384546 -224.730206) (xy 364.332584 -224.742066)
			(xy 364.279434 -224.74605) (xy 364.226284 -224.742066) (xy 364.174322 -224.730206) (xy 364.124708 -224.710734)
			(xy 364.07855 -224.684085) (xy 364.036879 -224.650854) (xy 364.000627 -224.611783) (xy 363.970603 -224.567746)
			(xy 363.947477 -224.519725) (xy 363.931767 -224.468795) (xy 363.923824 -224.416091) (xy 363.923326 -224.389442)
			(xy 363.695742 -224.389442) (xy 363.695352 -224.412686) (xy 363.689313 -224.458781) (xy 363.677332 -224.5037)
			(xy 363.668818 -224.525332) (xy 363.659166 -224.548446) (xy 363.831632 -224.846896) (xy 363.85627 -224.850198)
			(xy 363.881619 -224.853984) (xy 363.930925 -224.86798) (xy 363.977717 -224.888897) (xy 364.021029 -224.916303)
			(xy 364.059966 -224.949633) (xy 364.093726 -224.988198) (xy 364.121611 -225.031202) (xy 364.143047 -225.077759)
			(xy 364.15759 -225.126907) (xy 364.16494 -225.177631) (xy 364.165388 -225.203258) (xy 364.16489 -225.229907)
			(xy 364.39347 -225.229907) (xy 364.39347 -225.176609) (xy 364.401413 -225.123905) (xy 364.417123 -225.072975)
			(xy 364.440249 -225.024954) (xy 364.470273 -224.980917) (xy 364.506525 -224.941846) (xy 364.548196 -224.908615)
			(xy 364.594354 -224.881966) (xy 364.643968 -224.862494) (xy 364.69593 -224.850634) (xy 364.74908 -224.846651)
			(xy 364.80223 -224.850634) (xy 364.854192 -224.862494) (xy 364.903806 -224.881966) (xy 364.949964 -224.908615)
			(xy 364.991635 -224.941846) (xy 365.027887 -224.980917) (xy 365.057911 -225.024954) (xy 365.081037 -225.072975)
			(xy 365.096747 -225.123905) (xy 365.10469 -225.176609) (xy 365.105188 -225.203258) (xy 365.10469 -225.229907)
			(xy 365.096747 -225.282611) (xy 365.081037 -225.333541) (xy 365.057911 -225.381562) (xy 365.027887 -225.425599)
			(xy 364.991635 -225.46467) (xy 364.949964 -225.497901) (xy 364.903806 -225.52455) (xy 364.854192 -225.544022)
			(xy 364.80223 -225.555882) (xy 364.74908 -225.559866) (xy 364.69593 -225.555882) (xy 364.643968 -225.544022)
			(xy 364.594354 -225.52455) (xy 364.548196 -225.497901) (xy 364.506525 -225.46467) (xy 364.470273 -225.425599)
			(xy 364.440249 -225.381562) (xy 364.417123 -225.333541) (xy 364.401413 -225.282611) (xy 364.39347 -225.229907)
			(xy 364.16489 -225.229907) (xy 364.156947 -225.282611) (xy 364.141237 -225.333541) (xy 364.118111 -225.381562)
			(xy 364.088087 -225.425599) (xy 364.051835 -225.46467) (xy 364.010164 -225.497901) (xy 363.964006 -225.52455)
			(xy 363.914392 -225.544022) (xy 363.86243 -225.555882) (xy 363.80928 -225.559866) (xy 363.75613 -225.555882)
			(xy 363.704168 -225.544022) (xy 363.654554 -225.52455) (xy 363.608396 -225.497901) (xy 363.566725 -225.46467)
			(xy 363.530473 -225.425599) (xy 363.500449 -225.381562) (xy 363.477323 -225.333541) (xy 363.461613 -225.282611)
			(xy 363.45367 -225.229907) (xy 363.453172 -225.203258) (xy 363.453561 -225.180014) (xy 363.4596 -225.133918)
			(xy 363.471582 -225.089) (xy 363.480096 -225.067368) (xy 363.489748 -225.044254) (xy 363.317282 -224.745804)
			(xy 363.292644 -224.742502) (xy 363.267297 -224.738705) (xy 363.217991 -224.724711) (xy 363.171199 -224.703796)
			(xy 363.127887 -224.676391) (xy 363.088949 -224.643063) (xy 363.055189 -224.604499) (xy 363.027303 -224.561495)
			(xy 363.005868 -224.514939) (xy 362.991325 -224.465792) (xy 362.983974 -224.415069) (xy 362.983526 -224.389442)
			(xy 362.755942 -224.389442) (xy 362.755444 -224.416091) (xy 362.747501 -224.468795) (xy 362.731791 -224.519725)
			(xy 362.708665 -224.567746) (xy 362.678641 -224.611783) (xy 362.642389 -224.650854) (xy 362.600718 -224.684085)
			(xy 362.55456 -224.710734) (xy 362.504946 -224.730206) (xy 362.452984 -224.742066) (xy 362.399834 -224.74605)
			(xy 362.346684 -224.742066) (xy 362.294722 -224.730206) (xy 362.245108 -224.710734) (xy 362.19895 -224.684085)
			(xy 362.157279 -224.650854) (xy 362.121027 -224.611783) (xy 362.091003 -224.567746) (xy 362.067877 -224.519725)
			(xy 362.052167 -224.468795) (xy 362.044224 -224.416091) (xy 362.043726 -224.389442) (xy 361.816142 -224.389442)
			(xy 361.815752 -224.412686) (xy 361.809713 -224.458781) (xy 361.797732 -224.5037) (xy 361.789218 -224.525332)
			(xy 361.779566 -224.548446) (xy 361.952032 -224.846896) (xy 361.97667 -224.850198) (xy 362.002019 -224.853984)
			(xy 362.051325 -224.86798) (xy 362.098117 -224.888897) (xy 362.141429 -224.916303) (xy 362.180366 -224.949633)
			(xy 362.214126 -224.988198) (xy 362.242011 -225.031202) (xy 362.263447 -225.077759) (xy 362.27799 -225.126907)
			(xy 362.28534 -225.177631) (xy 362.285788 -225.203258) (xy 362.28529 -225.229907) (xy 362.51387 -225.229907)
			(xy 362.51387 -225.176609) (xy 362.521813 -225.123905) (xy 362.537523 -225.072975) (xy 362.560649 -225.024954)
			(xy 362.590673 -224.980917) (xy 362.626925 -224.941846) (xy 362.668596 -224.908615) (xy 362.714754 -224.881966)
			(xy 362.764368 -224.862494) (xy 362.81633 -224.850634) (xy 362.86948 -224.846651) (xy 362.92263 -224.850634)
			(xy 362.974592 -224.862494) (xy 363.024206 -224.881966) (xy 363.070364 -224.908615) (xy 363.112035 -224.941846)
			(xy 363.148287 -224.980917) (xy 363.178311 -225.024954) (xy 363.201437 -225.072975) (xy 363.217147 -225.123905)
			(xy 363.22509 -225.176609) (xy 363.225588 -225.203258) (xy 363.22509 -225.229907) (xy 363.217147 -225.282611)
			(xy 363.201437 -225.333541) (xy 363.178311 -225.381562) (xy 363.148287 -225.425599) (xy 363.112035 -225.46467)
			(xy 363.070364 -225.497901) (xy 363.024206 -225.52455) (xy 362.974592 -225.544022) (xy 362.92263 -225.555882)
			(xy 362.86948 -225.559866) (xy 362.81633 -225.555882) (xy 362.764368 -225.544022) (xy 362.714754 -225.52455)
			(xy 362.668596 -225.497901) (xy 362.626925 -225.46467) (xy 362.590673 -225.425599) (xy 362.560649 -225.381562)
			(xy 362.537523 -225.333541) (xy 362.521813 -225.282611) (xy 362.51387 -225.229907) (xy 362.28529 -225.229907)
			(xy 362.277347 -225.282611) (xy 362.261637 -225.333541) (xy 362.238511 -225.381562) (xy 362.208487 -225.425599)
			(xy 362.172235 -225.46467) (xy 362.130564 -225.497901) (xy 362.084406 -225.52455) (xy 362.034792 -225.544022)
			(xy 361.98283 -225.555882) (xy 361.92968 -225.559866) (xy 361.87653 -225.555882) (xy 361.824568 -225.544022)
			(xy 361.774954 -225.52455) (xy 361.728796 -225.497901) (xy 361.687125 -225.46467) (xy 361.650873 -225.425599)
			(xy 361.620849 -225.381562) (xy 361.597723 -225.333541) (xy 361.582013 -225.282611) (xy 361.57407 -225.229907)
			(xy 361.573572 -225.203258) (xy 361.573961 -225.180014) (xy 361.58 -225.133918) (xy 361.591982 -225.089)
			(xy 361.600496 -225.067368) (xy 361.610148 -225.044254) (xy 361.437682 -224.745804) (xy 361.413044 -224.742502)
			(xy 361.387697 -224.738705) (xy 361.338391 -224.724711) (xy 361.291599 -224.703796) (xy 361.248287 -224.676391)
			(xy 361.209349 -224.643063) (xy 361.175589 -224.604499) (xy 361.147703 -224.561495) (xy 361.126268 -224.514939)
			(xy 361.111725 -224.465792) (xy 361.104374 -224.415069) (xy 361.103926 -224.389442) (xy 360.876342 -224.389442)
			(xy 360.875844 -224.416091) (xy 360.867901 -224.468795) (xy 360.852191 -224.519725) (xy 360.829065 -224.567746)
			(xy 360.799041 -224.611783) (xy 360.762789 -224.650854) (xy 360.721118 -224.684085) (xy 360.67496 -224.710734)
			(xy 360.625346 -224.730206) (xy 360.573384 -224.742066) (xy 360.520234 -224.74605) (xy 360.467084 -224.742066)
			(xy 360.415122 -224.730206) (xy 360.365508 -224.710734) (xy 360.31935 -224.684085) (xy 360.277679 -224.650854)
			(xy 360.241427 -224.611783) (xy 360.211403 -224.567746) (xy 360.188277 -224.519725) (xy 360.172567 -224.468795)
			(xy 360.164624 -224.416091) (xy 360.164126 -224.389442) (xy 359.936542 -224.389442) (xy 359.936051 -224.416273)
			(xy 359.92801 -224.469331) (xy 359.92054 -224.495106) (xy 359.918254 -224.502472) (xy 359.918254 -224.579942)
			(xy 360.072432 -224.846896) (xy 360.09707 -224.850198) (xy 360.122413 -224.854021) (xy 360.171722 -224.867998)
			(xy 360.218518 -224.888902) (xy 360.261832 -224.916299) (xy 360.30077 -224.949625) (xy 360.334527 -224.988189)
			(xy 360.362405 -225.031196) (xy 360.383827 -225.077756) (xy 360.398352 -225.126906) (xy 360.405679 -225.177632)
			(xy 360.406188 -225.203258) (xy 360.405696 -225.229907) (xy 360.63427 -225.229907) (xy 360.63427 -225.176609)
			(xy 360.642213 -225.123905) (xy 360.657923 -225.072975) (xy 360.681049 -225.024954) (xy 360.711073 -224.980917)
			(xy 360.747325 -224.941846) (xy 360.788996 -224.908615) (xy 360.835154 -224.881966) (xy 360.884768 -224.862494)
			(xy 360.93673 -224.850634) (xy 360.98988 -224.846651) (xy 361.04303 -224.850634) (xy 361.094992 -224.862494)
			(xy 361.144606 -224.881966) (xy 361.190764 -224.908615) (xy 361.232435 -224.941846) (xy 361.268687 -224.980917)
			(xy 361.298711 -225.024954) (xy 361.321837 -225.072975) (xy 361.337547 -225.123905) (xy 361.34549 -225.176609)
			(xy 361.345988 -225.203258) (xy 361.34549 -225.229907) (xy 361.337547 -225.282611) (xy 361.321837 -225.333541)
			(xy 361.298711 -225.381562) (xy 361.268687 -225.425599) (xy 361.232435 -225.46467) (xy 361.190764 -225.497901)
			(xy 361.144606 -225.52455) (xy 361.094992 -225.544022) (xy 361.04303 -225.555882) (xy 360.98988 -225.559866)
			(xy 360.93673 -225.555882) (xy 360.884768 -225.544022) (xy 360.835154 -225.52455) (xy 360.788996 -225.497901)
			(xy 360.747325 -225.46467) (xy 360.711073 -225.425599) (xy 360.681049 -225.381562) (xy 360.657923 -225.333541)
			(xy 360.642213 -225.282611) (xy 360.63427 -225.229907) (xy 360.405696 -225.229907) (xy 360.405671 -225.231245)
			(xy 360.39692 -225.28653) (xy 360.379628 -225.339766) (xy 360.354219 -225.389641) (xy 360.321321 -225.434926)
			(xy 360.281743 -225.474507) (xy 360.236459 -225.507408) (xy 360.186586 -225.532819) (xy 360.133352 -225.550115)
			(xy 360.078067 -225.558869) (xy 360.05008 -225.559366) (xy 360.026458 -225.558604) (xy 360.012591 -225.558177)
			(xy 359.985458 -225.5639) (xy 359.960866 -225.576715) (xy 359.94063 -225.595675) (xy 359.926243 -225.619381)
			(xy 359.918767 -225.646085) (xy 359.918254 -225.65995) (xy 359.918254 -225.904298) (xy 359.92054 -225.911664)
			(xy 359.928039 -225.937433) (xy 359.936076 -225.990494) (xy 359.936542 -226.017328) (xy 359.936055 -226.043977)
			(xy 360.164624 -226.043977) (xy 360.164624 -225.990679) (xy 360.172567 -225.937975) (xy 360.188277 -225.887045)
			(xy 360.211403 -225.839024) (xy 360.241427 -225.794987) (xy 360.277679 -225.755916) (xy 360.31935 -225.722685)
			(xy 360.365508 -225.696036) (xy 360.415122 -225.676564) (xy 360.467084 -225.664704) (xy 360.520234 -225.660721)
			(xy 360.573384 -225.664704) (xy 360.625346 -225.676564) (xy 360.67496 -225.696036) (xy 360.721118 -225.722685)
			(xy 360.762789 -225.755916) (xy 360.799041 -225.794987) (xy 360.829065 -225.839024) (xy 360.852191 -225.887045)
			(xy 360.867901 -225.937975) (xy 360.875844 -225.990679) (xy 360.876342 -226.017328) (xy 360.875844 -226.043977)
			(xy 361.104424 -226.043977) (xy 361.104424 -225.990679) (xy 361.112367 -225.937975) (xy 361.128077 -225.887045)
			(xy 361.151203 -225.839024) (xy 361.181227 -225.794987) (xy 361.217479 -225.755916) (xy 361.25915 -225.722685)
			(xy 361.305308 -225.696036) (xy 361.354922 -225.676564) (xy 361.406884 -225.664704) (xy 361.460034 -225.660721)
			(xy 361.513184 -225.664704) (xy 361.565146 -225.676564) (xy 361.61476 -225.696036) (xy 361.660918 -225.722685)
			(xy 361.702589 -225.755916) (xy 361.738841 -225.794987) (xy 361.768865 -225.839024) (xy 361.791991 -225.887045)
			(xy 361.807701 -225.937975) (xy 361.815644 -225.990679) (xy 361.816142 -226.017328) (xy 361.815644 -226.043977)
			(xy 362.044224 -226.043977) (xy 362.044224 -225.990679) (xy 362.052167 -225.937975) (xy 362.067877 -225.887045)
			(xy 362.091003 -225.839024) (xy 362.121027 -225.794987) (xy 362.157279 -225.755916) (xy 362.19895 -225.722685)
			(xy 362.245108 -225.696036) (xy 362.294722 -225.676564) (xy 362.346684 -225.664704) (xy 362.399834 -225.660721)
			(xy 362.452984 -225.664704) (xy 362.504946 -225.676564) (xy 362.55456 -225.696036) (xy 362.600718 -225.722685)
			(xy 362.642389 -225.755916) (xy 362.678641 -225.794987) (xy 362.708665 -225.839024) (xy 362.731791 -225.887045)
			(xy 362.747501 -225.937975) (xy 362.755444 -225.990679) (xy 362.755942 -226.017328) (xy 362.755444 -226.043977)
			(xy 362.984024 -226.043977) (xy 362.984024 -225.990679) (xy 362.991967 -225.937975) (xy 363.007677 -225.887045)
			(xy 363.030803 -225.839024) (xy 363.060827 -225.794987) (xy 363.097079 -225.755916) (xy 363.13875 -225.722685)
			(xy 363.184908 -225.696036) (xy 363.234522 -225.676564) (xy 363.286484 -225.664704) (xy 363.339634 -225.660721)
			(xy 363.392784 -225.664704) (xy 363.444746 -225.676564) (xy 363.49436 -225.696036) (xy 363.540518 -225.722685)
			(xy 363.582189 -225.755916) (xy 363.618441 -225.794987) (xy 363.648465 -225.839024) (xy 363.671591 -225.887045)
			(xy 363.687301 -225.937975) (xy 363.695244 -225.990679) (xy 363.695742 -226.017328) (xy 363.695244 -226.043977)
			(xy 363.923824 -226.043977) (xy 363.923824 -225.990679) (xy 363.931767 -225.937975) (xy 363.947477 -225.887045)
			(xy 363.970603 -225.839024) (xy 364.000627 -225.794987) (xy 364.036879 -225.755916) (xy 364.07855 -225.722685)
			(xy 364.124708 -225.696036) (xy 364.174322 -225.676564) (xy 364.226284 -225.664704) (xy 364.279434 -225.660721)
			(xy 364.332584 -225.664704) (xy 364.384546 -225.676564) (xy 364.43416 -225.696036) (xy 364.480318 -225.722685)
			(xy 364.521989 -225.755916) (xy 364.558241 -225.794987) (xy 364.588265 -225.839024) (xy 364.611391 -225.887045)
			(xy 364.627101 -225.937975) (xy 364.635044 -225.990679) (xy 364.635542 -226.017328) (xy 364.635044 -226.043977)
			(xy 364.863624 -226.043977) (xy 364.863624 -225.990679) (xy 364.871567 -225.937975) (xy 364.887277 -225.887045)
			(xy 364.910403 -225.839024) (xy 364.940427 -225.794987) (xy 364.976679 -225.755916) (xy 365.01835 -225.722685)
			(xy 365.064508 -225.696036) (xy 365.114122 -225.676564) (xy 365.166084 -225.664704) (xy 365.219234 -225.660721)
			(xy 365.272384 -225.664704) (xy 365.324346 -225.676564) (xy 365.37396 -225.696036) (xy 365.420118 -225.722685)
			(xy 365.461789 -225.755916) (xy 365.498041 -225.794987) (xy 365.528065 -225.839024) (xy 365.551191 -225.887045)
			(xy 365.566901 -225.937975) (xy 365.574844 -225.990679) (xy 365.575342 -226.017328) (xy 365.574844 -226.043977)
			(xy 365.803424 -226.043977) (xy 365.803424 -225.990679) (xy 365.811367 -225.937975) (xy 365.827077 -225.887045)
			(xy 365.850203 -225.839024) (xy 365.880227 -225.794987) (xy 365.916479 -225.755916) (xy 365.95815 -225.722685)
			(xy 366.004308 -225.696036) (xy 366.053922 -225.676564) (xy 366.105884 -225.664704) (xy 366.159034 -225.660721)
			(xy 366.212184 -225.664704) (xy 366.264146 -225.676564) (xy 366.31376 -225.696036) (xy 366.359918 -225.722685)
			(xy 366.401589 -225.755916) (xy 366.437841 -225.794987) (xy 366.467865 -225.839024) (xy 366.490991 -225.887045)
			(xy 366.506701 -225.937975) (xy 366.514644 -225.990679) (xy 366.515142 -226.017328) (xy 366.514644 -226.043977)
			(xy 366.743224 -226.043977) (xy 366.743224 -225.990679) (xy 366.751167 -225.937975) (xy 366.766877 -225.887045)
			(xy 366.790003 -225.839024) (xy 366.820027 -225.794987) (xy 366.856279 -225.755916) (xy 366.89795 -225.722685)
			(xy 366.944108 -225.696036) (xy 366.993722 -225.676564) (xy 367.045684 -225.664704) (xy 367.098834 -225.660721)
			(xy 367.151984 -225.664704) (xy 367.203946 -225.676564) (xy 367.25356 -225.696036) (xy 367.299718 -225.722685)
			(xy 367.341389 -225.755916) (xy 367.377641 -225.794987) (xy 367.407665 -225.839024) (xy 367.430791 -225.887045)
			(xy 367.446501 -225.937975) (xy 367.454444 -225.990679) (xy 367.454942 -226.017328) (xy 367.454444 -226.043977)
			(xy 367.683024 -226.043977) (xy 367.683024 -225.990679) (xy 367.690967 -225.937975) (xy 367.706677 -225.887045)
			(xy 367.729803 -225.839024) (xy 367.759827 -225.794987) (xy 367.796079 -225.755916) (xy 367.83775 -225.722685)
			(xy 367.883908 -225.696036) (xy 367.933522 -225.676564) (xy 367.985484 -225.664704) (xy 368.038634 -225.660721)
			(xy 368.091784 -225.664704) (xy 368.143746 -225.676564) (xy 368.19336 -225.696036) (xy 368.239518 -225.722685)
			(xy 368.281189 -225.755916) (xy 368.317441 -225.794987) (xy 368.347465 -225.839024) (xy 368.370591 -225.887045)
			(xy 368.386301 -225.937975) (xy 368.394244 -225.990679) (xy 368.394742 -226.017328) (xy 368.394244 -226.043977)
			(xy 368.622824 -226.043977) (xy 368.622824 -225.990679) (xy 368.630767 -225.937975) (xy 368.646477 -225.887045)
			(xy 368.669603 -225.839024) (xy 368.699627 -225.794987) (xy 368.735879 -225.755916) (xy 368.77755 -225.722685)
			(xy 368.823708 -225.696036) (xy 368.873322 -225.676564) (xy 368.925284 -225.664704) (xy 368.978434 -225.660721)
			(xy 369.031584 -225.664704) (xy 369.083546 -225.676564) (xy 369.13316 -225.696036) (xy 369.179318 -225.722685)
			(xy 369.220989 -225.755916) (xy 369.257241 -225.794987) (xy 369.287265 -225.839024) (xy 369.310391 -225.887045)
			(xy 369.326101 -225.937975) (xy 369.334044 -225.990679) (xy 369.334542 -226.017328) (xy 369.334044 -226.043977)
			(xy 369.562624 -226.043977) (xy 369.562624 -225.990679) (xy 369.570567 -225.937975) (xy 369.586277 -225.887045)
			(xy 369.609403 -225.839024) (xy 369.639427 -225.794987) (xy 369.675679 -225.755916) (xy 369.71735 -225.722685)
			(xy 369.763508 -225.696036) (xy 369.813122 -225.676564) (xy 369.865084 -225.664704) (xy 369.918234 -225.660721)
			(xy 369.971384 -225.664704) (xy 370.023346 -225.676564) (xy 370.07296 -225.696036) (xy 370.119118 -225.722685)
			(xy 370.160789 -225.755916) (xy 370.197041 -225.794987) (xy 370.227065 -225.839024) (xy 370.250191 -225.887045)
			(xy 370.265901 -225.937975) (xy 370.273844 -225.990679) (xy 370.274342 -226.017328) (xy 370.273844 -226.043977)
			(xy 370.502424 -226.043977) (xy 370.502424 -225.990679) (xy 370.510367 -225.937975) (xy 370.526077 -225.887045)
			(xy 370.549203 -225.839024) (xy 370.579227 -225.794987) (xy 370.615479 -225.755916) (xy 370.65715 -225.722685)
			(xy 370.703308 -225.696036) (xy 370.752922 -225.676564) (xy 370.804884 -225.664704) (xy 370.858034 -225.660721)
			(xy 370.911184 -225.664704) (xy 370.963146 -225.676564) (xy 371.01276 -225.696036) (xy 371.058918 -225.722685)
			(xy 371.100589 -225.755916) (xy 371.136841 -225.794987) (xy 371.166865 -225.839024) (xy 371.189991 -225.887045)
			(xy 371.205701 -225.937975) (xy 371.213644 -225.990679) (xy 371.214142 -226.017328) (xy 371.213644 -226.043977)
			(xy 371.442224 -226.043977) (xy 371.442224 -225.990679) (xy 371.450167 -225.937975) (xy 371.465877 -225.887045)
			(xy 371.489003 -225.839024) (xy 371.519027 -225.794987) (xy 371.555279 -225.755916) (xy 371.59695 -225.722685)
			(xy 371.643108 -225.696036) (xy 371.692722 -225.676564) (xy 371.744684 -225.664704) (xy 371.797834 -225.660721)
			(xy 371.850984 -225.664704) (xy 371.902946 -225.676564) (xy 371.95256 -225.696036) (xy 371.998718 -225.722685)
			(xy 372.040389 -225.755916) (xy 372.076641 -225.794987) (xy 372.106665 -225.839024) (xy 372.129791 -225.887045)
			(xy 372.145501 -225.937975) (xy 372.153444 -225.990679) (xy 372.153942 -226.017328) (xy 372.153444 -226.043977)
			(xy 372.382024 -226.043977) (xy 372.382024 -225.990679) (xy 372.389967 -225.937975) (xy 372.405677 -225.887045)
			(xy 372.428803 -225.839024) (xy 372.458827 -225.794987) (xy 372.495079 -225.755916) (xy 372.53675 -225.722685)
			(xy 372.582908 -225.696036) (xy 372.632522 -225.676564) (xy 372.684484 -225.664704) (xy 372.737634 -225.660721)
			(xy 372.790784 -225.664704) (xy 372.842746 -225.676564) (xy 372.89236 -225.696036) (xy 372.938518 -225.722685)
			(xy 372.980189 -225.755916) (xy 373.016441 -225.794987) (xy 373.046465 -225.839024) (xy 373.069591 -225.887045)
			(xy 373.085301 -225.937975) (xy 373.093244 -225.990679) (xy 373.093742 -226.017328) (xy 373.093244 -226.043977)
			(xy 373.321824 -226.043977) (xy 373.321824 -225.990679) (xy 373.329767 -225.937975) (xy 373.345477 -225.887045)
			(xy 373.368603 -225.839024) (xy 373.398627 -225.794987) (xy 373.434879 -225.755916) (xy 373.47655 -225.722685)
			(xy 373.522708 -225.696036) (xy 373.572322 -225.676564) (xy 373.624284 -225.664704) (xy 373.677434 -225.660721)
			(xy 373.730584 -225.664704) (xy 373.782546 -225.676564) (xy 373.83216 -225.696036) (xy 373.878318 -225.722685)
			(xy 373.919989 -225.755916) (xy 373.956241 -225.794987) (xy 373.986265 -225.839024) (xy 374.009391 -225.887045)
			(xy 374.025101 -225.937975) (xy 374.033044 -225.990679) (xy 374.033542 -226.017328) (xy 374.033044 -226.043977)
			(xy 374.261624 -226.043977) (xy 374.261624 -225.990679) (xy 374.269567 -225.937975) (xy 374.285277 -225.887045)
			(xy 374.308403 -225.839024) (xy 374.338427 -225.794987) (xy 374.374679 -225.755916) (xy 374.41635 -225.722685)
			(xy 374.462508 -225.696036) (xy 374.512122 -225.676564) (xy 374.564084 -225.664704) (xy 374.617234 -225.660721)
			(xy 374.670384 -225.664704) (xy 374.722346 -225.676564) (xy 374.77196 -225.696036) (xy 374.818118 -225.722685)
			(xy 374.859789 -225.755916) (xy 374.896041 -225.794987) (xy 374.926065 -225.839024) (xy 374.949191 -225.887045)
			(xy 374.964901 -225.937975) (xy 374.972844 -225.990679) (xy 374.973342 -226.017328) (xy 374.972844 -226.043977)
			(xy 375.201424 -226.043977) (xy 375.201424 -225.990679) (xy 375.209367 -225.937975) (xy 375.225077 -225.887045)
			(xy 375.248203 -225.839024) (xy 375.278227 -225.794987) (xy 375.314479 -225.755916) (xy 375.35615 -225.722685)
			(xy 375.402308 -225.696036) (xy 375.451922 -225.676564) (xy 375.503884 -225.664704) (xy 375.557034 -225.660721)
			(xy 375.610184 -225.664704) (xy 375.662146 -225.676564) (xy 375.71176 -225.696036) (xy 375.757918 -225.722685)
			(xy 375.799589 -225.755916) (xy 375.835841 -225.794987) (xy 375.865865 -225.839024) (xy 375.888991 -225.887045)
			(xy 375.904701 -225.937975) (xy 375.912644 -225.990679) (xy 375.913142 -226.017328) (xy 375.912644 -226.043977)
			(xy 376.141224 -226.043977) (xy 376.141224 -225.990679) (xy 376.149167 -225.937975) (xy 376.164877 -225.887045)
			(xy 376.188003 -225.839024) (xy 376.218027 -225.794987) (xy 376.254279 -225.755916) (xy 376.29595 -225.722685)
			(xy 376.342108 -225.696036) (xy 376.391722 -225.676564) (xy 376.443684 -225.664704) (xy 376.496834 -225.660721)
			(xy 376.549984 -225.664704) (xy 376.601946 -225.676564) (xy 376.65156 -225.696036) (xy 376.697718 -225.722685)
			(xy 376.739389 -225.755916) (xy 376.775641 -225.794987) (xy 376.805665 -225.839024) (xy 376.828791 -225.887045)
			(xy 376.844501 -225.937975) (xy 376.852444 -225.990679) (xy 376.852942 -226.017328) (xy 376.852444 -226.043977)
			(xy 377.081024 -226.043977) (xy 377.081024 -225.990679) (xy 377.088967 -225.937975) (xy 377.104677 -225.887045)
			(xy 377.127803 -225.839024) (xy 377.157827 -225.794987) (xy 377.194079 -225.755916) (xy 377.23575 -225.722685)
			(xy 377.281908 -225.696036) (xy 377.331522 -225.676564) (xy 377.383484 -225.664704) (xy 377.436634 -225.660721)
			(xy 377.489784 -225.664704) (xy 377.541746 -225.676564) (xy 377.59136 -225.696036) (xy 377.637518 -225.722685)
			(xy 377.679189 -225.755916) (xy 377.715441 -225.794987) (xy 377.745465 -225.839024) (xy 377.768591 -225.887045)
			(xy 377.784301 -225.937975) (xy 377.792244 -225.990679) (xy 377.792742 -226.017328) (xy 377.792244 -226.043977)
			(xy 378.020824 -226.043977) (xy 378.020824 -225.990679) (xy 378.028767 -225.937975) (xy 378.044477 -225.887045)
			(xy 378.067603 -225.839024) (xy 378.097627 -225.794987) (xy 378.133879 -225.755916) (xy 378.17555 -225.722685)
			(xy 378.221708 -225.696036) (xy 378.271322 -225.676564) (xy 378.323284 -225.664704) (xy 378.376434 -225.660721)
			(xy 378.429584 -225.664704) (xy 378.481546 -225.676564) (xy 378.53116 -225.696036) (xy 378.577318 -225.722685)
			(xy 378.618989 -225.755916) (xy 378.655241 -225.794987) (xy 378.685265 -225.839024) (xy 378.708391 -225.887045)
			(xy 378.724101 -225.937975) (xy 378.732044 -225.990679) (xy 378.732542 -226.017328) (xy 378.732044 -226.043977)
			(xy 378.960624 -226.043977) (xy 378.960624 -225.990679) (xy 378.968567 -225.937975) (xy 378.984277 -225.887045)
			(xy 379.007403 -225.839024) (xy 379.037427 -225.794987) (xy 379.073679 -225.755916) (xy 379.11535 -225.722685)
			(xy 379.161508 -225.696036) (xy 379.211122 -225.676564) (xy 379.263084 -225.664704) (xy 379.316234 -225.660721)
			(xy 379.369384 -225.664704) (xy 379.421346 -225.676564) (xy 379.47096 -225.696036) (xy 379.517118 -225.722685)
			(xy 379.558789 -225.755916) (xy 379.595041 -225.794987) (xy 379.625065 -225.839024) (xy 379.648191 -225.887045)
			(xy 379.663901 -225.937975) (xy 379.671844 -225.990679) (xy 379.672342 -226.017328) (xy 379.671844 -226.043977)
			(xy 379.900424 -226.043977) (xy 379.900424 -225.990679) (xy 379.908367 -225.937975) (xy 379.924077 -225.887045)
			(xy 379.947203 -225.839024) (xy 379.977227 -225.794987) (xy 380.013479 -225.755916) (xy 380.05515 -225.722685)
			(xy 380.101308 -225.696036) (xy 380.150922 -225.676564) (xy 380.202884 -225.664704) (xy 380.256034 -225.660721)
			(xy 380.309184 -225.664704) (xy 380.361146 -225.676564) (xy 380.41076 -225.696036) (xy 380.456918 -225.722685)
			(xy 380.498589 -225.755916) (xy 380.534841 -225.794987) (xy 380.564865 -225.839024) (xy 380.587991 -225.887045)
			(xy 380.603701 -225.937975) (xy 380.611644 -225.990679) (xy 380.612142 -226.017328) (xy 380.611644 -226.043977)
			(xy 380.603701 -226.096681) (xy 380.587991 -226.147611) (xy 380.564865 -226.195632) (xy 380.534841 -226.239669)
			(xy 380.498589 -226.27874) (xy 380.456918 -226.311971) (xy 380.41076 -226.33862) (xy 380.361146 -226.358092)
			(xy 380.309184 -226.369952) (xy 380.256034 -226.373936) (xy 380.202884 -226.369952) (xy 380.150922 -226.358092)
			(xy 380.101308 -226.33862) (xy 380.05515 -226.311971) (xy 380.013479 -226.27874) (xy 379.977227 -226.239669)
			(xy 379.947203 -226.195632) (xy 379.924077 -226.147611) (xy 379.908367 -226.096681) (xy 379.900424 -226.043977)
			(xy 379.671844 -226.043977) (xy 379.663901 -226.096681) (xy 379.648191 -226.147611) (xy 379.625065 -226.195632)
			(xy 379.595041 -226.239669) (xy 379.558789 -226.27874) (xy 379.517118 -226.311971) (xy 379.47096 -226.33862)
			(xy 379.421346 -226.358092) (xy 379.369384 -226.369952) (xy 379.316234 -226.373936) (xy 379.263084 -226.369952)
			(xy 379.211122 -226.358092) (xy 379.161508 -226.33862) (xy 379.11535 -226.311971) (xy 379.073679 -226.27874)
			(xy 379.037427 -226.239669) (xy 379.007403 -226.195632) (xy 378.984277 -226.147611) (xy 378.968567 -226.096681)
			(xy 378.960624 -226.043977) (xy 378.732044 -226.043977) (xy 378.724101 -226.096681) (xy 378.708391 -226.147611)
			(xy 378.685265 -226.195632) (xy 378.655241 -226.239669) (xy 378.618989 -226.27874) (xy 378.577318 -226.311971)
			(xy 378.53116 -226.33862) (xy 378.481546 -226.358092) (xy 378.429584 -226.369952) (xy 378.376434 -226.373936)
			(xy 378.323284 -226.369952) (xy 378.271322 -226.358092) (xy 378.221708 -226.33862) (xy 378.17555 -226.311971)
			(xy 378.133879 -226.27874) (xy 378.097627 -226.239669) (xy 378.067603 -226.195632) (xy 378.044477 -226.147611)
			(xy 378.028767 -226.096681) (xy 378.020824 -226.043977) (xy 377.792244 -226.043977) (xy 377.784301 -226.096681)
			(xy 377.768591 -226.147611) (xy 377.745465 -226.195632) (xy 377.715441 -226.239669) (xy 377.679189 -226.27874)
			(xy 377.637518 -226.311971) (xy 377.59136 -226.33862) (xy 377.541746 -226.358092) (xy 377.489784 -226.369952)
			(xy 377.436634 -226.373936) (xy 377.383484 -226.369952) (xy 377.331522 -226.358092) (xy 377.281908 -226.33862)
			(xy 377.23575 -226.311971) (xy 377.194079 -226.27874) (xy 377.157827 -226.239669) (xy 377.127803 -226.195632)
			(xy 377.104677 -226.147611) (xy 377.088967 -226.096681) (xy 377.081024 -226.043977) (xy 376.852444 -226.043977)
			(xy 376.844501 -226.096681) (xy 376.828791 -226.147611) (xy 376.805665 -226.195632) (xy 376.775641 -226.239669)
			(xy 376.739389 -226.27874) (xy 376.697718 -226.311971) (xy 376.65156 -226.33862) (xy 376.601946 -226.358092)
			(xy 376.549984 -226.369952) (xy 376.496834 -226.373936) (xy 376.443684 -226.369952) (xy 376.391722 -226.358092)
			(xy 376.342108 -226.33862) (xy 376.29595 -226.311971) (xy 376.254279 -226.27874) (xy 376.218027 -226.239669)
			(xy 376.188003 -226.195632) (xy 376.164877 -226.147611) (xy 376.149167 -226.096681) (xy 376.141224 -226.043977)
			(xy 375.912644 -226.043977) (xy 375.904701 -226.096681) (xy 375.888991 -226.147611) (xy 375.865865 -226.195632)
			(xy 375.835841 -226.239669) (xy 375.799589 -226.27874) (xy 375.757918 -226.311971) (xy 375.71176 -226.33862)
			(xy 375.662146 -226.358092) (xy 375.610184 -226.369952) (xy 375.557034 -226.373936) (xy 375.503884 -226.369952)
			(xy 375.451922 -226.358092) (xy 375.402308 -226.33862) (xy 375.35615 -226.311971) (xy 375.314479 -226.27874)
			(xy 375.278227 -226.239669) (xy 375.248203 -226.195632) (xy 375.225077 -226.147611) (xy 375.209367 -226.096681)
			(xy 375.201424 -226.043977) (xy 374.972844 -226.043977) (xy 374.964901 -226.096681) (xy 374.949191 -226.147611)
			(xy 374.926065 -226.195632) (xy 374.896041 -226.239669) (xy 374.859789 -226.27874) (xy 374.818118 -226.311971)
			(xy 374.77196 -226.33862) (xy 374.722346 -226.358092) (xy 374.670384 -226.369952) (xy 374.617234 -226.373936)
			(xy 374.564084 -226.369952) (xy 374.512122 -226.358092) (xy 374.462508 -226.33862) (xy 374.41635 -226.311971)
			(xy 374.374679 -226.27874) (xy 374.338427 -226.239669) (xy 374.308403 -226.195632) (xy 374.285277 -226.147611)
			(xy 374.269567 -226.096681) (xy 374.261624 -226.043977) (xy 374.033044 -226.043977) (xy 374.025101 -226.096681)
			(xy 374.009391 -226.147611) (xy 373.986265 -226.195632) (xy 373.956241 -226.239669) (xy 373.919989 -226.27874)
			(xy 373.878318 -226.311971) (xy 373.83216 -226.33862) (xy 373.782546 -226.358092) (xy 373.730584 -226.369952)
			(xy 373.677434 -226.373936) (xy 373.624284 -226.369952) (xy 373.572322 -226.358092) (xy 373.522708 -226.33862)
			(xy 373.47655 -226.311971) (xy 373.434879 -226.27874) (xy 373.398627 -226.239669) (xy 373.368603 -226.195632)
			(xy 373.345477 -226.147611) (xy 373.329767 -226.096681) (xy 373.321824 -226.043977) (xy 373.093244 -226.043977)
			(xy 373.085301 -226.096681) (xy 373.069591 -226.147611) (xy 373.046465 -226.195632) (xy 373.016441 -226.239669)
			(xy 372.980189 -226.27874) (xy 372.938518 -226.311971) (xy 372.89236 -226.33862) (xy 372.842746 -226.358092)
			(xy 372.790784 -226.369952) (xy 372.737634 -226.373936) (xy 372.684484 -226.369952) (xy 372.632522 -226.358092)
			(xy 372.582908 -226.33862) (xy 372.53675 -226.311971) (xy 372.495079 -226.27874) (xy 372.458827 -226.239669)
			(xy 372.428803 -226.195632) (xy 372.405677 -226.147611) (xy 372.389967 -226.096681) (xy 372.382024 -226.043977)
			(xy 372.153444 -226.043977) (xy 372.145501 -226.096681) (xy 372.129791 -226.147611) (xy 372.106665 -226.195632)
			(xy 372.076641 -226.239669) (xy 372.040389 -226.27874) (xy 371.998718 -226.311971) (xy 371.95256 -226.33862)
			(xy 371.902946 -226.358092) (xy 371.850984 -226.369952) (xy 371.797834 -226.373936) (xy 371.744684 -226.369952)
			(xy 371.692722 -226.358092) (xy 371.643108 -226.33862) (xy 371.59695 -226.311971) (xy 371.555279 -226.27874)
			(xy 371.519027 -226.239669) (xy 371.489003 -226.195632) (xy 371.465877 -226.147611) (xy 371.450167 -226.096681)
			(xy 371.442224 -226.043977) (xy 371.213644 -226.043977) (xy 371.205701 -226.096681) (xy 371.189991 -226.147611)
			(xy 371.166865 -226.195632) (xy 371.136841 -226.239669) (xy 371.100589 -226.27874) (xy 371.058918 -226.311971)
			(xy 371.01276 -226.33862) (xy 370.963146 -226.358092) (xy 370.911184 -226.369952) (xy 370.858034 -226.373936)
			(xy 370.804884 -226.369952) (xy 370.752922 -226.358092) (xy 370.703308 -226.33862) (xy 370.65715 -226.311971)
			(xy 370.615479 -226.27874) (xy 370.579227 -226.239669) (xy 370.549203 -226.195632) (xy 370.526077 -226.147611)
			(xy 370.510367 -226.096681) (xy 370.502424 -226.043977) (xy 370.273844 -226.043977) (xy 370.265901 -226.096681)
			(xy 370.250191 -226.147611) (xy 370.227065 -226.195632) (xy 370.197041 -226.239669) (xy 370.160789 -226.27874)
			(xy 370.119118 -226.311971) (xy 370.07296 -226.33862) (xy 370.023346 -226.358092) (xy 369.971384 -226.369952)
			(xy 369.918234 -226.373936) (xy 369.865084 -226.369952) (xy 369.813122 -226.358092) (xy 369.763508 -226.33862)
			(xy 369.71735 -226.311971) (xy 369.675679 -226.27874) (xy 369.639427 -226.239669) (xy 369.609403 -226.195632)
			(xy 369.586277 -226.147611) (xy 369.570567 -226.096681) (xy 369.562624 -226.043977) (xy 369.334044 -226.043977)
			(xy 369.326101 -226.096681) (xy 369.310391 -226.147611) (xy 369.287265 -226.195632) (xy 369.257241 -226.239669)
			(xy 369.220989 -226.27874) (xy 369.179318 -226.311971) (xy 369.13316 -226.33862) (xy 369.083546 -226.358092)
			(xy 369.031584 -226.369952) (xy 368.978434 -226.373936) (xy 368.925284 -226.369952) (xy 368.873322 -226.358092)
			(xy 368.823708 -226.33862) (xy 368.77755 -226.311971) (xy 368.735879 -226.27874) (xy 368.699627 -226.239669)
			(xy 368.669603 -226.195632) (xy 368.646477 -226.147611) (xy 368.630767 -226.096681) (xy 368.622824 -226.043977)
			(xy 368.394244 -226.043977) (xy 368.386301 -226.096681) (xy 368.370591 -226.147611) (xy 368.347465 -226.195632)
			(xy 368.317441 -226.239669) (xy 368.281189 -226.27874) (xy 368.239518 -226.311971) (xy 368.19336 -226.33862)
			(xy 368.143746 -226.358092) (xy 368.091784 -226.369952) (xy 368.038634 -226.373936) (xy 367.985484 -226.369952)
			(xy 367.933522 -226.358092) (xy 367.883908 -226.33862) (xy 367.83775 -226.311971) (xy 367.796079 -226.27874)
			(xy 367.759827 -226.239669) (xy 367.729803 -226.195632) (xy 367.706677 -226.147611) (xy 367.690967 -226.096681)
			(xy 367.683024 -226.043977) (xy 367.454444 -226.043977) (xy 367.446501 -226.096681) (xy 367.430791 -226.147611)
			(xy 367.407665 -226.195632) (xy 367.377641 -226.239669) (xy 367.341389 -226.27874) (xy 367.299718 -226.311971)
			(xy 367.25356 -226.33862) (xy 367.203946 -226.358092) (xy 367.151984 -226.369952) (xy 367.098834 -226.373936)
			(xy 367.045684 -226.369952) (xy 366.993722 -226.358092) (xy 366.944108 -226.33862) (xy 366.89795 -226.311971)
			(xy 366.856279 -226.27874) (xy 366.820027 -226.239669) (xy 366.790003 -226.195632) (xy 366.766877 -226.147611)
			(xy 366.751167 -226.096681) (xy 366.743224 -226.043977) (xy 366.514644 -226.043977) (xy 366.506701 -226.096681)
			(xy 366.490991 -226.147611) (xy 366.467865 -226.195632) (xy 366.437841 -226.239669) (xy 366.401589 -226.27874)
			(xy 366.359918 -226.311971) (xy 366.31376 -226.33862) (xy 366.264146 -226.358092) (xy 366.212184 -226.369952)
			(xy 366.159034 -226.373936) (xy 366.105884 -226.369952) (xy 366.053922 -226.358092) (xy 366.004308 -226.33862)
			(xy 365.95815 -226.311971) (xy 365.916479 -226.27874) (xy 365.880227 -226.239669) (xy 365.850203 -226.195632)
			(xy 365.827077 -226.147611) (xy 365.811367 -226.096681) (xy 365.803424 -226.043977) (xy 365.574844 -226.043977)
			(xy 365.566901 -226.096681) (xy 365.551191 -226.147611) (xy 365.528065 -226.195632) (xy 365.498041 -226.239669)
			(xy 365.461789 -226.27874) (xy 365.420118 -226.311971) (xy 365.37396 -226.33862) (xy 365.324346 -226.358092)
			(xy 365.272384 -226.369952) (xy 365.219234 -226.373936) (xy 365.166084 -226.369952) (xy 365.114122 -226.358092)
			(xy 365.064508 -226.33862) (xy 365.01835 -226.311971) (xy 364.976679 -226.27874) (xy 364.940427 -226.239669)
			(xy 364.910403 -226.195632) (xy 364.887277 -226.147611) (xy 364.871567 -226.096681) (xy 364.863624 -226.043977)
			(xy 364.635044 -226.043977) (xy 364.627101 -226.096681) (xy 364.611391 -226.147611) (xy 364.588265 -226.195632)
			(xy 364.558241 -226.239669) (xy 364.521989 -226.27874) (xy 364.480318 -226.311971) (xy 364.43416 -226.33862)
			(xy 364.384546 -226.358092) (xy 364.332584 -226.369952) (xy 364.279434 -226.373936) (xy 364.226284 -226.369952)
			(xy 364.174322 -226.358092) (xy 364.124708 -226.33862) (xy 364.07855 -226.311971) (xy 364.036879 -226.27874)
			(xy 364.000627 -226.239669) (xy 363.970603 -226.195632) (xy 363.947477 -226.147611) (xy 363.931767 -226.096681)
			(xy 363.923824 -226.043977) (xy 363.695244 -226.043977) (xy 363.687301 -226.096681) (xy 363.671591 -226.147611)
			(xy 363.648465 -226.195632) (xy 363.618441 -226.239669) (xy 363.582189 -226.27874) (xy 363.540518 -226.311971)
			(xy 363.49436 -226.33862) (xy 363.444746 -226.358092) (xy 363.392784 -226.369952) (xy 363.339634 -226.373936)
			(xy 363.286484 -226.369952) (xy 363.234522 -226.358092) (xy 363.184908 -226.33862) (xy 363.13875 -226.311971)
			(xy 363.097079 -226.27874) (xy 363.060827 -226.239669) (xy 363.030803 -226.195632) (xy 363.007677 -226.147611)
			(xy 362.991967 -226.096681) (xy 362.984024 -226.043977) (xy 362.755444 -226.043977) (xy 362.747501 -226.096681)
			(xy 362.731791 -226.147611) (xy 362.708665 -226.195632) (xy 362.678641 -226.239669) (xy 362.642389 -226.27874)
			(xy 362.600718 -226.311971) (xy 362.55456 -226.33862) (xy 362.504946 -226.358092) (xy 362.452984 -226.369952)
			(xy 362.399834 -226.373936) (xy 362.346684 -226.369952) (xy 362.294722 -226.358092) (xy 362.245108 -226.33862)
			(xy 362.19895 -226.311971) (xy 362.157279 -226.27874) (xy 362.121027 -226.239669) (xy 362.091003 -226.195632)
			(xy 362.067877 -226.147611) (xy 362.052167 -226.096681) (xy 362.044224 -226.043977) (xy 361.815644 -226.043977)
			(xy 361.807701 -226.096681) (xy 361.791991 -226.147611) (xy 361.768865 -226.195632) (xy 361.738841 -226.239669)
			(xy 361.702589 -226.27874) (xy 361.660918 -226.311971) (xy 361.61476 -226.33862) (xy 361.565146 -226.358092)
			(xy 361.513184 -226.369952) (xy 361.460034 -226.373936) (xy 361.406884 -226.369952) (xy 361.354922 -226.358092)
			(xy 361.305308 -226.33862) (xy 361.25915 -226.311971) (xy 361.217479 -226.27874) (xy 361.181227 -226.239669)
			(xy 361.151203 -226.195632) (xy 361.128077 -226.147611) (xy 361.112367 -226.096681) (xy 361.104424 -226.043977)
			(xy 360.875844 -226.043977) (xy 360.867901 -226.096681) (xy 360.852191 -226.147611) (xy 360.829065 -226.195632)
			(xy 360.799041 -226.239669) (xy 360.762789 -226.27874) (xy 360.721118 -226.311971) (xy 360.67496 -226.33862)
			(xy 360.625346 -226.358092) (xy 360.573384 -226.369952) (xy 360.520234 -226.373936) (xy 360.467084 -226.369952)
			(xy 360.415122 -226.358092) (xy 360.365508 -226.33862) (xy 360.31935 -226.311971) (xy 360.277679 -226.27874)
			(xy 360.241427 -226.239669) (xy 360.211403 -226.195632) (xy 360.188277 -226.147611) (xy 360.172567 -226.096681)
			(xy 360.164624 -226.043977) (xy 359.936055 -226.043977) (xy 359.936052 -226.04416) (xy 359.928013 -226.097217)
			(xy 359.92054 -226.122992) (xy 359.918254 -226.130358) (xy 359.918254 -226.374452) (xy 359.918676 -226.388353)
			(xy 359.926166 -226.415127) (xy 359.940602 -226.438887) (xy 359.960915 -226.457869) (xy 359.985596 -226.470666)
			(xy 360.012815 -226.476329) (xy 360.026712 -226.475798) (xy 360.050334 -226.475036) (xy 360.076978 -226.475536)
			(xy 360.129671 -226.483483) (xy 360.180591 -226.499194) (xy 360.228601 -226.522319) (xy 360.272629 -226.55234)
			(xy 360.31169 -226.588587) (xy 360.344913 -226.630252) (xy 360.371556 -226.676402) (xy 360.391024 -226.726007)
			(xy 360.402881 -226.77796) (xy 360.406863 -226.8311) (xy 360.404863 -226.857793) (xy 360.63427 -226.857793)
			(xy 360.63427 -226.804495) (xy 360.642213 -226.751791) (xy 360.657923 -226.700861) (xy 360.681049 -226.65284)
			(xy 360.711073 -226.608803) (xy 360.747325 -226.569732) (xy 360.788996 -226.536501) (xy 360.835154 -226.509852)
			(xy 360.884768 -226.49038) (xy 360.93673 -226.47852) (xy 360.98988 -226.474537) (xy 361.04303 -226.47852)
			(xy 361.094992 -226.49038) (xy 361.144606 -226.509852) (xy 361.190764 -226.536501) (xy 361.232435 -226.569732)
			(xy 361.268687 -226.608803) (xy 361.298711 -226.65284) (xy 361.321837 -226.700861) (xy 361.337547 -226.751791)
			(xy 361.34549 -226.804495) (xy 361.345988 -226.831144) (xy 361.34549 -226.857793) (xy 361.574324 -226.857793)
			(xy 361.574324 -226.804495) (xy 361.582267 -226.751791) (xy 361.597977 -226.700861) (xy 361.621103 -226.65284)
			(xy 361.651127 -226.608803) (xy 361.687379 -226.569732) (xy 361.72905 -226.536501) (xy 361.775208 -226.509852)
			(xy 361.824822 -226.49038) (xy 361.876784 -226.47852) (xy 361.929934 -226.474537) (xy 361.983084 -226.47852)
			(xy 362.035046 -226.49038) (xy 362.08466 -226.509852) (xy 362.130818 -226.536501) (xy 362.172489 -226.569732)
			(xy 362.208741 -226.608803) (xy 362.238765 -226.65284) (xy 362.261891 -226.700861) (xy 362.277601 -226.751791)
			(xy 362.285544 -226.804495) (xy 362.286042 -226.831144) (xy 362.285544 -226.857793) (xy 362.514124 -226.857793)
			(xy 362.514124 -226.804495) (xy 362.522067 -226.751791) (xy 362.537777 -226.700861) (xy 362.560903 -226.65284)
			(xy 362.590927 -226.608803) (xy 362.627179 -226.569732) (xy 362.66885 -226.536501) (xy 362.715008 -226.509852)
			(xy 362.764622 -226.49038) (xy 362.816584 -226.47852) (xy 362.869734 -226.474537) (xy 362.922884 -226.47852)
			(xy 362.974846 -226.49038) (xy 363.02446 -226.509852) (xy 363.070618 -226.536501) (xy 363.112289 -226.569732)
			(xy 363.148541 -226.608803) (xy 363.178565 -226.65284) (xy 363.201691 -226.700861) (xy 363.217401 -226.751791)
			(xy 363.225344 -226.804495) (xy 363.225842 -226.831144) (xy 363.225344 -226.857793) (xy 363.453924 -226.857793)
			(xy 363.453924 -226.804495) (xy 363.461867 -226.751791) (xy 363.477577 -226.700861) (xy 363.500703 -226.65284)
			(xy 363.530727 -226.608803) (xy 363.566979 -226.569732) (xy 363.60865 -226.536501) (xy 363.654808 -226.509852)
			(xy 363.704422 -226.49038) (xy 363.756384 -226.47852) (xy 363.809534 -226.474537) (xy 363.862684 -226.47852)
			(xy 363.914646 -226.49038) (xy 363.96426 -226.509852) (xy 364.010418 -226.536501) (xy 364.052089 -226.569732)
			(xy 364.088341 -226.608803) (xy 364.118365 -226.65284) (xy 364.141491 -226.700861) (xy 364.157201 -226.751791)
			(xy 364.165144 -226.804495) (xy 364.165642 -226.831144) (xy 364.165144 -226.857793) (xy 364.39347 -226.857793)
			(xy 364.39347 -226.804495) (xy 364.401413 -226.751791) (xy 364.417123 -226.700861) (xy 364.440249 -226.65284)
			(xy 364.470273 -226.608803) (xy 364.506525 -226.569732) (xy 364.548196 -226.536501) (xy 364.594354 -226.509852)
			(xy 364.643968 -226.49038) (xy 364.69593 -226.47852) (xy 364.74908 -226.474537) (xy 364.80223 -226.47852)
			(xy 364.854192 -226.49038) (xy 364.903806 -226.509852) (xy 364.949964 -226.536501) (xy 364.991635 -226.569732)
			(xy 365.027887 -226.608803) (xy 365.057911 -226.65284) (xy 365.081037 -226.700861) (xy 365.096747 -226.751791)
			(xy 365.10469 -226.804495) (xy 365.105188 -226.831144) (xy 365.10469 -226.857793) (xy 365.333524 -226.857793)
			(xy 365.333524 -226.804495) (xy 365.341467 -226.751791) (xy 365.357177 -226.700861) (xy 365.380303 -226.65284)
			(xy 365.410327 -226.608803) (xy 365.446579 -226.569732) (xy 365.48825 -226.536501) (xy 365.534408 -226.509852)
			(xy 365.584022 -226.49038) (xy 365.635984 -226.47852) (xy 365.689134 -226.474537) (xy 365.742284 -226.47852)
			(xy 365.794246 -226.49038) (xy 365.84386 -226.509852) (xy 365.890018 -226.536501) (xy 365.931689 -226.569732)
			(xy 365.967941 -226.608803) (xy 365.997965 -226.65284) (xy 366.021091 -226.700861) (xy 366.036801 -226.751791)
			(xy 366.044744 -226.804495) (xy 366.045242 -226.831144) (xy 366.044744 -226.857793) (xy 366.27307 -226.857793)
			(xy 366.27307 -226.804495) (xy 366.281013 -226.751791) (xy 366.296723 -226.700861) (xy 366.319849 -226.65284)
			(xy 366.349873 -226.608803) (xy 366.386125 -226.569732) (xy 366.427796 -226.536501) (xy 366.473954 -226.509852)
			(xy 366.523568 -226.49038) (xy 366.57553 -226.47852) (xy 366.62868 -226.474537) (xy 366.68183 -226.47852)
			(xy 366.733792 -226.49038) (xy 366.783406 -226.509852) (xy 366.829564 -226.536501) (xy 366.871235 -226.569732)
			(xy 366.907487 -226.608803) (xy 366.937511 -226.65284) (xy 366.960637 -226.700861) (xy 366.976347 -226.751791)
			(xy 366.98429 -226.804495) (xy 366.984788 -226.831144) (xy 366.98429 -226.857793) (xy 367.213124 -226.857793)
			(xy 367.213124 -226.804495) (xy 367.221067 -226.751791) (xy 367.236777 -226.700861) (xy 367.259903 -226.65284)
			(xy 367.289927 -226.608803) (xy 367.326179 -226.569732) (xy 367.36785 -226.536501) (xy 367.414008 -226.509852)
			(xy 367.463622 -226.49038) (xy 367.515584 -226.47852) (xy 367.568734 -226.474537) (xy 367.621884 -226.47852)
			(xy 367.673846 -226.49038) (xy 367.72346 -226.509852) (xy 367.769618 -226.536501) (xy 367.811289 -226.569732)
			(xy 367.847541 -226.608803) (xy 367.877565 -226.65284) (xy 367.900691 -226.700861) (xy 367.916401 -226.751791)
			(xy 367.924344 -226.804495) (xy 367.924842 -226.831144) (xy 367.924344 -226.857793) (xy 368.15267 -226.857793)
			(xy 368.15267 -226.804495) (xy 368.160613 -226.751791) (xy 368.176323 -226.700861) (xy 368.199449 -226.65284)
			(xy 368.229473 -226.608803) (xy 368.265725 -226.569732) (xy 368.307396 -226.536501) (xy 368.353554 -226.509852)
			(xy 368.403168 -226.49038) (xy 368.45513 -226.47852) (xy 368.50828 -226.474537) (xy 368.56143 -226.47852)
			(xy 368.613392 -226.49038) (xy 368.663006 -226.509852) (xy 368.709164 -226.536501) (xy 368.750835 -226.569732)
			(xy 368.787087 -226.608803) (xy 368.817111 -226.65284) (xy 368.840237 -226.700861) (xy 368.855947 -226.751791)
			(xy 368.86389 -226.804495) (xy 368.864388 -226.831144) (xy 368.86389 -226.857793) (xy 369.092724 -226.857793)
			(xy 369.092724 -226.804495) (xy 369.100667 -226.751791) (xy 369.116377 -226.700861) (xy 369.139503 -226.65284)
			(xy 369.169527 -226.608803) (xy 369.205779 -226.569732) (xy 369.24745 -226.536501) (xy 369.293608 -226.509852)
			(xy 369.343222 -226.49038) (xy 369.395184 -226.47852) (xy 369.448334 -226.474537) (xy 369.501484 -226.47852)
			(xy 369.553446 -226.49038) (xy 369.60306 -226.509852) (xy 369.649218 -226.536501) (xy 369.690889 -226.569732)
			(xy 369.727141 -226.608803) (xy 369.757165 -226.65284) (xy 369.780291 -226.700861) (xy 369.796001 -226.751791)
			(xy 369.803944 -226.804495) (xy 369.804442 -226.831144) (xy 369.803944 -226.857793) (xy 370.03227 -226.857793)
			(xy 370.03227 -226.804495) (xy 370.040213 -226.751791) (xy 370.055923 -226.700861) (xy 370.079049 -226.65284)
			(xy 370.109073 -226.608803) (xy 370.145325 -226.569732) (xy 370.186996 -226.536501) (xy 370.233154 -226.509852)
			(xy 370.282768 -226.49038) (xy 370.33473 -226.47852) (xy 370.38788 -226.474537) (xy 370.44103 -226.47852)
			(xy 370.492992 -226.49038) (xy 370.542606 -226.509852) (xy 370.588764 -226.536501) (xy 370.630435 -226.569732)
			(xy 370.666687 -226.608803) (xy 370.696711 -226.65284) (xy 370.719837 -226.700861) (xy 370.735547 -226.751791)
			(xy 370.74349 -226.804495) (xy 370.743988 -226.831144) (xy 370.74349 -226.857793) (xy 370.97207 -226.857793)
			(xy 370.97207 -226.804495) (xy 370.980013 -226.751791) (xy 370.995723 -226.700861) (xy 371.018849 -226.65284)
			(xy 371.048873 -226.608803) (xy 371.085125 -226.569732) (xy 371.126796 -226.536501) (xy 371.172954 -226.509852)
			(xy 371.222568 -226.49038) (xy 371.27453 -226.47852) (xy 371.32768 -226.474537) (xy 371.38083 -226.47852)
			(xy 371.432792 -226.49038) (xy 371.482406 -226.509852) (xy 371.528564 -226.536501) (xy 371.570235 -226.569732)
			(xy 371.606487 -226.608803) (xy 371.636511 -226.65284) (xy 371.659637 -226.700861) (xy 371.675347 -226.751791)
			(xy 371.68329 -226.804495) (xy 371.683788 -226.831144) (xy 371.68329 -226.857793) (xy 371.912124 -226.857793)
			(xy 371.912124 -226.804495) (xy 371.920067 -226.751791) (xy 371.935777 -226.700861) (xy 371.958903 -226.65284)
			(xy 371.988927 -226.608803) (xy 372.025179 -226.569732) (xy 372.06685 -226.536501) (xy 372.113008 -226.509852)
			(xy 372.162622 -226.49038) (xy 372.214584 -226.47852) (xy 372.267734 -226.474537) (xy 372.320884 -226.47852)
			(xy 372.372846 -226.49038) (xy 372.42246 -226.509852) (xy 372.468618 -226.536501) (xy 372.510289 -226.569732)
			(xy 372.546541 -226.608803) (xy 372.576565 -226.65284) (xy 372.599691 -226.700861) (xy 372.615401 -226.751791)
			(xy 372.623344 -226.804495) (xy 372.623842 -226.831144) (xy 372.623344 -226.857793) (xy 372.85167 -226.857793)
			(xy 372.85167 -226.804495) (xy 372.859613 -226.751791) (xy 372.875323 -226.700861) (xy 372.898449 -226.65284)
			(xy 372.928473 -226.608803) (xy 372.964725 -226.569732) (xy 373.006396 -226.536501) (xy 373.052554 -226.509852)
			(xy 373.102168 -226.49038) (xy 373.15413 -226.47852) (xy 373.20728 -226.474537) (xy 373.26043 -226.47852)
			(xy 373.312392 -226.49038) (xy 373.362006 -226.509852) (xy 373.408164 -226.536501) (xy 373.449835 -226.569732)
			(xy 373.486087 -226.608803) (xy 373.516111 -226.65284) (xy 373.539237 -226.700861) (xy 373.554947 -226.751791)
			(xy 373.56289 -226.804495) (xy 373.563388 -226.831144) (xy 373.56289 -226.857793) (xy 373.79147 -226.857793)
			(xy 373.79147 -226.804495) (xy 373.799413 -226.751791) (xy 373.815123 -226.700861) (xy 373.838249 -226.65284)
			(xy 373.868273 -226.608803) (xy 373.904525 -226.569732) (xy 373.946196 -226.536501) (xy 373.992354 -226.509852)
			(xy 374.041968 -226.49038) (xy 374.09393 -226.47852) (xy 374.14708 -226.474537) (xy 374.20023 -226.47852)
			(xy 374.252192 -226.49038) (xy 374.301806 -226.509852) (xy 374.347964 -226.536501) (xy 374.389635 -226.569732)
			(xy 374.425887 -226.608803) (xy 374.455911 -226.65284) (xy 374.479037 -226.700861) (xy 374.494747 -226.751791)
			(xy 374.50269 -226.804495) (xy 374.503188 -226.831144) (xy 374.50269 -226.857793) (xy 374.731524 -226.857793)
			(xy 374.731524 -226.804495) (xy 374.739467 -226.751791) (xy 374.755177 -226.700861) (xy 374.778303 -226.65284)
			(xy 374.808327 -226.608803) (xy 374.844579 -226.569732) (xy 374.88625 -226.536501) (xy 374.932408 -226.509852)
			(xy 374.982022 -226.49038) (xy 375.033984 -226.47852) (xy 375.087134 -226.474537) (xy 375.140284 -226.47852)
			(xy 375.192246 -226.49038) (xy 375.24186 -226.509852) (xy 375.288018 -226.536501) (xy 375.329689 -226.569732)
			(xy 375.365941 -226.608803) (xy 375.395965 -226.65284) (xy 375.419091 -226.700861) (xy 375.434801 -226.751791)
			(xy 375.442744 -226.804495) (xy 375.443242 -226.831144) (xy 375.442744 -226.857793) (xy 375.671324 -226.857793)
			(xy 375.671324 -226.804495) (xy 375.679267 -226.751791) (xy 375.694977 -226.700861) (xy 375.718103 -226.65284)
			(xy 375.748127 -226.608803) (xy 375.784379 -226.569732) (xy 375.82605 -226.536501) (xy 375.872208 -226.509852)
			(xy 375.921822 -226.49038) (xy 375.973784 -226.47852) (xy 376.026934 -226.474537) (xy 376.080084 -226.47852)
			(xy 376.132046 -226.49038) (xy 376.18166 -226.509852) (xy 376.227818 -226.536501) (xy 376.269489 -226.569732)
			(xy 376.305741 -226.608803) (xy 376.335765 -226.65284) (xy 376.358891 -226.700861) (xy 376.374601 -226.751791)
			(xy 376.382544 -226.804495) (xy 376.383042 -226.831144) (xy 376.382544 -226.857793) (xy 376.61087 -226.857793)
			(xy 376.61087 -226.804495) (xy 376.618813 -226.751791) (xy 376.634523 -226.700861) (xy 376.657649 -226.65284)
			(xy 376.687673 -226.608803) (xy 376.723925 -226.569732) (xy 376.765596 -226.536501) (xy 376.811754 -226.509852)
			(xy 376.861368 -226.49038) (xy 376.91333 -226.47852) (xy 376.96648 -226.474537) (xy 377.01963 -226.47852)
			(xy 377.071592 -226.49038) (xy 377.121206 -226.509852) (xy 377.167364 -226.536501) (xy 377.209035 -226.569732)
			(xy 377.245287 -226.608803) (xy 377.275311 -226.65284) (xy 377.298437 -226.700861) (xy 377.314147 -226.751791)
			(xy 377.32209 -226.804495) (xy 377.322588 -226.831144) (xy 377.32209 -226.857793) (xy 377.55067 -226.857793)
			(xy 377.55067 -226.804495) (xy 377.558613 -226.751791) (xy 377.574323 -226.700861) (xy 377.597449 -226.65284)
			(xy 377.627473 -226.608803) (xy 377.663725 -226.569732) (xy 377.705396 -226.536501) (xy 377.751554 -226.509852)
			(xy 377.801168 -226.49038) (xy 377.85313 -226.47852) (xy 377.90628 -226.474537) (xy 377.95943 -226.47852)
			(xy 378.011392 -226.49038) (xy 378.061006 -226.509852) (xy 378.107164 -226.536501) (xy 378.148835 -226.569732)
			(xy 378.185087 -226.608803) (xy 378.215111 -226.65284) (xy 378.238237 -226.700861) (xy 378.253947 -226.751791)
			(xy 378.26189 -226.804495) (xy 378.262388 -226.831144) (xy 378.26189 -226.857793) (xy 378.490724 -226.857793)
			(xy 378.490724 -226.804495) (xy 378.498667 -226.751791) (xy 378.514377 -226.700861) (xy 378.537503 -226.65284)
			(xy 378.567527 -226.608803) (xy 378.603779 -226.569732) (xy 378.64545 -226.536501) (xy 378.691608 -226.509852)
			(xy 378.741222 -226.49038) (xy 378.793184 -226.47852) (xy 378.846334 -226.474537) (xy 378.899484 -226.47852)
			(xy 378.951446 -226.49038) (xy 379.00106 -226.509852) (xy 379.047218 -226.536501) (xy 379.088889 -226.569732)
			(xy 379.125141 -226.608803) (xy 379.155165 -226.65284) (xy 379.178291 -226.700861) (xy 379.194001 -226.751791)
			(xy 379.201944 -226.804495) (xy 379.202442 -226.831144) (xy 379.201944 -226.857793) (xy 379.43027 -226.857793)
			(xy 379.43027 -226.804495) (xy 379.438213 -226.751791) (xy 379.453923 -226.700861) (xy 379.477049 -226.65284)
			(xy 379.507073 -226.608803) (xy 379.543325 -226.569732) (xy 379.584996 -226.536501) (xy 379.631154 -226.509852)
			(xy 379.680768 -226.49038) (xy 379.73273 -226.47852) (xy 379.78588 -226.474537) (xy 379.83903 -226.47852)
			(xy 379.890992 -226.49038) (xy 379.940606 -226.509852) (xy 379.986764 -226.536501) (xy 380.028435 -226.569732)
			(xy 380.064687 -226.608803) (xy 380.094711 -226.65284) (xy 380.117837 -226.700861) (xy 380.133547 -226.751791)
			(xy 380.14149 -226.804495) (xy 380.141988 -226.831144) (xy 380.14149 -226.857793) (xy 380.133547 -226.910497)
			(xy 380.117837 -226.961427) (xy 380.094711 -227.009448) (xy 380.064687 -227.053485) (xy 380.028435 -227.092556)
			(xy 379.986764 -227.125787) (xy 379.940606 -227.152436) (xy 379.890992 -227.171908) (xy 379.83903 -227.183768)
			(xy 379.78588 -227.187752) (xy 379.73273 -227.183768) (xy 379.680768 -227.171908) (xy 379.631154 -227.152436)
			(xy 379.584996 -227.125787) (xy 379.543325 -227.092556) (xy 379.507073 -227.053485) (xy 379.477049 -227.009448)
			(xy 379.453923 -226.961427) (xy 379.438213 -226.910497) (xy 379.43027 -226.857793) (xy 379.201944 -226.857793)
			(xy 379.194001 -226.910497) (xy 379.178291 -226.961427) (xy 379.155165 -227.009448) (xy 379.125141 -227.053485)
			(xy 379.088889 -227.092556) (xy 379.047218 -227.125787) (xy 379.00106 -227.152436) (xy 378.951446 -227.171908)
			(xy 378.899484 -227.183768) (xy 378.846334 -227.187752) (xy 378.793184 -227.183768) (xy 378.741222 -227.171908)
			(xy 378.691608 -227.152436) (xy 378.64545 -227.125787) (xy 378.603779 -227.092556) (xy 378.567527 -227.053485)
			(xy 378.537503 -227.009448) (xy 378.514377 -226.961427) (xy 378.498667 -226.910497) (xy 378.490724 -226.857793)
			(xy 378.26189 -226.857793) (xy 378.253947 -226.910497) (xy 378.238237 -226.961427) (xy 378.215111 -227.009448)
			(xy 378.185087 -227.053485) (xy 378.148835 -227.092556) (xy 378.107164 -227.125787) (xy 378.061006 -227.152436)
			(xy 378.011392 -227.171908) (xy 377.95943 -227.183768) (xy 377.90628 -227.187752) (xy 377.85313 -227.183768)
			(xy 377.801168 -227.171908) (xy 377.751554 -227.152436) (xy 377.705396 -227.125787) (xy 377.663725 -227.092556)
			(xy 377.627473 -227.053485) (xy 377.597449 -227.009448) (xy 377.574323 -226.961427) (xy 377.558613 -226.910497)
			(xy 377.55067 -226.857793) (xy 377.32209 -226.857793) (xy 377.314147 -226.910497) (xy 377.298437 -226.961427)
			(xy 377.275311 -227.009448) (xy 377.245287 -227.053485) (xy 377.209035 -227.092556) (xy 377.167364 -227.125787)
			(xy 377.121206 -227.152436) (xy 377.071592 -227.171908) (xy 377.01963 -227.183768) (xy 376.96648 -227.187752)
			(xy 376.91333 -227.183768) (xy 376.861368 -227.171908) (xy 376.811754 -227.152436) (xy 376.765596 -227.125787)
			(xy 376.723925 -227.092556) (xy 376.687673 -227.053485) (xy 376.657649 -227.009448) (xy 376.634523 -226.961427)
			(xy 376.618813 -226.910497) (xy 376.61087 -226.857793) (xy 376.382544 -226.857793) (xy 376.374601 -226.910497)
			(xy 376.358891 -226.961427) (xy 376.335765 -227.009448) (xy 376.305741 -227.053485) (xy 376.269489 -227.092556)
			(xy 376.227818 -227.125787) (xy 376.18166 -227.152436) (xy 376.132046 -227.171908) (xy 376.080084 -227.183768)
			(xy 376.026934 -227.187752) (xy 375.973784 -227.183768) (xy 375.921822 -227.171908) (xy 375.872208 -227.152436)
			(xy 375.82605 -227.125787) (xy 375.784379 -227.092556) (xy 375.748127 -227.053485) (xy 375.718103 -227.009448)
			(xy 375.694977 -226.961427) (xy 375.679267 -226.910497) (xy 375.671324 -226.857793) (xy 375.442744 -226.857793)
			(xy 375.434801 -226.910497) (xy 375.419091 -226.961427) (xy 375.395965 -227.009448) (xy 375.365941 -227.053485)
			(xy 375.329689 -227.092556) (xy 375.288018 -227.125787) (xy 375.24186 -227.152436) (xy 375.192246 -227.171908)
			(xy 375.140284 -227.183768) (xy 375.087134 -227.187752) (xy 375.033984 -227.183768) (xy 374.982022 -227.171908)
			(xy 374.932408 -227.152436) (xy 374.88625 -227.125787) (xy 374.844579 -227.092556) (xy 374.808327 -227.053485)
			(xy 374.778303 -227.009448) (xy 374.755177 -226.961427) (xy 374.739467 -226.910497) (xy 374.731524 -226.857793)
			(xy 374.50269 -226.857793) (xy 374.494747 -226.910497) (xy 374.479037 -226.961427) (xy 374.455911 -227.009448)
			(xy 374.425887 -227.053485) (xy 374.389635 -227.092556) (xy 374.347964 -227.125787) (xy 374.301806 -227.152436)
			(xy 374.252192 -227.171908) (xy 374.20023 -227.183768) (xy 374.14708 -227.187752) (xy 374.09393 -227.183768)
			(xy 374.041968 -227.171908) (xy 373.992354 -227.152436) (xy 373.946196 -227.125787) (xy 373.904525 -227.092556)
			(xy 373.868273 -227.053485) (xy 373.838249 -227.009448) (xy 373.815123 -226.961427) (xy 373.799413 -226.910497)
			(xy 373.79147 -226.857793) (xy 373.56289 -226.857793) (xy 373.554947 -226.910497) (xy 373.539237 -226.961427)
			(xy 373.516111 -227.009448) (xy 373.486087 -227.053485) (xy 373.449835 -227.092556) (xy 373.408164 -227.125787)
			(xy 373.362006 -227.152436) (xy 373.312392 -227.171908) (xy 373.26043 -227.183768) (xy 373.20728 -227.187752)
			(xy 373.15413 -227.183768) (xy 373.102168 -227.171908) (xy 373.052554 -227.152436) (xy 373.006396 -227.125787)
			(xy 372.964725 -227.092556) (xy 372.928473 -227.053485) (xy 372.898449 -227.009448) (xy 372.875323 -226.961427)
			(xy 372.859613 -226.910497) (xy 372.85167 -226.857793) (xy 372.623344 -226.857793) (xy 372.615401 -226.910497)
			(xy 372.599691 -226.961427) (xy 372.576565 -227.009448) (xy 372.546541 -227.053485) (xy 372.510289 -227.092556)
			(xy 372.468618 -227.125787) (xy 372.42246 -227.152436) (xy 372.372846 -227.171908) (xy 372.320884 -227.183768)
			(xy 372.267734 -227.187752) (xy 372.214584 -227.183768) (xy 372.162622 -227.171908) (xy 372.113008 -227.152436)
			(xy 372.06685 -227.125787) (xy 372.025179 -227.092556) (xy 371.988927 -227.053485) (xy 371.958903 -227.009448)
			(xy 371.935777 -226.961427) (xy 371.920067 -226.910497) (xy 371.912124 -226.857793) (xy 371.68329 -226.857793)
			(xy 371.675347 -226.910497) (xy 371.659637 -226.961427) (xy 371.636511 -227.009448) (xy 371.606487 -227.053485)
			(xy 371.570235 -227.092556) (xy 371.528564 -227.125787) (xy 371.482406 -227.152436) (xy 371.432792 -227.171908)
			(xy 371.38083 -227.183768) (xy 371.32768 -227.187752) (xy 371.27453 -227.183768) (xy 371.222568 -227.171908)
			(xy 371.172954 -227.152436) (xy 371.126796 -227.125787) (xy 371.085125 -227.092556) (xy 371.048873 -227.053485)
			(xy 371.018849 -227.009448) (xy 370.995723 -226.961427) (xy 370.980013 -226.910497) (xy 370.97207 -226.857793)
			(xy 370.74349 -226.857793) (xy 370.735547 -226.910497) (xy 370.719837 -226.961427) (xy 370.696711 -227.009448)
			(xy 370.666687 -227.053485) (xy 370.630435 -227.092556) (xy 370.588764 -227.125787) (xy 370.542606 -227.152436)
			(xy 370.492992 -227.171908) (xy 370.44103 -227.183768) (xy 370.38788 -227.187752) (xy 370.33473 -227.183768)
			(xy 370.282768 -227.171908) (xy 370.233154 -227.152436) (xy 370.186996 -227.125787) (xy 370.145325 -227.092556)
			(xy 370.109073 -227.053485) (xy 370.079049 -227.009448) (xy 370.055923 -226.961427) (xy 370.040213 -226.910497)
			(xy 370.03227 -226.857793) (xy 369.803944 -226.857793) (xy 369.796001 -226.910497) (xy 369.780291 -226.961427)
			(xy 369.757165 -227.009448) (xy 369.727141 -227.053485) (xy 369.690889 -227.092556) (xy 369.649218 -227.125787)
			(xy 369.60306 -227.152436) (xy 369.553446 -227.171908) (xy 369.501484 -227.183768) (xy 369.448334 -227.187752)
			(xy 369.395184 -227.183768) (xy 369.343222 -227.171908) (xy 369.293608 -227.152436) (xy 369.24745 -227.125787)
			(xy 369.205779 -227.092556) (xy 369.169527 -227.053485) (xy 369.139503 -227.009448) (xy 369.116377 -226.961427)
			(xy 369.100667 -226.910497) (xy 369.092724 -226.857793) (xy 368.86389 -226.857793) (xy 368.855947 -226.910497)
			(xy 368.840237 -226.961427) (xy 368.817111 -227.009448) (xy 368.787087 -227.053485) (xy 368.750835 -227.092556)
			(xy 368.709164 -227.125787) (xy 368.663006 -227.152436) (xy 368.613392 -227.171908) (xy 368.56143 -227.183768)
			(xy 368.50828 -227.187752) (xy 368.45513 -227.183768) (xy 368.403168 -227.171908) (xy 368.353554 -227.152436)
			(xy 368.307396 -227.125787) (xy 368.265725 -227.092556) (xy 368.229473 -227.053485) (xy 368.199449 -227.009448)
			(xy 368.176323 -226.961427) (xy 368.160613 -226.910497) (xy 368.15267 -226.857793) (xy 367.924344 -226.857793)
			(xy 367.916401 -226.910497) (xy 367.900691 -226.961427) (xy 367.877565 -227.009448) (xy 367.847541 -227.053485)
			(xy 367.811289 -227.092556) (xy 367.769618 -227.125787) (xy 367.72346 -227.152436) (xy 367.673846 -227.171908)
			(xy 367.621884 -227.183768) (xy 367.568734 -227.187752) (xy 367.515584 -227.183768) (xy 367.463622 -227.171908)
			(xy 367.414008 -227.152436) (xy 367.36785 -227.125787) (xy 367.326179 -227.092556) (xy 367.289927 -227.053485)
			(xy 367.259903 -227.009448) (xy 367.236777 -226.961427) (xy 367.221067 -226.910497) (xy 367.213124 -226.857793)
			(xy 366.98429 -226.857793) (xy 366.976347 -226.910497) (xy 366.960637 -226.961427) (xy 366.937511 -227.009448)
			(xy 366.907487 -227.053485) (xy 366.871235 -227.092556) (xy 366.829564 -227.125787) (xy 366.783406 -227.152436)
			(xy 366.733792 -227.171908) (xy 366.68183 -227.183768) (xy 366.62868 -227.187752) (xy 366.57553 -227.183768)
			(xy 366.523568 -227.171908) (xy 366.473954 -227.152436) (xy 366.427796 -227.125787) (xy 366.386125 -227.092556)
			(xy 366.349873 -227.053485) (xy 366.319849 -227.009448) (xy 366.296723 -226.961427) (xy 366.281013 -226.910497)
			(xy 366.27307 -226.857793) (xy 366.044744 -226.857793) (xy 366.036801 -226.910497) (xy 366.021091 -226.961427)
			(xy 365.997965 -227.009448) (xy 365.967941 -227.053485) (xy 365.931689 -227.092556) (xy 365.890018 -227.125787)
			(xy 365.84386 -227.152436) (xy 365.794246 -227.171908) (xy 365.742284 -227.183768) (xy 365.689134 -227.187752)
			(xy 365.635984 -227.183768) (xy 365.584022 -227.171908) (xy 365.534408 -227.152436) (xy 365.48825 -227.125787)
			(xy 365.446579 -227.092556) (xy 365.410327 -227.053485) (xy 365.380303 -227.009448) (xy 365.357177 -226.961427)
			(xy 365.341467 -226.910497) (xy 365.333524 -226.857793) (xy 365.10469 -226.857793) (xy 365.096747 -226.910497)
			(xy 365.081037 -226.961427) (xy 365.057911 -227.009448) (xy 365.027887 -227.053485) (xy 364.991635 -227.092556)
			(xy 364.949964 -227.125787) (xy 364.903806 -227.152436) (xy 364.854192 -227.171908) (xy 364.80223 -227.183768)
			(xy 364.74908 -227.187752) (xy 364.69593 -227.183768) (xy 364.643968 -227.171908) (xy 364.594354 -227.152436)
			(xy 364.548196 -227.125787) (xy 364.506525 -227.092556) (xy 364.470273 -227.053485) (xy 364.440249 -227.009448)
			(xy 364.417123 -226.961427) (xy 364.401413 -226.910497) (xy 364.39347 -226.857793) (xy 364.165144 -226.857793)
			(xy 364.157201 -226.910497) (xy 364.141491 -226.961427) (xy 364.118365 -227.009448) (xy 364.088341 -227.053485)
			(xy 364.052089 -227.092556) (xy 364.010418 -227.125787) (xy 363.96426 -227.152436) (xy 363.914646 -227.171908)
			(xy 363.862684 -227.183768) (xy 363.809534 -227.187752) (xy 363.756384 -227.183768) (xy 363.704422 -227.171908)
			(xy 363.654808 -227.152436) (xy 363.60865 -227.125787) (xy 363.566979 -227.092556) (xy 363.530727 -227.053485)
			(xy 363.500703 -227.009448) (xy 363.477577 -226.961427) (xy 363.461867 -226.910497) (xy 363.453924 -226.857793)
			(xy 363.225344 -226.857793) (xy 363.217401 -226.910497) (xy 363.201691 -226.961427) (xy 363.178565 -227.009448)
			(xy 363.148541 -227.053485) (xy 363.112289 -227.092556) (xy 363.070618 -227.125787) (xy 363.02446 -227.152436)
			(xy 362.974846 -227.171908) (xy 362.922884 -227.183768) (xy 362.869734 -227.187752) (xy 362.816584 -227.183768)
			(xy 362.764622 -227.171908) (xy 362.715008 -227.152436) (xy 362.66885 -227.125787) (xy 362.627179 -227.092556)
			(xy 362.590927 -227.053485) (xy 362.560903 -227.009448) (xy 362.537777 -226.961427) (xy 362.522067 -226.910497)
			(xy 362.514124 -226.857793) (xy 362.285544 -226.857793) (xy 362.277601 -226.910497) (xy 362.261891 -226.961427)
			(xy 362.238765 -227.009448) (xy 362.208741 -227.053485) (xy 362.172489 -227.092556) (xy 362.130818 -227.125787)
			(xy 362.08466 -227.152436) (xy 362.035046 -227.171908) (xy 361.983084 -227.183768) (xy 361.929934 -227.187752)
			(xy 361.876784 -227.183768) (xy 361.824822 -227.171908) (xy 361.775208 -227.152436) (xy 361.72905 -227.125787)
			(xy 361.687379 -227.092556) (xy 361.651127 -227.053485) (xy 361.621103 -227.009448) (xy 361.597977 -226.961427)
			(xy 361.582267 -226.910497) (xy 361.574324 -226.857793) (xy 361.34549 -226.857793) (xy 361.337547 -226.910497)
			(xy 361.321837 -226.961427) (xy 361.298711 -227.009448) (xy 361.268687 -227.053485) (xy 361.232435 -227.092556)
			(xy 361.190764 -227.125787) (xy 361.144606 -227.152436) (xy 361.094992 -227.171908) (xy 361.04303 -227.183768)
			(xy 360.98988 -227.187752) (xy 360.93673 -227.183768) (xy 360.884768 -227.171908) (xy 360.835154 -227.152436)
			(xy 360.788996 -227.125787) (xy 360.747325 -227.092556) (xy 360.711073 -227.053485) (xy 360.681049 -227.009448)
			(xy 360.657923 -226.961427) (xy 360.642213 -226.910497) (xy 360.63427 -226.857793) (xy 360.404863 -226.857793)
			(xy 360.402881 -226.88424) (xy 360.391024 -226.936193) (xy 360.371556 -226.985798) (xy 360.344913 -227.031948)
			(xy 360.31169 -227.073613) (xy 360.272629 -227.10986) (xy 360.228601 -227.139881) (xy 360.180591 -227.163006)
			(xy 360.129671 -227.178717) (xy 360.076978 -227.186664) (xy 360.050334 -227.187252) (xy 360.026712 -227.18649)
			(xy 360.012822 -227.186029) (xy 359.98563 -227.191706) (xy 359.960974 -227.2045) (xy 359.940678 -227.223467)
			(xy 359.926244 -227.247201) (xy 359.918741 -227.273947) (xy 359.918254 -227.287836) (xy 359.918254 -227.53193)
			(xy 359.92054 -227.539296) (xy 359.928037 -227.565065) (xy 359.936069 -227.618127) (xy 359.936542 -227.64496)
			(xy 359.93606 -227.671609) (xy 360.164624 -227.671609) (xy 360.164624 -227.618311) (xy 360.172567 -227.565607)
			(xy 360.188277 -227.514677) (xy 360.211403 -227.466656) (xy 360.241427 -227.422619) (xy 360.277679 -227.383548)
			(xy 360.31935 -227.350317) (xy 360.365508 -227.323668) (xy 360.415122 -227.304196) (xy 360.467084 -227.292336)
			(xy 360.520234 -227.288353) (xy 360.573384 -227.292336) (xy 360.625346 -227.304196) (xy 360.67496 -227.323668)
			(xy 360.721118 -227.350317) (xy 360.762789 -227.383548) (xy 360.799041 -227.422619) (xy 360.829065 -227.466656)
			(xy 360.852191 -227.514677) (xy 360.867901 -227.565607) (xy 360.875844 -227.618311) (xy 360.876342 -227.64496)
			(xy 360.875844 -227.671609) (xy 361.104424 -227.671609) (xy 361.104424 -227.618311) (xy 361.112367 -227.565607)
			(xy 361.128077 -227.514677) (xy 361.151203 -227.466656) (xy 361.181227 -227.422619) (xy 361.217479 -227.383548)
			(xy 361.25915 -227.350317) (xy 361.305308 -227.323668) (xy 361.354922 -227.304196) (xy 361.406884 -227.292336)
			(xy 361.460034 -227.288353) (xy 361.513184 -227.292336) (xy 361.565146 -227.304196) (xy 361.61476 -227.323668)
			(xy 361.660918 -227.350317) (xy 361.702589 -227.383548) (xy 361.738841 -227.422619) (xy 361.768865 -227.466656)
			(xy 361.791991 -227.514677) (xy 361.807701 -227.565607) (xy 361.815644 -227.618311) (xy 361.816142 -227.64496)
			(xy 361.815644 -227.671609) (xy 362.044478 -227.671609) (xy 362.044478 -227.618311) (xy 362.052421 -227.565607)
			(xy 362.068131 -227.514677) (xy 362.091257 -227.466656) (xy 362.121281 -227.422619) (xy 362.157533 -227.383548)
			(xy 362.199204 -227.350317) (xy 362.245362 -227.323668) (xy 362.294976 -227.304196) (xy 362.346938 -227.292336)
			(xy 362.400088 -227.288353) (xy 362.453238 -227.292336) (xy 362.5052 -227.304196) (xy 362.554814 -227.323668)
			(xy 362.600972 -227.350317) (xy 362.642643 -227.383548) (xy 362.678895 -227.422619) (xy 362.708919 -227.466656)
			(xy 362.732045 -227.514677) (xy 362.747755 -227.565607) (xy 362.755698 -227.618311) (xy 362.756196 -227.64496)
			(xy 362.755698 -227.671609) (xy 362.984024 -227.671609) (xy 362.984024 -227.618311) (xy 362.991967 -227.565607)
			(xy 363.007677 -227.514677) (xy 363.030803 -227.466656) (xy 363.060827 -227.422619) (xy 363.097079 -227.383548)
			(xy 363.13875 -227.350317) (xy 363.184908 -227.323668) (xy 363.234522 -227.304196) (xy 363.286484 -227.292336)
			(xy 363.339634 -227.288353) (xy 363.392784 -227.292336) (xy 363.444746 -227.304196) (xy 363.49436 -227.323668)
			(xy 363.540518 -227.350317) (xy 363.582189 -227.383548) (xy 363.618441 -227.422619) (xy 363.648465 -227.466656)
			(xy 363.671591 -227.514677) (xy 363.687301 -227.565607) (xy 363.695244 -227.618311) (xy 363.695742 -227.64496)
			(xy 363.695244 -227.671609) (xy 363.923824 -227.671609) (xy 363.923824 -227.618311) (xy 363.931767 -227.565607)
			(xy 363.947477 -227.514677) (xy 363.970603 -227.466656) (xy 364.000627 -227.422619) (xy 364.036879 -227.383548)
			(xy 364.07855 -227.350317) (xy 364.124708 -227.323668) (xy 364.174322 -227.304196) (xy 364.226284 -227.292336)
			(xy 364.279434 -227.288353) (xy 364.332584 -227.292336) (xy 364.384546 -227.304196) (xy 364.43416 -227.323668)
			(xy 364.480318 -227.350317) (xy 364.521989 -227.383548) (xy 364.558241 -227.422619) (xy 364.588265 -227.466656)
			(xy 364.611391 -227.514677) (xy 364.627101 -227.565607) (xy 364.635044 -227.618311) (xy 364.635542 -227.64496)
			(xy 364.635044 -227.671609) (xy 364.863624 -227.671609) (xy 364.863624 -227.618311) (xy 364.871567 -227.565607)
			(xy 364.887277 -227.514677) (xy 364.910403 -227.466656) (xy 364.940427 -227.422619) (xy 364.976679 -227.383548)
			(xy 365.01835 -227.350317) (xy 365.064508 -227.323668) (xy 365.114122 -227.304196) (xy 365.166084 -227.292336)
			(xy 365.219234 -227.288353) (xy 365.272384 -227.292336) (xy 365.324346 -227.304196) (xy 365.37396 -227.323668)
			(xy 365.420118 -227.350317) (xy 365.461789 -227.383548) (xy 365.498041 -227.422619) (xy 365.528065 -227.466656)
			(xy 365.551191 -227.514677) (xy 365.566901 -227.565607) (xy 365.574844 -227.618311) (xy 365.575342 -227.64496)
			(xy 365.574844 -227.671609) (xy 365.803424 -227.671609) (xy 365.803424 -227.618311) (xy 365.811367 -227.565607)
			(xy 365.827077 -227.514677) (xy 365.850203 -227.466656) (xy 365.880227 -227.422619) (xy 365.916479 -227.383548)
			(xy 365.95815 -227.350317) (xy 366.004308 -227.323668) (xy 366.053922 -227.304196) (xy 366.105884 -227.292336)
			(xy 366.159034 -227.288353) (xy 366.212184 -227.292336) (xy 366.264146 -227.304196) (xy 366.31376 -227.323668)
			(xy 366.359918 -227.350317) (xy 366.401589 -227.383548) (xy 366.437841 -227.422619) (xy 366.467865 -227.466656)
			(xy 366.490991 -227.514677) (xy 366.506701 -227.565607) (xy 366.514644 -227.618311) (xy 366.515142 -227.64496)
			(xy 366.514644 -227.671609) (xy 366.743224 -227.671609) (xy 366.743224 -227.618311) (xy 366.751167 -227.565607)
			(xy 366.766877 -227.514677) (xy 366.790003 -227.466656) (xy 366.820027 -227.422619) (xy 366.856279 -227.383548)
			(xy 366.89795 -227.350317) (xy 366.944108 -227.323668) (xy 366.993722 -227.304196) (xy 367.045684 -227.292336)
			(xy 367.098834 -227.288353) (xy 367.151984 -227.292336) (xy 367.203946 -227.304196) (xy 367.25356 -227.323668)
			(xy 367.299718 -227.350317) (xy 367.341389 -227.383548) (xy 367.377641 -227.422619) (xy 367.407665 -227.466656)
			(xy 367.430791 -227.514677) (xy 367.446501 -227.565607) (xy 367.454444 -227.618311) (xy 367.454942 -227.64496)
			(xy 367.454444 -227.671609) (xy 367.683024 -227.671609) (xy 367.683024 -227.618311) (xy 367.690967 -227.565607)
			(xy 367.706677 -227.514677) (xy 367.729803 -227.466656) (xy 367.759827 -227.422619) (xy 367.796079 -227.383548)
			(xy 367.83775 -227.350317) (xy 367.883908 -227.323668) (xy 367.933522 -227.304196) (xy 367.985484 -227.292336)
			(xy 368.038634 -227.288353) (xy 368.091784 -227.292336) (xy 368.143746 -227.304196) (xy 368.19336 -227.323668)
			(xy 368.239518 -227.350317) (xy 368.281189 -227.383548) (xy 368.317441 -227.422619) (xy 368.347465 -227.466656)
			(xy 368.370591 -227.514677) (xy 368.386301 -227.565607) (xy 368.394244 -227.618311) (xy 368.394742 -227.64496)
			(xy 368.394244 -227.671609) (xy 368.622824 -227.671609) (xy 368.622824 -227.618311) (xy 368.630767 -227.565607)
			(xy 368.646477 -227.514677) (xy 368.669603 -227.466656) (xy 368.699627 -227.422619) (xy 368.735879 -227.383548)
			(xy 368.77755 -227.350317) (xy 368.823708 -227.323668) (xy 368.873322 -227.304196) (xy 368.925284 -227.292336)
			(xy 368.978434 -227.288353) (xy 369.031584 -227.292336) (xy 369.083546 -227.304196) (xy 369.13316 -227.323668)
			(xy 369.179318 -227.350317) (xy 369.220989 -227.383548) (xy 369.257241 -227.422619) (xy 369.287265 -227.466656)
			(xy 369.310391 -227.514677) (xy 369.326101 -227.565607) (xy 369.334044 -227.618311) (xy 369.334542 -227.64496)
			(xy 369.334044 -227.671609) (xy 369.56237 -227.671609) (xy 369.56237 -227.618311) (xy 369.570313 -227.565607)
			(xy 369.586023 -227.514677) (xy 369.609149 -227.466656) (xy 369.639173 -227.422619) (xy 369.675425 -227.383548)
			(xy 369.717096 -227.350317) (xy 369.763254 -227.323668) (xy 369.812868 -227.304196) (xy 369.86483 -227.292336)
			(xy 369.91798 -227.288353) (xy 369.97113 -227.292336) (xy 370.023092 -227.304196) (xy 370.072706 -227.323668)
			(xy 370.118864 -227.350317) (xy 370.160535 -227.383548) (xy 370.196787 -227.422619) (xy 370.226811 -227.466656)
			(xy 370.249937 -227.514677) (xy 370.265647 -227.565607) (xy 370.27359 -227.618311) (xy 370.274088 -227.64496)
			(xy 370.27359 -227.671609) (xy 370.502424 -227.671609) (xy 370.502424 -227.618311) (xy 370.510367 -227.565607)
			(xy 370.526077 -227.514677) (xy 370.549203 -227.466656) (xy 370.579227 -227.422619) (xy 370.615479 -227.383548)
			(xy 370.65715 -227.350317) (xy 370.703308 -227.323668) (xy 370.752922 -227.304196) (xy 370.804884 -227.292336)
			(xy 370.858034 -227.288353) (xy 370.911184 -227.292336) (xy 370.963146 -227.304196) (xy 371.01276 -227.323668)
			(xy 371.058918 -227.350317) (xy 371.100589 -227.383548) (xy 371.136841 -227.422619) (xy 371.166865 -227.466656)
			(xy 371.189991 -227.514677) (xy 371.205701 -227.565607) (xy 371.213644 -227.618311) (xy 371.214142 -227.64496)
			(xy 371.213644 -227.671609) (xy 371.442224 -227.671609) (xy 371.442224 -227.618311) (xy 371.450167 -227.565607)
			(xy 371.465877 -227.514677) (xy 371.489003 -227.466656) (xy 371.519027 -227.422619) (xy 371.555279 -227.383548)
			(xy 371.59695 -227.350317) (xy 371.643108 -227.323668) (xy 371.692722 -227.304196) (xy 371.744684 -227.292336)
			(xy 371.797834 -227.288353) (xy 371.850984 -227.292336) (xy 371.902946 -227.304196) (xy 371.95256 -227.323668)
			(xy 371.998718 -227.350317) (xy 372.040389 -227.383548) (xy 372.076641 -227.422619) (xy 372.106665 -227.466656)
			(xy 372.129791 -227.514677) (xy 372.145501 -227.565607) (xy 372.153444 -227.618311) (xy 372.153942 -227.64496)
			(xy 372.153444 -227.671609) (xy 372.382024 -227.671609) (xy 372.382024 -227.618311) (xy 372.389967 -227.565607)
			(xy 372.405677 -227.514677) (xy 372.428803 -227.466656) (xy 372.458827 -227.422619) (xy 372.495079 -227.383548)
			(xy 372.53675 -227.350317) (xy 372.582908 -227.323668) (xy 372.632522 -227.304196) (xy 372.684484 -227.292336)
			(xy 372.737634 -227.288353) (xy 372.790784 -227.292336) (xy 372.842746 -227.304196) (xy 372.89236 -227.323668)
			(xy 372.938518 -227.350317) (xy 372.980189 -227.383548) (xy 373.016441 -227.422619) (xy 373.046465 -227.466656)
			(xy 373.069591 -227.514677) (xy 373.085301 -227.565607) (xy 373.093244 -227.618311) (xy 373.093742 -227.64496)
			(xy 373.093244 -227.671609) (xy 373.321824 -227.671609) (xy 373.321824 -227.618311) (xy 373.329767 -227.565607)
			(xy 373.345477 -227.514677) (xy 373.368603 -227.466656) (xy 373.398627 -227.422619) (xy 373.434879 -227.383548)
			(xy 373.47655 -227.350317) (xy 373.522708 -227.323668) (xy 373.572322 -227.304196) (xy 373.624284 -227.292336)
			(xy 373.677434 -227.288353) (xy 373.730584 -227.292336) (xy 373.782546 -227.304196) (xy 373.83216 -227.323668)
			(xy 373.878318 -227.350317) (xy 373.919989 -227.383548) (xy 373.956241 -227.422619) (xy 373.986265 -227.466656)
			(xy 374.009391 -227.514677) (xy 374.025101 -227.565607) (xy 374.033044 -227.618311) (xy 374.033542 -227.64496)
			(xy 374.033044 -227.671609) (xy 374.261624 -227.671609) (xy 374.261624 -227.618311) (xy 374.269567 -227.565607)
			(xy 374.285277 -227.514677) (xy 374.308403 -227.466656) (xy 374.338427 -227.422619) (xy 374.374679 -227.383548)
			(xy 374.41635 -227.350317) (xy 374.462508 -227.323668) (xy 374.512122 -227.304196) (xy 374.564084 -227.292336)
			(xy 374.617234 -227.288353) (xy 374.670384 -227.292336) (xy 374.722346 -227.304196) (xy 374.77196 -227.323668)
			(xy 374.818118 -227.350317) (xy 374.859789 -227.383548) (xy 374.896041 -227.422619) (xy 374.926065 -227.466656)
			(xy 374.949191 -227.514677) (xy 374.964901 -227.565607) (xy 374.972844 -227.618311) (xy 374.973342 -227.64496)
			(xy 374.972844 -227.671609) (xy 375.20117 -227.671609) (xy 375.20117 -227.618311) (xy 375.209113 -227.565607)
			(xy 375.224823 -227.514677) (xy 375.247949 -227.466656) (xy 375.277973 -227.422619) (xy 375.314225 -227.383548)
			(xy 375.355896 -227.350317) (xy 375.402054 -227.323668) (xy 375.451668 -227.304196) (xy 375.50363 -227.292336)
			(xy 375.55678 -227.288353) (xy 375.60993 -227.292336) (xy 375.661892 -227.304196) (xy 375.711506 -227.323668)
			(xy 375.757664 -227.350317) (xy 375.799335 -227.383548) (xy 375.835587 -227.422619) (xy 375.865611 -227.466656)
			(xy 375.888737 -227.514677) (xy 375.904447 -227.565607) (xy 375.91239 -227.618311) (xy 375.912888 -227.64496)
			(xy 375.91239 -227.671609) (xy 376.14097 -227.671609) (xy 376.14097 -227.618311) (xy 376.148913 -227.565607)
			(xy 376.164623 -227.514677) (xy 376.187749 -227.466656) (xy 376.217773 -227.422619) (xy 376.254025 -227.383548)
			(xy 376.295696 -227.350317) (xy 376.341854 -227.323668) (xy 376.391468 -227.304196) (xy 376.44343 -227.292336)
			(xy 376.49658 -227.288353) (xy 376.54973 -227.292336) (xy 376.601692 -227.304196) (xy 376.651306 -227.323668)
			(xy 376.697464 -227.350317) (xy 376.739135 -227.383548) (xy 376.775387 -227.422619) (xy 376.805411 -227.466656)
			(xy 376.828537 -227.514677) (xy 376.844247 -227.565607) (xy 376.85219 -227.618311) (xy 376.852688 -227.64496)
			(xy 376.85219 -227.671609) (xy 377.081024 -227.671609) (xy 377.081024 -227.618311) (xy 377.088967 -227.565607)
			(xy 377.104677 -227.514677) (xy 377.127803 -227.466656) (xy 377.157827 -227.422619) (xy 377.194079 -227.383548)
			(xy 377.23575 -227.350317) (xy 377.281908 -227.323668) (xy 377.331522 -227.304196) (xy 377.383484 -227.292336)
			(xy 377.436634 -227.288353) (xy 377.489784 -227.292336) (xy 377.541746 -227.304196) (xy 377.59136 -227.323668)
			(xy 377.637518 -227.350317) (xy 377.679189 -227.383548) (xy 377.715441 -227.422619) (xy 377.745465 -227.466656)
			(xy 377.768591 -227.514677) (xy 377.784301 -227.565607) (xy 377.792244 -227.618311) (xy 377.792742 -227.64496)
			(xy 377.792244 -227.671609) (xy 378.020824 -227.671609) (xy 378.020824 -227.618311) (xy 378.028767 -227.565607)
			(xy 378.044477 -227.514677) (xy 378.067603 -227.466656) (xy 378.097627 -227.422619) (xy 378.133879 -227.383548)
			(xy 378.17555 -227.350317) (xy 378.221708 -227.323668) (xy 378.271322 -227.304196) (xy 378.323284 -227.292336)
			(xy 378.376434 -227.288353) (xy 378.429584 -227.292336) (xy 378.481546 -227.304196) (xy 378.53116 -227.323668)
			(xy 378.577318 -227.350317) (xy 378.618989 -227.383548) (xy 378.655241 -227.422619) (xy 378.685265 -227.466656)
			(xy 378.708391 -227.514677) (xy 378.724101 -227.565607) (xy 378.732044 -227.618311) (xy 378.732542 -227.64496)
			(xy 378.732044 -227.671609) (xy 378.960624 -227.671609) (xy 378.960624 -227.618311) (xy 378.968567 -227.565607)
			(xy 378.984277 -227.514677) (xy 379.007403 -227.466656) (xy 379.037427 -227.422619) (xy 379.073679 -227.383548)
			(xy 379.11535 -227.350317) (xy 379.161508 -227.323668) (xy 379.211122 -227.304196) (xy 379.263084 -227.292336)
			(xy 379.316234 -227.288353) (xy 379.369384 -227.292336) (xy 379.421346 -227.304196) (xy 379.47096 -227.323668)
			(xy 379.517118 -227.350317) (xy 379.558789 -227.383548) (xy 379.595041 -227.422619) (xy 379.625065 -227.466656)
			(xy 379.648191 -227.514677) (xy 379.663901 -227.565607) (xy 379.671844 -227.618311) (xy 379.672342 -227.64496)
			(xy 379.671844 -227.671609) (xy 379.900424 -227.671609) (xy 379.900424 -227.618311) (xy 379.908367 -227.565607)
			(xy 379.924077 -227.514677) (xy 379.947203 -227.466656) (xy 379.977227 -227.422619) (xy 380.013479 -227.383548)
			(xy 380.05515 -227.350317) (xy 380.101308 -227.323668) (xy 380.150922 -227.304196) (xy 380.202884 -227.292336)
			(xy 380.256034 -227.288353) (xy 380.309184 -227.292336) (xy 380.361146 -227.304196) (xy 380.41076 -227.323668)
			(xy 380.456918 -227.350317) (xy 380.498589 -227.383548) (xy 380.534841 -227.422619) (xy 380.564865 -227.466656)
			(xy 380.587991 -227.514677) (xy 380.603701 -227.565607) (xy 380.611644 -227.618311) (xy 380.612142 -227.64496)
			(xy 380.611644 -227.671609) (xy 380.603701 -227.724313) (xy 380.587991 -227.775243) (xy 380.564865 -227.823264)
			(xy 380.534841 -227.867301) (xy 380.498589 -227.906372) (xy 380.456918 -227.939603) (xy 380.41076 -227.966252)
			(xy 380.361146 -227.985724) (xy 380.309184 -227.997584) (xy 380.256034 -228.001568) (xy 380.202884 -227.997584)
			(xy 380.150922 -227.985724) (xy 380.101308 -227.966252) (xy 380.05515 -227.939603) (xy 380.013479 -227.906372)
			(xy 379.977227 -227.867301) (xy 379.947203 -227.823264) (xy 379.924077 -227.775243) (xy 379.908367 -227.724313)
			(xy 379.900424 -227.671609) (xy 379.671844 -227.671609) (xy 379.663901 -227.724313) (xy 379.648191 -227.775243)
			(xy 379.625065 -227.823264) (xy 379.595041 -227.867301) (xy 379.558789 -227.906372) (xy 379.517118 -227.939603)
			(xy 379.47096 -227.966252) (xy 379.421346 -227.985724) (xy 379.369384 -227.997584) (xy 379.316234 -228.001568)
			(xy 379.263084 -227.997584) (xy 379.211122 -227.985724) (xy 379.161508 -227.966252) (xy 379.11535 -227.939603)
			(xy 379.073679 -227.906372) (xy 379.037427 -227.867301) (xy 379.007403 -227.823264) (xy 378.984277 -227.775243)
			(xy 378.968567 -227.724313) (xy 378.960624 -227.671609) (xy 378.732044 -227.671609) (xy 378.724101 -227.724313)
			(xy 378.708391 -227.775243) (xy 378.685265 -227.823264) (xy 378.655241 -227.867301) (xy 378.618989 -227.906372)
			(xy 378.577318 -227.939603) (xy 378.53116 -227.966252) (xy 378.481546 -227.985724) (xy 378.429584 -227.997584)
			(xy 378.376434 -228.001568) (xy 378.323284 -227.997584) (xy 378.271322 -227.985724) (xy 378.221708 -227.966252)
			(xy 378.17555 -227.939603) (xy 378.133879 -227.906372) (xy 378.097627 -227.867301) (xy 378.067603 -227.823264)
			(xy 378.044477 -227.775243) (xy 378.028767 -227.724313) (xy 378.020824 -227.671609) (xy 377.792244 -227.671609)
			(xy 377.784301 -227.724313) (xy 377.768591 -227.775243) (xy 377.745465 -227.823264) (xy 377.715441 -227.867301)
			(xy 377.679189 -227.906372) (xy 377.637518 -227.939603) (xy 377.59136 -227.966252) (xy 377.541746 -227.985724)
			(xy 377.489784 -227.997584) (xy 377.436634 -228.001568) (xy 377.383484 -227.997584) (xy 377.331522 -227.985724)
			(xy 377.281908 -227.966252) (xy 377.23575 -227.939603) (xy 377.194079 -227.906372) (xy 377.157827 -227.867301)
			(xy 377.127803 -227.823264) (xy 377.104677 -227.775243) (xy 377.088967 -227.724313) (xy 377.081024 -227.671609)
			(xy 376.85219 -227.671609) (xy 376.844247 -227.724313) (xy 376.828537 -227.775243) (xy 376.805411 -227.823264)
			(xy 376.775387 -227.867301) (xy 376.739135 -227.906372) (xy 376.697464 -227.939603) (xy 376.651306 -227.966252)
			(xy 376.601692 -227.985724) (xy 376.54973 -227.997584) (xy 376.49658 -228.001568) (xy 376.44343 -227.997584)
			(xy 376.391468 -227.985724) (xy 376.341854 -227.966252) (xy 376.295696 -227.939603) (xy 376.254025 -227.906372)
			(xy 376.217773 -227.867301) (xy 376.187749 -227.823264) (xy 376.164623 -227.775243) (xy 376.148913 -227.724313)
			(xy 376.14097 -227.671609) (xy 375.91239 -227.671609) (xy 375.904447 -227.724313) (xy 375.888737 -227.775243)
			(xy 375.865611 -227.823264) (xy 375.835587 -227.867301) (xy 375.799335 -227.906372) (xy 375.757664 -227.939603)
			(xy 375.711506 -227.966252) (xy 375.661892 -227.985724) (xy 375.60993 -227.997584) (xy 375.55678 -228.001568)
			(xy 375.50363 -227.997584) (xy 375.451668 -227.985724) (xy 375.402054 -227.966252) (xy 375.355896 -227.939603)
			(xy 375.314225 -227.906372) (xy 375.277973 -227.867301) (xy 375.247949 -227.823264) (xy 375.224823 -227.775243)
			(xy 375.209113 -227.724313) (xy 375.20117 -227.671609) (xy 374.972844 -227.671609) (xy 374.964901 -227.724313)
			(xy 374.949191 -227.775243) (xy 374.926065 -227.823264) (xy 374.896041 -227.867301) (xy 374.859789 -227.906372)
			(xy 374.818118 -227.939603) (xy 374.77196 -227.966252) (xy 374.722346 -227.985724) (xy 374.670384 -227.997584)
			(xy 374.617234 -228.001568) (xy 374.564084 -227.997584) (xy 374.512122 -227.985724) (xy 374.462508 -227.966252)
			(xy 374.41635 -227.939603) (xy 374.374679 -227.906372) (xy 374.338427 -227.867301) (xy 374.308403 -227.823264)
			(xy 374.285277 -227.775243) (xy 374.269567 -227.724313) (xy 374.261624 -227.671609) (xy 374.033044 -227.671609)
			(xy 374.025101 -227.724313) (xy 374.009391 -227.775243) (xy 373.986265 -227.823264) (xy 373.956241 -227.867301)
			(xy 373.919989 -227.906372) (xy 373.878318 -227.939603) (xy 373.83216 -227.966252) (xy 373.782546 -227.985724)
			(xy 373.730584 -227.997584) (xy 373.677434 -228.001568) (xy 373.624284 -227.997584) (xy 373.572322 -227.985724)
			(xy 373.522708 -227.966252) (xy 373.47655 -227.939603) (xy 373.434879 -227.906372) (xy 373.398627 -227.867301)
			(xy 373.368603 -227.823264) (xy 373.345477 -227.775243) (xy 373.329767 -227.724313) (xy 373.321824 -227.671609)
			(xy 373.093244 -227.671609) (xy 373.085301 -227.724313) (xy 373.069591 -227.775243) (xy 373.046465 -227.823264)
			(xy 373.016441 -227.867301) (xy 372.980189 -227.906372) (xy 372.938518 -227.939603) (xy 372.89236 -227.966252)
			(xy 372.842746 -227.985724) (xy 372.790784 -227.997584) (xy 372.737634 -228.001568) (xy 372.684484 -227.997584)
			(xy 372.632522 -227.985724) (xy 372.582908 -227.966252) (xy 372.53675 -227.939603) (xy 372.495079 -227.906372)
			(xy 372.458827 -227.867301) (xy 372.428803 -227.823264) (xy 372.405677 -227.775243) (xy 372.389967 -227.724313)
			(xy 372.382024 -227.671609) (xy 372.153444 -227.671609) (xy 372.145501 -227.724313) (xy 372.129791 -227.775243)
			(xy 372.106665 -227.823264) (xy 372.076641 -227.867301) (xy 372.040389 -227.906372) (xy 371.998718 -227.939603)
			(xy 371.95256 -227.966252) (xy 371.902946 -227.985724) (xy 371.850984 -227.997584) (xy 371.797834 -228.001568)
			(xy 371.744684 -227.997584) (xy 371.692722 -227.985724) (xy 371.643108 -227.966252) (xy 371.59695 -227.939603)
			(xy 371.555279 -227.906372) (xy 371.519027 -227.867301) (xy 371.489003 -227.823264) (xy 371.465877 -227.775243)
			(xy 371.450167 -227.724313) (xy 371.442224 -227.671609) (xy 371.213644 -227.671609) (xy 371.205701 -227.724313)
			(xy 371.189991 -227.775243) (xy 371.166865 -227.823264) (xy 371.136841 -227.867301) (xy 371.100589 -227.906372)
			(xy 371.058918 -227.939603) (xy 371.01276 -227.966252) (xy 370.963146 -227.985724) (xy 370.911184 -227.997584)
			(xy 370.858034 -228.001568) (xy 370.804884 -227.997584) (xy 370.752922 -227.985724) (xy 370.703308 -227.966252)
			(xy 370.65715 -227.939603) (xy 370.615479 -227.906372) (xy 370.579227 -227.867301) (xy 370.549203 -227.823264)
			(xy 370.526077 -227.775243) (xy 370.510367 -227.724313) (xy 370.502424 -227.671609) (xy 370.27359 -227.671609)
			(xy 370.265647 -227.724313) (xy 370.249937 -227.775243) (xy 370.226811 -227.823264) (xy 370.196787 -227.867301)
			(xy 370.160535 -227.906372) (xy 370.118864 -227.939603) (xy 370.072706 -227.966252) (xy 370.023092 -227.985724)
			(xy 369.97113 -227.997584) (xy 369.91798 -228.001568) (xy 369.86483 -227.997584) (xy 369.812868 -227.985724)
			(xy 369.763254 -227.966252) (xy 369.717096 -227.939603) (xy 369.675425 -227.906372) (xy 369.639173 -227.867301)
			(xy 369.609149 -227.823264) (xy 369.586023 -227.775243) (xy 369.570313 -227.724313) (xy 369.56237 -227.671609)
			(xy 369.334044 -227.671609) (xy 369.326101 -227.724313) (xy 369.310391 -227.775243) (xy 369.287265 -227.823264)
			(xy 369.257241 -227.867301) (xy 369.220989 -227.906372) (xy 369.179318 -227.939603) (xy 369.13316 -227.966252)
			(xy 369.083546 -227.985724) (xy 369.031584 -227.997584) (xy 368.978434 -228.001568) (xy 368.925284 -227.997584)
			(xy 368.873322 -227.985724) (xy 368.823708 -227.966252) (xy 368.77755 -227.939603) (xy 368.735879 -227.906372)
			(xy 368.699627 -227.867301) (xy 368.669603 -227.823264) (xy 368.646477 -227.775243) (xy 368.630767 -227.724313)
			(xy 368.622824 -227.671609) (xy 368.394244 -227.671609) (xy 368.386301 -227.724313) (xy 368.370591 -227.775243)
			(xy 368.347465 -227.823264) (xy 368.317441 -227.867301) (xy 368.281189 -227.906372) (xy 368.239518 -227.939603)
			(xy 368.19336 -227.966252) (xy 368.143746 -227.985724) (xy 368.091784 -227.997584) (xy 368.038634 -228.001568)
			(xy 367.985484 -227.997584) (xy 367.933522 -227.985724) (xy 367.883908 -227.966252) (xy 367.83775 -227.939603)
			(xy 367.796079 -227.906372) (xy 367.759827 -227.867301) (xy 367.729803 -227.823264) (xy 367.706677 -227.775243)
			(xy 367.690967 -227.724313) (xy 367.683024 -227.671609) (xy 367.454444 -227.671609) (xy 367.446501 -227.724313)
			(xy 367.430791 -227.775243) (xy 367.407665 -227.823264) (xy 367.377641 -227.867301) (xy 367.341389 -227.906372)
			(xy 367.299718 -227.939603) (xy 367.25356 -227.966252) (xy 367.203946 -227.985724) (xy 367.151984 -227.997584)
			(xy 367.098834 -228.001568) (xy 367.045684 -227.997584) (xy 366.993722 -227.985724) (xy 366.944108 -227.966252)
			(xy 366.89795 -227.939603) (xy 366.856279 -227.906372) (xy 366.820027 -227.867301) (xy 366.790003 -227.823264)
			(xy 366.766877 -227.775243) (xy 366.751167 -227.724313) (xy 366.743224 -227.671609) (xy 366.514644 -227.671609)
			(xy 366.506701 -227.724313) (xy 366.490991 -227.775243) (xy 366.467865 -227.823264) (xy 366.437841 -227.867301)
			(xy 366.401589 -227.906372) (xy 366.359918 -227.939603) (xy 366.31376 -227.966252) (xy 366.264146 -227.985724)
			(xy 366.212184 -227.997584) (xy 366.159034 -228.001568) (xy 366.105884 -227.997584) (xy 366.053922 -227.985724)
			(xy 366.004308 -227.966252) (xy 365.95815 -227.939603) (xy 365.916479 -227.906372) (xy 365.880227 -227.867301)
			(xy 365.850203 -227.823264) (xy 365.827077 -227.775243) (xy 365.811367 -227.724313) (xy 365.803424 -227.671609)
			(xy 365.574844 -227.671609) (xy 365.566901 -227.724313) (xy 365.551191 -227.775243) (xy 365.528065 -227.823264)
			(xy 365.498041 -227.867301) (xy 365.461789 -227.906372) (xy 365.420118 -227.939603) (xy 365.37396 -227.966252)
			(xy 365.324346 -227.985724) (xy 365.272384 -227.997584) (xy 365.219234 -228.001568) (xy 365.166084 -227.997584)
			(xy 365.114122 -227.985724) (xy 365.064508 -227.966252) (xy 365.01835 -227.939603) (xy 364.976679 -227.906372)
			(xy 364.940427 -227.867301) (xy 364.910403 -227.823264) (xy 364.887277 -227.775243) (xy 364.871567 -227.724313)
			(xy 364.863624 -227.671609) (xy 364.635044 -227.671609) (xy 364.627101 -227.724313) (xy 364.611391 -227.775243)
			(xy 364.588265 -227.823264) (xy 364.558241 -227.867301) (xy 364.521989 -227.906372) (xy 364.480318 -227.939603)
			(xy 364.43416 -227.966252) (xy 364.384546 -227.985724) (xy 364.332584 -227.997584) (xy 364.279434 -228.001568)
			(xy 364.226284 -227.997584) (xy 364.174322 -227.985724) (xy 364.124708 -227.966252) (xy 364.07855 -227.939603)
			(xy 364.036879 -227.906372) (xy 364.000627 -227.867301) (xy 363.970603 -227.823264) (xy 363.947477 -227.775243)
			(xy 363.931767 -227.724313) (xy 363.923824 -227.671609) (xy 363.695244 -227.671609) (xy 363.687301 -227.724313)
			(xy 363.671591 -227.775243) (xy 363.648465 -227.823264) (xy 363.618441 -227.867301) (xy 363.582189 -227.906372)
			(xy 363.540518 -227.939603) (xy 363.49436 -227.966252) (xy 363.444746 -227.985724) (xy 363.392784 -227.997584)
			(xy 363.339634 -228.001568) (xy 363.286484 -227.997584) (xy 363.234522 -227.985724) (xy 363.184908 -227.966252)
			(xy 363.13875 -227.939603) (xy 363.097079 -227.906372) (xy 363.060827 -227.867301) (xy 363.030803 -227.823264)
			(xy 363.007677 -227.775243) (xy 362.991967 -227.724313) (xy 362.984024 -227.671609) (xy 362.755698 -227.671609)
			(xy 362.747755 -227.724313) (xy 362.732045 -227.775243) (xy 362.708919 -227.823264) (xy 362.678895 -227.867301)
			(xy 362.642643 -227.906372) (xy 362.600972 -227.939603) (xy 362.554814 -227.966252) (xy 362.5052 -227.985724)
			(xy 362.453238 -227.997584) (xy 362.400088 -228.001568) (xy 362.346938 -227.997584) (xy 362.294976 -227.985724)
			(xy 362.245362 -227.966252) (xy 362.199204 -227.939603) (xy 362.157533 -227.906372) (xy 362.121281 -227.867301)
			(xy 362.091257 -227.823264) (xy 362.068131 -227.775243) (xy 362.052421 -227.724313) (xy 362.044478 -227.671609)
			(xy 361.815644 -227.671609) (xy 361.807701 -227.724313) (xy 361.791991 -227.775243) (xy 361.768865 -227.823264)
			(xy 361.738841 -227.867301) (xy 361.702589 -227.906372) (xy 361.660918 -227.939603) (xy 361.61476 -227.966252)
			(xy 361.565146 -227.985724) (xy 361.513184 -227.997584) (xy 361.460034 -228.001568) (xy 361.406884 -227.997584)
			(xy 361.354922 -227.985724) (xy 361.305308 -227.966252) (xy 361.25915 -227.939603) (xy 361.217479 -227.906372)
			(xy 361.181227 -227.867301) (xy 361.151203 -227.823264) (xy 361.128077 -227.775243) (xy 361.112367 -227.724313)
			(xy 361.104424 -227.671609) (xy 360.875844 -227.671609) (xy 360.867901 -227.724313) (xy 360.852191 -227.775243)
			(xy 360.829065 -227.823264) (xy 360.799041 -227.867301) (xy 360.762789 -227.906372) (xy 360.721118 -227.939603)
			(xy 360.67496 -227.966252) (xy 360.625346 -227.985724) (xy 360.573384 -227.997584) (xy 360.520234 -228.001568)
			(xy 360.467084 -227.997584) (xy 360.415122 -227.985724) (xy 360.365508 -227.966252) (xy 360.31935 -227.939603)
			(xy 360.277679 -227.906372) (xy 360.241427 -227.867301) (xy 360.211403 -227.823264) (xy 360.188277 -227.775243)
			(xy 360.172567 -227.724313) (xy 360.164624 -227.671609) (xy 359.93606 -227.671609) (xy 359.936057 -227.671792)
			(xy 359.928027 -227.724853) (xy 359.92054 -227.750624) (xy 359.918254 -227.75799) (xy 359.918254 -228.002338)
			(xy 359.918716 -228.016213) (xy 359.926177 -228.042941) (xy 359.940565 -228.06667) (xy 359.960815 -228.085644)
			(xy 359.985428 -228.098459) (xy 360.012585 -228.104168) (xy 360.026458 -228.103684) (xy 360.05008 -228.102922)
			(xy 360.07673 -228.103394) (xy 360.129435 -228.111335) (xy 360.180367 -228.127043) (xy 360.228389 -228.150167)
			(xy 360.272429 -228.18019) (xy 360.311501 -228.216442) (xy 360.344734 -228.258113) (xy 360.371385 -228.304271)
			(xy 360.390858 -228.353886) (xy 360.402719 -228.405849) (xy 360.406702 -228.459) (xy 360.404703 -228.485679)
			(xy 360.63427 -228.485679) (xy 360.63427 -228.432381) (xy 360.642213 -228.379677) (xy 360.657923 -228.328747)
			(xy 360.681049 -228.280726) (xy 360.711073 -228.236689) (xy 360.747325 -228.197618) (xy 360.788996 -228.164387)
			(xy 360.835154 -228.137738) (xy 360.884768 -228.118266) (xy 360.93673 -228.106406) (xy 360.98988 -228.102423)
			(xy 361.04303 -228.106406) (xy 361.094992 -228.118266) (xy 361.144606 -228.137738) (xy 361.190764 -228.164387)
			(xy 361.232435 -228.197618) (xy 361.268687 -228.236689) (xy 361.298711 -228.280726) (xy 361.321837 -228.328747)
			(xy 361.337547 -228.379677) (xy 361.34549 -228.432381) (xy 361.345988 -228.45903) (xy 361.34549 -228.485679)
			(xy 361.57407 -228.485679) (xy 361.57407 -228.432381) (xy 361.582013 -228.379677) (xy 361.597723 -228.328747)
			(xy 361.620849 -228.280726) (xy 361.650873 -228.236689) (xy 361.687125 -228.197618) (xy 361.728796 -228.164387)
			(xy 361.774954 -228.137738) (xy 361.824568 -228.118266) (xy 361.87653 -228.106406) (xy 361.92968 -228.102423)
			(xy 361.98283 -228.106406) (xy 362.034792 -228.118266) (xy 362.084406 -228.137738) (xy 362.130564 -228.164387)
			(xy 362.172235 -228.197618) (xy 362.208487 -228.236689) (xy 362.238511 -228.280726) (xy 362.261637 -228.328747)
			(xy 362.277347 -228.379677) (xy 362.28529 -228.432381) (xy 362.285788 -228.45903) (xy 362.28529 -228.485679)
			(xy 362.51387 -228.485679) (xy 362.51387 -228.432381) (xy 362.521813 -228.379677) (xy 362.537523 -228.328747)
			(xy 362.560649 -228.280726) (xy 362.590673 -228.236689) (xy 362.626925 -228.197618) (xy 362.668596 -228.164387)
			(xy 362.714754 -228.137738) (xy 362.764368 -228.118266) (xy 362.81633 -228.106406) (xy 362.86948 -228.102423)
			(xy 362.92263 -228.106406) (xy 362.974592 -228.118266) (xy 363.024206 -228.137738) (xy 363.070364 -228.164387)
			(xy 363.112035 -228.197618) (xy 363.148287 -228.236689) (xy 363.178311 -228.280726) (xy 363.201437 -228.328747)
			(xy 363.217147 -228.379677) (xy 363.22509 -228.432381) (xy 363.225588 -228.45903) (xy 363.22509 -228.485679)
			(xy 363.45367 -228.485679) (xy 363.45367 -228.432381) (xy 363.461613 -228.379677) (xy 363.477323 -228.328747)
			(xy 363.500449 -228.280726) (xy 363.530473 -228.236689) (xy 363.566725 -228.197618) (xy 363.608396 -228.164387)
			(xy 363.654554 -228.137738) (xy 363.704168 -228.118266) (xy 363.75613 -228.106406) (xy 363.80928 -228.102423)
			(xy 363.86243 -228.106406) (xy 363.914392 -228.118266) (xy 363.964006 -228.137738) (xy 364.010164 -228.164387)
			(xy 364.051835 -228.197618) (xy 364.088087 -228.236689) (xy 364.118111 -228.280726) (xy 364.141237 -228.328747)
			(xy 364.156947 -228.379677) (xy 364.16489 -228.432381) (xy 364.165388 -228.45903) (xy 364.16489 -228.485679)
			(xy 364.39347 -228.485679) (xy 364.39347 -228.432381) (xy 364.401413 -228.379677) (xy 364.417123 -228.328747)
			(xy 364.440249 -228.280726) (xy 364.470273 -228.236689) (xy 364.506525 -228.197618) (xy 364.548196 -228.164387)
			(xy 364.594354 -228.137738) (xy 364.643968 -228.118266) (xy 364.69593 -228.106406) (xy 364.74908 -228.102423)
			(xy 364.80223 -228.106406) (xy 364.854192 -228.118266) (xy 364.903806 -228.137738) (xy 364.949964 -228.164387)
			(xy 364.991635 -228.197618) (xy 365.027887 -228.236689) (xy 365.057911 -228.280726) (xy 365.081037 -228.328747)
			(xy 365.096747 -228.379677) (xy 365.10469 -228.432381) (xy 365.105188 -228.45903) (xy 365.10469 -228.485679)
			(xy 365.33327 -228.485679) (xy 365.33327 -228.432381) (xy 365.341213 -228.379677) (xy 365.356923 -228.328747)
			(xy 365.380049 -228.280726) (xy 365.410073 -228.236689) (xy 365.446325 -228.197618) (xy 365.487996 -228.164387)
			(xy 365.534154 -228.137738) (xy 365.583768 -228.118266) (xy 365.63573 -228.106406) (xy 365.68888 -228.102423)
			(xy 365.74203 -228.106406) (xy 365.793992 -228.118266) (xy 365.843606 -228.137738) (xy 365.889764 -228.164387)
			(xy 365.931435 -228.197618) (xy 365.967687 -228.236689) (xy 365.997711 -228.280726) (xy 366.020837 -228.328747)
			(xy 366.036547 -228.379677) (xy 366.04449 -228.432381) (xy 366.044988 -228.45903) (xy 366.04449 -228.485679)
			(xy 366.27307 -228.485679) (xy 366.27307 -228.432381) (xy 366.281013 -228.379677) (xy 366.296723 -228.328747)
			(xy 366.319849 -228.280726) (xy 366.349873 -228.236689) (xy 366.386125 -228.197618) (xy 366.427796 -228.164387)
			(xy 366.473954 -228.137738) (xy 366.523568 -228.118266) (xy 366.57553 -228.106406) (xy 366.62868 -228.102423)
			(xy 366.68183 -228.106406) (xy 366.733792 -228.118266) (xy 366.783406 -228.137738) (xy 366.829564 -228.164387)
			(xy 366.871235 -228.197618) (xy 366.907487 -228.236689) (xy 366.937511 -228.280726) (xy 366.960637 -228.328747)
			(xy 366.976347 -228.379677) (xy 366.98429 -228.432381) (xy 366.984788 -228.45903) (xy 366.98429 -228.485679)
			(xy 367.21287 -228.485679) (xy 367.21287 -228.432381) (xy 367.220813 -228.379677) (xy 367.236523 -228.328747)
			(xy 367.259649 -228.280726) (xy 367.289673 -228.236689) (xy 367.325925 -228.197618) (xy 367.367596 -228.164387)
			(xy 367.413754 -228.137738) (xy 367.463368 -228.118266) (xy 367.51533 -228.106406) (xy 367.56848 -228.102423)
			(xy 367.62163 -228.106406) (xy 367.673592 -228.118266) (xy 367.723206 -228.137738) (xy 367.769364 -228.164387)
			(xy 367.811035 -228.197618) (xy 367.847287 -228.236689) (xy 367.877311 -228.280726) (xy 367.900437 -228.328747)
			(xy 367.916147 -228.379677) (xy 367.92409 -228.432381) (xy 367.924588 -228.45903) (xy 367.92409 -228.485679)
			(xy 368.15267 -228.485679) (xy 368.15267 -228.432381) (xy 368.160613 -228.379677) (xy 368.176323 -228.328747)
			(xy 368.199449 -228.280726) (xy 368.229473 -228.236689) (xy 368.265725 -228.197618) (xy 368.307396 -228.164387)
			(xy 368.353554 -228.137738) (xy 368.403168 -228.118266) (xy 368.45513 -228.106406) (xy 368.50828 -228.102423)
			(xy 368.56143 -228.106406) (xy 368.613392 -228.118266) (xy 368.663006 -228.137738) (xy 368.709164 -228.164387)
			(xy 368.750835 -228.197618) (xy 368.787087 -228.236689) (xy 368.817111 -228.280726) (xy 368.840237 -228.328747)
			(xy 368.855947 -228.379677) (xy 368.86389 -228.432381) (xy 368.864388 -228.45903) (xy 368.86389 -228.485679)
			(xy 369.09247 -228.485679) (xy 369.09247 -228.432381) (xy 369.100413 -228.379677) (xy 369.116123 -228.328747)
			(xy 369.139249 -228.280726) (xy 369.169273 -228.236689) (xy 369.205525 -228.197618) (xy 369.247196 -228.164387)
			(xy 369.293354 -228.137738) (xy 369.342968 -228.118266) (xy 369.39493 -228.106406) (xy 369.44808 -228.102423)
			(xy 369.50123 -228.106406) (xy 369.553192 -228.118266) (xy 369.602806 -228.137738) (xy 369.648964 -228.164387)
			(xy 369.690635 -228.197618) (xy 369.726887 -228.236689) (xy 369.756911 -228.280726) (xy 369.780037 -228.328747)
			(xy 369.795747 -228.379677) (xy 369.80369 -228.432381) (xy 369.804188 -228.45903) (xy 369.80369 -228.485679)
			(xy 370.03227 -228.485679) (xy 370.03227 -228.432381) (xy 370.040213 -228.379677) (xy 370.055923 -228.328747)
			(xy 370.079049 -228.280726) (xy 370.109073 -228.236689) (xy 370.145325 -228.197618) (xy 370.186996 -228.164387)
			(xy 370.233154 -228.137738) (xy 370.282768 -228.118266) (xy 370.33473 -228.106406) (xy 370.38788 -228.102423)
			(xy 370.44103 -228.106406) (xy 370.492992 -228.118266) (xy 370.542606 -228.137738) (xy 370.588764 -228.164387)
			(xy 370.630435 -228.197618) (xy 370.666687 -228.236689) (xy 370.696711 -228.280726) (xy 370.719837 -228.328747)
			(xy 370.735547 -228.379677) (xy 370.74349 -228.432381) (xy 370.743988 -228.45903) (xy 370.74349 -228.485679)
			(xy 370.97207 -228.485679) (xy 370.97207 -228.432381) (xy 370.980013 -228.379677) (xy 370.995723 -228.328747)
			(xy 371.018849 -228.280726) (xy 371.048873 -228.236689) (xy 371.085125 -228.197618) (xy 371.126796 -228.164387)
			(xy 371.172954 -228.137738) (xy 371.222568 -228.118266) (xy 371.27453 -228.106406) (xy 371.32768 -228.102423)
			(xy 371.38083 -228.106406) (xy 371.432792 -228.118266) (xy 371.482406 -228.137738) (xy 371.528564 -228.164387)
			(xy 371.570235 -228.197618) (xy 371.606487 -228.236689) (xy 371.636511 -228.280726) (xy 371.659637 -228.328747)
			(xy 371.675347 -228.379677) (xy 371.68329 -228.432381) (xy 371.683788 -228.45903) (xy 371.68329 -228.485679)
			(xy 371.91187 -228.485679) (xy 371.91187 -228.432381) (xy 371.919813 -228.379677) (xy 371.935523 -228.328747)
			(xy 371.958649 -228.280726) (xy 371.988673 -228.236689) (xy 372.024925 -228.197618) (xy 372.066596 -228.164387)
			(xy 372.112754 -228.137738) (xy 372.162368 -228.118266) (xy 372.21433 -228.106406) (xy 372.26748 -228.102423)
			(xy 372.32063 -228.106406) (xy 372.372592 -228.118266) (xy 372.422206 -228.137738) (xy 372.468364 -228.164387)
			(xy 372.510035 -228.197618) (xy 372.546287 -228.236689) (xy 372.576311 -228.280726) (xy 372.599437 -228.328747)
			(xy 372.615147 -228.379677) (xy 372.62309 -228.432381) (xy 372.623588 -228.45903) (xy 372.62309 -228.485679)
			(xy 372.85167 -228.485679) (xy 372.85167 -228.432381) (xy 372.859613 -228.379677) (xy 372.875323 -228.328747)
			(xy 372.898449 -228.280726) (xy 372.928473 -228.236689) (xy 372.964725 -228.197618) (xy 373.006396 -228.164387)
			(xy 373.052554 -228.137738) (xy 373.102168 -228.118266) (xy 373.15413 -228.106406) (xy 373.20728 -228.102423)
			(xy 373.26043 -228.106406) (xy 373.312392 -228.118266) (xy 373.362006 -228.137738) (xy 373.408164 -228.164387)
			(xy 373.449835 -228.197618) (xy 373.486087 -228.236689) (xy 373.516111 -228.280726) (xy 373.539237 -228.328747)
			(xy 373.554947 -228.379677) (xy 373.56289 -228.432381) (xy 373.563388 -228.45903) (xy 373.56289 -228.485679)
			(xy 373.791724 -228.485679) (xy 373.791724 -228.432381) (xy 373.799667 -228.379677) (xy 373.815377 -228.328747)
			(xy 373.838503 -228.280726) (xy 373.868527 -228.236689) (xy 373.904779 -228.197618) (xy 373.94645 -228.164387)
			(xy 373.992608 -228.137738) (xy 374.042222 -228.118266) (xy 374.094184 -228.106406) (xy 374.147334 -228.102423)
			(xy 374.200484 -228.106406) (xy 374.252446 -228.118266) (xy 374.30206 -228.137738) (xy 374.348218 -228.164387)
			(xy 374.389889 -228.197618) (xy 374.426141 -228.236689) (xy 374.456165 -228.280726) (xy 374.479291 -228.328747)
			(xy 374.495001 -228.379677) (xy 374.502944 -228.432381) (xy 374.503442 -228.45903) (xy 374.502944 -228.485679)
			(xy 374.73127 -228.485679) (xy 374.73127 -228.432381) (xy 374.739213 -228.379677) (xy 374.754923 -228.328747)
			(xy 374.778049 -228.280726) (xy 374.808073 -228.236689) (xy 374.844325 -228.197618) (xy 374.885996 -228.164387)
			(xy 374.932154 -228.137738) (xy 374.981768 -228.118266) (xy 375.03373 -228.106406) (xy 375.08688 -228.102423)
			(xy 375.14003 -228.106406) (xy 375.191992 -228.118266) (xy 375.241606 -228.137738) (xy 375.287764 -228.164387)
			(xy 375.329435 -228.197618) (xy 375.365687 -228.236689) (xy 375.395711 -228.280726) (xy 375.418837 -228.328747)
			(xy 375.434547 -228.379677) (xy 375.44249 -228.432381) (xy 375.442988 -228.45903) (xy 375.44249 -228.485679)
			(xy 375.67107 -228.485679) (xy 375.67107 -228.432381) (xy 375.679013 -228.379677) (xy 375.694723 -228.328747)
			(xy 375.717849 -228.280726) (xy 375.747873 -228.236689) (xy 375.784125 -228.197618) (xy 375.825796 -228.164387)
			(xy 375.871954 -228.137738) (xy 375.921568 -228.118266) (xy 375.97353 -228.106406) (xy 376.02668 -228.102423)
			(xy 376.07983 -228.106406) (xy 376.131792 -228.118266) (xy 376.181406 -228.137738) (xy 376.227564 -228.164387)
			(xy 376.269235 -228.197618) (xy 376.305487 -228.236689) (xy 376.335511 -228.280726) (xy 376.358637 -228.328747)
			(xy 376.374347 -228.379677) (xy 376.38229 -228.432381) (xy 376.382788 -228.45903) (xy 376.38229 -228.485679)
			(xy 376.61087 -228.485679) (xy 376.61087 -228.432381) (xy 376.618813 -228.379677) (xy 376.634523 -228.328747)
			(xy 376.657649 -228.280726) (xy 376.687673 -228.236689) (xy 376.723925 -228.197618) (xy 376.765596 -228.164387)
			(xy 376.811754 -228.137738) (xy 376.861368 -228.118266) (xy 376.91333 -228.106406) (xy 376.96648 -228.102423)
			(xy 377.01963 -228.106406) (xy 377.071592 -228.118266) (xy 377.121206 -228.137738) (xy 377.167364 -228.164387)
			(xy 377.209035 -228.197618) (xy 377.245287 -228.236689) (xy 377.275311 -228.280726) (xy 377.298437 -228.328747)
			(xy 377.314147 -228.379677) (xy 377.32209 -228.432381) (xy 377.322588 -228.45903) (xy 377.32209 -228.485679)
			(xy 377.55067 -228.485679) (xy 377.55067 -228.432381) (xy 377.558613 -228.379677) (xy 377.574323 -228.328747)
			(xy 377.597449 -228.280726) (xy 377.627473 -228.236689) (xy 377.663725 -228.197618) (xy 377.705396 -228.164387)
			(xy 377.751554 -228.137738) (xy 377.801168 -228.118266) (xy 377.85313 -228.106406) (xy 377.90628 -228.102423)
			(xy 377.95943 -228.106406) (xy 378.011392 -228.118266) (xy 378.061006 -228.137738) (xy 378.107164 -228.164387)
			(xy 378.148835 -228.197618) (xy 378.185087 -228.236689) (xy 378.215111 -228.280726) (xy 378.238237 -228.328747)
			(xy 378.253947 -228.379677) (xy 378.26189 -228.432381) (xy 378.262388 -228.45903) (xy 378.26189 -228.485679)
			(xy 378.49047 -228.485679) (xy 378.49047 -228.432381) (xy 378.498413 -228.379677) (xy 378.514123 -228.328747)
			(xy 378.537249 -228.280726) (xy 378.567273 -228.236689) (xy 378.603525 -228.197618) (xy 378.645196 -228.164387)
			(xy 378.691354 -228.137738) (xy 378.740968 -228.118266) (xy 378.79293 -228.106406) (xy 378.84608 -228.102423)
			(xy 378.89923 -228.106406) (xy 378.951192 -228.118266) (xy 379.000806 -228.137738) (xy 379.046964 -228.164387)
			(xy 379.088635 -228.197618) (xy 379.124887 -228.236689) (xy 379.154911 -228.280726) (xy 379.178037 -228.328747)
			(xy 379.193747 -228.379677) (xy 379.20169 -228.432381) (xy 379.202188 -228.45903) (xy 379.20169 -228.485679)
			(xy 379.43027 -228.485679) (xy 379.43027 -228.432381) (xy 379.438213 -228.379677) (xy 379.453923 -228.328747)
			(xy 379.477049 -228.280726) (xy 379.507073 -228.236689) (xy 379.543325 -228.197618) (xy 379.584996 -228.164387)
			(xy 379.631154 -228.137738) (xy 379.680768 -228.118266) (xy 379.73273 -228.106406) (xy 379.78588 -228.102423)
			(xy 379.83903 -228.106406) (xy 379.890992 -228.118266) (xy 379.940606 -228.137738) (xy 379.986764 -228.164387)
			(xy 380.028435 -228.197618) (xy 380.064687 -228.236689) (xy 380.094711 -228.280726) (xy 380.117837 -228.328747)
			(xy 380.133547 -228.379677) (xy 380.14149 -228.432381) (xy 380.141988 -228.45903) (xy 380.14149 -228.485679)
			(xy 380.133547 -228.538383) (xy 380.117837 -228.589313) (xy 380.094711 -228.637334) (xy 380.064687 -228.681371)
			(xy 380.028435 -228.720442) (xy 379.986764 -228.753673) (xy 379.940606 -228.780322) (xy 379.890992 -228.799794)
			(xy 379.83903 -228.811654) (xy 379.78588 -228.815638) (xy 379.73273 -228.811654) (xy 379.680768 -228.799794)
			(xy 379.631154 -228.780322) (xy 379.584996 -228.753673) (xy 379.543325 -228.720442) (xy 379.507073 -228.681371)
			(xy 379.477049 -228.637334) (xy 379.453923 -228.589313) (xy 379.438213 -228.538383) (xy 379.43027 -228.485679)
			(xy 379.20169 -228.485679) (xy 379.193747 -228.538383) (xy 379.178037 -228.589313) (xy 379.154911 -228.637334)
			(xy 379.124887 -228.681371) (xy 379.088635 -228.720442) (xy 379.046964 -228.753673) (xy 379.000806 -228.780322)
			(xy 378.951192 -228.799794) (xy 378.89923 -228.811654) (xy 378.84608 -228.815638) (xy 378.79293 -228.811654)
			(xy 378.740968 -228.799794) (xy 378.691354 -228.780322) (xy 378.645196 -228.753673) (xy 378.603525 -228.720442)
			(xy 378.567273 -228.681371) (xy 378.537249 -228.637334) (xy 378.514123 -228.589313) (xy 378.498413 -228.538383)
			(xy 378.49047 -228.485679) (xy 378.26189 -228.485679) (xy 378.253947 -228.538383) (xy 378.238237 -228.589313)
			(xy 378.215111 -228.637334) (xy 378.185087 -228.681371) (xy 378.148835 -228.720442) (xy 378.107164 -228.753673)
			(xy 378.061006 -228.780322) (xy 378.011392 -228.799794) (xy 377.95943 -228.811654) (xy 377.90628 -228.815638)
			(xy 377.85313 -228.811654) (xy 377.801168 -228.799794) (xy 377.751554 -228.780322) (xy 377.705396 -228.753673)
			(xy 377.663725 -228.720442) (xy 377.627473 -228.681371) (xy 377.597449 -228.637334) (xy 377.574323 -228.589313)
			(xy 377.558613 -228.538383) (xy 377.55067 -228.485679) (xy 377.32209 -228.485679) (xy 377.314147 -228.538383)
			(xy 377.298437 -228.589313) (xy 377.275311 -228.637334) (xy 377.245287 -228.681371) (xy 377.209035 -228.720442)
			(xy 377.167364 -228.753673) (xy 377.121206 -228.780322) (xy 377.071592 -228.799794) (xy 377.01963 -228.811654)
			(xy 376.96648 -228.815638) (xy 376.91333 -228.811654) (xy 376.861368 -228.799794) (xy 376.811754 -228.780322)
			(xy 376.765596 -228.753673) (xy 376.723925 -228.720442) (xy 376.687673 -228.681371) (xy 376.657649 -228.637334)
			(xy 376.634523 -228.589313) (xy 376.618813 -228.538383) (xy 376.61087 -228.485679) (xy 376.38229 -228.485679)
			(xy 376.374347 -228.538383) (xy 376.358637 -228.589313) (xy 376.335511 -228.637334) (xy 376.305487 -228.681371)
			(xy 376.269235 -228.720442) (xy 376.227564 -228.753673) (xy 376.181406 -228.780322) (xy 376.131792 -228.799794)
			(xy 376.07983 -228.811654) (xy 376.02668 -228.815638) (xy 375.97353 -228.811654) (xy 375.921568 -228.799794)
			(xy 375.871954 -228.780322) (xy 375.825796 -228.753673) (xy 375.784125 -228.720442) (xy 375.747873 -228.681371)
			(xy 375.717849 -228.637334) (xy 375.694723 -228.589313) (xy 375.679013 -228.538383) (xy 375.67107 -228.485679)
			(xy 375.44249 -228.485679) (xy 375.434547 -228.538383) (xy 375.418837 -228.589313) (xy 375.395711 -228.637334)
			(xy 375.365687 -228.681371) (xy 375.329435 -228.720442) (xy 375.287764 -228.753673) (xy 375.241606 -228.780322)
			(xy 375.191992 -228.799794) (xy 375.14003 -228.811654) (xy 375.08688 -228.815638) (xy 375.03373 -228.811654)
			(xy 374.981768 -228.799794) (xy 374.932154 -228.780322) (xy 374.885996 -228.753673) (xy 374.844325 -228.720442)
			(xy 374.808073 -228.681371) (xy 374.778049 -228.637334) (xy 374.754923 -228.589313) (xy 374.739213 -228.538383)
			(xy 374.73127 -228.485679) (xy 374.502944 -228.485679) (xy 374.495001 -228.538383) (xy 374.479291 -228.589313)
			(xy 374.456165 -228.637334) (xy 374.426141 -228.681371) (xy 374.389889 -228.720442) (xy 374.348218 -228.753673)
			(xy 374.30206 -228.780322) (xy 374.252446 -228.799794) (xy 374.200484 -228.811654) (xy 374.147334 -228.815638)
			(xy 374.094184 -228.811654) (xy 374.042222 -228.799794) (xy 373.992608 -228.780322) (xy 373.94645 -228.753673)
			(xy 373.904779 -228.720442) (xy 373.868527 -228.681371) (xy 373.838503 -228.637334) (xy 373.815377 -228.589313)
			(xy 373.799667 -228.538383) (xy 373.791724 -228.485679) (xy 373.56289 -228.485679) (xy 373.554947 -228.538383)
			(xy 373.539237 -228.589313) (xy 373.516111 -228.637334) (xy 373.486087 -228.681371) (xy 373.449835 -228.720442)
			(xy 373.408164 -228.753673) (xy 373.362006 -228.780322) (xy 373.312392 -228.799794) (xy 373.26043 -228.811654)
			(xy 373.20728 -228.815638) (xy 373.15413 -228.811654) (xy 373.102168 -228.799794) (xy 373.052554 -228.780322)
			(xy 373.006396 -228.753673) (xy 372.964725 -228.720442) (xy 372.928473 -228.681371) (xy 372.898449 -228.637334)
			(xy 372.875323 -228.589313) (xy 372.859613 -228.538383) (xy 372.85167 -228.485679) (xy 372.62309 -228.485679)
			(xy 372.615147 -228.538383) (xy 372.599437 -228.589313) (xy 372.576311 -228.637334) (xy 372.546287 -228.681371)
			(xy 372.510035 -228.720442) (xy 372.468364 -228.753673) (xy 372.422206 -228.780322) (xy 372.372592 -228.799794)
			(xy 372.32063 -228.811654) (xy 372.26748 -228.815638) (xy 372.21433 -228.811654) (xy 372.162368 -228.799794)
			(xy 372.112754 -228.780322) (xy 372.066596 -228.753673) (xy 372.024925 -228.720442) (xy 371.988673 -228.681371)
			(xy 371.958649 -228.637334) (xy 371.935523 -228.589313) (xy 371.919813 -228.538383) (xy 371.91187 -228.485679)
			(xy 371.68329 -228.485679) (xy 371.675347 -228.538383) (xy 371.659637 -228.589313) (xy 371.636511 -228.637334)
			(xy 371.606487 -228.681371) (xy 371.570235 -228.720442) (xy 371.528564 -228.753673) (xy 371.482406 -228.780322)
			(xy 371.432792 -228.799794) (xy 371.38083 -228.811654) (xy 371.32768 -228.815638) (xy 371.27453 -228.811654)
			(xy 371.222568 -228.799794) (xy 371.172954 -228.780322) (xy 371.126796 -228.753673) (xy 371.085125 -228.720442)
			(xy 371.048873 -228.681371) (xy 371.018849 -228.637334) (xy 370.995723 -228.589313) (xy 370.980013 -228.538383)
			(xy 370.97207 -228.485679) (xy 370.74349 -228.485679) (xy 370.735547 -228.538383) (xy 370.719837 -228.589313)
			(xy 370.696711 -228.637334) (xy 370.666687 -228.681371) (xy 370.630435 -228.720442) (xy 370.588764 -228.753673)
			(xy 370.542606 -228.780322) (xy 370.492992 -228.799794) (xy 370.44103 -228.811654) (xy 370.38788 -228.815638)
			(xy 370.33473 -228.811654) (xy 370.282768 -228.799794) (xy 370.233154 -228.780322) (xy 370.186996 -228.753673)
			(xy 370.145325 -228.720442) (xy 370.109073 -228.681371) (xy 370.079049 -228.637334) (xy 370.055923 -228.589313)
			(xy 370.040213 -228.538383) (xy 370.03227 -228.485679) (xy 369.80369 -228.485679) (xy 369.795747 -228.538383)
			(xy 369.780037 -228.589313) (xy 369.756911 -228.637334) (xy 369.726887 -228.681371) (xy 369.690635 -228.720442)
			(xy 369.648964 -228.753673) (xy 369.602806 -228.780322) (xy 369.553192 -228.799794) (xy 369.50123 -228.811654)
			(xy 369.44808 -228.815638) (xy 369.39493 -228.811654) (xy 369.342968 -228.799794) (xy 369.293354 -228.780322)
			(xy 369.247196 -228.753673) (xy 369.205525 -228.720442) (xy 369.169273 -228.681371) (xy 369.139249 -228.637334)
			(xy 369.116123 -228.589313) (xy 369.100413 -228.538383) (xy 369.09247 -228.485679) (xy 368.86389 -228.485679)
			(xy 368.855947 -228.538383) (xy 368.840237 -228.589313) (xy 368.817111 -228.637334) (xy 368.787087 -228.681371)
			(xy 368.750835 -228.720442) (xy 368.709164 -228.753673) (xy 368.663006 -228.780322) (xy 368.613392 -228.799794)
			(xy 368.56143 -228.811654) (xy 368.50828 -228.815638) (xy 368.45513 -228.811654) (xy 368.403168 -228.799794)
			(xy 368.353554 -228.780322) (xy 368.307396 -228.753673) (xy 368.265725 -228.720442) (xy 368.229473 -228.681371)
			(xy 368.199449 -228.637334) (xy 368.176323 -228.589313) (xy 368.160613 -228.538383) (xy 368.15267 -228.485679)
			(xy 367.92409 -228.485679) (xy 367.916147 -228.538383) (xy 367.900437 -228.589313) (xy 367.877311 -228.637334)
			(xy 367.847287 -228.681371) (xy 367.811035 -228.720442) (xy 367.769364 -228.753673) (xy 367.723206 -228.780322)
			(xy 367.673592 -228.799794) (xy 367.62163 -228.811654) (xy 367.56848 -228.815638) (xy 367.51533 -228.811654)
			(xy 367.463368 -228.799794) (xy 367.413754 -228.780322) (xy 367.367596 -228.753673) (xy 367.325925 -228.720442)
			(xy 367.289673 -228.681371) (xy 367.259649 -228.637334) (xy 367.236523 -228.589313) (xy 367.220813 -228.538383)
			(xy 367.21287 -228.485679) (xy 366.98429 -228.485679) (xy 366.976347 -228.538383) (xy 366.960637 -228.589313)
			(xy 366.937511 -228.637334) (xy 366.907487 -228.681371) (xy 366.871235 -228.720442) (xy 366.829564 -228.753673)
			(xy 366.783406 -228.780322) (xy 366.733792 -228.799794) (xy 366.68183 -228.811654) (xy 366.62868 -228.815638)
			(xy 366.57553 -228.811654) (xy 366.523568 -228.799794) (xy 366.473954 -228.780322) (xy 366.427796 -228.753673)
			(xy 366.386125 -228.720442) (xy 366.349873 -228.681371) (xy 366.319849 -228.637334) (xy 366.296723 -228.589313)
			(xy 366.281013 -228.538383) (xy 366.27307 -228.485679) (xy 366.04449 -228.485679) (xy 366.036547 -228.538383)
			(xy 366.020837 -228.589313) (xy 365.997711 -228.637334) (xy 365.967687 -228.681371) (xy 365.931435 -228.720442)
			(xy 365.889764 -228.753673) (xy 365.843606 -228.780322) (xy 365.793992 -228.799794) (xy 365.74203 -228.811654)
			(xy 365.68888 -228.815638) (xy 365.63573 -228.811654) (xy 365.583768 -228.799794) (xy 365.534154 -228.780322)
			(xy 365.487996 -228.753673) (xy 365.446325 -228.720442) (xy 365.410073 -228.681371) (xy 365.380049 -228.637334)
			(xy 365.356923 -228.589313) (xy 365.341213 -228.538383) (xy 365.33327 -228.485679) (xy 365.10469 -228.485679)
			(xy 365.096747 -228.538383) (xy 365.081037 -228.589313) (xy 365.057911 -228.637334) (xy 365.027887 -228.681371)
			(xy 364.991635 -228.720442) (xy 364.949964 -228.753673) (xy 364.903806 -228.780322) (xy 364.854192 -228.799794)
			(xy 364.80223 -228.811654) (xy 364.74908 -228.815638) (xy 364.69593 -228.811654) (xy 364.643968 -228.799794)
			(xy 364.594354 -228.780322) (xy 364.548196 -228.753673) (xy 364.506525 -228.720442) (xy 364.470273 -228.681371)
			(xy 364.440249 -228.637334) (xy 364.417123 -228.589313) (xy 364.401413 -228.538383) (xy 364.39347 -228.485679)
			(xy 364.16489 -228.485679) (xy 364.156947 -228.538383) (xy 364.141237 -228.589313) (xy 364.118111 -228.637334)
			(xy 364.088087 -228.681371) (xy 364.051835 -228.720442) (xy 364.010164 -228.753673) (xy 363.964006 -228.780322)
			(xy 363.914392 -228.799794) (xy 363.86243 -228.811654) (xy 363.80928 -228.815638) (xy 363.75613 -228.811654)
			(xy 363.704168 -228.799794) (xy 363.654554 -228.780322) (xy 363.608396 -228.753673) (xy 363.566725 -228.720442)
			(xy 363.530473 -228.681371) (xy 363.500449 -228.637334) (xy 363.477323 -228.589313) (xy 363.461613 -228.538383)
			(xy 363.45367 -228.485679) (xy 363.22509 -228.485679) (xy 363.217147 -228.538383) (xy 363.201437 -228.589313)
			(xy 363.178311 -228.637334) (xy 363.148287 -228.681371) (xy 363.112035 -228.720442) (xy 363.070364 -228.753673)
			(xy 363.024206 -228.780322) (xy 362.974592 -228.799794) (xy 362.92263 -228.811654) (xy 362.86948 -228.815638)
			(xy 362.81633 -228.811654) (xy 362.764368 -228.799794) (xy 362.714754 -228.780322) (xy 362.668596 -228.753673)
			(xy 362.626925 -228.720442) (xy 362.590673 -228.681371) (xy 362.560649 -228.637334) (xy 362.537523 -228.589313)
			(xy 362.521813 -228.538383) (xy 362.51387 -228.485679) (xy 362.28529 -228.485679) (xy 362.277347 -228.538383)
			(xy 362.261637 -228.589313) (xy 362.238511 -228.637334) (xy 362.208487 -228.681371) (xy 362.172235 -228.720442)
			(xy 362.130564 -228.753673) (xy 362.084406 -228.780322) (xy 362.034792 -228.799794) (xy 361.98283 -228.811654)
			(xy 361.92968 -228.815638) (xy 361.87653 -228.811654) (xy 361.824568 -228.799794) (xy 361.774954 -228.780322)
			(xy 361.728796 -228.753673) (xy 361.687125 -228.720442) (xy 361.650873 -228.681371) (xy 361.620849 -228.637334)
			(xy 361.597723 -228.589313) (xy 361.582013 -228.538383) (xy 361.57407 -228.485679) (xy 361.34549 -228.485679)
			(xy 361.337547 -228.538383) (xy 361.321837 -228.589313) (xy 361.298711 -228.637334) (xy 361.268687 -228.681371)
			(xy 361.232435 -228.720442) (xy 361.190764 -228.753673) (xy 361.144606 -228.780322) (xy 361.094992 -228.799794)
			(xy 361.04303 -228.811654) (xy 360.98988 -228.815638) (xy 360.93673 -228.811654) (xy 360.884768 -228.799794)
			(xy 360.835154 -228.780322) (xy 360.788996 -228.753673) (xy 360.747325 -228.720442) (xy 360.711073 -228.681371)
			(xy 360.681049 -228.637334) (xy 360.657923 -228.589313) (xy 360.642213 -228.538383) (xy 360.63427 -228.485679)
			(xy 360.404703 -228.485679) (xy 360.402719 -228.512151) (xy 360.390858 -228.564114) (xy 360.371385 -228.613729)
			(xy 360.344734 -228.659887) (xy 360.311501 -228.701558) (xy 360.272429 -228.73781) (xy 360.228389 -228.767833)
			(xy 360.180367 -228.790957) (xy 360.129435 -228.806665) (xy 360.07673 -228.814606) (xy 360.05008 -228.815138)
			(xy 360.026458 -228.814376) (xy 360.01259 -228.813948) (xy 359.985454 -228.819671) (xy 359.960858 -228.832485)
			(xy 359.940618 -228.851445) (xy 359.926226 -228.875151) (xy 359.918743 -228.901856) (xy 359.918254 -228.915722)
			(xy 359.918254 -229.160578) (xy 359.92054 -229.167944) (xy 359.927888 -229.193545) (xy 359.93579 -229.246216)
			(xy 359.936288 -229.272846) (xy 359.935838 -229.29948) (xy 359.935836 -229.299495) (xy 360.164624 -229.299495)
			(xy 360.164624 -229.246197) (xy 360.172567 -229.193493) (xy 360.188277 -229.142563) (xy 360.211403 -229.094542)
			(xy 360.241427 -229.050505) (xy 360.277679 -229.011434) (xy 360.31935 -228.978203) (xy 360.365508 -228.951554)
			(xy 360.415122 -228.932082) (xy 360.467084 -228.920222) (xy 360.520234 -228.916239) (xy 360.573384 -228.920222)
			(xy 360.625346 -228.932082) (xy 360.67496 -228.951554) (xy 360.721118 -228.978203) (xy 360.762789 -229.011434)
			(xy 360.799041 -229.050505) (xy 360.829065 -229.094542) (xy 360.852191 -229.142563) (xy 360.867901 -229.193493)
			(xy 360.875844 -229.246197) (xy 360.876342 -229.272846) (xy 360.875844 -229.299495) (xy 361.104424 -229.299495)
			(xy 361.104424 -229.246197) (xy 361.112367 -229.193493) (xy 361.128077 -229.142563) (xy 361.151203 -229.094542)
			(xy 361.181227 -229.050505) (xy 361.217479 -229.011434) (xy 361.25915 -228.978203) (xy 361.305308 -228.951554)
			(xy 361.354922 -228.932082) (xy 361.406884 -228.920222) (xy 361.460034 -228.916239) (xy 361.513184 -228.920222)
			(xy 361.565146 -228.932082) (xy 361.61476 -228.951554) (xy 361.660918 -228.978203) (xy 361.702589 -229.011434)
			(xy 361.738841 -229.050505) (xy 361.768865 -229.094542) (xy 361.791991 -229.142563) (xy 361.807701 -229.193493)
			(xy 361.815644 -229.246197) (xy 361.816142 -229.272846) (xy 361.815644 -229.299495) (xy 362.044224 -229.299495)
			(xy 362.044224 -229.246197) (xy 362.052167 -229.193493) (xy 362.067877 -229.142563) (xy 362.091003 -229.094542)
			(xy 362.121027 -229.050505) (xy 362.157279 -229.011434) (xy 362.19895 -228.978203) (xy 362.245108 -228.951554)
			(xy 362.294722 -228.932082) (xy 362.346684 -228.920222) (xy 362.399834 -228.916239) (xy 362.452984 -228.920222)
			(xy 362.504946 -228.932082) (xy 362.55456 -228.951554) (xy 362.600718 -228.978203) (xy 362.642389 -229.011434)
			(xy 362.678641 -229.050505) (xy 362.708665 -229.094542) (xy 362.731791 -229.142563) (xy 362.747501 -229.193493)
			(xy 362.755444 -229.246197) (xy 362.755942 -229.272846) (xy 362.755444 -229.299495) (xy 362.984024 -229.299495)
			(xy 362.984024 -229.246197) (xy 362.991967 -229.193493) (xy 363.007677 -229.142563) (xy 363.030803 -229.094542)
			(xy 363.060827 -229.050505) (xy 363.097079 -229.011434) (xy 363.13875 -228.978203) (xy 363.184908 -228.951554)
			(xy 363.234522 -228.932082) (xy 363.286484 -228.920222) (xy 363.339634 -228.916239) (xy 363.392784 -228.920222)
			(xy 363.444746 -228.932082) (xy 363.49436 -228.951554) (xy 363.540518 -228.978203) (xy 363.582189 -229.011434)
			(xy 363.618441 -229.050505) (xy 363.648465 -229.094542) (xy 363.671591 -229.142563) (xy 363.687301 -229.193493)
			(xy 363.695244 -229.246197) (xy 363.695742 -229.272846) (xy 363.695244 -229.299495) (xy 363.923824 -229.299495)
			(xy 363.923824 -229.246197) (xy 363.931767 -229.193493) (xy 363.947477 -229.142563) (xy 363.970603 -229.094542)
			(xy 364.000627 -229.050505) (xy 364.036879 -229.011434) (xy 364.07855 -228.978203) (xy 364.124708 -228.951554)
			(xy 364.174322 -228.932082) (xy 364.226284 -228.920222) (xy 364.279434 -228.916239) (xy 364.332584 -228.920222)
			(xy 364.384546 -228.932082) (xy 364.43416 -228.951554) (xy 364.480318 -228.978203) (xy 364.521989 -229.011434)
			(xy 364.558241 -229.050505) (xy 364.588265 -229.094542) (xy 364.611391 -229.142563) (xy 364.627101 -229.193493)
			(xy 364.635044 -229.246197) (xy 364.635542 -229.272846) (xy 364.635044 -229.299495) (xy 364.863624 -229.299495)
			(xy 364.863624 -229.246197) (xy 364.871567 -229.193493) (xy 364.887277 -229.142563) (xy 364.910403 -229.094542)
			(xy 364.940427 -229.050505) (xy 364.976679 -229.011434) (xy 365.01835 -228.978203) (xy 365.064508 -228.951554)
			(xy 365.114122 -228.932082) (xy 365.166084 -228.920222) (xy 365.219234 -228.916239) (xy 365.272384 -228.920222)
			(xy 365.324346 -228.932082) (xy 365.37396 -228.951554) (xy 365.420118 -228.978203) (xy 365.461789 -229.011434)
			(xy 365.498041 -229.050505) (xy 365.528065 -229.094542) (xy 365.551191 -229.142563) (xy 365.566901 -229.193493)
			(xy 365.574844 -229.246197) (xy 365.575342 -229.272846) (xy 365.574844 -229.299495) (xy 365.803424 -229.299495)
			(xy 365.803424 -229.246197) (xy 365.811367 -229.193493) (xy 365.827077 -229.142563) (xy 365.850203 -229.094542)
			(xy 365.880227 -229.050505) (xy 365.916479 -229.011434) (xy 365.95815 -228.978203) (xy 366.004308 -228.951554)
			(xy 366.053922 -228.932082) (xy 366.105884 -228.920222) (xy 366.159034 -228.916239) (xy 366.212184 -228.920222)
			(xy 366.264146 -228.932082) (xy 366.31376 -228.951554) (xy 366.359918 -228.978203) (xy 366.401589 -229.011434)
			(xy 366.437841 -229.050505) (xy 366.467865 -229.094542) (xy 366.490991 -229.142563) (xy 366.506701 -229.193493)
			(xy 366.514644 -229.246197) (xy 366.515142 -229.272846) (xy 366.514644 -229.299495) (xy 366.743224 -229.299495)
			(xy 366.743224 -229.246197) (xy 366.751167 -229.193493) (xy 366.766877 -229.142563) (xy 366.790003 -229.094542)
			(xy 366.820027 -229.050505) (xy 366.856279 -229.011434) (xy 366.89795 -228.978203) (xy 366.944108 -228.951554)
			(xy 366.993722 -228.932082) (xy 367.045684 -228.920222) (xy 367.098834 -228.916239) (xy 367.151984 -228.920222)
			(xy 367.203946 -228.932082) (xy 367.25356 -228.951554) (xy 367.299718 -228.978203) (xy 367.341389 -229.011434)
			(xy 367.377641 -229.050505) (xy 367.407665 -229.094542) (xy 367.430791 -229.142563) (xy 367.446501 -229.193493)
			(xy 367.454444 -229.246197) (xy 367.454942 -229.272846) (xy 367.454444 -229.299495) (xy 367.683024 -229.299495)
			(xy 367.683024 -229.246197) (xy 367.690967 -229.193493) (xy 367.706677 -229.142563) (xy 367.729803 -229.094542)
			(xy 367.759827 -229.050505) (xy 367.796079 -229.011434) (xy 367.83775 -228.978203) (xy 367.883908 -228.951554)
			(xy 367.933522 -228.932082) (xy 367.985484 -228.920222) (xy 368.038634 -228.916239) (xy 368.091784 -228.920222)
			(xy 368.143746 -228.932082) (xy 368.19336 -228.951554) (xy 368.239518 -228.978203) (xy 368.281189 -229.011434)
			(xy 368.317441 -229.050505) (xy 368.347465 -229.094542) (xy 368.370591 -229.142563) (xy 368.386301 -229.193493)
			(xy 368.394244 -229.246197) (xy 368.394742 -229.272846) (xy 368.394244 -229.299495) (xy 368.622824 -229.299495)
			(xy 368.622824 -229.246197) (xy 368.630767 -229.193493) (xy 368.646477 -229.142563) (xy 368.669603 -229.094542)
			(xy 368.699627 -229.050505) (xy 368.735879 -229.011434) (xy 368.77755 -228.978203) (xy 368.823708 -228.951554)
			(xy 368.873322 -228.932082) (xy 368.925284 -228.920222) (xy 368.978434 -228.916239) (xy 369.031584 -228.920222)
			(xy 369.083546 -228.932082) (xy 369.13316 -228.951554) (xy 369.179318 -228.978203) (xy 369.220989 -229.011434)
			(xy 369.257241 -229.050505) (xy 369.287265 -229.094542) (xy 369.310391 -229.142563) (xy 369.326101 -229.193493)
			(xy 369.334044 -229.246197) (xy 369.334542 -229.272846) (xy 369.334044 -229.299495) (xy 369.562624 -229.299495)
			(xy 369.562624 -229.246197) (xy 369.570567 -229.193493) (xy 369.586277 -229.142563) (xy 369.609403 -229.094542)
			(xy 369.639427 -229.050505) (xy 369.675679 -229.011434) (xy 369.71735 -228.978203) (xy 369.763508 -228.951554)
			(xy 369.813122 -228.932082) (xy 369.865084 -228.920222) (xy 369.918234 -228.916239) (xy 369.971384 -228.920222)
			(xy 370.023346 -228.932082) (xy 370.07296 -228.951554) (xy 370.119118 -228.978203) (xy 370.160789 -229.011434)
			(xy 370.197041 -229.050505) (xy 370.227065 -229.094542) (xy 370.250191 -229.142563) (xy 370.265901 -229.193493)
			(xy 370.273844 -229.246197) (xy 370.274342 -229.272846) (xy 370.273844 -229.299495) (xy 370.50217 -229.299495)
			(xy 370.50217 -229.246197) (xy 370.510113 -229.193493) (xy 370.525823 -229.142563) (xy 370.548949 -229.094542)
			(xy 370.578973 -229.050505) (xy 370.615225 -229.011434) (xy 370.656896 -228.978203) (xy 370.703054 -228.951554)
			(xy 370.752668 -228.932082) (xy 370.80463 -228.920222) (xy 370.85778 -228.916239) (xy 370.91093 -228.920222)
			(xy 370.962892 -228.932082) (xy 371.012506 -228.951554) (xy 371.058664 -228.978203) (xy 371.100335 -229.011434)
			(xy 371.136587 -229.050505) (xy 371.166611 -229.094542) (xy 371.189737 -229.142563) (xy 371.205447 -229.193493)
			(xy 371.21339 -229.246197) (xy 371.213888 -229.272846) (xy 371.21339 -229.299495) (xy 371.442224 -229.299495)
			(xy 371.442224 -229.246197) (xy 371.450167 -229.193493) (xy 371.465877 -229.142563) (xy 371.489003 -229.094542)
			(xy 371.519027 -229.050505) (xy 371.555279 -229.011434) (xy 371.59695 -228.978203) (xy 371.643108 -228.951554)
			(xy 371.692722 -228.932082) (xy 371.744684 -228.920222) (xy 371.797834 -228.916239) (xy 371.850984 -228.920222)
			(xy 371.902946 -228.932082) (xy 371.95256 -228.951554) (xy 371.998718 -228.978203) (xy 372.040389 -229.011434)
			(xy 372.076641 -229.050505) (xy 372.106665 -229.094542) (xy 372.129791 -229.142563) (xy 372.145501 -229.193493)
			(xy 372.153444 -229.246197) (xy 372.153942 -229.272846) (xy 372.153444 -229.299495) (xy 372.382024 -229.299495)
			(xy 372.382024 -229.246197) (xy 372.389967 -229.193493) (xy 372.405677 -229.142563) (xy 372.428803 -229.094542)
			(xy 372.458827 -229.050505) (xy 372.495079 -229.011434) (xy 372.53675 -228.978203) (xy 372.582908 -228.951554)
			(xy 372.632522 -228.932082) (xy 372.684484 -228.920222) (xy 372.737634 -228.916239) (xy 372.790784 -228.920222)
			(xy 372.842746 -228.932082) (xy 372.89236 -228.951554) (xy 372.938518 -228.978203) (xy 372.980189 -229.011434)
			(xy 373.016441 -229.050505) (xy 373.046465 -229.094542) (xy 373.069591 -229.142563) (xy 373.085301 -229.193493)
			(xy 373.093244 -229.246197) (xy 373.093742 -229.272846) (xy 373.093244 -229.299495) (xy 373.321824 -229.299495)
			(xy 373.321824 -229.246197) (xy 373.329767 -229.193493) (xy 373.345477 -229.142563) (xy 373.368603 -229.094542)
			(xy 373.398627 -229.050505) (xy 373.434879 -229.011434) (xy 373.47655 -228.978203) (xy 373.522708 -228.951554)
			(xy 373.572322 -228.932082) (xy 373.624284 -228.920222) (xy 373.677434 -228.916239) (xy 373.730584 -228.920222)
			(xy 373.782546 -228.932082) (xy 373.83216 -228.951554) (xy 373.878318 -228.978203) (xy 373.919989 -229.011434)
			(xy 373.956241 -229.050505) (xy 373.986265 -229.094542) (xy 374.009391 -229.142563) (xy 374.025101 -229.193493)
			(xy 374.033044 -229.246197) (xy 374.033542 -229.272846) (xy 374.033044 -229.299495) (xy 374.261624 -229.299495)
			(xy 374.261624 -229.246197) (xy 374.269567 -229.193493) (xy 374.285277 -229.142563) (xy 374.308403 -229.094542)
			(xy 374.338427 -229.050505) (xy 374.374679 -229.011434) (xy 374.41635 -228.978203) (xy 374.462508 -228.951554)
			(xy 374.512122 -228.932082) (xy 374.564084 -228.920222) (xy 374.617234 -228.916239) (xy 374.670384 -228.920222)
			(xy 374.722346 -228.932082) (xy 374.77196 -228.951554) (xy 374.818118 -228.978203) (xy 374.859789 -229.011434)
			(xy 374.896041 -229.050505) (xy 374.926065 -229.094542) (xy 374.949191 -229.142563) (xy 374.964901 -229.193493)
			(xy 374.972844 -229.246197) (xy 374.973342 -229.272846) (xy 374.972844 -229.299495) (xy 375.201424 -229.299495)
			(xy 375.201424 -229.246197) (xy 375.209367 -229.193493) (xy 375.225077 -229.142563) (xy 375.248203 -229.094542)
			(xy 375.278227 -229.050505) (xy 375.314479 -229.011434) (xy 375.35615 -228.978203) (xy 375.402308 -228.951554)
			(xy 375.451922 -228.932082) (xy 375.503884 -228.920222) (xy 375.557034 -228.916239) (xy 375.610184 -228.920222)
			(xy 375.662146 -228.932082) (xy 375.71176 -228.951554) (xy 375.757918 -228.978203) (xy 375.799589 -229.011434)
			(xy 375.835841 -229.050505) (xy 375.865865 -229.094542) (xy 375.888991 -229.142563) (xy 375.904701 -229.193493)
			(xy 375.912644 -229.246197) (xy 375.913142 -229.272846) (xy 375.912644 -229.299495) (xy 376.141224 -229.299495)
			(xy 376.141224 -229.246197) (xy 376.149167 -229.193493) (xy 376.164877 -229.142563) (xy 376.188003 -229.094542)
			(xy 376.218027 -229.050505) (xy 376.254279 -229.011434) (xy 376.29595 -228.978203) (xy 376.342108 -228.951554)
			(xy 376.391722 -228.932082) (xy 376.443684 -228.920222) (xy 376.496834 -228.916239) (xy 376.549984 -228.920222)
			(xy 376.601946 -228.932082) (xy 376.65156 -228.951554) (xy 376.697718 -228.978203) (xy 376.739389 -229.011434)
			(xy 376.775641 -229.050505) (xy 376.805665 -229.094542) (xy 376.828791 -229.142563) (xy 376.844501 -229.193493)
			(xy 376.852444 -229.246197) (xy 376.852942 -229.272846) (xy 376.852444 -229.299495) (xy 377.08077 -229.299495)
			(xy 377.08077 -229.246197) (xy 377.088713 -229.193493) (xy 377.104423 -229.142563) (xy 377.127549 -229.094542)
			(xy 377.157573 -229.050505) (xy 377.193825 -229.011434) (xy 377.235496 -228.978203) (xy 377.281654 -228.951554)
			(xy 377.331268 -228.932082) (xy 377.38323 -228.920222) (xy 377.43638 -228.916239) (xy 377.48953 -228.920222)
			(xy 377.541492 -228.932082) (xy 377.591106 -228.951554) (xy 377.637264 -228.978203) (xy 377.678935 -229.011434)
			(xy 377.715187 -229.050505) (xy 377.745211 -229.094542) (xy 377.768337 -229.142563) (xy 377.784047 -229.193493)
			(xy 377.79199 -229.246197) (xy 377.792488 -229.272846) (xy 377.79199 -229.299495) (xy 378.020824 -229.299495)
			(xy 378.020824 -229.246197) (xy 378.028767 -229.193493) (xy 378.044477 -229.142563) (xy 378.067603 -229.094542)
			(xy 378.097627 -229.050505) (xy 378.133879 -229.011434) (xy 378.17555 -228.978203) (xy 378.221708 -228.951554)
			(xy 378.271322 -228.932082) (xy 378.323284 -228.920222) (xy 378.376434 -228.916239) (xy 378.429584 -228.920222)
			(xy 378.481546 -228.932082) (xy 378.53116 -228.951554) (xy 378.577318 -228.978203) (xy 378.618989 -229.011434)
			(xy 378.655241 -229.050505) (xy 378.685265 -229.094542) (xy 378.708391 -229.142563) (xy 378.724101 -229.193493)
			(xy 378.732044 -229.246197) (xy 378.732542 -229.272846) (xy 378.732044 -229.299495) (xy 378.960624 -229.299495)
			(xy 378.960624 -229.246197) (xy 378.968567 -229.193493) (xy 378.984277 -229.142563) (xy 379.007403 -229.094542)
			(xy 379.037427 -229.050505) (xy 379.073679 -229.011434) (xy 379.11535 -228.978203) (xy 379.161508 -228.951554)
			(xy 379.211122 -228.932082) (xy 379.263084 -228.920222) (xy 379.316234 -228.916239) (xy 379.369384 -228.920222)
			(xy 379.421346 -228.932082) (xy 379.47096 -228.951554) (xy 379.517118 -228.978203) (xy 379.558789 -229.011434)
			(xy 379.595041 -229.050505) (xy 379.625065 -229.094542) (xy 379.648191 -229.142563) (xy 379.663901 -229.193493)
			(xy 379.671844 -229.246197) (xy 379.672342 -229.272846) (xy 379.671844 -229.299495) (xy 379.900424 -229.299495)
			(xy 379.900424 -229.246197) (xy 379.908367 -229.193493) (xy 379.924077 -229.142563) (xy 379.947203 -229.094542)
			(xy 379.977227 -229.050505) (xy 380.013479 -229.011434) (xy 380.05515 -228.978203) (xy 380.101308 -228.951554)
			(xy 380.150922 -228.932082) (xy 380.202884 -228.920222) (xy 380.256034 -228.916239) (xy 380.309184 -228.920222)
			(xy 380.361146 -228.932082) (xy 380.41076 -228.951554) (xy 380.456918 -228.978203) (xy 380.498589 -229.011434)
			(xy 380.534841 -229.050505) (xy 380.564865 -229.094542) (xy 380.587991 -229.142563) (xy 380.603701 -229.193493)
			(xy 380.611644 -229.246197) (xy 380.612142 -229.272846) (xy 380.611644 -229.299495) (xy 380.603701 -229.352199)
			(xy 380.587991 -229.403129) (xy 380.564865 -229.45115) (xy 380.534841 -229.495187) (xy 380.498589 -229.534258)
			(xy 380.456918 -229.567489) (xy 380.41076 -229.594138) (xy 380.361146 -229.61361) (xy 380.309184 -229.62547)
			(xy 380.256034 -229.629454) (xy 380.202884 -229.62547) (xy 380.150922 -229.61361) (xy 380.101308 -229.594138)
			(xy 380.05515 -229.567489) (xy 380.013479 -229.534258) (xy 379.977227 -229.495187) (xy 379.947203 -229.45115)
			(xy 379.924077 -229.403129) (xy 379.908367 -229.352199) (xy 379.900424 -229.299495) (xy 379.671844 -229.299495)
			(xy 379.663901 -229.352199) (xy 379.648191 -229.403129) (xy 379.625065 -229.45115) (xy 379.595041 -229.495187)
			(xy 379.558789 -229.534258) (xy 379.517118 -229.567489) (xy 379.47096 -229.594138) (xy 379.421346 -229.61361)
			(xy 379.369384 -229.62547) (xy 379.316234 -229.629454) (xy 379.263084 -229.62547) (xy 379.211122 -229.61361)
			(xy 379.161508 -229.594138) (xy 379.11535 -229.567489) (xy 379.073679 -229.534258) (xy 379.037427 -229.495187)
			(xy 379.007403 -229.45115) (xy 378.984277 -229.403129) (xy 378.968567 -229.352199) (xy 378.960624 -229.299495)
			(xy 378.732044 -229.299495) (xy 378.724101 -229.352199) (xy 378.708391 -229.403129) (xy 378.685265 -229.45115)
			(xy 378.655241 -229.495187) (xy 378.618989 -229.534258) (xy 378.577318 -229.567489) (xy 378.53116 -229.594138)
			(xy 378.481546 -229.61361) (xy 378.429584 -229.62547) (xy 378.376434 -229.629454) (xy 378.323284 -229.62547)
			(xy 378.271322 -229.61361) (xy 378.221708 -229.594138) (xy 378.17555 -229.567489) (xy 378.133879 -229.534258)
			(xy 378.097627 -229.495187) (xy 378.067603 -229.45115) (xy 378.044477 -229.403129) (xy 378.028767 -229.352199)
			(xy 378.020824 -229.299495) (xy 377.79199 -229.299495) (xy 377.784047 -229.352199) (xy 377.768337 -229.403129)
			(xy 377.745211 -229.45115) (xy 377.715187 -229.495187) (xy 377.678935 -229.534258) (xy 377.637264 -229.567489)
			(xy 377.591106 -229.594138) (xy 377.541492 -229.61361) (xy 377.48953 -229.62547) (xy 377.43638 -229.629454)
			(xy 377.38323 -229.62547) (xy 377.331268 -229.61361) (xy 377.281654 -229.594138) (xy 377.235496 -229.567489)
			(xy 377.193825 -229.534258) (xy 377.157573 -229.495187) (xy 377.127549 -229.45115) (xy 377.104423 -229.403129)
			(xy 377.088713 -229.352199) (xy 377.08077 -229.299495) (xy 376.852444 -229.299495) (xy 376.844501 -229.352199)
			(xy 376.828791 -229.403129) (xy 376.805665 -229.45115) (xy 376.775641 -229.495187) (xy 376.739389 -229.534258)
			(xy 376.697718 -229.567489) (xy 376.65156 -229.594138) (xy 376.601946 -229.61361) (xy 376.549984 -229.62547)
			(xy 376.496834 -229.629454) (xy 376.443684 -229.62547) (xy 376.391722 -229.61361) (xy 376.342108 -229.594138)
			(xy 376.29595 -229.567489) (xy 376.254279 -229.534258) (xy 376.218027 -229.495187) (xy 376.188003 -229.45115)
			(xy 376.164877 -229.403129) (xy 376.149167 -229.352199) (xy 376.141224 -229.299495) (xy 375.912644 -229.299495)
			(xy 375.904701 -229.352199) (xy 375.888991 -229.403129) (xy 375.865865 -229.45115) (xy 375.835841 -229.495187)
			(xy 375.799589 -229.534258) (xy 375.757918 -229.567489) (xy 375.71176 -229.594138) (xy 375.662146 -229.61361)
			(xy 375.610184 -229.62547) (xy 375.557034 -229.629454) (xy 375.503884 -229.62547) (xy 375.451922 -229.61361)
			(xy 375.402308 -229.594138) (xy 375.35615 -229.567489) (xy 375.314479 -229.534258) (xy 375.278227 -229.495187)
			(xy 375.248203 -229.45115) (xy 375.225077 -229.403129) (xy 375.209367 -229.352199) (xy 375.201424 -229.299495)
			(xy 374.972844 -229.299495) (xy 374.964901 -229.352199) (xy 374.949191 -229.403129) (xy 374.926065 -229.45115)
			(xy 374.896041 -229.495187) (xy 374.859789 -229.534258) (xy 374.818118 -229.567489) (xy 374.77196 -229.594138)
			(xy 374.722346 -229.61361) (xy 374.670384 -229.62547) (xy 374.617234 -229.629454) (xy 374.564084 -229.62547)
			(xy 374.512122 -229.61361) (xy 374.462508 -229.594138) (xy 374.41635 -229.567489) (xy 374.374679 -229.534258)
			(xy 374.338427 -229.495187) (xy 374.308403 -229.45115) (xy 374.285277 -229.403129) (xy 374.269567 -229.352199)
			(xy 374.261624 -229.299495) (xy 374.033044 -229.299495) (xy 374.025101 -229.352199) (xy 374.009391 -229.403129)
			(xy 373.986265 -229.45115) (xy 373.956241 -229.495187) (xy 373.919989 -229.534258) (xy 373.878318 -229.567489)
			(xy 373.83216 -229.594138) (xy 373.782546 -229.61361) (xy 373.730584 -229.62547) (xy 373.677434 -229.629454)
			(xy 373.624284 -229.62547) (xy 373.572322 -229.61361) (xy 373.522708 -229.594138) (xy 373.47655 -229.567489)
			(xy 373.434879 -229.534258) (xy 373.398627 -229.495187) (xy 373.368603 -229.45115) (xy 373.345477 -229.403129)
			(xy 373.329767 -229.352199) (xy 373.321824 -229.299495) (xy 373.093244 -229.299495) (xy 373.085301 -229.352199)
			(xy 373.069591 -229.403129) (xy 373.046465 -229.45115) (xy 373.016441 -229.495187) (xy 372.980189 -229.534258)
			(xy 372.938518 -229.567489) (xy 372.89236 -229.594138) (xy 372.842746 -229.61361) (xy 372.790784 -229.62547)
			(xy 372.737634 -229.629454) (xy 372.684484 -229.62547) (xy 372.632522 -229.61361) (xy 372.582908 -229.594138)
			(xy 372.53675 -229.567489) (xy 372.495079 -229.534258) (xy 372.458827 -229.495187) (xy 372.428803 -229.45115)
			(xy 372.405677 -229.403129) (xy 372.389967 -229.352199) (xy 372.382024 -229.299495) (xy 372.153444 -229.299495)
			(xy 372.145501 -229.352199) (xy 372.129791 -229.403129) (xy 372.106665 -229.45115) (xy 372.076641 -229.495187)
			(xy 372.040389 -229.534258) (xy 371.998718 -229.567489) (xy 371.95256 -229.594138) (xy 371.902946 -229.61361)
			(xy 371.850984 -229.62547) (xy 371.797834 -229.629454) (xy 371.744684 -229.62547) (xy 371.692722 -229.61361)
			(xy 371.643108 -229.594138) (xy 371.59695 -229.567489) (xy 371.555279 -229.534258) (xy 371.519027 -229.495187)
			(xy 371.489003 -229.45115) (xy 371.465877 -229.403129) (xy 371.450167 -229.352199) (xy 371.442224 -229.299495)
			(xy 371.21339 -229.299495) (xy 371.205447 -229.352199) (xy 371.189737 -229.403129) (xy 371.166611 -229.45115)
			(xy 371.136587 -229.495187) (xy 371.100335 -229.534258) (xy 371.058664 -229.567489) (xy 371.012506 -229.594138)
			(xy 370.962892 -229.61361) (xy 370.91093 -229.62547) (xy 370.85778 -229.629454) (xy 370.80463 -229.62547)
			(xy 370.752668 -229.61361) (xy 370.703054 -229.594138) (xy 370.656896 -229.567489) (xy 370.615225 -229.534258)
			(xy 370.578973 -229.495187) (xy 370.548949 -229.45115) (xy 370.525823 -229.403129) (xy 370.510113 -229.352199)
			(xy 370.50217 -229.299495) (xy 370.273844 -229.299495) (xy 370.265901 -229.352199) (xy 370.250191 -229.403129)
			(xy 370.227065 -229.45115) (xy 370.197041 -229.495187) (xy 370.160789 -229.534258) (xy 370.119118 -229.567489)
			(xy 370.07296 -229.594138) (xy 370.023346 -229.61361) (xy 369.971384 -229.62547) (xy 369.918234 -229.629454)
			(xy 369.865084 -229.62547) (xy 369.813122 -229.61361) (xy 369.763508 -229.594138) (xy 369.71735 -229.567489)
			(xy 369.675679 -229.534258) (xy 369.639427 -229.495187) (xy 369.609403 -229.45115) (xy 369.586277 -229.403129)
			(xy 369.570567 -229.352199) (xy 369.562624 -229.299495) (xy 369.334044 -229.299495) (xy 369.326101 -229.352199)
			(xy 369.310391 -229.403129) (xy 369.287265 -229.45115) (xy 369.257241 -229.495187) (xy 369.220989 -229.534258)
			(xy 369.179318 -229.567489) (xy 369.13316 -229.594138) (xy 369.083546 -229.61361) (xy 369.031584 -229.62547)
			(xy 368.978434 -229.629454) (xy 368.925284 -229.62547) (xy 368.873322 -229.61361) (xy 368.823708 -229.594138)
			(xy 368.77755 -229.567489) (xy 368.735879 -229.534258) (xy 368.699627 -229.495187) (xy 368.669603 -229.45115)
			(xy 368.646477 -229.403129) (xy 368.630767 -229.352199) (xy 368.622824 -229.299495) (xy 368.394244 -229.299495)
			(xy 368.386301 -229.352199) (xy 368.370591 -229.403129) (xy 368.347465 -229.45115) (xy 368.317441 -229.495187)
			(xy 368.281189 -229.534258) (xy 368.239518 -229.567489) (xy 368.19336 -229.594138) (xy 368.143746 -229.61361)
			(xy 368.091784 -229.62547) (xy 368.038634 -229.629454) (xy 367.985484 -229.62547) (xy 367.933522 -229.61361)
			(xy 367.883908 -229.594138) (xy 367.83775 -229.567489) (xy 367.796079 -229.534258) (xy 367.759827 -229.495187)
			(xy 367.729803 -229.45115) (xy 367.706677 -229.403129) (xy 367.690967 -229.352199) (xy 367.683024 -229.299495)
			(xy 367.454444 -229.299495) (xy 367.446501 -229.352199) (xy 367.430791 -229.403129) (xy 367.407665 -229.45115)
			(xy 367.377641 -229.495187) (xy 367.341389 -229.534258) (xy 367.299718 -229.567489) (xy 367.25356 -229.594138)
			(xy 367.203946 -229.61361) (xy 367.151984 -229.62547) (xy 367.098834 -229.629454) (xy 367.045684 -229.62547)
			(xy 366.993722 -229.61361) (xy 366.944108 -229.594138) (xy 366.89795 -229.567489) (xy 366.856279 -229.534258)
			(xy 366.820027 -229.495187) (xy 366.790003 -229.45115) (xy 366.766877 -229.403129) (xy 366.751167 -229.352199)
			(xy 366.743224 -229.299495) (xy 366.514644 -229.299495) (xy 366.506701 -229.352199) (xy 366.490991 -229.403129)
			(xy 366.467865 -229.45115) (xy 366.437841 -229.495187) (xy 366.401589 -229.534258) (xy 366.359918 -229.567489)
			(xy 366.31376 -229.594138) (xy 366.264146 -229.61361) (xy 366.212184 -229.62547) (xy 366.159034 -229.629454)
			(xy 366.105884 -229.62547) (xy 366.053922 -229.61361) (xy 366.004308 -229.594138) (xy 365.95815 -229.567489)
			(xy 365.916479 -229.534258) (xy 365.880227 -229.495187) (xy 365.850203 -229.45115) (xy 365.827077 -229.403129)
			(xy 365.811367 -229.352199) (xy 365.803424 -229.299495) (xy 365.574844 -229.299495) (xy 365.566901 -229.352199)
			(xy 365.551191 -229.403129) (xy 365.528065 -229.45115) (xy 365.498041 -229.495187) (xy 365.461789 -229.534258)
			(xy 365.420118 -229.567489) (xy 365.37396 -229.594138) (xy 365.324346 -229.61361) (xy 365.272384 -229.62547)
			(xy 365.219234 -229.629454) (xy 365.166084 -229.62547) (xy 365.114122 -229.61361) (xy 365.064508 -229.594138)
			(xy 365.01835 -229.567489) (xy 364.976679 -229.534258) (xy 364.940427 -229.495187) (xy 364.910403 -229.45115)
			(xy 364.887277 -229.403129) (xy 364.871567 -229.352199) (xy 364.863624 -229.299495) (xy 364.635044 -229.299495)
			(xy 364.627101 -229.352199) (xy 364.611391 -229.403129) (xy 364.588265 -229.45115) (xy 364.558241 -229.495187)
			(xy 364.521989 -229.534258) (xy 364.480318 -229.567489) (xy 364.43416 -229.594138) (xy 364.384546 -229.61361)
			(xy 364.332584 -229.62547) (xy 364.279434 -229.629454) (xy 364.226284 -229.62547) (xy 364.174322 -229.61361)
			(xy 364.124708 -229.594138) (xy 364.07855 -229.567489) (xy 364.036879 -229.534258) (xy 364.000627 -229.495187)
			(xy 363.970603 -229.45115) (xy 363.947477 -229.403129) (xy 363.931767 -229.352199) (xy 363.923824 -229.299495)
			(xy 363.695244 -229.299495) (xy 363.687301 -229.352199) (xy 363.671591 -229.403129) (xy 363.648465 -229.45115)
			(xy 363.618441 -229.495187) (xy 363.582189 -229.534258) (xy 363.540518 -229.567489) (xy 363.49436 -229.594138)
			(xy 363.444746 -229.61361) (xy 363.392784 -229.62547) (xy 363.339634 -229.629454) (xy 363.286484 -229.62547)
			(xy 363.234522 -229.61361) (xy 363.184908 -229.594138) (xy 363.13875 -229.567489) (xy 363.097079 -229.534258)
			(xy 363.060827 -229.495187) (xy 363.030803 -229.45115) (xy 363.007677 -229.403129) (xy 362.991967 -229.352199)
			(xy 362.984024 -229.299495) (xy 362.755444 -229.299495) (xy 362.747501 -229.352199) (xy 362.731791 -229.403129)
			(xy 362.708665 -229.45115) (xy 362.678641 -229.495187) (xy 362.642389 -229.534258) (xy 362.600718 -229.567489)
			(xy 362.55456 -229.594138) (xy 362.504946 -229.61361) (xy 362.452984 -229.62547) (xy 362.399834 -229.629454)
			(xy 362.346684 -229.62547) (xy 362.294722 -229.61361) (xy 362.245108 -229.594138) (xy 362.19895 -229.567489)
			(xy 362.157279 -229.534258) (xy 362.121027 -229.495187) (xy 362.091003 -229.45115) (xy 362.067877 -229.403129)
			(xy 362.052167 -229.352199) (xy 362.044224 -229.299495) (xy 361.815644 -229.299495) (xy 361.807701 -229.352199)
			(xy 361.791991 -229.403129) (xy 361.768865 -229.45115) (xy 361.738841 -229.495187) (xy 361.702589 -229.534258)
			(xy 361.660918 -229.567489) (xy 361.61476 -229.594138) (xy 361.565146 -229.61361) (xy 361.513184 -229.62547)
			(xy 361.460034 -229.629454) (xy 361.406884 -229.62547) (xy 361.354922 -229.61361) (xy 361.305308 -229.594138)
			(xy 361.25915 -229.567489) (xy 361.217479 -229.534258) (xy 361.181227 -229.495187) (xy 361.151203 -229.45115)
			(xy 361.128077 -229.403129) (xy 361.112367 -229.352199) (xy 361.104424 -229.299495) (xy 360.875844 -229.299495)
			(xy 360.867901 -229.352199) (xy 360.852191 -229.403129) (xy 360.829065 -229.45115) (xy 360.799041 -229.495187)
			(xy 360.762789 -229.534258) (xy 360.721118 -229.567489) (xy 360.67496 -229.594138) (xy 360.625346 -229.61361)
			(xy 360.573384 -229.62547) (xy 360.520234 -229.629454) (xy 360.467084 -229.62547) (xy 360.415122 -229.61361)
			(xy 360.365508 -229.594138) (xy 360.31935 -229.567489) (xy 360.277679 -229.534258) (xy 360.241427 -229.495187)
			(xy 360.211403 -229.45115) (xy 360.188277 -229.403129) (xy 360.172567 -229.352199) (xy 360.164624 -229.299495)
			(xy 359.935836 -229.299495) (xy 359.927932 -229.352157) (xy 359.92054 -229.377748) (xy 359.918254 -229.385114)
			(xy 359.918254 -229.62997) (xy 359.918679 -229.643869) (xy 359.926171 -229.670639) (xy 359.940609 -229.694394)
			(xy 359.96092 -229.713373) (xy 359.9856 -229.726168) (xy 360.012815 -229.731829) (xy 360.026712 -229.731316)
			(xy 360.050334 -229.730554) (xy 360.076984 -229.731054) (xy 360.12969 -229.739003) (xy 360.180621 -229.754718)
			(xy 360.228642 -229.777847) (xy 360.27268 -229.807875) (xy 360.311751 -229.844131) (xy 360.344982 -229.885805)
			(xy 360.371631 -229.931966) (xy 360.391103 -229.981583) (xy 360.402963 -230.033548) (xy 360.406946 -230.0867)
			(xy 360.404952 -230.113311) (xy 360.634524 -230.113311) (xy 360.634524 -230.060013) (xy 360.642467 -230.007309)
			(xy 360.658177 -229.956379) (xy 360.681303 -229.908358) (xy 360.711327 -229.864321) (xy 360.747579 -229.82525)
			(xy 360.78925 -229.792019) (xy 360.835408 -229.76537) (xy 360.885022 -229.745898) (xy 360.936984 -229.734038)
			(xy 360.990134 -229.730055) (xy 361.043284 -229.734038) (xy 361.095246 -229.745898) (xy 361.14486 -229.76537)
			(xy 361.191018 -229.792019) (xy 361.232689 -229.82525) (xy 361.268941 -229.864321) (xy 361.298965 -229.908358)
			(xy 361.322091 -229.956379) (xy 361.337801 -230.007309) (xy 361.345744 -230.060013) (xy 361.346242 -230.086662)
			(xy 361.345744 -230.113311) (xy 361.574324 -230.113311) (xy 361.574324 -230.060013) (xy 361.582267 -230.007309)
			(xy 361.597977 -229.956379) (xy 361.621103 -229.908358) (xy 361.651127 -229.864321) (xy 361.687379 -229.82525)
			(xy 361.72905 -229.792019) (xy 361.775208 -229.76537) (xy 361.824822 -229.745898) (xy 361.876784 -229.734038)
			(xy 361.929934 -229.730055) (xy 361.983084 -229.734038) (xy 362.035046 -229.745898) (xy 362.08466 -229.76537)
			(xy 362.130818 -229.792019) (xy 362.172489 -229.82525) (xy 362.208741 -229.864321) (xy 362.238765 -229.908358)
			(xy 362.261891 -229.956379) (xy 362.277601 -230.007309) (xy 362.285544 -230.060013) (xy 362.286042 -230.086662)
			(xy 362.285544 -230.113311) (xy 362.514124 -230.113311) (xy 362.514124 -230.060013) (xy 362.522067 -230.007309)
			(xy 362.537777 -229.956379) (xy 362.560903 -229.908358) (xy 362.590927 -229.864321) (xy 362.627179 -229.82525)
			(xy 362.66885 -229.792019) (xy 362.715008 -229.76537) (xy 362.764622 -229.745898) (xy 362.816584 -229.734038)
			(xy 362.869734 -229.730055) (xy 362.922884 -229.734038) (xy 362.974846 -229.745898) (xy 363.02446 -229.76537)
			(xy 363.070618 -229.792019) (xy 363.112289 -229.82525) (xy 363.148541 -229.864321) (xy 363.178565 -229.908358)
			(xy 363.201691 -229.956379) (xy 363.217401 -230.007309) (xy 363.225344 -230.060013) (xy 363.225842 -230.086662)
			(xy 363.225344 -230.113311) (xy 363.45367 -230.113311) (xy 363.45367 -230.060013) (xy 363.461613 -230.007309)
			(xy 363.477323 -229.956379) (xy 363.500449 -229.908358) (xy 363.530473 -229.864321) (xy 363.566725 -229.82525)
			(xy 363.608396 -229.792019) (xy 363.654554 -229.76537) (xy 363.704168 -229.745898) (xy 363.75613 -229.734038)
			(xy 363.80928 -229.730055) (xy 363.86243 -229.734038) (xy 363.914392 -229.745898) (xy 363.964006 -229.76537)
			(xy 364.010164 -229.792019) (xy 364.051835 -229.82525) (xy 364.088087 -229.864321) (xy 364.118111 -229.908358)
			(xy 364.141237 -229.956379) (xy 364.156947 -230.007309) (xy 364.16489 -230.060013) (xy 364.165388 -230.086662)
			(xy 364.16489 -230.113311) (xy 364.39347 -230.113311) (xy 364.39347 -230.060013) (xy 364.401413 -230.007309)
			(xy 364.417123 -229.956379) (xy 364.440249 -229.908358) (xy 364.470273 -229.864321) (xy 364.506525 -229.82525)
			(xy 364.548196 -229.792019) (xy 364.594354 -229.76537) (xy 364.643968 -229.745898) (xy 364.69593 -229.734038)
			(xy 364.74908 -229.730055) (xy 364.80223 -229.734038) (xy 364.854192 -229.745898) (xy 364.903806 -229.76537)
			(xy 364.949964 -229.792019) (xy 364.991635 -229.82525) (xy 365.027887 -229.864321) (xy 365.057911 -229.908358)
			(xy 365.081037 -229.956379) (xy 365.096747 -230.007309) (xy 365.10469 -230.060013) (xy 365.105188 -230.086662)
			(xy 365.10469 -230.113311) (xy 365.33327 -230.113311) (xy 365.33327 -230.060013) (xy 365.341213 -230.007309)
			(xy 365.356923 -229.956379) (xy 365.380049 -229.908358) (xy 365.410073 -229.864321) (xy 365.446325 -229.82525)
			(xy 365.487996 -229.792019) (xy 365.534154 -229.76537) (xy 365.583768 -229.745898) (xy 365.63573 -229.734038)
			(xy 365.68888 -229.730055) (xy 365.74203 -229.734038) (xy 365.793992 -229.745898) (xy 365.843606 -229.76537)
			(xy 365.889764 -229.792019) (xy 365.931435 -229.82525) (xy 365.967687 -229.864321) (xy 365.997711 -229.908358)
			(xy 366.020837 -229.956379) (xy 366.036547 -230.007309) (xy 366.04449 -230.060013) (xy 366.044988 -230.086662)
			(xy 366.04449 -230.113311) (xy 366.27307 -230.113311) (xy 366.27307 -230.060013) (xy 366.281013 -230.007309)
			(xy 366.296723 -229.956379) (xy 366.319849 -229.908358) (xy 366.349873 -229.864321) (xy 366.386125 -229.82525)
			(xy 366.427796 -229.792019) (xy 366.473954 -229.76537) (xy 366.523568 -229.745898) (xy 366.57553 -229.734038)
			(xy 366.62868 -229.730055) (xy 366.68183 -229.734038) (xy 366.733792 -229.745898) (xy 366.783406 -229.76537)
			(xy 366.829564 -229.792019) (xy 366.871235 -229.82525) (xy 366.907487 -229.864321) (xy 366.937511 -229.908358)
			(xy 366.960637 -229.956379) (xy 366.976347 -230.007309) (xy 366.98429 -230.060013) (xy 366.984788 -230.086662)
			(xy 366.98429 -230.113311) (xy 367.21287 -230.113311) (xy 367.21287 -230.060013) (xy 367.220813 -230.007309)
			(xy 367.236523 -229.956379) (xy 367.259649 -229.908358) (xy 367.289673 -229.864321) (xy 367.325925 -229.82525)
			(xy 367.367596 -229.792019) (xy 367.413754 -229.76537) (xy 367.463368 -229.745898) (xy 367.51533 -229.734038)
			(xy 367.56848 -229.730055) (xy 367.62163 -229.734038) (xy 367.673592 -229.745898) (xy 367.723206 -229.76537)
			(xy 367.769364 -229.792019) (xy 367.811035 -229.82525) (xy 367.847287 -229.864321) (xy 367.877311 -229.908358)
			(xy 367.900437 -229.956379) (xy 367.916147 -230.007309) (xy 367.92409 -230.060013) (xy 367.924588 -230.086662)
			(xy 367.92409 -230.113311) (xy 368.15267 -230.113311) (xy 368.15267 -230.060013) (xy 368.160613 -230.007309)
			(xy 368.176323 -229.956379) (xy 368.199449 -229.908358) (xy 368.229473 -229.864321) (xy 368.265725 -229.82525)
			(xy 368.307396 -229.792019) (xy 368.353554 -229.76537) (xy 368.403168 -229.745898) (xy 368.45513 -229.734038)
			(xy 368.50828 -229.730055) (xy 368.56143 -229.734038) (xy 368.613392 -229.745898) (xy 368.663006 -229.76537)
			(xy 368.709164 -229.792019) (xy 368.750835 -229.82525) (xy 368.787087 -229.864321) (xy 368.817111 -229.908358)
			(xy 368.840237 -229.956379) (xy 368.855947 -230.007309) (xy 368.86389 -230.060013) (xy 368.864388 -230.086662)
			(xy 368.86389 -230.113311) (xy 369.09247 -230.113311) (xy 369.09247 -230.060013) (xy 369.100413 -230.007309)
			(xy 369.116123 -229.956379) (xy 369.139249 -229.908358) (xy 369.169273 -229.864321) (xy 369.205525 -229.82525)
			(xy 369.247196 -229.792019) (xy 369.293354 -229.76537) (xy 369.342968 -229.745898) (xy 369.39493 -229.734038)
			(xy 369.44808 -229.730055) (xy 369.50123 -229.734038) (xy 369.553192 -229.745898) (xy 369.602806 -229.76537)
			(xy 369.648964 -229.792019) (xy 369.690635 -229.82525) (xy 369.726887 -229.864321) (xy 369.756911 -229.908358)
			(xy 369.780037 -229.956379) (xy 369.795747 -230.007309) (xy 369.80369 -230.060013) (xy 369.804188 -230.086662)
			(xy 369.80369 -230.113311) (xy 370.03227 -230.113311) (xy 370.03227 -230.060013) (xy 370.040213 -230.007309)
			(xy 370.055923 -229.956379) (xy 370.079049 -229.908358) (xy 370.109073 -229.864321) (xy 370.145325 -229.82525)
			(xy 370.186996 -229.792019) (xy 370.233154 -229.76537) (xy 370.282768 -229.745898) (xy 370.33473 -229.734038)
			(xy 370.38788 -229.730055) (xy 370.44103 -229.734038) (xy 370.492992 -229.745898) (xy 370.542606 -229.76537)
			(xy 370.588764 -229.792019) (xy 370.630435 -229.82525) (xy 370.666687 -229.864321) (xy 370.696711 -229.908358)
			(xy 370.719837 -229.956379) (xy 370.735547 -230.007309) (xy 370.74349 -230.060013) (xy 370.743988 -230.086662)
			(xy 370.74349 -230.113311) (xy 370.97207 -230.113311) (xy 370.97207 -230.060013) (xy 370.980013 -230.007309)
			(xy 370.995723 -229.956379) (xy 371.018849 -229.908358) (xy 371.048873 -229.864321) (xy 371.085125 -229.82525)
			(xy 371.126796 -229.792019) (xy 371.172954 -229.76537) (xy 371.222568 -229.745898) (xy 371.27453 -229.734038)
			(xy 371.32768 -229.730055) (xy 371.38083 -229.734038) (xy 371.432792 -229.745898) (xy 371.482406 -229.76537)
			(xy 371.528564 -229.792019) (xy 371.570235 -229.82525) (xy 371.606487 -229.864321) (xy 371.636511 -229.908358)
			(xy 371.659637 -229.956379) (xy 371.675347 -230.007309) (xy 371.68329 -230.060013) (xy 371.683788 -230.086662)
			(xy 371.68329 -230.113311) (xy 371.91187 -230.113311) (xy 371.91187 -230.060013) (xy 371.919813 -230.007309)
			(xy 371.935523 -229.956379) (xy 371.958649 -229.908358) (xy 371.988673 -229.864321) (xy 372.024925 -229.82525)
			(xy 372.066596 -229.792019) (xy 372.112754 -229.76537) (xy 372.162368 -229.745898) (xy 372.21433 -229.734038)
			(xy 372.26748 -229.730055) (xy 372.32063 -229.734038) (xy 372.372592 -229.745898) (xy 372.422206 -229.76537)
			(xy 372.468364 -229.792019) (xy 372.510035 -229.82525) (xy 372.546287 -229.864321) (xy 372.576311 -229.908358)
			(xy 372.599437 -229.956379) (xy 372.615147 -230.007309) (xy 372.62309 -230.060013) (xy 372.623588 -230.086662)
			(xy 372.62309 -230.113311) (xy 372.851924 -230.113311) (xy 372.851924 -230.060013) (xy 372.859867 -230.007309)
			(xy 372.875577 -229.956379) (xy 372.898703 -229.908358) (xy 372.928727 -229.864321) (xy 372.964979 -229.82525)
			(xy 373.00665 -229.792019) (xy 373.052808 -229.76537) (xy 373.102422 -229.745898) (xy 373.154384 -229.734038)
			(xy 373.207534 -229.730055) (xy 373.260684 -229.734038) (xy 373.312646 -229.745898) (xy 373.36226 -229.76537)
			(xy 373.408418 -229.792019) (xy 373.450089 -229.82525) (xy 373.486341 -229.864321) (xy 373.516365 -229.908358)
			(xy 373.539491 -229.956379) (xy 373.555201 -230.007309) (xy 373.563144 -230.060013) (xy 373.563642 -230.086662)
			(xy 373.563144 -230.113311) (xy 373.79147 -230.113311) (xy 373.79147 -230.060013) (xy 373.799413 -230.007309)
			(xy 373.815123 -229.956379) (xy 373.838249 -229.908358) (xy 373.868273 -229.864321) (xy 373.904525 -229.82525)
			(xy 373.946196 -229.792019) (xy 373.992354 -229.76537) (xy 374.041968 -229.745898) (xy 374.09393 -229.734038)
			(xy 374.14708 -229.730055) (xy 374.20023 -229.734038) (xy 374.252192 -229.745898) (xy 374.301806 -229.76537)
			(xy 374.347964 -229.792019) (xy 374.389635 -229.82525) (xy 374.425887 -229.864321) (xy 374.455911 -229.908358)
			(xy 374.479037 -229.956379) (xy 374.494747 -230.007309) (xy 374.50269 -230.060013) (xy 374.503188 -230.086662)
			(xy 374.50269 -230.113311) (xy 374.73127 -230.113311) (xy 374.73127 -230.060013) (xy 374.739213 -230.007309)
			(xy 374.754923 -229.956379) (xy 374.778049 -229.908358) (xy 374.808073 -229.864321) (xy 374.844325 -229.82525)
			(xy 374.885996 -229.792019) (xy 374.932154 -229.76537) (xy 374.981768 -229.745898) (xy 375.03373 -229.734038)
			(xy 375.08688 -229.730055) (xy 375.14003 -229.734038) (xy 375.191992 -229.745898) (xy 375.241606 -229.76537)
			(xy 375.287764 -229.792019) (xy 375.329435 -229.82525) (xy 375.365687 -229.864321) (xy 375.395711 -229.908358)
			(xy 375.418837 -229.956379) (xy 375.434547 -230.007309) (xy 375.44249 -230.060013) (xy 375.442988 -230.086662)
			(xy 375.44249 -230.113311) (xy 375.67107 -230.113311) (xy 375.67107 -230.060013) (xy 375.679013 -230.007309)
			(xy 375.694723 -229.956379) (xy 375.717849 -229.908358) (xy 375.747873 -229.864321) (xy 375.784125 -229.82525)
			(xy 375.825796 -229.792019) (xy 375.871954 -229.76537) (xy 375.921568 -229.745898) (xy 375.97353 -229.734038)
			(xy 376.02668 -229.730055) (xy 376.07983 -229.734038) (xy 376.131792 -229.745898) (xy 376.181406 -229.76537)
			(xy 376.227564 -229.792019) (xy 376.269235 -229.82525) (xy 376.305487 -229.864321) (xy 376.335511 -229.908358)
			(xy 376.358637 -229.956379) (xy 376.374347 -230.007309) (xy 376.38229 -230.060013) (xy 376.382788 -230.086662)
			(xy 376.38229 -230.113311) (xy 376.61087 -230.113311) (xy 376.61087 -230.060013) (xy 376.618813 -230.007309)
			(xy 376.634523 -229.956379) (xy 376.657649 -229.908358) (xy 376.687673 -229.864321) (xy 376.723925 -229.82525)
			(xy 376.765596 -229.792019) (xy 376.811754 -229.76537) (xy 376.861368 -229.745898) (xy 376.91333 -229.734038)
			(xy 376.96648 -229.730055) (xy 377.01963 -229.734038) (xy 377.071592 -229.745898) (xy 377.121206 -229.76537)
			(xy 377.167364 -229.792019) (xy 377.209035 -229.82525) (xy 377.245287 -229.864321) (xy 377.275311 -229.908358)
			(xy 377.298437 -229.956379) (xy 377.314147 -230.007309) (xy 377.32209 -230.060013) (xy 377.322588 -230.086662)
			(xy 377.32209 -230.113311) (xy 377.55067 -230.113311) (xy 377.55067 -230.060013) (xy 377.558613 -230.007309)
			(xy 377.574323 -229.956379) (xy 377.597449 -229.908358) (xy 377.627473 -229.864321) (xy 377.663725 -229.82525)
			(xy 377.705396 -229.792019) (xy 377.751554 -229.76537) (xy 377.801168 -229.745898) (xy 377.85313 -229.734038)
			(xy 377.90628 -229.730055) (xy 377.95943 -229.734038) (xy 378.011392 -229.745898) (xy 378.061006 -229.76537)
			(xy 378.107164 -229.792019) (xy 378.148835 -229.82525) (xy 378.185087 -229.864321) (xy 378.215111 -229.908358)
			(xy 378.238237 -229.956379) (xy 378.253947 -230.007309) (xy 378.26189 -230.060013) (xy 378.262388 -230.086662)
			(xy 378.26189 -230.113311) (xy 378.49047 -230.113311) (xy 378.49047 -230.060013) (xy 378.498413 -230.007309)
			(xy 378.514123 -229.956379) (xy 378.537249 -229.908358) (xy 378.567273 -229.864321) (xy 378.603525 -229.82525)
			(xy 378.645196 -229.792019) (xy 378.691354 -229.76537) (xy 378.740968 -229.745898) (xy 378.79293 -229.734038)
			(xy 378.84608 -229.730055) (xy 378.89923 -229.734038) (xy 378.951192 -229.745898) (xy 379.000806 -229.76537)
			(xy 379.046964 -229.792019) (xy 379.088635 -229.82525) (xy 379.124887 -229.864321) (xy 379.154911 -229.908358)
			(xy 379.178037 -229.956379) (xy 379.193747 -230.007309) (xy 379.20169 -230.060013) (xy 379.202188 -230.086662)
			(xy 379.20169 -230.113311) (xy 379.430524 -230.113311) (xy 379.430524 -230.060013) (xy 379.438467 -230.007309)
			(xy 379.454177 -229.956379) (xy 379.477303 -229.908358) (xy 379.507327 -229.864321) (xy 379.543579 -229.82525)
			(xy 379.58525 -229.792019) (xy 379.631408 -229.76537) (xy 379.681022 -229.745898) (xy 379.732984 -229.734038)
			(xy 379.786134 -229.730055) (xy 379.839284 -229.734038) (xy 379.891246 -229.745898) (xy 379.94086 -229.76537)
			(xy 379.987018 -229.792019) (xy 380.028689 -229.82525) (xy 380.064941 -229.864321) (xy 380.094965 -229.908358)
			(xy 380.118091 -229.956379) (xy 380.133801 -230.007309) (xy 380.141744 -230.060013) (xy 380.142242 -230.086662)
			(xy 380.141744 -230.113311) (xy 380.133801 -230.166015) (xy 380.118091 -230.216945) (xy 380.094965 -230.264966)
			(xy 380.064941 -230.309003) (xy 380.028689 -230.348074) (xy 379.987018 -230.381305) (xy 379.94086 -230.407954)
			(xy 379.891246 -230.427426) (xy 379.839284 -230.439286) (xy 379.786134 -230.44327) (xy 379.732984 -230.439286)
			(xy 379.681022 -230.427426) (xy 379.631408 -230.407954) (xy 379.58525 -230.381305) (xy 379.543579 -230.348074)
			(xy 379.507327 -230.309003) (xy 379.477303 -230.264966) (xy 379.454177 -230.216945) (xy 379.438467 -230.166015)
			(xy 379.430524 -230.113311) (xy 379.20169 -230.113311) (xy 379.193747 -230.166015) (xy 379.178037 -230.216945)
			(xy 379.154911 -230.264966) (xy 379.124887 -230.309003) (xy 379.088635 -230.348074) (xy 379.046964 -230.381305)
			(xy 379.000806 -230.407954) (xy 378.951192 -230.427426) (xy 378.89923 -230.439286) (xy 378.84608 -230.44327)
			(xy 378.79293 -230.439286) (xy 378.740968 -230.427426) (xy 378.691354 -230.407954) (xy 378.645196 -230.381305)
			(xy 378.603525 -230.348074) (xy 378.567273 -230.309003) (xy 378.537249 -230.264966) (xy 378.514123 -230.216945)
			(xy 378.498413 -230.166015) (xy 378.49047 -230.113311) (xy 378.26189 -230.113311) (xy 378.253947 -230.166015)
			(xy 378.238237 -230.216945) (xy 378.215111 -230.264966) (xy 378.185087 -230.309003) (xy 378.148835 -230.348074)
			(xy 378.107164 -230.381305) (xy 378.061006 -230.407954) (xy 378.011392 -230.427426) (xy 377.95943 -230.439286)
			(xy 377.90628 -230.44327) (xy 377.85313 -230.439286) (xy 377.801168 -230.427426) (xy 377.751554 -230.407954)
			(xy 377.705396 -230.381305) (xy 377.663725 -230.348074) (xy 377.627473 -230.309003) (xy 377.597449 -230.264966)
			(xy 377.574323 -230.216945) (xy 377.558613 -230.166015) (xy 377.55067 -230.113311) (xy 377.32209 -230.113311)
			(xy 377.314147 -230.166015) (xy 377.298437 -230.216945) (xy 377.275311 -230.264966) (xy 377.245287 -230.309003)
			(xy 377.209035 -230.348074) (xy 377.167364 -230.381305) (xy 377.121206 -230.407954) (xy 377.071592 -230.427426)
			(xy 377.01963 -230.439286) (xy 376.96648 -230.44327) (xy 376.91333 -230.439286) (xy 376.861368 -230.427426)
			(xy 376.811754 -230.407954) (xy 376.765596 -230.381305) (xy 376.723925 -230.348074) (xy 376.687673 -230.309003)
			(xy 376.657649 -230.264966) (xy 376.634523 -230.216945) (xy 376.618813 -230.166015) (xy 376.61087 -230.113311)
			(xy 376.38229 -230.113311) (xy 376.374347 -230.166015) (xy 376.358637 -230.216945) (xy 376.335511 -230.264966)
			(xy 376.305487 -230.309003) (xy 376.269235 -230.348074) (xy 376.227564 -230.381305) (xy 376.181406 -230.407954)
			(xy 376.131792 -230.427426) (xy 376.07983 -230.439286) (xy 376.02668 -230.44327) (xy 375.97353 -230.439286)
			(xy 375.921568 -230.427426) (xy 375.871954 -230.407954) (xy 375.825796 -230.381305) (xy 375.784125 -230.348074)
			(xy 375.747873 -230.309003) (xy 375.717849 -230.264966) (xy 375.694723 -230.216945) (xy 375.679013 -230.166015)
			(xy 375.67107 -230.113311) (xy 375.44249 -230.113311) (xy 375.434547 -230.166015) (xy 375.418837 -230.216945)
			(xy 375.395711 -230.264966) (xy 375.365687 -230.309003) (xy 375.329435 -230.348074) (xy 375.287764 -230.381305)
			(xy 375.241606 -230.407954) (xy 375.191992 -230.427426) (xy 375.14003 -230.439286) (xy 375.08688 -230.44327)
			(xy 375.03373 -230.439286) (xy 374.981768 -230.427426) (xy 374.932154 -230.407954) (xy 374.885996 -230.381305)
			(xy 374.844325 -230.348074) (xy 374.808073 -230.309003) (xy 374.778049 -230.264966) (xy 374.754923 -230.216945)
			(xy 374.739213 -230.166015) (xy 374.73127 -230.113311) (xy 374.50269 -230.113311) (xy 374.494747 -230.166015)
			(xy 374.479037 -230.216945) (xy 374.455911 -230.264966) (xy 374.425887 -230.309003) (xy 374.389635 -230.348074)
			(xy 374.347964 -230.381305) (xy 374.301806 -230.407954) (xy 374.252192 -230.427426) (xy 374.20023 -230.439286)
			(xy 374.14708 -230.44327) (xy 374.09393 -230.439286) (xy 374.041968 -230.427426) (xy 373.992354 -230.407954)
			(xy 373.946196 -230.381305) (xy 373.904525 -230.348074) (xy 373.868273 -230.309003) (xy 373.838249 -230.264966)
			(xy 373.815123 -230.216945) (xy 373.799413 -230.166015) (xy 373.79147 -230.113311) (xy 373.563144 -230.113311)
			(xy 373.555201 -230.166015) (xy 373.539491 -230.216945) (xy 373.516365 -230.264966) (xy 373.486341 -230.309003)
			(xy 373.450089 -230.348074) (xy 373.408418 -230.381305) (xy 373.36226 -230.407954) (xy 373.312646 -230.427426)
			(xy 373.260684 -230.439286) (xy 373.207534 -230.44327) (xy 373.154384 -230.439286) (xy 373.102422 -230.427426)
			(xy 373.052808 -230.407954) (xy 373.00665 -230.381305) (xy 372.964979 -230.348074) (xy 372.928727 -230.309003)
			(xy 372.898703 -230.264966) (xy 372.875577 -230.216945) (xy 372.859867 -230.166015) (xy 372.851924 -230.113311)
			(xy 372.62309 -230.113311) (xy 372.615147 -230.166015) (xy 372.599437 -230.216945) (xy 372.576311 -230.264966)
			(xy 372.546287 -230.309003) (xy 372.510035 -230.348074) (xy 372.468364 -230.381305) (xy 372.422206 -230.407954)
			(xy 372.372592 -230.427426) (xy 372.32063 -230.439286) (xy 372.26748 -230.44327) (xy 372.21433 -230.439286)
			(xy 372.162368 -230.427426) (xy 372.112754 -230.407954) (xy 372.066596 -230.381305) (xy 372.024925 -230.348074)
			(xy 371.988673 -230.309003) (xy 371.958649 -230.264966) (xy 371.935523 -230.216945) (xy 371.919813 -230.166015)
			(xy 371.91187 -230.113311) (xy 371.68329 -230.113311) (xy 371.675347 -230.166015) (xy 371.659637 -230.216945)
			(xy 371.636511 -230.264966) (xy 371.606487 -230.309003) (xy 371.570235 -230.348074) (xy 371.528564 -230.381305)
			(xy 371.482406 -230.407954) (xy 371.432792 -230.427426) (xy 371.38083 -230.439286) (xy 371.32768 -230.44327)
			(xy 371.27453 -230.439286) (xy 371.222568 -230.427426) (xy 371.172954 -230.407954) (xy 371.126796 -230.381305)
			(xy 371.085125 -230.348074) (xy 371.048873 -230.309003) (xy 371.018849 -230.264966) (xy 370.995723 -230.216945)
			(xy 370.980013 -230.166015) (xy 370.97207 -230.113311) (xy 370.74349 -230.113311) (xy 370.735547 -230.166015)
			(xy 370.719837 -230.216945) (xy 370.696711 -230.264966) (xy 370.666687 -230.309003) (xy 370.630435 -230.348074)
			(xy 370.588764 -230.381305) (xy 370.542606 -230.407954) (xy 370.492992 -230.427426) (xy 370.44103 -230.439286)
			(xy 370.38788 -230.44327) (xy 370.33473 -230.439286) (xy 370.282768 -230.427426) (xy 370.233154 -230.407954)
			(xy 370.186996 -230.381305) (xy 370.145325 -230.348074) (xy 370.109073 -230.309003) (xy 370.079049 -230.264966)
			(xy 370.055923 -230.216945) (xy 370.040213 -230.166015) (xy 370.03227 -230.113311) (xy 369.80369 -230.113311)
			(xy 369.795747 -230.166015) (xy 369.780037 -230.216945) (xy 369.756911 -230.264966) (xy 369.726887 -230.309003)
			(xy 369.690635 -230.348074) (xy 369.648964 -230.381305) (xy 369.602806 -230.407954) (xy 369.553192 -230.427426)
			(xy 369.50123 -230.439286) (xy 369.44808 -230.44327) (xy 369.39493 -230.439286) (xy 369.342968 -230.427426)
			(xy 369.293354 -230.407954) (xy 369.247196 -230.381305) (xy 369.205525 -230.348074) (xy 369.169273 -230.309003)
			(xy 369.139249 -230.264966) (xy 369.116123 -230.216945) (xy 369.100413 -230.166015) (xy 369.09247 -230.113311)
			(xy 368.86389 -230.113311) (xy 368.855947 -230.166015) (xy 368.840237 -230.216945) (xy 368.817111 -230.264966)
			(xy 368.787087 -230.309003) (xy 368.750835 -230.348074) (xy 368.709164 -230.381305) (xy 368.663006 -230.407954)
			(xy 368.613392 -230.427426) (xy 368.56143 -230.439286) (xy 368.50828 -230.44327) (xy 368.45513 -230.439286)
			(xy 368.403168 -230.427426) (xy 368.353554 -230.407954) (xy 368.307396 -230.381305) (xy 368.265725 -230.348074)
			(xy 368.229473 -230.309003) (xy 368.199449 -230.264966) (xy 368.176323 -230.216945) (xy 368.160613 -230.166015)
			(xy 368.15267 -230.113311) (xy 367.92409 -230.113311) (xy 367.916147 -230.166015) (xy 367.900437 -230.216945)
			(xy 367.877311 -230.264966) (xy 367.847287 -230.309003) (xy 367.811035 -230.348074) (xy 367.769364 -230.381305)
			(xy 367.723206 -230.407954) (xy 367.673592 -230.427426) (xy 367.62163 -230.439286) (xy 367.56848 -230.44327)
			(xy 367.51533 -230.439286) (xy 367.463368 -230.427426) (xy 367.413754 -230.407954) (xy 367.367596 -230.381305)
			(xy 367.325925 -230.348074) (xy 367.289673 -230.309003) (xy 367.259649 -230.264966) (xy 367.236523 -230.216945)
			(xy 367.220813 -230.166015) (xy 367.21287 -230.113311) (xy 366.98429 -230.113311) (xy 366.976347 -230.166015)
			(xy 366.960637 -230.216945) (xy 366.937511 -230.264966) (xy 366.907487 -230.309003) (xy 366.871235 -230.348074)
			(xy 366.829564 -230.381305) (xy 366.783406 -230.407954) (xy 366.733792 -230.427426) (xy 366.68183 -230.439286)
			(xy 366.62868 -230.44327) (xy 366.57553 -230.439286) (xy 366.523568 -230.427426) (xy 366.473954 -230.407954)
			(xy 366.427796 -230.381305) (xy 366.386125 -230.348074) (xy 366.349873 -230.309003) (xy 366.319849 -230.264966)
			(xy 366.296723 -230.216945) (xy 366.281013 -230.166015) (xy 366.27307 -230.113311) (xy 366.04449 -230.113311)
			(xy 366.036547 -230.166015) (xy 366.020837 -230.216945) (xy 365.997711 -230.264966) (xy 365.967687 -230.309003)
			(xy 365.931435 -230.348074) (xy 365.889764 -230.381305) (xy 365.843606 -230.407954) (xy 365.793992 -230.427426)
			(xy 365.74203 -230.439286) (xy 365.68888 -230.44327) (xy 365.63573 -230.439286) (xy 365.583768 -230.427426)
			(xy 365.534154 -230.407954) (xy 365.487996 -230.381305) (xy 365.446325 -230.348074) (xy 365.410073 -230.309003)
			(xy 365.380049 -230.264966) (xy 365.356923 -230.216945) (xy 365.341213 -230.166015) (xy 365.33327 -230.113311)
			(xy 365.10469 -230.113311) (xy 365.096747 -230.166015) (xy 365.081037 -230.216945) (xy 365.057911 -230.264966)
			(xy 365.027887 -230.309003) (xy 364.991635 -230.348074) (xy 364.949964 -230.381305) (xy 364.903806 -230.407954)
			(xy 364.854192 -230.427426) (xy 364.80223 -230.439286) (xy 364.74908 -230.44327) (xy 364.69593 -230.439286)
			(xy 364.643968 -230.427426) (xy 364.594354 -230.407954) (xy 364.548196 -230.381305) (xy 364.506525 -230.348074)
			(xy 364.470273 -230.309003) (xy 364.440249 -230.264966) (xy 364.417123 -230.216945) (xy 364.401413 -230.166015)
			(xy 364.39347 -230.113311) (xy 364.16489 -230.113311) (xy 364.156947 -230.166015) (xy 364.141237 -230.216945)
			(xy 364.118111 -230.264966) (xy 364.088087 -230.309003) (xy 364.051835 -230.348074) (xy 364.010164 -230.381305)
			(xy 363.964006 -230.407954) (xy 363.914392 -230.427426) (xy 363.86243 -230.439286) (xy 363.80928 -230.44327)
			(xy 363.75613 -230.439286) (xy 363.704168 -230.427426) (xy 363.654554 -230.407954) (xy 363.608396 -230.381305)
			(xy 363.566725 -230.348074) (xy 363.530473 -230.309003) (xy 363.500449 -230.264966) (xy 363.477323 -230.216945)
			(xy 363.461613 -230.166015) (xy 363.45367 -230.113311) (xy 363.225344 -230.113311) (xy 363.217401 -230.166015)
			(xy 363.201691 -230.216945) (xy 363.178565 -230.264966) (xy 363.148541 -230.309003) (xy 363.112289 -230.348074)
			(xy 363.070618 -230.381305) (xy 363.02446 -230.407954) (xy 362.974846 -230.427426) (xy 362.922884 -230.439286)
			(xy 362.869734 -230.44327) (xy 362.816584 -230.439286) (xy 362.764622 -230.427426) (xy 362.715008 -230.407954)
			(xy 362.66885 -230.381305) (xy 362.627179 -230.348074) (xy 362.590927 -230.309003) (xy 362.560903 -230.264966)
			(xy 362.537777 -230.216945) (xy 362.522067 -230.166015) (xy 362.514124 -230.113311) (xy 362.285544 -230.113311)
			(xy 362.277601 -230.166015) (xy 362.261891 -230.216945) (xy 362.238765 -230.264966) (xy 362.208741 -230.309003)
			(xy 362.172489 -230.348074) (xy 362.130818 -230.381305) (xy 362.08466 -230.407954) (xy 362.035046 -230.427426)
			(xy 361.983084 -230.439286) (xy 361.929934 -230.44327) (xy 361.876784 -230.439286) (xy 361.824822 -230.427426)
			(xy 361.775208 -230.407954) (xy 361.72905 -230.381305) (xy 361.687379 -230.348074) (xy 361.651127 -230.309003)
			(xy 361.621103 -230.264966) (xy 361.597977 -230.216945) (xy 361.582267 -230.166015) (xy 361.574324 -230.113311)
			(xy 361.345744 -230.113311) (xy 361.337801 -230.166015) (xy 361.322091 -230.216945) (xy 361.298965 -230.264966)
			(xy 361.268941 -230.309003) (xy 361.232689 -230.348074) (xy 361.191018 -230.381305) (xy 361.14486 -230.407954)
			(xy 361.095246 -230.427426) (xy 361.043284 -230.439286) (xy 360.990134 -230.44327) (xy 360.936984 -230.439286)
			(xy 360.885022 -230.427426) (xy 360.835408 -230.407954) (xy 360.78925 -230.381305) (xy 360.747579 -230.348074)
			(xy 360.711327 -230.309003) (xy 360.681303 -230.264966) (xy 360.658177 -230.216945) (xy 360.642467 -230.166015)
			(xy 360.634524 -230.113311) (xy 360.404952 -230.113311) (xy 360.402963 -230.139852) (xy 360.391103 -230.191817)
			(xy 360.371631 -230.241434) (xy 360.344982 -230.287595) (xy 360.311751 -230.329269) (xy 360.27268 -230.365525)
			(xy 360.228642 -230.395553) (xy 360.180621 -230.418682) (xy 360.12969 -230.434397) (xy 360.076984 -230.442346)
			(xy 360.050334 -230.44277) (xy 360.026712 -230.442008) (xy 360.012823 -230.441547) (xy 359.985633 -230.447224)
			(xy 359.960979 -230.460019) (xy 359.940686 -230.478986) (xy 359.926256 -230.502721) (xy 359.918757 -230.529466)
			(xy 359.918254 -230.543354) (xy 359.918254 -230.746808) (xy 359.90784 -230.757222) (xy 359.918 -230.78694)
			(xy 359.926683 -230.814516) (xy 359.935999 -230.871572) (xy 359.936542 -230.900478) (xy 359.936021 -230.927127)
			(xy 360.164624 -230.927127) (xy 360.164624 -230.873829) (xy 360.172567 -230.821125) (xy 360.188277 -230.770195)
			(xy 360.211403 -230.722174) (xy 360.241427 -230.678137) (xy 360.277679 -230.639066) (xy 360.31935 -230.605835)
			(xy 360.365508 -230.579186) (xy 360.415122 -230.559714) (xy 360.467084 -230.547854) (xy 360.520234 -230.543871)
			(xy 360.573384 -230.547854) (xy 360.625346 -230.559714) (xy 360.67496 -230.579186) (xy 360.721118 -230.605835)
			(xy 360.762789 -230.639066) (xy 360.799041 -230.678137) (xy 360.829065 -230.722174) (xy 360.852191 -230.770195)
			(xy 360.867901 -230.821125) (xy 360.875844 -230.873829) (xy 360.876342 -230.900478) (xy 360.875844 -230.927127)
			(xy 361.104424 -230.927127) (xy 361.104424 -230.873829) (xy 361.112367 -230.821125) (xy 361.128077 -230.770195)
			(xy 361.151203 -230.722174) (xy 361.181227 -230.678137) (xy 361.217479 -230.639066) (xy 361.25915 -230.605835)
			(xy 361.305308 -230.579186) (xy 361.354922 -230.559714) (xy 361.406884 -230.547854) (xy 361.460034 -230.543871)
			(xy 361.513184 -230.547854) (xy 361.565146 -230.559714) (xy 361.61476 -230.579186) (xy 361.660918 -230.605835)
			(xy 361.702589 -230.639066) (xy 361.738841 -230.678137) (xy 361.768865 -230.722174) (xy 361.791991 -230.770195)
			(xy 361.807701 -230.821125) (xy 361.815644 -230.873829) (xy 361.816142 -230.900478) (xy 361.815644 -230.927127)
			(xy 362.044478 -230.927127) (xy 362.044478 -230.873829) (xy 362.052421 -230.821125) (xy 362.068131 -230.770195)
			(xy 362.091257 -230.722174) (xy 362.121281 -230.678137) (xy 362.157533 -230.639066) (xy 362.199204 -230.605835)
			(xy 362.245362 -230.579186) (xy 362.294976 -230.559714) (xy 362.346938 -230.547854) (xy 362.400088 -230.543871)
			(xy 362.453238 -230.547854) (xy 362.5052 -230.559714) (xy 362.554814 -230.579186) (xy 362.600972 -230.605835)
			(xy 362.642643 -230.639066) (xy 362.678895 -230.678137) (xy 362.708919 -230.722174) (xy 362.732045 -230.770195)
			(xy 362.747755 -230.821125) (xy 362.755698 -230.873829) (xy 362.756196 -230.900478) (xy 362.755698 -230.927127)
			(xy 362.984024 -230.927127) (xy 362.984024 -230.873829) (xy 362.991967 -230.821125) (xy 363.007677 -230.770195)
			(xy 363.030803 -230.722174) (xy 363.060827 -230.678137) (xy 363.097079 -230.639066) (xy 363.13875 -230.605835)
			(xy 363.184908 -230.579186) (xy 363.234522 -230.559714) (xy 363.286484 -230.547854) (xy 363.339634 -230.543871)
			(xy 363.392784 -230.547854) (xy 363.444746 -230.559714) (xy 363.49436 -230.579186) (xy 363.540518 -230.605835)
			(xy 363.582189 -230.639066) (xy 363.618441 -230.678137) (xy 363.648465 -230.722174) (xy 363.671591 -230.770195)
			(xy 363.687301 -230.821125) (xy 363.695244 -230.873829) (xy 363.695742 -230.900478) (xy 363.695244 -230.927127)
			(xy 363.923824 -230.927127) (xy 363.923824 -230.873829) (xy 363.931767 -230.821125) (xy 363.947477 -230.770195)
			(xy 363.970603 -230.722174) (xy 364.000627 -230.678137) (xy 364.036879 -230.639066) (xy 364.07855 -230.605835)
			(xy 364.124708 -230.579186) (xy 364.174322 -230.559714) (xy 364.226284 -230.547854) (xy 364.279434 -230.543871)
			(xy 364.332584 -230.547854) (xy 364.384546 -230.559714) (xy 364.43416 -230.579186) (xy 364.480318 -230.605835)
			(xy 364.521989 -230.639066) (xy 364.558241 -230.678137) (xy 364.588265 -230.722174) (xy 364.611391 -230.770195)
			(xy 364.627101 -230.821125) (xy 364.635044 -230.873829) (xy 364.635542 -230.900478) (xy 364.635044 -230.927127)
			(xy 364.863624 -230.927127) (xy 364.863624 -230.873829) (xy 364.871567 -230.821125) (xy 364.887277 -230.770195)
			(xy 364.910403 -230.722174) (xy 364.940427 -230.678137) (xy 364.976679 -230.639066) (xy 365.01835 -230.605835)
			(xy 365.064508 -230.579186) (xy 365.114122 -230.559714) (xy 365.166084 -230.547854) (xy 365.219234 -230.543871)
			(xy 365.272384 -230.547854) (xy 365.324346 -230.559714) (xy 365.37396 -230.579186) (xy 365.420118 -230.605835)
			(xy 365.461789 -230.639066) (xy 365.498041 -230.678137) (xy 365.528065 -230.722174) (xy 365.551191 -230.770195)
			(xy 365.566901 -230.821125) (xy 365.574844 -230.873829) (xy 365.575342 -230.900478) (xy 365.574844 -230.927127)
			(xy 365.803424 -230.927127) (xy 365.803424 -230.873829) (xy 365.811367 -230.821125) (xy 365.827077 -230.770195)
			(xy 365.850203 -230.722174) (xy 365.880227 -230.678137) (xy 365.916479 -230.639066) (xy 365.95815 -230.605835)
			(xy 366.004308 -230.579186) (xy 366.053922 -230.559714) (xy 366.105884 -230.547854) (xy 366.159034 -230.543871)
			(xy 366.212184 -230.547854) (xy 366.264146 -230.559714) (xy 366.31376 -230.579186) (xy 366.359918 -230.605835)
			(xy 366.401589 -230.639066) (xy 366.437841 -230.678137) (xy 366.467865 -230.722174) (xy 366.490991 -230.770195)
			(xy 366.506701 -230.821125) (xy 366.514644 -230.873829) (xy 366.515142 -230.900478) (xy 366.514644 -230.927127)
			(xy 366.743224 -230.927127) (xy 366.743224 -230.873829) (xy 366.751167 -230.821125) (xy 366.766877 -230.770195)
			(xy 366.790003 -230.722174) (xy 366.820027 -230.678137) (xy 366.856279 -230.639066) (xy 366.89795 -230.605835)
			(xy 366.944108 -230.579186) (xy 366.993722 -230.559714) (xy 367.045684 -230.547854) (xy 367.098834 -230.543871)
			(xy 367.151984 -230.547854) (xy 367.203946 -230.559714) (xy 367.25356 -230.579186) (xy 367.299718 -230.605835)
			(xy 367.341389 -230.639066) (xy 367.377641 -230.678137) (xy 367.407665 -230.722174) (xy 367.430791 -230.770195)
			(xy 367.446501 -230.821125) (xy 367.454444 -230.873829) (xy 367.454942 -230.900478) (xy 367.454444 -230.927127)
			(xy 367.683024 -230.927127) (xy 367.683024 -230.873829) (xy 367.690967 -230.821125) (xy 367.706677 -230.770195)
			(xy 367.729803 -230.722174) (xy 367.759827 -230.678137) (xy 367.796079 -230.639066) (xy 367.83775 -230.605835)
			(xy 367.883908 -230.579186) (xy 367.933522 -230.559714) (xy 367.985484 -230.547854) (xy 368.038634 -230.543871)
			(xy 368.091784 -230.547854) (xy 368.143746 -230.559714) (xy 368.19336 -230.579186) (xy 368.239518 -230.605835)
			(xy 368.281189 -230.639066) (xy 368.317441 -230.678137) (xy 368.347465 -230.722174) (xy 368.370591 -230.770195)
			(xy 368.386301 -230.821125) (xy 368.394244 -230.873829) (xy 368.394742 -230.900478) (xy 368.394244 -230.927127)
			(xy 368.622824 -230.927127) (xy 368.622824 -230.873829) (xy 368.630767 -230.821125) (xy 368.646477 -230.770195)
			(xy 368.669603 -230.722174) (xy 368.699627 -230.678137) (xy 368.735879 -230.639066) (xy 368.77755 -230.605835)
			(xy 368.823708 -230.579186) (xy 368.873322 -230.559714) (xy 368.925284 -230.547854) (xy 368.978434 -230.543871)
			(xy 369.031584 -230.547854) (xy 369.083546 -230.559714) (xy 369.13316 -230.579186) (xy 369.179318 -230.605835)
			(xy 369.220989 -230.639066) (xy 369.257241 -230.678137) (xy 369.287265 -230.722174) (xy 369.310391 -230.770195)
			(xy 369.326101 -230.821125) (xy 369.334044 -230.873829) (xy 369.334542 -230.900478) (xy 369.334044 -230.927127)
			(xy 369.56237 -230.927127) (xy 369.56237 -230.873829) (xy 369.570313 -230.821125) (xy 369.586023 -230.770195)
			(xy 369.609149 -230.722174) (xy 369.639173 -230.678137) (xy 369.675425 -230.639066) (xy 369.717096 -230.605835)
			(xy 369.763254 -230.579186) (xy 369.812868 -230.559714) (xy 369.86483 -230.547854) (xy 369.91798 -230.543871)
			(xy 369.97113 -230.547854) (xy 370.023092 -230.559714) (xy 370.072706 -230.579186) (xy 370.118864 -230.605835)
			(xy 370.160535 -230.639066) (xy 370.196787 -230.678137) (xy 370.226811 -230.722174) (xy 370.249937 -230.770195)
			(xy 370.265647 -230.821125) (xy 370.27359 -230.873829) (xy 370.274088 -230.900478) (xy 370.27359 -230.927127)
			(xy 370.502424 -230.927127) (xy 370.502424 -230.873829) (xy 370.510367 -230.821125) (xy 370.526077 -230.770195)
			(xy 370.549203 -230.722174) (xy 370.579227 -230.678137) (xy 370.615479 -230.639066) (xy 370.65715 -230.605835)
			(xy 370.703308 -230.579186) (xy 370.752922 -230.559714) (xy 370.804884 -230.547854) (xy 370.858034 -230.543871)
			(xy 370.911184 -230.547854) (xy 370.963146 -230.559714) (xy 371.01276 -230.579186) (xy 371.058918 -230.605835)
			(xy 371.100589 -230.639066) (xy 371.136841 -230.678137) (xy 371.166865 -230.722174) (xy 371.189991 -230.770195)
			(xy 371.205701 -230.821125) (xy 371.213644 -230.873829) (xy 371.214142 -230.900478) (xy 371.213644 -230.927127)
			(xy 371.442224 -230.927127) (xy 371.442224 -230.873829) (xy 371.450167 -230.821125) (xy 371.465877 -230.770195)
			(xy 371.489003 -230.722174) (xy 371.519027 -230.678137) (xy 371.555279 -230.639066) (xy 371.59695 -230.605835)
			(xy 371.643108 -230.579186) (xy 371.692722 -230.559714) (xy 371.744684 -230.547854) (xy 371.797834 -230.543871)
			(xy 371.850984 -230.547854) (xy 371.902946 -230.559714) (xy 371.95256 -230.579186) (xy 371.998718 -230.605835)
			(xy 372.040389 -230.639066) (xy 372.076641 -230.678137) (xy 372.106665 -230.722174) (xy 372.129791 -230.770195)
			(xy 372.145501 -230.821125) (xy 372.153444 -230.873829) (xy 372.153942 -230.900478) (xy 372.153444 -230.927127)
			(xy 372.382024 -230.927127) (xy 372.382024 -230.873829) (xy 372.389967 -230.821125) (xy 372.405677 -230.770195)
			(xy 372.428803 -230.722174) (xy 372.458827 -230.678137) (xy 372.495079 -230.639066) (xy 372.53675 -230.605835)
			(xy 372.582908 -230.579186) (xy 372.632522 -230.559714) (xy 372.684484 -230.547854) (xy 372.737634 -230.543871)
			(xy 372.790784 -230.547854) (xy 372.842746 -230.559714) (xy 372.89236 -230.579186) (xy 372.938518 -230.605835)
			(xy 372.980189 -230.639066) (xy 373.016441 -230.678137) (xy 373.046465 -230.722174) (xy 373.069591 -230.770195)
			(xy 373.085301 -230.821125) (xy 373.093244 -230.873829) (xy 373.093742 -230.900478) (xy 373.093244 -230.927127)
			(xy 373.321824 -230.927127) (xy 373.321824 -230.873829) (xy 373.329767 -230.821125) (xy 373.345477 -230.770195)
			(xy 373.368603 -230.722174) (xy 373.398627 -230.678137) (xy 373.434879 -230.639066) (xy 373.47655 -230.605835)
			(xy 373.522708 -230.579186) (xy 373.572322 -230.559714) (xy 373.624284 -230.547854) (xy 373.677434 -230.543871)
			(xy 373.730584 -230.547854) (xy 373.782546 -230.559714) (xy 373.83216 -230.579186) (xy 373.878318 -230.605835)
			(xy 373.919989 -230.639066) (xy 373.956241 -230.678137) (xy 373.986265 -230.722174) (xy 374.009391 -230.770195)
			(xy 374.025101 -230.821125) (xy 374.033044 -230.873829) (xy 374.033542 -230.900478) (xy 374.033044 -230.927127)
			(xy 374.261624 -230.927127) (xy 374.261624 -230.873829) (xy 374.269567 -230.821125) (xy 374.285277 -230.770195)
			(xy 374.308403 -230.722174) (xy 374.338427 -230.678137) (xy 374.374679 -230.639066) (xy 374.41635 -230.605835)
			(xy 374.462508 -230.579186) (xy 374.512122 -230.559714) (xy 374.564084 -230.547854) (xy 374.617234 -230.543871)
			(xy 374.670384 -230.547854) (xy 374.722346 -230.559714) (xy 374.77196 -230.579186) (xy 374.818118 -230.605835)
			(xy 374.859789 -230.639066) (xy 374.896041 -230.678137) (xy 374.926065 -230.722174) (xy 374.949191 -230.770195)
			(xy 374.964901 -230.821125) (xy 374.972844 -230.873829) (xy 374.973342 -230.900478) (xy 374.972844 -230.927127)
			(xy 375.201424 -230.927127) (xy 375.201424 -230.873829) (xy 375.209367 -230.821125) (xy 375.225077 -230.770195)
			(xy 375.248203 -230.722174) (xy 375.278227 -230.678137) (xy 375.314479 -230.639066) (xy 375.35615 -230.605835)
			(xy 375.402308 -230.579186) (xy 375.451922 -230.559714) (xy 375.503884 -230.547854) (xy 375.557034 -230.543871)
			(xy 375.610184 -230.547854) (xy 375.662146 -230.559714) (xy 375.71176 -230.579186) (xy 375.757918 -230.605835)
			(xy 375.799589 -230.639066) (xy 375.835841 -230.678137) (xy 375.865865 -230.722174) (xy 375.888991 -230.770195)
			(xy 375.904701 -230.821125) (xy 375.912644 -230.873829) (xy 375.913142 -230.900478) (xy 375.912644 -230.927127)
			(xy 376.141224 -230.927127) (xy 376.141224 -230.873829) (xy 376.149167 -230.821125) (xy 376.164877 -230.770195)
			(xy 376.188003 -230.722174) (xy 376.218027 -230.678137) (xy 376.254279 -230.639066) (xy 376.29595 -230.605835)
			(xy 376.342108 -230.579186) (xy 376.391722 -230.559714) (xy 376.443684 -230.547854) (xy 376.496834 -230.543871)
			(xy 376.549984 -230.547854) (xy 376.601946 -230.559714) (xy 376.65156 -230.579186) (xy 376.697718 -230.605835)
			(xy 376.739389 -230.639066) (xy 376.775641 -230.678137) (xy 376.805665 -230.722174) (xy 376.828791 -230.770195)
			(xy 376.844501 -230.821125) (xy 376.852444 -230.873829) (xy 376.852942 -230.900478) (xy 376.852444 -230.927127)
			(xy 377.081024 -230.927127) (xy 377.081024 -230.873829) (xy 377.088967 -230.821125) (xy 377.104677 -230.770195)
			(xy 377.127803 -230.722174) (xy 377.157827 -230.678137) (xy 377.194079 -230.639066) (xy 377.23575 -230.605835)
			(xy 377.281908 -230.579186) (xy 377.331522 -230.559714) (xy 377.383484 -230.547854) (xy 377.436634 -230.543871)
			(xy 377.489784 -230.547854) (xy 377.541746 -230.559714) (xy 377.59136 -230.579186) (xy 377.637518 -230.605835)
			(xy 377.679189 -230.639066) (xy 377.715441 -230.678137) (xy 377.745465 -230.722174) (xy 377.768591 -230.770195)
			(xy 377.784301 -230.821125) (xy 377.792244 -230.873829) (xy 377.792742 -230.900478) (xy 377.792244 -230.927127)
			(xy 378.020824 -230.927127) (xy 378.020824 -230.873829) (xy 378.028767 -230.821125) (xy 378.044477 -230.770195)
			(xy 378.067603 -230.722174) (xy 378.097627 -230.678137) (xy 378.133879 -230.639066) (xy 378.17555 -230.605835)
			(xy 378.221708 -230.579186) (xy 378.271322 -230.559714) (xy 378.323284 -230.547854) (xy 378.376434 -230.543871)
			(xy 378.429584 -230.547854) (xy 378.481546 -230.559714) (xy 378.53116 -230.579186) (xy 378.577318 -230.605835)
			(xy 378.618989 -230.639066) (xy 378.655241 -230.678137) (xy 378.685265 -230.722174) (xy 378.708391 -230.770195)
			(xy 378.724101 -230.821125) (xy 378.732044 -230.873829) (xy 378.732542 -230.900478) (xy 378.732044 -230.927127)
			(xy 378.960624 -230.927127) (xy 378.960624 -230.873829) (xy 378.968567 -230.821125) (xy 378.984277 -230.770195)
			(xy 379.007403 -230.722174) (xy 379.037427 -230.678137) (xy 379.073679 -230.639066) (xy 379.11535 -230.605835)
			(xy 379.161508 -230.579186) (xy 379.211122 -230.559714) (xy 379.263084 -230.547854) (xy 379.316234 -230.543871)
			(xy 379.369384 -230.547854) (xy 379.421346 -230.559714) (xy 379.47096 -230.579186) (xy 379.517118 -230.605835)
			(xy 379.558789 -230.639066) (xy 379.595041 -230.678137) (xy 379.625065 -230.722174) (xy 379.648191 -230.770195)
			(xy 379.663901 -230.821125) (xy 379.671844 -230.873829) (xy 379.672342 -230.900478) (xy 379.671844 -230.927127)
			(xy 379.90017 -230.927127) (xy 379.90017 -230.873829) (xy 379.908113 -230.821125) (xy 379.923823 -230.770195)
			(xy 379.946949 -230.722174) (xy 379.976973 -230.678137) (xy 380.013225 -230.639066) (xy 380.054896 -230.605835)
			(xy 380.101054 -230.579186) (xy 380.150668 -230.559714) (xy 380.20263 -230.547854) (xy 380.25578 -230.543871)
			(xy 380.30893 -230.547854) (xy 380.360892 -230.559714) (xy 380.410506 -230.579186) (xy 380.456664 -230.605835)
			(xy 380.498335 -230.639066) (xy 380.534587 -230.678137) (xy 380.564611 -230.722174) (xy 380.587737 -230.770195)
			(xy 380.603447 -230.821125) (xy 380.61139 -230.873829) (xy 380.611888 -230.900478) (xy 380.61139 -230.927127)
			(xy 380.603447 -230.979831) (xy 380.587737 -231.030761) (xy 380.564611 -231.078782) (xy 380.534587 -231.122819)
			(xy 380.498335 -231.16189) (xy 380.456664 -231.195121) (xy 380.410506 -231.22177) (xy 380.360892 -231.241242)
			(xy 380.30893 -231.253102) (xy 380.25578 -231.257086) (xy 380.20263 -231.253102) (xy 380.150668 -231.241242)
			(xy 380.101054 -231.22177) (xy 380.054896 -231.195121) (xy 380.013225 -231.16189) (xy 379.976973 -231.122819)
			(xy 379.946949 -231.078782) (xy 379.923823 -231.030761) (xy 379.908113 -230.979831) (xy 379.90017 -230.927127)
			(xy 379.671844 -230.927127) (xy 379.663901 -230.979831) (xy 379.648191 -231.030761) (xy 379.625065 -231.078782)
			(xy 379.595041 -231.122819) (xy 379.558789 -231.16189) (xy 379.517118 -231.195121) (xy 379.47096 -231.22177)
			(xy 379.421346 -231.241242) (xy 379.369384 -231.253102) (xy 379.316234 -231.257086) (xy 379.263084 -231.253102)
			(xy 379.211122 -231.241242) (xy 379.161508 -231.22177) (xy 379.11535 -231.195121) (xy 379.073679 -231.16189)
			(xy 379.037427 -231.122819) (xy 379.007403 -231.078782) (xy 378.984277 -231.030761) (xy 378.968567 -230.979831)
			(xy 378.960624 -230.927127) (xy 378.732044 -230.927127) (xy 378.724101 -230.979831) (xy 378.708391 -231.030761)
			(xy 378.685265 -231.078782) (xy 378.655241 -231.122819) (xy 378.618989 -231.16189) (xy 378.577318 -231.195121)
			(xy 378.53116 -231.22177) (xy 378.481546 -231.241242) (xy 378.429584 -231.253102) (xy 378.376434 -231.257086)
			(xy 378.323284 -231.253102) (xy 378.271322 -231.241242) (xy 378.221708 -231.22177) (xy 378.17555 -231.195121)
			(xy 378.133879 -231.16189) (xy 378.097627 -231.122819) (xy 378.067603 -231.078782) (xy 378.044477 -231.030761)
			(xy 378.028767 -230.979831) (xy 378.020824 -230.927127) (xy 377.792244 -230.927127) (xy 377.784301 -230.979831)
			(xy 377.768591 -231.030761) (xy 377.745465 -231.078782) (xy 377.715441 -231.122819) (xy 377.679189 -231.16189)
			(xy 377.637518 -231.195121) (xy 377.59136 -231.22177) (xy 377.541746 -231.241242) (xy 377.489784 -231.253102)
			(xy 377.436634 -231.257086) (xy 377.383484 -231.253102) (xy 377.331522 -231.241242) (xy 377.281908 -231.22177)
			(xy 377.23575 -231.195121) (xy 377.194079 -231.16189) (xy 377.157827 -231.122819) (xy 377.127803 -231.078782)
			(xy 377.104677 -231.030761) (xy 377.088967 -230.979831) (xy 377.081024 -230.927127) (xy 376.852444 -230.927127)
			(xy 376.844501 -230.979831) (xy 376.828791 -231.030761) (xy 376.805665 -231.078782) (xy 376.775641 -231.122819)
			(xy 376.739389 -231.16189) (xy 376.697718 -231.195121) (xy 376.65156 -231.22177) (xy 376.601946 -231.241242)
			(xy 376.549984 -231.253102) (xy 376.496834 -231.257086) (xy 376.443684 -231.253102) (xy 376.391722 -231.241242)
			(xy 376.342108 -231.22177) (xy 376.29595 -231.195121) (xy 376.254279 -231.16189) (xy 376.218027 -231.122819)
			(xy 376.188003 -231.078782) (xy 376.164877 -231.030761) (xy 376.149167 -230.979831) (xy 376.141224 -230.927127)
			(xy 375.912644 -230.927127) (xy 375.904701 -230.979831) (xy 375.888991 -231.030761) (xy 375.865865 -231.078782)
			(xy 375.835841 -231.122819) (xy 375.799589 -231.16189) (xy 375.757918 -231.195121) (xy 375.71176 -231.22177)
			(xy 375.662146 -231.241242) (xy 375.610184 -231.253102) (xy 375.557034 -231.257086) (xy 375.503884 -231.253102)
			(xy 375.451922 -231.241242) (xy 375.402308 -231.22177) (xy 375.35615 -231.195121) (xy 375.314479 -231.16189)
			(xy 375.278227 -231.122819) (xy 375.248203 -231.078782) (xy 375.225077 -231.030761) (xy 375.209367 -230.979831)
			(xy 375.201424 -230.927127) (xy 374.972844 -230.927127) (xy 374.964901 -230.979831) (xy 374.949191 -231.030761)
			(xy 374.926065 -231.078782) (xy 374.896041 -231.122819) (xy 374.859789 -231.16189) (xy 374.818118 -231.195121)
			(xy 374.77196 -231.22177) (xy 374.722346 -231.241242) (xy 374.670384 -231.253102) (xy 374.617234 -231.257086)
			(xy 374.564084 -231.253102) (xy 374.512122 -231.241242) (xy 374.462508 -231.22177) (xy 374.41635 -231.195121)
			(xy 374.374679 -231.16189) (xy 374.338427 -231.122819) (xy 374.308403 -231.078782) (xy 374.285277 -231.030761)
			(xy 374.269567 -230.979831) (xy 374.261624 -230.927127) (xy 374.033044 -230.927127) (xy 374.025101 -230.979831)
			(xy 374.009391 -231.030761) (xy 373.986265 -231.078782) (xy 373.956241 -231.122819) (xy 373.919989 -231.16189)
			(xy 373.878318 -231.195121) (xy 373.83216 -231.22177) (xy 373.782546 -231.241242) (xy 373.730584 -231.253102)
			(xy 373.677434 -231.257086) (xy 373.624284 -231.253102) (xy 373.572322 -231.241242) (xy 373.522708 -231.22177)
			(xy 373.47655 -231.195121) (xy 373.434879 -231.16189) (xy 373.398627 -231.122819) (xy 373.368603 -231.078782)
			(xy 373.345477 -231.030761) (xy 373.329767 -230.979831) (xy 373.321824 -230.927127) (xy 373.093244 -230.927127)
			(xy 373.085301 -230.979831) (xy 373.069591 -231.030761) (xy 373.046465 -231.078782) (xy 373.016441 -231.122819)
			(xy 372.980189 -231.16189) (xy 372.938518 -231.195121) (xy 372.89236 -231.22177) (xy 372.842746 -231.241242)
			(xy 372.790784 -231.253102) (xy 372.737634 -231.257086) (xy 372.684484 -231.253102) (xy 372.632522 -231.241242)
			(xy 372.582908 -231.22177) (xy 372.53675 -231.195121) (xy 372.495079 -231.16189) (xy 372.458827 -231.122819)
			(xy 372.428803 -231.078782) (xy 372.405677 -231.030761) (xy 372.389967 -230.979831) (xy 372.382024 -230.927127)
			(xy 372.153444 -230.927127) (xy 372.145501 -230.979831) (xy 372.129791 -231.030761) (xy 372.106665 -231.078782)
			(xy 372.076641 -231.122819) (xy 372.040389 -231.16189) (xy 371.998718 -231.195121) (xy 371.95256 -231.22177)
			(xy 371.902946 -231.241242) (xy 371.850984 -231.253102) (xy 371.797834 -231.257086) (xy 371.744684 -231.253102)
			(xy 371.692722 -231.241242) (xy 371.643108 -231.22177) (xy 371.59695 -231.195121) (xy 371.555279 -231.16189)
			(xy 371.519027 -231.122819) (xy 371.489003 -231.078782) (xy 371.465877 -231.030761) (xy 371.450167 -230.979831)
			(xy 371.442224 -230.927127) (xy 371.213644 -230.927127) (xy 371.205701 -230.979831) (xy 371.189991 -231.030761)
			(xy 371.166865 -231.078782) (xy 371.136841 -231.122819) (xy 371.100589 -231.16189) (xy 371.058918 -231.195121)
			(xy 371.01276 -231.22177) (xy 370.963146 -231.241242) (xy 370.911184 -231.253102) (xy 370.858034 -231.257086)
			(xy 370.804884 -231.253102) (xy 370.752922 -231.241242) (xy 370.703308 -231.22177) (xy 370.65715 -231.195121)
			(xy 370.615479 -231.16189) (xy 370.579227 -231.122819) (xy 370.549203 -231.078782) (xy 370.526077 -231.030761)
			(xy 370.510367 -230.979831) (xy 370.502424 -230.927127) (xy 370.27359 -230.927127) (xy 370.265647 -230.979831)
			(xy 370.249937 -231.030761) (xy 370.226811 -231.078782) (xy 370.196787 -231.122819) (xy 370.160535 -231.16189)
			(xy 370.118864 -231.195121) (xy 370.072706 -231.22177) (xy 370.023092 -231.241242) (xy 369.97113 -231.253102)
			(xy 369.91798 -231.257086) (xy 369.86483 -231.253102) (xy 369.812868 -231.241242) (xy 369.763254 -231.22177)
			(xy 369.717096 -231.195121) (xy 369.675425 -231.16189) (xy 369.639173 -231.122819) (xy 369.609149 -231.078782)
			(xy 369.586023 -231.030761) (xy 369.570313 -230.979831) (xy 369.56237 -230.927127) (xy 369.334044 -230.927127)
			(xy 369.326101 -230.979831) (xy 369.310391 -231.030761) (xy 369.287265 -231.078782) (xy 369.257241 -231.122819)
			(xy 369.220989 -231.16189) (xy 369.179318 -231.195121) (xy 369.13316 -231.22177) (xy 369.083546 -231.241242)
			(xy 369.031584 -231.253102) (xy 368.978434 -231.257086) (xy 368.925284 -231.253102) (xy 368.873322 -231.241242)
			(xy 368.823708 -231.22177) (xy 368.77755 -231.195121) (xy 368.735879 -231.16189) (xy 368.699627 -231.122819)
			(xy 368.669603 -231.078782) (xy 368.646477 -231.030761) (xy 368.630767 -230.979831) (xy 368.622824 -230.927127)
			(xy 368.394244 -230.927127) (xy 368.386301 -230.979831) (xy 368.370591 -231.030761) (xy 368.347465 -231.078782)
			(xy 368.317441 -231.122819) (xy 368.281189 -231.16189) (xy 368.239518 -231.195121) (xy 368.19336 -231.22177)
			(xy 368.143746 -231.241242) (xy 368.091784 -231.253102) (xy 368.038634 -231.257086) (xy 367.985484 -231.253102)
			(xy 367.933522 -231.241242) (xy 367.883908 -231.22177) (xy 367.83775 -231.195121) (xy 367.796079 -231.16189)
			(xy 367.759827 -231.122819) (xy 367.729803 -231.078782) (xy 367.706677 -231.030761) (xy 367.690967 -230.979831)
			(xy 367.683024 -230.927127) (xy 367.454444 -230.927127) (xy 367.446501 -230.979831) (xy 367.430791 -231.030761)
			(xy 367.407665 -231.078782) (xy 367.377641 -231.122819) (xy 367.341389 -231.16189) (xy 367.299718 -231.195121)
			(xy 367.25356 -231.22177) (xy 367.203946 -231.241242) (xy 367.151984 -231.253102) (xy 367.098834 -231.257086)
			(xy 367.045684 -231.253102) (xy 366.993722 -231.241242) (xy 366.944108 -231.22177) (xy 366.89795 -231.195121)
			(xy 366.856279 -231.16189) (xy 366.820027 -231.122819) (xy 366.790003 -231.078782) (xy 366.766877 -231.030761)
			(xy 366.751167 -230.979831) (xy 366.743224 -230.927127) (xy 366.514644 -230.927127) (xy 366.506701 -230.979831)
			(xy 366.490991 -231.030761) (xy 366.467865 -231.078782) (xy 366.437841 -231.122819) (xy 366.401589 -231.16189)
			(xy 366.359918 -231.195121) (xy 366.31376 -231.22177) (xy 366.264146 -231.241242) (xy 366.212184 -231.253102)
			(xy 366.159034 -231.257086) (xy 366.105884 -231.253102) (xy 366.053922 -231.241242) (xy 366.004308 -231.22177)
			(xy 365.95815 -231.195121) (xy 365.916479 -231.16189) (xy 365.880227 -231.122819) (xy 365.850203 -231.078782)
			(xy 365.827077 -231.030761) (xy 365.811367 -230.979831) (xy 365.803424 -230.927127) (xy 365.574844 -230.927127)
			(xy 365.566901 -230.979831) (xy 365.551191 -231.030761) (xy 365.528065 -231.078782) (xy 365.498041 -231.122819)
			(xy 365.461789 -231.16189) (xy 365.420118 -231.195121) (xy 365.37396 -231.22177) (xy 365.324346 -231.241242)
			(xy 365.272384 -231.253102) (xy 365.219234 -231.257086) (xy 365.166084 -231.253102) (xy 365.114122 -231.241242)
			(xy 365.064508 -231.22177) (xy 365.01835 -231.195121) (xy 364.976679 -231.16189) (xy 364.940427 -231.122819)
			(xy 364.910403 -231.078782) (xy 364.887277 -231.030761) (xy 364.871567 -230.979831) (xy 364.863624 -230.927127)
			(xy 364.635044 -230.927127) (xy 364.627101 -230.979831) (xy 364.611391 -231.030761) (xy 364.588265 -231.078782)
			(xy 364.558241 -231.122819) (xy 364.521989 -231.16189) (xy 364.480318 -231.195121) (xy 364.43416 -231.22177)
			(xy 364.384546 -231.241242) (xy 364.332584 -231.253102) (xy 364.279434 -231.257086) (xy 364.226284 -231.253102)
			(xy 364.174322 -231.241242) (xy 364.124708 -231.22177) (xy 364.07855 -231.195121) (xy 364.036879 -231.16189)
			(xy 364.000627 -231.122819) (xy 363.970603 -231.078782) (xy 363.947477 -231.030761) (xy 363.931767 -230.979831)
			(xy 363.923824 -230.927127) (xy 363.695244 -230.927127) (xy 363.687301 -230.979831) (xy 363.671591 -231.030761)
			(xy 363.648465 -231.078782) (xy 363.618441 -231.122819) (xy 363.582189 -231.16189) (xy 363.540518 -231.195121)
			(xy 363.49436 -231.22177) (xy 363.444746 -231.241242) (xy 363.392784 -231.253102) (xy 363.339634 -231.257086)
			(xy 363.286484 -231.253102) (xy 363.234522 -231.241242) (xy 363.184908 -231.22177) (xy 363.13875 -231.195121)
			(xy 363.097079 -231.16189) (xy 363.060827 -231.122819) (xy 363.030803 -231.078782) (xy 363.007677 -231.030761)
			(xy 362.991967 -230.979831) (xy 362.984024 -230.927127) (xy 362.755698 -230.927127) (xy 362.747755 -230.979831)
			(xy 362.732045 -231.030761) (xy 362.708919 -231.078782) (xy 362.678895 -231.122819) (xy 362.642643 -231.16189)
			(xy 362.600972 -231.195121) (xy 362.554814 -231.22177) (xy 362.5052 -231.241242) (xy 362.453238 -231.253102)
			(xy 362.400088 -231.257086) (xy 362.346938 -231.253102) (xy 362.294976 -231.241242) (xy 362.245362 -231.22177)
			(xy 362.199204 -231.195121) (xy 362.157533 -231.16189) (xy 362.121281 -231.122819) (xy 362.091257 -231.078782)
			(xy 362.068131 -231.030761) (xy 362.052421 -230.979831) (xy 362.044478 -230.927127) (xy 361.815644 -230.927127)
			(xy 361.807701 -230.979831) (xy 361.791991 -231.030761) (xy 361.768865 -231.078782) (xy 361.738841 -231.122819)
			(xy 361.702589 -231.16189) (xy 361.660918 -231.195121) (xy 361.61476 -231.22177) (xy 361.565146 -231.241242)
			(xy 361.513184 -231.253102) (xy 361.460034 -231.257086) (xy 361.406884 -231.253102) (xy 361.354922 -231.241242)
			(xy 361.305308 -231.22177) (xy 361.25915 -231.195121) (xy 361.217479 -231.16189) (xy 361.181227 -231.122819)
			(xy 361.151203 -231.078782) (xy 361.128077 -231.030761) (xy 361.112367 -230.979831) (xy 361.104424 -230.927127)
			(xy 360.875844 -230.927127) (xy 360.867901 -230.979831) (xy 360.852191 -231.030761) (xy 360.829065 -231.078782)
			(xy 360.799041 -231.122819) (xy 360.762789 -231.16189) (xy 360.721118 -231.195121) (xy 360.67496 -231.22177)
			(xy 360.625346 -231.241242) (xy 360.573384 -231.253102) (xy 360.520234 -231.257086) (xy 360.467084 -231.253102)
			(xy 360.415122 -231.241242) (xy 360.365508 -231.22177) (xy 360.31935 -231.195121) (xy 360.277679 -231.16189)
			(xy 360.241427 -231.122819) (xy 360.211403 -231.078782) (xy 360.188277 -231.030761) (xy 360.172567 -230.979831)
			(xy 360.164624 -230.927127) (xy 359.936021 -230.927127) (xy 359.935995 -230.928463) (xy 359.927243 -230.983745)
			(xy 359.90995 -231.036977) (xy 359.884544 -231.086849) (xy 359.851649 -231.132132) (xy 359.812075 -231.171712)
			(xy 359.766797 -231.204615) (xy 359.716929 -231.230029) (xy 359.6637 -231.24733) (xy 359.608419 -231.25609)
			(xy 359.580434 -231.256586) (xy 359.551531 -231.256018) (xy 359.49448 -231.246695) (xy 359.466896 -231.238044)
			(xy 359.437178 -231.227884) (xy 359.353866 -231.311196) (xy 359.344591 -231.321048) (xy 359.331143 -231.344516)
			(xy 359.324343 -231.370695) (xy 359.324669 -231.397741) (xy 359.332099 -231.423749) (xy 359.346109 -231.446885)
			(xy 359.355644 -231.456484) (xy 359.376189 -231.476794) (xy 359.411078 -231.522834) (xy 359.438081 -231.573901)
			(xy 359.456488 -231.628657) (xy 359.465819 -231.685665) (xy 359.466388 -231.714548) (xy 359.465861 -231.741197)
			(xy 359.694978 -231.741197) (xy 359.694978 -231.687899) (xy 359.702921 -231.635195) (xy 359.718631 -231.584265)
			(xy 359.741757 -231.536244) (xy 359.771781 -231.492207) (xy 359.808033 -231.453136) (xy 359.849704 -231.419905)
			(xy 359.895862 -231.393256) (xy 359.945476 -231.373784) (xy 359.997438 -231.361924) (xy 360.050588 -231.357941)
			(xy 360.103738 -231.361924) (xy 360.1557 -231.373784) (xy 360.205314 -231.393256) (xy 360.251472 -231.419905)
			(xy 360.293143 -231.453136) (xy 360.329395 -231.492207) (xy 360.359419 -231.536244) (xy 360.382545 -231.584265)
			(xy 360.398255 -231.635195) (xy 360.406198 -231.687899) (xy 360.406696 -231.714548) (xy 360.406198 -231.741197)
			(xy 360.634778 -231.741197) (xy 360.634778 -231.687899) (xy 360.642721 -231.635195) (xy 360.658431 -231.584265)
			(xy 360.681557 -231.536244) (xy 360.711581 -231.492207) (xy 360.747833 -231.453136) (xy 360.789504 -231.419905)
			(xy 360.835662 -231.393256) (xy 360.885276 -231.373784) (xy 360.937238 -231.361924) (xy 360.990388 -231.357941)
			(xy 361.043538 -231.361924) (xy 361.0955 -231.373784) (xy 361.145114 -231.393256) (xy 361.191272 -231.419905)
			(xy 361.232943 -231.453136) (xy 361.269195 -231.492207) (xy 361.299219 -231.536244) (xy 361.322345 -231.584265)
			(xy 361.338055 -231.635195) (xy 361.345998 -231.687899) (xy 361.346496 -231.714548) (xy 361.345998 -231.741197)
			(xy 361.574578 -231.741197) (xy 361.574578 -231.687899) (xy 361.582521 -231.635195) (xy 361.598231 -231.584265)
			(xy 361.621357 -231.536244) (xy 361.651381 -231.492207) (xy 361.687633 -231.453136) (xy 361.729304 -231.419905)
			(xy 361.775462 -231.393256) (xy 361.825076 -231.373784) (xy 361.877038 -231.361924) (xy 361.930188 -231.357941)
			(xy 361.983338 -231.361924) (xy 362.0353 -231.373784) (xy 362.084914 -231.393256) (xy 362.131072 -231.419905)
			(xy 362.172743 -231.453136) (xy 362.208995 -231.492207) (xy 362.239019 -231.536244) (xy 362.262145 -231.584265)
			(xy 362.277855 -231.635195) (xy 362.285798 -231.687899) (xy 362.286296 -231.714548) (xy 362.285798 -231.741197)
			(xy 362.51387 -231.741197) (xy 362.51387 -231.687899) (xy 362.521813 -231.635195) (xy 362.537523 -231.584265)
			(xy 362.560649 -231.536244) (xy 362.590673 -231.492207) (xy 362.626925 -231.453136) (xy 362.668596 -231.419905)
			(xy 362.714754 -231.393256) (xy 362.764368 -231.373784) (xy 362.81633 -231.361924) (xy 362.86948 -231.357941)
			(xy 362.92263 -231.361924) (xy 362.974592 -231.373784) (xy 363.024206 -231.393256) (xy 363.070364 -231.419905)
			(xy 363.112035 -231.453136) (xy 363.148287 -231.492207) (xy 363.178311 -231.536244) (xy 363.201437 -231.584265)
			(xy 363.217147 -231.635195) (xy 363.22509 -231.687899) (xy 363.225588 -231.714548) (xy 363.22509 -231.741197)
			(xy 363.45367 -231.741197) (xy 363.45367 -231.687899) (xy 363.461613 -231.635195) (xy 363.477323 -231.584265)
			(xy 363.500449 -231.536244) (xy 363.530473 -231.492207) (xy 363.566725 -231.453136) (xy 363.608396 -231.419905)
			(xy 363.654554 -231.393256) (xy 363.704168 -231.373784) (xy 363.75613 -231.361924) (xy 363.80928 -231.357941)
			(xy 363.86243 -231.361924) (xy 363.914392 -231.373784) (xy 363.964006 -231.393256) (xy 364.010164 -231.419905)
			(xy 364.051835 -231.453136) (xy 364.088087 -231.492207) (xy 364.118111 -231.536244) (xy 364.141237 -231.584265)
			(xy 364.156947 -231.635195) (xy 364.16489 -231.687899) (xy 364.165388 -231.714548) (xy 364.16489 -231.741197)
			(xy 364.39347 -231.741197) (xy 364.39347 -231.687899) (xy 364.401413 -231.635195) (xy 364.417123 -231.584265)
			(xy 364.440249 -231.536244) (xy 364.470273 -231.492207) (xy 364.506525 -231.453136) (xy 364.548196 -231.419905)
			(xy 364.594354 -231.393256) (xy 364.643968 -231.373784) (xy 364.69593 -231.361924) (xy 364.74908 -231.357941)
			(xy 364.80223 -231.361924) (xy 364.854192 -231.373784) (xy 364.903806 -231.393256) (xy 364.949964 -231.419905)
			(xy 364.991635 -231.453136) (xy 365.027887 -231.492207) (xy 365.057911 -231.536244) (xy 365.081037 -231.584265)
			(xy 365.096747 -231.635195) (xy 365.10469 -231.687899) (xy 365.105188 -231.714548) (xy 365.10469 -231.741197)
			(xy 365.33327 -231.741197) (xy 365.33327 -231.687899) (xy 365.341213 -231.635195) (xy 365.356923 -231.584265)
			(xy 365.380049 -231.536244) (xy 365.410073 -231.492207) (xy 365.446325 -231.453136) (xy 365.487996 -231.419905)
			(xy 365.534154 -231.393256) (xy 365.583768 -231.373784) (xy 365.63573 -231.361924) (xy 365.68888 -231.357941)
			(xy 365.74203 -231.361924) (xy 365.793992 -231.373784) (xy 365.843606 -231.393256) (xy 365.889764 -231.419905)
			(xy 365.931435 -231.453136) (xy 365.967687 -231.492207) (xy 365.997711 -231.536244) (xy 366.020837 -231.584265)
			(xy 366.036547 -231.635195) (xy 366.04449 -231.687899) (xy 366.044988 -231.714548) (xy 366.04449 -231.741197)
			(xy 366.27307 -231.741197) (xy 366.27307 -231.687899) (xy 366.281013 -231.635195) (xy 366.296723 -231.584265)
			(xy 366.319849 -231.536244) (xy 366.349873 -231.492207) (xy 366.386125 -231.453136) (xy 366.427796 -231.419905)
			(xy 366.473954 -231.393256) (xy 366.523568 -231.373784) (xy 366.57553 -231.361924) (xy 366.62868 -231.357941)
			(xy 366.68183 -231.361924) (xy 366.733792 -231.373784) (xy 366.783406 -231.393256) (xy 366.829564 -231.419905)
			(xy 366.871235 -231.453136) (xy 366.907487 -231.492207) (xy 366.937511 -231.536244) (xy 366.960637 -231.584265)
			(xy 366.976347 -231.635195) (xy 366.98429 -231.687899) (xy 366.984788 -231.714548) (xy 366.98429 -231.741197)
			(xy 367.213378 -231.741197) (xy 367.213378 -231.687899) (xy 367.221321 -231.635195) (xy 367.237031 -231.584265)
			(xy 367.260157 -231.536244) (xy 367.290181 -231.492207) (xy 367.326433 -231.453136) (xy 367.368104 -231.419905)
			(xy 367.414262 -231.393256) (xy 367.463876 -231.373784) (xy 367.515838 -231.361924) (xy 367.568988 -231.357941)
			(xy 367.622138 -231.361924) (xy 367.6741 -231.373784) (xy 367.723714 -231.393256) (xy 367.769872 -231.419905)
			(xy 367.811543 -231.453136) (xy 367.847795 -231.492207) (xy 367.877819 -231.536244) (xy 367.900945 -231.584265)
			(xy 367.916655 -231.635195) (xy 367.924598 -231.687899) (xy 367.925096 -231.714548) (xy 367.924598 -231.741197)
			(xy 368.15267 -231.741197) (xy 368.15267 -231.687899) (xy 368.160613 -231.635195) (xy 368.176323 -231.584265)
			(xy 368.199449 -231.536244) (xy 368.229473 -231.492207) (xy 368.265725 -231.453136) (xy 368.307396 -231.419905)
			(xy 368.353554 -231.393256) (xy 368.403168 -231.373784) (xy 368.45513 -231.361924) (xy 368.50828 -231.357941)
			(xy 368.56143 -231.361924) (xy 368.613392 -231.373784) (xy 368.663006 -231.393256) (xy 368.709164 -231.419905)
			(xy 368.750835 -231.453136) (xy 368.787087 -231.492207) (xy 368.817111 -231.536244) (xy 368.840237 -231.584265)
			(xy 368.855947 -231.635195) (xy 368.86389 -231.687899) (xy 368.864388 -231.714548) (xy 368.86389 -231.741197)
			(xy 369.092978 -231.741197) (xy 369.092978 -231.687899) (xy 369.100921 -231.635195) (xy 369.116631 -231.584265)
			(xy 369.139757 -231.536244) (xy 369.169781 -231.492207) (xy 369.206033 -231.453136) (xy 369.247704 -231.419905)
			(xy 369.293862 -231.393256) (xy 369.343476 -231.373784) (xy 369.395438 -231.361924) (xy 369.448588 -231.357941)
			(xy 369.501738 -231.361924) (xy 369.5537 -231.373784) (xy 369.603314 -231.393256) (xy 369.649472 -231.419905)
			(xy 369.691143 -231.453136) (xy 369.727395 -231.492207) (xy 369.757419 -231.536244) (xy 369.780545 -231.584265)
			(xy 369.796255 -231.635195) (xy 369.804198 -231.687899) (xy 369.804696 -231.714548) (xy 369.804198 -231.741197)
			(xy 370.032524 -231.741197) (xy 370.032524 -231.687899) (xy 370.040467 -231.635195) (xy 370.056177 -231.584265)
			(xy 370.079303 -231.536244) (xy 370.109327 -231.492207) (xy 370.145579 -231.453136) (xy 370.18725 -231.419905)
			(xy 370.233408 -231.393256) (xy 370.283022 -231.373784) (xy 370.334984 -231.361924) (xy 370.388134 -231.357941)
			(xy 370.441284 -231.361924) (xy 370.493246 -231.373784) (xy 370.54286 -231.393256) (xy 370.589018 -231.419905)
			(xy 370.630689 -231.453136) (xy 370.666941 -231.492207) (xy 370.696965 -231.536244) (xy 370.720091 -231.584265)
			(xy 370.735801 -231.635195) (xy 370.743744 -231.687899) (xy 370.744242 -231.714548) (xy 370.743744 -231.741197)
			(xy 370.97207 -231.741197) (xy 370.97207 -231.687899) (xy 370.980013 -231.635195) (xy 370.995723 -231.584265)
			(xy 371.018849 -231.536244) (xy 371.048873 -231.492207) (xy 371.085125 -231.453136) (xy 371.126796 -231.419905)
			(xy 371.172954 -231.393256) (xy 371.222568 -231.373784) (xy 371.27453 -231.361924) (xy 371.32768 -231.357941)
			(xy 371.38083 -231.361924) (xy 371.432792 -231.373784) (xy 371.482406 -231.393256) (xy 371.528564 -231.419905)
			(xy 371.570235 -231.453136) (xy 371.606487 -231.492207) (xy 371.636511 -231.536244) (xy 371.659637 -231.584265)
			(xy 371.675347 -231.635195) (xy 371.68329 -231.687899) (xy 371.683788 -231.714548) (xy 371.68329 -231.741197)
			(xy 371.91187 -231.741197) (xy 371.91187 -231.687899) (xy 371.919813 -231.635195) (xy 371.935523 -231.584265)
			(xy 371.958649 -231.536244) (xy 371.988673 -231.492207) (xy 372.024925 -231.453136) (xy 372.066596 -231.419905)
			(xy 372.112754 -231.393256) (xy 372.162368 -231.373784) (xy 372.21433 -231.361924) (xy 372.26748 -231.357941)
			(xy 372.32063 -231.361924) (xy 372.372592 -231.373784) (xy 372.422206 -231.393256) (xy 372.468364 -231.419905)
			(xy 372.510035 -231.453136) (xy 372.546287 -231.492207) (xy 372.576311 -231.536244) (xy 372.599437 -231.584265)
			(xy 372.615147 -231.635195) (xy 372.62309 -231.687899) (xy 372.623588 -231.714548) (xy 372.62309 -231.741197)
			(xy 372.85167 -231.741197) (xy 372.85167 -231.687899) (xy 372.859613 -231.635195) (xy 372.875323 -231.584265)
			(xy 372.898449 -231.536244) (xy 372.928473 -231.492207) (xy 372.964725 -231.453136) (xy 373.006396 -231.419905)
			(xy 373.052554 -231.393256) (xy 373.102168 -231.373784) (xy 373.15413 -231.361924) (xy 373.20728 -231.357941)
			(xy 373.26043 -231.361924) (xy 373.312392 -231.373784) (xy 373.362006 -231.393256) (xy 373.408164 -231.419905)
			(xy 373.449835 -231.453136) (xy 373.486087 -231.492207) (xy 373.516111 -231.536244) (xy 373.539237 -231.584265)
			(xy 373.554947 -231.635195) (xy 373.56289 -231.687899) (xy 373.563388 -231.714548) (xy 373.56289 -231.741197)
			(xy 373.79147 -231.741197) (xy 373.79147 -231.687899) (xy 373.799413 -231.635195) (xy 373.815123 -231.584265)
			(xy 373.838249 -231.536244) (xy 373.868273 -231.492207) (xy 373.904525 -231.453136) (xy 373.946196 -231.419905)
			(xy 373.992354 -231.393256) (xy 374.041968 -231.373784) (xy 374.09393 -231.361924) (xy 374.14708 -231.357941)
			(xy 374.20023 -231.361924) (xy 374.252192 -231.373784) (xy 374.301806 -231.393256) (xy 374.347964 -231.419905)
			(xy 374.389635 -231.453136) (xy 374.425887 -231.492207) (xy 374.455911 -231.536244) (xy 374.479037 -231.584265)
			(xy 374.494747 -231.635195) (xy 374.50269 -231.687899) (xy 374.503188 -231.714548) (xy 374.50269 -231.741197)
			(xy 374.73127 -231.741197) (xy 374.73127 -231.687899) (xy 374.739213 -231.635195) (xy 374.754923 -231.584265)
			(xy 374.778049 -231.536244) (xy 374.808073 -231.492207) (xy 374.844325 -231.453136) (xy 374.885996 -231.419905)
			(xy 374.932154 -231.393256) (xy 374.981768 -231.373784) (xy 375.03373 -231.361924) (xy 375.08688 -231.357941)
			(xy 375.14003 -231.361924) (xy 375.191992 -231.373784) (xy 375.241606 -231.393256) (xy 375.287764 -231.419905)
			(xy 375.329435 -231.453136) (xy 375.365687 -231.492207) (xy 375.395711 -231.536244) (xy 375.418837 -231.584265)
			(xy 375.434547 -231.635195) (xy 375.44249 -231.687899) (xy 375.442988 -231.714548) (xy 375.44249 -231.741197)
			(xy 375.67107 -231.741197) (xy 375.67107 -231.687899) (xy 375.679013 -231.635195) (xy 375.694723 -231.584265)
			(xy 375.717849 -231.536244) (xy 375.747873 -231.492207) (xy 375.784125 -231.453136) (xy 375.825796 -231.419905)
			(xy 375.871954 -231.393256) (xy 375.921568 -231.373784) (xy 375.97353 -231.361924) (xy 376.02668 -231.357941)
			(xy 376.07983 -231.361924) (xy 376.131792 -231.373784) (xy 376.181406 -231.393256) (xy 376.227564 -231.419905)
			(xy 376.269235 -231.453136) (xy 376.305487 -231.492207) (xy 376.335511 -231.536244) (xy 376.358637 -231.584265)
			(xy 376.374347 -231.635195) (xy 376.38229 -231.687899) (xy 376.382788 -231.714548) (xy 376.38229 -231.741197)
			(xy 376.611124 -231.741197) (xy 376.611124 -231.687899) (xy 376.619067 -231.635195) (xy 376.634777 -231.584265)
			(xy 376.657903 -231.536244) (xy 376.687927 -231.492207) (xy 376.724179 -231.453136) (xy 376.76585 -231.419905)
			(xy 376.812008 -231.393256) (xy 376.861622 -231.373784) (xy 376.913584 -231.361924) (xy 376.966734 -231.357941)
			(xy 377.019884 -231.361924) (xy 377.071846 -231.373784) (xy 377.12146 -231.393256) (xy 377.167618 -231.419905)
			(xy 377.209289 -231.453136) (xy 377.245541 -231.492207) (xy 377.275565 -231.536244) (xy 377.298691 -231.584265)
			(xy 377.314401 -231.635195) (xy 377.322344 -231.687899) (xy 377.322842 -231.714548) (xy 377.322344 -231.741197)
			(xy 377.55067 -231.741197) (xy 377.55067 -231.687899) (xy 377.558613 -231.635195) (xy 377.574323 -231.584265)
			(xy 377.597449 -231.536244) (xy 377.627473 -231.492207) (xy 377.663725 -231.453136) (xy 377.705396 -231.419905)
			(xy 377.751554 -231.393256) (xy 377.801168 -231.373784) (xy 377.85313 -231.361924) (xy 377.90628 -231.357941)
			(xy 377.95943 -231.361924) (xy 378.011392 -231.373784) (xy 378.061006 -231.393256) (xy 378.107164 -231.419905)
			(xy 378.148835 -231.453136) (xy 378.185087 -231.492207) (xy 378.215111 -231.536244) (xy 378.238237 -231.584265)
			(xy 378.253947 -231.635195) (xy 378.26189 -231.687899) (xy 378.262388 -231.714548) (xy 378.26189 -231.741197)
			(xy 378.49047 -231.741197) (xy 378.49047 -231.687899) (xy 378.498413 -231.635195) (xy 378.514123 -231.584265)
			(xy 378.537249 -231.536244) (xy 378.567273 -231.492207) (xy 378.603525 -231.453136) (xy 378.645196 -231.419905)
			(xy 378.691354 -231.393256) (xy 378.740968 -231.373784) (xy 378.79293 -231.361924) (xy 378.84608 -231.357941)
			(xy 378.89923 -231.361924) (xy 378.951192 -231.373784) (xy 379.000806 -231.393256) (xy 379.046964 -231.419905)
			(xy 379.088635 -231.453136) (xy 379.124887 -231.492207) (xy 379.154911 -231.536244) (xy 379.178037 -231.584265)
			(xy 379.193747 -231.635195) (xy 379.20169 -231.687899) (xy 379.202188 -231.714548) (xy 379.20169 -231.741197)
			(xy 379.43027 -231.741197) (xy 379.43027 -231.687899) (xy 379.438213 -231.635195) (xy 379.453923 -231.584265)
			(xy 379.477049 -231.536244) (xy 379.507073 -231.492207) (xy 379.543325 -231.453136) (xy 379.584996 -231.419905)
			(xy 379.631154 -231.393256) (xy 379.680768 -231.373784) (xy 379.73273 -231.361924) (xy 379.78588 -231.357941)
			(xy 379.83903 -231.361924) (xy 379.890992 -231.373784) (xy 379.940606 -231.393256) (xy 379.986764 -231.419905)
			(xy 380.028435 -231.453136) (xy 380.064687 -231.492207) (xy 380.094711 -231.536244) (xy 380.117837 -231.584265)
			(xy 380.133547 -231.635195) (xy 380.14149 -231.687899) (xy 380.141988 -231.714548) (xy 380.14149 -231.741197)
			(xy 380.133547 -231.793901) (xy 380.117837 -231.844831) (xy 380.094711 -231.892852) (xy 380.064687 -231.936889)
			(xy 380.028435 -231.97596) (xy 379.986764 -232.009191) (xy 379.940606 -232.03584) (xy 379.890992 -232.055312)
			(xy 379.83903 -232.067172) (xy 379.78588 -232.071156) (xy 379.73273 -232.067172) (xy 379.680768 -232.055312)
			(xy 379.631154 -232.03584) (xy 379.584996 -232.009191) (xy 379.543325 -231.97596) (xy 379.507073 -231.936889)
			(xy 379.477049 -231.892852) (xy 379.453923 -231.844831) (xy 379.438213 -231.793901) (xy 379.43027 -231.741197)
			(xy 379.20169 -231.741197) (xy 379.193747 -231.793901) (xy 379.178037 -231.844831) (xy 379.154911 -231.892852)
			(xy 379.124887 -231.936889) (xy 379.088635 -231.97596) (xy 379.046964 -232.009191) (xy 379.000806 -232.03584)
			(xy 378.951192 -232.055312) (xy 378.89923 -232.067172) (xy 378.84608 -232.071156) (xy 378.79293 -232.067172)
			(xy 378.740968 -232.055312) (xy 378.691354 -232.03584) (xy 378.645196 -232.009191) (xy 378.603525 -231.97596)
			(xy 378.567273 -231.936889) (xy 378.537249 -231.892852) (xy 378.514123 -231.844831) (xy 378.498413 -231.793901)
			(xy 378.49047 -231.741197) (xy 378.26189 -231.741197) (xy 378.253947 -231.793901) (xy 378.238237 -231.844831)
			(xy 378.215111 -231.892852) (xy 378.185087 -231.936889) (xy 378.148835 -231.97596) (xy 378.107164 -232.009191)
			(xy 378.061006 -232.03584) (xy 378.011392 -232.055312) (xy 377.95943 -232.067172) (xy 377.90628 -232.071156)
			(xy 377.85313 -232.067172) (xy 377.801168 -232.055312) (xy 377.751554 -232.03584) (xy 377.705396 -232.009191)
			(xy 377.663725 -231.97596) (xy 377.627473 -231.936889) (xy 377.597449 -231.892852) (xy 377.574323 -231.844831)
			(xy 377.558613 -231.793901) (xy 377.55067 -231.741197) (xy 377.322344 -231.741197) (xy 377.314401 -231.793901)
			(xy 377.298691 -231.844831) (xy 377.275565 -231.892852) (xy 377.245541 -231.936889) (xy 377.209289 -231.97596)
			(xy 377.167618 -232.009191) (xy 377.12146 -232.03584) (xy 377.071846 -232.055312) (xy 377.019884 -232.067172)
			(xy 376.966734 -232.071156) (xy 376.913584 -232.067172) (xy 376.861622 -232.055312) (xy 376.812008 -232.03584)
			(xy 376.76585 -232.009191) (xy 376.724179 -231.97596) (xy 376.687927 -231.936889) (xy 376.657903 -231.892852)
			(xy 376.634777 -231.844831) (xy 376.619067 -231.793901) (xy 376.611124 -231.741197) (xy 376.38229 -231.741197)
			(xy 376.374347 -231.793901) (xy 376.358637 -231.844831) (xy 376.335511 -231.892852) (xy 376.305487 -231.936889)
			(xy 376.269235 -231.97596) (xy 376.227564 -232.009191) (xy 376.181406 -232.03584) (xy 376.131792 -232.055312)
			(xy 376.07983 -232.067172) (xy 376.02668 -232.071156) (xy 375.97353 -232.067172) (xy 375.921568 -232.055312)
			(xy 375.871954 -232.03584) (xy 375.825796 -232.009191) (xy 375.784125 -231.97596) (xy 375.747873 -231.936889)
			(xy 375.717849 -231.892852) (xy 375.694723 -231.844831) (xy 375.679013 -231.793901) (xy 375.67107 -231.741197)
			(xy 375.44249 -231.741197) (xy 375.434547 -231.793901) (xy 375.418837 -231.844831) (xy 375.395711 -231.892852)
			(xy 375.365687 -231.936889) (xy 375.329435 -231.97596) (xy 375.287764 -232.009191) (xy 375.241606 -232.03584)
			(xy 375.191992 -232.055312) (xy 375.14003 -232.067172) (xy 375.08688 -232.071156) (xy 375.03373 -232.067172)
			(xy 374.981768 -232.055312) (xy 374.932154 -232.03584) (xy 374.885996 -232.009191) (xy 374.844325 -231.97596)
			(xy 374.808073 -231.936889) (xy 374.778049 -231.892852) (xy 374.754923 -231.844831) (xy 374.739213 -231.793901)
			(xy 374.73127 -231.741197) (xy 374.50269 -231.741197) (xy 374.494747 -231.793901) (xy 374.479037 -231.844831)
			(xy 374.455911 -231.892852) (xy 374.425887 -231.936889) (xy 374.389635 -231.97596) (xy 374.347964 -232.009191)
			(xy 374.301806 -232.03584) (xy 374.252192 -232.055312) (xy 374.20023 -232.067172) (xy 374.14708 -232.071156)
			(xy 374.09393 -232.067172) (xy 374.041968 -232.055312) (xy 373.992354 -232.03584) (xy 373.946196 -232.009191)
			(xy 373.904525 -231.97596) (xy 373.868273 -231.936889) (xy 373.838249 -231.892852) (xy 373.815123 -231.844831)
			(xy 373.799413 -231.793901) (xy 373.79147 -231.741197) (xy 373.56289 -231.741197) (xy 373.554947 -231.793901)
			(xy 373.539237 -231.844831) (xy 373.516111 -231.892852) (xy 373.486087 -231.936889) (xy 373.449835 -231.97596)
			(xy 373.408164 -232.009191) (xy 373.362006 -232.03584) (xy 373.312392 -232.055312) (xy 373.26043 -232.067172)
			(xy 373.20728 -232.071156) (xy 373.15413 -232.067172) (xy 373.102168 -232.055312) (xy 373.052554 -232.03584)
			(xy 373.006396 -232.009191) (xy 372.964725 -231.97596) (xy 372.928473 -231.936889) (xy 372.898449 -231.892852)
			(xy 372.875323 -231.844831) (xy 372.859613 -231.793901) (xy 372.85167 -231.741197) (xy 372.62309 -231.741197)
			(xy 372.615147 -231.793901) (xy 372.599437 -231.844831) (xy 372.576311 -231.892852) (xy 372.546287 -231.936889)
			(xy 372.510035 -231.97596) (xy 372.468364 -232.009191) (xy 372.422206 -232.03584) (xy 372.372592 -232.055312)
			(xy 372.32063 -232.067172) (xy 372.26748 -232.071156) (xy 372.21433 -232.067172) (xy 372.162368 -232.055312)
			(xy 372.112754 -232.03584) (xy 372.066596 -232.009191) (xy 372.024925 -231.97596) (xy 371.988673 -231.936889)
			(xy 371.958649 -231.892852) (xy 371.935523 -231.844831) (xy 371.919813 -231.793901) (xy 371.91187 -231.741197)
			(xy 371.68329 -231.741197) (xy 371.675347 -231.793901) (xy 371.659637 -231.844831) (xy 371.636511 -231.892852)
			(xy 371.606487 -231.936889) (xy 371.570235 -231.97596) (xy 371.528564 -232.009191) (xy 371.482406 -232.03584)
			(xy 371.432792 -232.055312) (xy 371.38083 -232.067172) (xy 371.32768 -232.071156) (xy 371.27453 -232.067172)
			(xy 371.222568 -232.055312) (xy 371.172954 -232.03584) (xy 371.126796 -232.009191) (xy 371.085125 -231.97596)
			(xy 371.048873 -231.936889) (xy 371.018849 -231.892852) (xy 370.995723 -231.844831) (xy 370.980013 -231.793901)
			(xy 370.97207 -231.741197) (xy 370.743744 -231.741197) (xy 370.735801 -231.793901) (xy 370.720091 -231.844831)
			(xy 370.696965 -231.892852) (xy 370.666941 -231.936889) (xy 370.630689 -231.97596) (xy 370.589018 -232.009191)
			(xy 370.54286 -232.03584) (xy 370.493246 -232.055312) (xy 370.441284 -232.067172) (xy 370.388134 -232.071156)
			(xy 370.334984 -232.067172) (xy 370.283022 -232.055312) (xy 370.233408 -232.03584) (xy 370.18725 -232.009191)
			(xy 370.145579 -231.97596) (xy 370.109327 -231.936889) (xy 370.079303 -231.892852) (xy 370.056177 -231.844831)
			(xy 370.040467 -231.793901) (xy 370.032524 -231.741197) (xy 369.804198 -231.741197) (xy 369.796255 -231.793901)
			(xy 369.780545 -231.844831) (xy 369.757419 -231.892852) (xy 369.727395 -231.936889) (xy 369.691143 -231.97596)
			(xy 369.649472 -232.009191) (xy 369.603314 -232.03584) (xy 369.5537 -232.055312) (xy 369.501738 -232.067172)
			(xy 369.448588 -232.071156) (xy 369.395438 -232.067172) (xy 369.343476 -232.055312) (xy 369.293862 -232.03584)
			(xy 369.247704 -232.009191) (xy 369.206033 -231.97596) (xy 369.169781 -231.936889) (xy 369.139757 -231.892852)
			(xy 369.116631 -231.844831) (xy 369.100921 -231.793901) (xy 369.092978 -231.741197) (xy 368.86389 -231.741197)
			(xy 368.855947 -231.793901) (xy 368.840237 -231.844831) (xy 368.817111 -231.892852) (xy 368.787087 -231.936889)
			(xy 368.750835 -231.97596) (xy 368.709164 -232.009191) (xy 368.663006 -232.03584) (xy 368.613392 -232.055312)
			(xy 368.56143 -232.067172) (xy 368.50828 -232.071156) (xy 368.45513 -232.067172) (xy 368.403168 -232.055312)
			(xy 368.353554 -232.03584) (xy 368.307396 -232.009191) (xy 368.265725 -231.97596) (xy 368.229473 -231.936889)
			(xy 368.199449 -231.892852) (xy 368.176323 -231.844831) (xy 368.160613 -231.793901) (xy 368.15267 -231.741197)
			(xy 367.924598 -231.741197) (xy 367.916655 -231.793901) (xy 367.900945 -231.844831) (xy 367.877819 -231.892852)
			(xy 367.847795 -231.936889) (xy 367.811543 -231.97596) (xy 367.769872 -232.009191) (xy 367.723714 -232.03584)
			(xy 367.6741 -232.055312) (xy 367.622138 -232.067172) (xy 367.568988 -232.071156) (xy 367.515838 -232.067172)
			(xy 367.463876 -232.055312) (xy 367.414262 -232.03584) (xy 367.368104 -232.009191) (xy 367.326433 -231.97596)
			(xy 367.290181 -231.936889) (xy 367.260157 -231.892852) (xy 367.237031 -231.844831) (xy 367.221321 -231.793901)
			(xy 367.213378 -231.741197) (xy 366.98429 -231.741197) (xy 366.976347 -231.793901) (xy 366.960637 -231.844831)
			(xy 366.937511 -231.892852) (xy 366.907487 -231.936889) (xy 366.871235 -231.97596) (xy 366.829564 -232.009191)
			(xy 366.783406 -232.03584) (xy 366.733792 -232.055312) (xy 366.68183 -232.067172) (xy 366.62868 -232.071156)
			(xy 366.57553 -232.067172) (xy 366.523568 -232.055312) (xy 366.473954 -232.03584) (xy 366.427796 -232.009191)
			(xy 366.386125 -231.97596) (xy 366.349873 -231.936889) (xy 366.319849 -231.892852) (xy 366.296723 -231.844831)
			(xy 366.281013 -231.793901) (xy 366.27307 -231.741197) (xy 366.04449 -231.741197) (xy 366.036547 -231.793901)
			(xy 366.020837 -231.844831) (xy 365.997711 -231.892852) (xy 365.967687 -231.936889) (xy 365.931435 -231.97596)
			(xy 365.889764 -232.009191) (xy 365.843606 -232.03584) (xy 365.793992 -232.055312) (xy 365.74203 -232.067172)
			(xy 365.68888 -232.071156) (xy 365.63573 -232.067172) (xy 365.583768 -232.055312) (xy 365.534154 -232.03584)
			(xy 365.487996 -232.009191) (xy 365.446325 -231.97596) (xy 365.410073 -231.936889) (xy 365.380049 -231.892852)
			(xy 365.356923 -231.844831) (xy 365.341213 -231.793901) (xy 365.33327 -231.741197) (xy 365.10469 -231.741197)
			(xy 365.096747 -231.793901) (xy 365.081037 -231.844831) (xy 365.057911 -231.892852) (xy 365.027887 -231.936889)
			(xy 364.991635 -231.97596) (xy 364.949964 -232.009191) (xy 364.903806 -232.03584) (xy 364.854192 -232.055312)
			(xy 364.80223 -232.067172) (xy 364.74908 -232.071156) (xy 364.69593 -232.067172) (xy 364.643968 -232.055312)
			(xy 364.594354 -232.03584) (xy 364.548196 -232.009191) (xy 364.506525 -231.97596) (xy 364.470273 -231.936889)
			(xy 364.440249 -231.892852) (xy 364.417123 -231.844831) (xy 364.401413 -231.793901) (xy 364.39347 -231.741197)
			(xy 364.16489 -231.741197) (xy 364.156947 -231.793901) (xy 364.141237 -231.844831) (xy 364.118111 -231.892852)
			(xy 364.088087 -231.936889) (xy 364.051835 -231.97596) (xy 364.010164 -232.009191) (xy 363.964006 -232.03584)
			(xy 363.914392 -232.055312) (xy 363.86243 -232.067172) (xy 363.80928 -232.071156) (xy 363.75613 -232.067172)
			(xy 363.704168 -232.055312) (xy 363.654554 -232.03584) (xy 363.608396 -232.009191) (xy 363.566725 -231.97596)
			(xy 363.530473 -231.936889) (xy 363.500449 -231.892852) (xy 363.477323 -231.844831) (xy 363.461613 -231.793901)
			(xy 363.45367 -231.741197) (xy 363.22509 -231.741197) (xy 363.217147 -231.793901) (xy 363.201437 -231.844831)
			(xy 363.178311 -231.892852) (xy 363.148287 -231.936889) (xy 363.112035 -231.97596) (xy 363.070364 -232.009191)
			(xy 363.024206 -232.03584) (xy 362.974592 -232.055312) (xy 362.92263 -232.067172) (xy 362.86948 -232.071156)
			(xy 362.81633 -232.067172) (xy 362.764368 -232.055312) (xy 362.714754 -232.03584) (xy 362.668596 -232.009191)
			(xy 362.626925 -231.97596) (xy 362.590673 -231.936889) (xy 362.560649 -231.892852) (xy 362.537523 -231.844831)
			(xy 362.521813 -231.793901) (xy 362.51387 -231.741197) (xy 362.285798 -231.741197) (xy 362.277855 -231.793901)
			(xy 362.262145 -231.844831) (xy 362.239019 -231.892852) (xy 362.208995 -231.936889) (xy 362.172743 -231.97596)
			(xy 362.131072 -232.009191) (xy 362.084914 -232.03584) (xy 362.0353 -232.055312) (xy 361.983338 -232.067172)
			(xy 361.930188 -232.071156) (xy 361.877038 -232.067172) (xy 361.825076 -232.055312) (xy 361.775462 -232.03584)
			(xy 361.729304 -232.009191) (xy 361.687633 -231.97596) (xy 361.651381 -231.936889) (xy 361.621357 -231.892852)
			(xy 361.598231 -231.844831) (xy 361.582521 -231.793901) (xy 361.574578 -231.741197) (xy 361.345998 -231.741197)
			(xy 361.338055 -231.793901) (xy 361.322345 -231.844831) (xy 361.299219 -231.892852) (xy 361.269195 -231.936889)
			(xy 361.232943 -231.97596) (xy 361.191272 -232.009191) (xy 361.145114 -232.03584) (xy 361.0955 -232.055312)
			(xy 361.043538 -232.067172) (xy 360.990388 -232.071156) (xy 360.937238 -232.067172) (xy 360.885276 -232.055312)
			(xy 360.835662 -232.03584) (xy 360.789504 -232.009191) (xy 360.747833 -231.97596) (xy 360.711581 -231.936889)
			(xy 360.681557 -231.892852) (xy 360.658431 -231.844831) (xy 360.642721 -231.793901) (xy 360.634778 -231.741197)
			(xy 360.406198 -231.741197) (xy 360.398255 -231.793901) (xy 360.382545 -231.844831) (xy 360.359419 -231.892852)
			(xy 360.329395 -231.936889) (xy 360.293143 -231.97596) (xy 360.251472 -232.009191) (xy 360.205314 -232.03584)
			(xy 360.1557 -232.055312) (xy 360.103738 -232.067172) (xy 360.050588 -232.071156) (xy 359.997438 -232.067172)
			(xy 359.945476 -232.055312) (xy 359.895862 -232.03584) (xy 359.849704 -232.009191) (xy 359.808033 -231.97596)
			(xy 359.771781 -231.936889) (xy 359.741757 -231.892852) (xy 359.718631 -231.844831) (xy 359.702921 -231.793901)
			(xy 359.694978 -231.741197) (xy 359.465861 -231.741197) (xy 359.465835 -231.742528) (xy 359.457074 -231.797798)
			(xy 359.439775 -231.851018) (xy 359.414364 -231.900876) (xy 359.381467 -231.946145) (xy 359.341893 -231.985711)
			(xy 359.296618 -232.0186) (xy 359.246755 -232.044001) (xy 359.193532 -232.06129) (xy 359.13826 -232.070041)
			(xy 359.11028 -232.070656) (xy 359.081397 -232.070093) (xy 359.024391 -232.060762) (xy 358.969639 -232.042349)
			(xy 358.918578 -232.015336) (xy 358.87255 -231.980433) (xy 358.852216 -231.959912) (xy 358.842573 -231.950444)
			(xy 358.819431 -231.936504) (xy 358.793447 -231.929111) (xy 358.766433 -231.92878) (xy 358.740276 -231.935536)
			(xy 358.7168 -231.948905) (xy 358.706928 -231.958134) (xy 358.657652 -232.00741) (xy 358.648231 -232.017452)
			(xy 358.634645 -232.04139) (xy 358.627941 -232.068085) (xy 358.628606 -232.095601) (xy 358.63659 -232.121942)
			(xy 358.651314 -232.145196) (xy 358.671711 -232.163677) (xy 358.696301 -232.176044) (xy 358.709722 -232.179114)
			(xy 358.736321 -232.18491) (xy 358.787487 -232.203491) (xy 358.83523 -232.229642) (xy 358.878438 -232.262754)
			(xy 358.916105 -232.302054) (xy 358.947353 -232.346628) (xy 358.971454 -232.395438) (xy 358.987847 -232.447347)
			(xy 358.996151 -232.501146) (xy 358.996742 -232.528364) (xy 358.99625 -232.555013) (xy 359.224824 -232.555013)
			(xy 359.224824 -232.501715) (xy 359.232767 -232.449011) (xy 359.248477 -232.398081) (xy 359.271603 -232.35006)
			(xy 359.301627 -232.306023) (xy 359.337879 -232.266952) (xy 359.37955 -232.233721) (xy 359.425708 -232.207072)
			(xy 359.475322 -232.1876) (xy 359.527284 -232.17574) (xy 359.580434 -232.171757) (xy 359.633584 -232.17574)
			(xy 359.685546 -232.1876) (xy 359.73516 -232.207072) (xy 359.781318 -232.233721) (xy 359.822989 -232.266952)
			(xy 359.859241 -232.306023) (xy 359.889265 -232.35006) (xy 359.912391 -232.398081) (xy 359.928101 -232.449011)
			(xy 359.936044 -232.501715) (xy 359.936542 -232.528364) (xy 359.936044 -232.555013) (xy 360.164624 -232.555013)
			(xy 360.164624 -232.501715) (xy 360.172567 -232.449011) (xy 360.188277 -232.398081) (xy 360.211403 -232.35006)
			(xy 360.241427 -232.306023) (xy 360.277679 -232.266952) (xy 360.31935 -232.233721) (xy 360.365508 -232.207072)
			(xy 360.415122 -232.1876) (xy 360.467084 -232.17574) (xy 360.520234 -232.171757) (xy 360.573384 -232.17574)
			(xy 360.625346 -232.1876) (xy 360.67496 -232.207072) (xy 360.721118 -232.233721) (xy 360.762789 -232.266952)
			(xy 360.799041 -232.306023) (xy 360.829065 -232.35006) (xy 360.852191 -232.398081) (xy 360.867901 -232.449011)
			(xy 360.875844 -232.501715) (xy 360.876342 -232.528364) (xy 360.875844 -232.555013) (xy 361.104424 -232.555013)
			(xy 361.104424 -232.501715) (xy 361.112367 -232.449011) (xy 361.128077 -232.398081) (xy 361.151203 -232.35006)
			(xy 361.181227 -232.306023) (xy 361.217479 -232.266952) (xy 361.25915 -232.233721) (xy 361.305308 -232.207072)
			(xy 361.354922 -232.1876) (xy 361.406884 -232.17574) (xy 361.460034 -232.171757) (xy 361.513184 -232.17574)
			(xy 361.565146 -232.1876) (xy 361.61476 -232.207072) (xy 361.660918 -232.233721) (xy 361.702589 -232.266952)
			(xy 361.738841 -232.306023) (xy 361.768865 -232.35006) (xy 361.791991 -232.398081) (xy 361.807701 -232.449011)
			(xy 361.815644 -232.501715) (xy 361.816142 -232.528364) (xy 361.815644 -232.555013) (xy 362.044224 -232.555013)
			(xy 362.044224 -232.501715) (xy 362.052167 -232.449011) (xy 362.067877 -232.398081) (xy 362.091003 -232.35006)
			(xy 362.121027 -232.306023) (xy 362.157279 -232.266952) (xy 362.19895 -232.233721) (xy 362.245108 -232.207072)
			(xy 362.294722 -232.1876) (xy 362.346684 -232.17574) (xy 362.399834 -232.171757) (xy 362.452984 -232.17574)
			(xy 362.504946 -232.1876) (xy 362.55456 -232.207072) (xy 362.600718 -232.233721) (xy 362.642389 -232.266952)
			(xy 362.678641 -232.306023) (xy 362.708665 -232.35006) (xy 362.731791 -232.398081) (xy 362.747501 -232.449011)
			(xy 362.755444 -232.501715) (xy 362.755942 -232.528364) (xy 362.755444 -232.555013) (xy 362.984024 -232.555013)
			(xy 362.984024 -232.501715) (xy 362.991967 -232.449011) (xy 363.007677 -232.398081) (xy 363.030803 -232.35006)
			(xy 363.060827 -232.306023) (xy 363.097079 -232.266952) (xy 363.13875 -232.233721) (xy 363.184908 -232.207072)
			(xy 363.234522 -232.1876) (xy 363.286484 -232.17574) (xy 363.339634 -232.171757) (xy 363.392784 -232.17574)
			(xy 363.444746 -232.1876) (xy 363.49436 -232.207072) (xy 363.540518 -232.233721) (xy 363.582189 -232.266952)
			(xy 363.618441 -232.306023) (xy 363.648465 -232.35006) (xy 363.671591 -232.398081) (xy 363.687301 -232.449011)
			(xy 363.695244 -232.501715) (xy 363.695742 -232.528364) (xy 363.695244 -232.555013) (xy 363.923824 -232.555013)
			(xy 363.923824 -232.501715) (xy 363.931767 -232.449011) (xy 363.947477 -232.398081) (xy 363.970603 -232.35006)
			(xy 364.000627 -232.306023) (xy 364.036879 -232.266952) (xy 364.07855 -232.233721) (xy 364.124708 -232.207072)
			(xy 364.174322 -232.1876) (xy 364.226284 -232.17574) (xy 364.279434 -232.171757) (xy 364.332584 -232.17574)
			(xy 364.384546 -232.1876) (xy 364.43416 -232.207072) (xy 364.480318 -232.233721) (xy 364.521989 -232.266952)
			(xy 364.558241 -232.306023) (xy 364.588265 -232.35006) (xy 364.611391 -232.398081) (xy 364.627101 -232.449011)
			(xy 364.635044 -232.501715) (xy 364.635542 -232.528364) (xy 364.635044 -232.555013) (xy 364.863624 -232.555013)
			(xy 364.863624 -232.501715) (xy 364.871567 -232.449011) (xy 364.887277 -232.398081) (xy 364.910403 -232.35006)
			(xy 364.940427 -232.306023) (xy 364.976679 -232.266952) (xy 365.01835 -232.233721) (xy 365.064508 -232.207072)
			(xy 365.114122 -232.1876) (xy 365.166084 -232.17574) (xy 365.219234 -232.171757) (xy 365.272384 -232.17574)
			(xy 365.324346 -232.1876) (xy 365.37396 -232.207072) (xy 365.420118 -232.233721) (xy 365.461789 -232.266952)
			(xy 365.498041 -232.306023) (xy 365.528065 -232.35006) (xy 365.551191 -232.398081) (xy 365.566901 -232.449011)
			(xy 365.574844 -232.501715) (xy 365.575342 -232.528364) (xy 365.574844 -232.555013) (xy 365.803424 -232.555013)
			(xy 365.803424 -232.501715) (xy 365.811367 -232.449011) (xy 365.827077 -232.398081) (xy 365.850203 -232.35006)
			(xy 365.880227 -232.306023) (xy 365.916479 -232.266952) (xy 365.95815 -232.233721) (xy 366.004308 -232.207072)
			(xy 366.053922 -232.1876) (xy 366.105884 -232.17574) (xy 366.159034 -232.171757) (xy 366.212184 -232.17574)
			(xy 366.264146 -232.1876) (xy 366.31376 -232.207072) (xy 366.359918 -232.233721) (xy 366.401589 -232.266952)
			(xy 366.437841 -232.306023) (xy 366.467865 -232.35006) (xy 366.490991 -232.398081) (xy 366.506701 -232.449011)
			(xy 366.514644 -232.501715) (xy 366.515142 -232.528364) (xy 366.514644 -232.555013) (xy 366.743224 -232.555013)
			(xy 366.743224 -232.501715) (xy 366.751167 -232.449011) (xy 366.766877 -232.398081) (xy 366.790003 -232.35006)
			(xy 366.820027 -232.306023) (xy 366.856279 -232.266952) (xy 366.89795 -232.233721) (xy 366.944108 -232.207072)
			(xy 366.993722 -232.1876) (xy 367.045684 -232.17574) (xy 367.098834 -232.171757) (xy 367.151984 -232.17574)
			(xy 367.203946 -232.1876) (xy 367.25356 -232.207072) (xy 367.299718 -232.233721) (xy 367.341389 -232.266952)
			(xy 367.377641 -232.306023) (xy 367.407665 -232.35006) (xy 367.430791 -232.398081) (xy 367.446501 -232.449011)
			(xy 367.454444 -232.501715) (xy 367.454942 -232.528364) (xy 367.454444 -232.555013) (xy 367.68277 -232.555013)
			(xy 367.68277 -232.501715) (xy 367.690713 -232.449011) (xy 367.706423 -232.398081) (xy 367.729549 -232.35006)
			(xy 367.759573 -232.306023) (xy 367.795825 -232.266952) (xy 367.837496 -232.233721) (xy 367.883654 -232.207072)
			(xy 367.933268 -232.1876) (xy 367.98523 -232.17574) (xy 368.03838 -232.171757) (xy 368.09153 -232.17574)
			(xy 368.143492 -232.1876) (xy 368.193106 -232.207072) (xy 368.239264 -232.233721) (xy 368.280935 -232.266952)
			(xy 368.317187 -232.306023) (xy 368.347211 -232.35006) (xy 368.370337 -232.398081) (xy 368.386047 -232.449011)
			(xy 368.39399 -232.501715) (xy 368.394488 -232.528364) (xy 368.39399 -232.555013) (xy 368.622824 -232.555013)
			(xy 368.622824 -232.501715) (xy 368.630767 -232.449011) (xy 368.646477 -232.398081) (xy 368.669603 -232.35006)
			(xy 368.699627 -232.306023) (xy 368.735879 -232.266952) (xy 368.77755 -232.233721) (xy 368.823708 -232.207072)
			(xy 368.873322 -232.1876) (xy 368.925284 -232.17574) (xy 368.978434 -232.171757) (xy 369.031584 -232.17574)
			(xy 369.083546 -232.1876) (xy 369.13316 -232.207072) (xy 369.179318 -232.233721) (xy 369.220989 -232.266952)
			(xy 369.257241 -232.306023) (xy 369.287265 -232.35006) (xy 369.310391 -232.398081) (xy 369.326101 -232.449011)
			(xy 369.334044 -232.501715) (xy 369.334542 -232.528364) (xy 369.334044 -232.555013) (xy 369.562624 -232.555013)
			(xy 369.562624 -232.501715) (xy 369.570567 -232.449011) (xy 369.586277 -232.398081) (xy 369.609403 -232.35006)
			(xy 369.639427 -232.306023) (xy 369.675679 -232.266952) (xy 369.71735 -232.233721) (xy 369.763508 -232.207072)
			(xy 369.813122 -232.1876) (xy 369.865084 -232.17574) (xy 369.918234 -232.171757) (xy 369.971384 -232.17574)
			(xy 370.023346 -232.1876) (xy 370.07296 -232.207072) (xy 370.119118 -232.233721) (xy 370.160789 -232.266952)
			(xy 370.197041 -232.306023) (xy 370.227065 -232.35006) (xy 370.250191 -232.398081) (xy 370.265901 -232.449011)
			(xy 370.273844 -232.501715) (xy 370.274342 -232.528364) (xy 370.273844 -232.555013) (xy 370.502424 -232.555013)
			(xy 370.502424 -232.501715) (xy 370.510367 -232.449011) (xy 370.526077 -232.398081) (xy 370.549203 -232.35006)
			(xy 370.579227 -232.306023) (xy 370.615479 -232.266952) (xy 370.65715 -232.233721) (xy 370.703308 -232.207072)
			(xy 370.752922 -232.1876) (xy 370.804884 -232.17574) (xy 370.858034 -232.171757) (xy 370.911184 -232.17574)
			(xy 370.963146 -232.1876) (xy 371.01276 -232.207072) (xy 371.058918 -232.233721) (xy 371.100589 -232.266952)
			(xy 371.136841 -232.306023) (xy 371.166865 -232.35006) (xy 371.189991 -232.398081) (xy 371.205701 -232.449011)
			(xy 371.213644 -232.501715) (xy 371.214142 -232.528364) (xy 371.213644 -232.555013) (xy 371.442224 -232.555013)
			(xy 371.442224 -232.501715) (xy 371.450167 -232.449011) (xy 371.465877 -232.398081) (xy 371.489003 -232.35006)
			(xy 371.519027 -232.306023) (xy 371.555279 -232.266952) (xy 371.59695 -232.233721) (xy 371.643108 -232.207072)
			(xy 371.692722 -232.1876) (xy 371.744684 -232.17574) (xy 371.797834 -232.171757) (xy 371.850984 -232.17574)
			(xy 371.902946 -232.1876) (xy 371.95256 -232.207072) (xy 371.998718 -232.233721) (xy 372.040389 -232.266952)
			(xy 372.076641 -232.306023) (xy 372.106665 -232.35006) (xy 372.129791 -232.398081) (xy 372.145501 -232.449011)
			(xy 372.153444 -232.501715) (xy 372.153942 -232.528364) (xy 372.153444 -232.555013) (xy 372.382024 -232.555013)
			(xy 372.382024 -232.501715) (xy 372.389967 -232.449011) (xy 372.405677 -232.398081) (xy 372.428803 -232.35006)
			(xy 372.458827 -232.306023) (xy 372.495079 -232.266952) (xy 372.53675 -232.233721) (xy 372.582908 -232.207072)
			(xy 372.632522 -232.1876) (xy 372.684484 -232.17574) (xy 372.737634 -232.171757) (xy 372.790784 -232.17574)
			(xy 372.842746 -232.1876) (xy 372.89236 -232.207072) (xy 372.938518 -232.233721) (xy 372.980189 -232.266952)
			(xy 373.016441 -232.306023) (xy 373.046465 -232.35006) (xy 373.069591 -232.398081) (xy 373.085301 -232.449011)
			(xy 373.093244 -232.501715) (xy 373.093742 -232.528364) (xy 373.093244 -232.555013) (xy 373.321824 -232.555013)
			(xy 373.321824 -232.501715) (xy 373.329767 -232.449011) (xy 373.345477 -232.398081) (xy 373.368603 -232.35006)
			(xy 373.398627 -232.306023) (xy 373.434879 -232.266952) (xy 373.47655 -232.233721) (xy 373.522708 -232.207072)
			(xy 373.572322 -232.1876) (xy 373.624284 -232.17574) (xy 373.677434 -232.171757) (xy 373.730584 -232.17574)
			(xy 373.782546 -232.1876) (xy 373.83216 -232.207072) (xy 373.878318 -232.233721) (xy 373.919989 -232.266952)
			(xy 373.956241 -232.306023) (xy 373.986265 -232.35006) (xy 374.009391 -232.398081) (xy 374.025101 -232.449011)
			(xy 374.033044 -232.501715) (xy 374.033542 -232.528364) (xy 374.033044 -232.555013) (xy 374.26137 -232.555013)
			(xy 374.26137 -232.501715) (xy 374.269313 -232.449011) (xy 374.285023 -232.398081) (xy 374.308149 -232.35006)
			(xy 374.338173 -232.306023) (xy 374.374425 -232.266952) (xy 374.416096 -232.233721) (xy 374.462254 -232.207072)
			(xy 374.511868 -232.1876) (xy 374.56383 -232.17574) (xy 374.61698 -232.171757) (xy 374.67013 -232.17574)
			(xy 374.722092 -232.1876) (xy 374.771706 -232.207072) (xy 374.817864 -232.233721) (xy 374.859535 -232.266952)
			(xy 374.895787 -232.306023) (xy 374.925811 -232.35006) (xy 374.948937 -232.398081) (xy 374.964647 -232.449011)
			(xy 374.97259 -232.501715) (xy 374.973088 -232.528364) (xy 374.97259 -232.555013) (xy 375.201424 -232.555013)
			(xy 375.201424 -232.501715) (xy 375.209367 -232.449011) (xy 375.225077 -232.398081) (xy 375.248203 -232.35006)
			(xy 375.278227 -232.306023) (xy 375.314479 -232.266952) (xy 375.35615 -232.233721) (xy 375.402308 -232.207072)
			(xy 375.451922 -232.1876) (xy 375.503884 -232.17574) (xy 375.557034 -232.171757) (xy 375.610184 -232.17574)
			(xy 375.662146 -232.1876) (xy 375.71176 -232.207072) (xy 375.757918 -232.233721) (xy 375.799589 -232.266952)
			(xy 375.835841 -232.306023) (xy 375.865865 -232.35006) (xy 375.888991 -232.398081) (xy 375.904701 -232.449011)
			(xy 375.912644 -232.501715) (xy 375.913142 -232.528364) (xy 375.912644 -232.555013) (xy 376.141224 -232.555013)
			(xy 376.141224 -232.501715) (xy 376.149167 -232.449011) (xy 376.164877 -232.398081) (xy 376.188003 -232.35006)
			(xy 376.218027 -232.306023) (xy 376.254279 -232.266952) (xy 376.29595 -232.233721) (xy 376.342108 -232.207072)
			(xy 376.391722 -232.1876) (xy 376.443684 -232.17574) (xy 376.496834 -232.171757) (xy 376.549984 -232.17574)
			(xy 376.601946 -232.1876) (xy 376.65156 -232.207072) (xy 376.697718 -232.233721) (xy 376.739389 -232.266952)
			(xy 376.775641 -232.306023) (xy 376.805665 -232.35006) (xy 376.828791 -232.398081) (xy 376.844501 -232.449011)
			(xy 376.852444 -232.501715) (xy 376.852942 -232.528364) (xy 376.852444 -232.555013) (xy 377.081024 -232.555013)
			(xy 377.081024 -232.501715) (xy 377.088967 -232.449011) (xy 377.104677 -232.398081) (xy 377.127803 -232.35006)
			(xy 377.157827 -232.306023) (xy 377.194079 -232.266952) (xy 377.23575 -232.233721) (xy 377.281908 -232.207072)
			(xy 377.331522 -232.1876) (xy 377.383484 -232.17574) (xy 377.436634 -232.171757) (xy 377.489784 -232.17574)
			(xy 377.541746 -232.1876) (xy 377.59136 -232.207072) (xy 377.637518 -232.233721) (xy 377.679189 -232.266952)
			(xy 377.715441 -232.306023) (xy 377.745465 -232.35006) (xy 377.768591 -232.398081) (xy 377.784301 -232.449011)
			(xy 377.792244 -232.501715) (xy 377.792742 -232.528364) (xy 377.792244 -232.555013) (xy 378.020824 -232.555013)
			(xy 378.020824 -232.501715) (xy 378.028767 -232.449011) (xy 378.044477 -232.398081) (xy 378.067603 -232.35006)
			(xy 378.097627 -232.306023) (xy 378.133879 -232.266952) (xy 378.17555 -232.233721) (xy 378.221708 -232.207072)
			(xy 378.271322 -232.1876) (xy 378.323284 -232.17574) (xy 378.376434 -232.171757) (xy 378.429584 -232.17574)
			(xy 378.481546 -232.1876) (xy 378.53116 -232.207072) (xy 378.577318 -232.233721) (xy 378.618989 -232.266952)
			(xy 378.655241 -232.306023) (xy 378.685265 -232.35006) (xy 378.708391 -232.398081) (xy 378.724101 -232.449011)
			(xy 378.732044 -232.501715) (xy 378.732542 -232.528364) (xy 378.732044 -232.555013) (xy 378.960624 -232.555013)
			(xy 378.960624 -232.501715) (xy 378.968567 -232.449011) (xy 378.984277 -232.398081) (xy 379.007403 -232.35006)
			(xy 379.037427 -232.306023) (xy 379.073679 -232.266952) (xy 379.11535 -232.233721) (xy 379.161508 -232.207072)
			(xy 379.211122 -232.1876) (xy 379.263084 -232.17574) (xy 379.316234 -232.171757) (xy 379.369384 -232.17574)
			(xy 379.421346 -232.1876) (xy 379.47096 -232.207072) (xy 379.517118 -232.233721) (xy 379.558789 -232.266952)
			(xy 379.595041 -232.306023) (xy 379.625065 -232.35006) (xy 379.648191 -232.398081) (xy 379.663901 -232.449011)
			(xy 379.671844 -232.501715) (xy 379.672342 -232.528364) (xy 379.671844 -232.555013) (xy 379.900424 -232.555013)
			(xy 379.900424 -232.501715) (xy 379.908367 -232.449011) (xy 379.924077 -232.398081) (xy 379.947203 -232.35006)
			(xy 379.977227 -232.306023) (xy 380.013479 -232.266952) (xy 380.05515 -232.233721) (xy 380.101308 -232.207072)
			(xy 380.150922 -232.1876) (xy 380.202884 -232.17574) (xy 380.256034 -232.171757) (xy 380.309184 -232.17574)
			(xy 380.361146 -232.1876) (xy 380.41076 -232.207072) (xy 380.456918 -232.233721) (xy 380.498589 -232.266952)
			(xy 380.534841 -232.306023) (xy 380.564865 -232.35006) (xy 380.587991 -232.398081) (xy 380.603701 -232.449011)
			(xy 380.611644 -232.501715) (xy 380.612142 -232.528364) (xy 380.611644 -232.555013) (xy 380.603701 -232.607717)
			(xy 380.587991 -232.658647) (xy 380.564865 -232.706668) (xy 380.534841 -232.750705) (xy 380.498589 -232.789776)
			(xy 380.456918 -232.823007) (xy 380.41076 -232.849656) (xy 380.361146 -232.869128) (xy 380.309184 -232.880988)
			(xy 380.256034 -232.884972) (xy 380.202884 -232.880988) (xy 380.150922 -232.869128) (xy 380.101308 -232.849656)
			(xy 380.05515 -232.823007) (xy 380.013479 -232.789776) (xy 379.977227 -232.750705) (xy 379.947203 -232.706668)
			(xy 379.924077 -232.658647) (xy 379.908367 -232.607717) (xy 379.900424 -232.555013) (xy 379.671844 -232.555013)
			(xy 379.663901 -232.607717) (xy 379.648191 -232.658647) (xy 379.625065 -232.706668) (xy 379.595041 -232.750705)
			(xy 379.558789 -232.789776) (xy 379.517118 -232.823007) (xy 379.47096 -232.849656) (xy 379.421346 -232.869128)
			(xy 379.369384 -232.880988) (xy 379.316234 -232.884972) (xy 379.263084 -232.880988) (xy 379.211122 -232.869128)
			(xy 379.161508 -232.849656) (xy 379.11535 -232.823007) (xy 379.073679 -232.789776) (xy 379.037427 -232.750705)
			(xy 379.007403 -232.706668) (xy 378.984277 -232.658647) (xy 378.968567 -232.607717) (xy 378.960624 -232.555013)
			(xy 378.732044 -232.555013) (xy 378.724101 -232.607717) (xy 378.708391 -232.658647) (xy 378.685265 -232.706668)
			(xy 378.655241 -232.750705) (xy 378.618989 -232.789776) (xy 378.577318 -232.823007) (xy 378.53116 -232.849656)
			(xy 378.481546 -232.869128) (xy 378.429584 -232.880988) (xy 378.376434 -232.884972) (xy 378.323284 -232.880988)
			(xy 378.271322 -232.869128) (xy 378.221708 -232.849656) (xy 378.17555 -232.823007) (xy 378.133879 -232.789776)
			(xy 378.097627 -232.750705) (xy 378.067603 -232.706668) (xy 378.044477 -232.658647) (xy 378.028767 -232.607717)
			(xy 378.020824 -232.555013) (xy 377.792244 -232.555013) (xy 377.784301 -232.607717) (xy 377.768591 -232.658647)
			(xy 377.745465 -232.706668) (xy 377.715441 -232.750705) (xy 377.679189 -232.789776) (xy 377.637518 -232.823007)
			(xy 377.59136 -232.849656) (xy 377.541746 -232.869128) (xy 377.489784 -232.880988) (xy 377.436634 -232.884972)
			(xy 377.383484 -232.880988) (xy 377.331522 -232.869128) (xy 377.281908 -232.849656) (xy 377.23575 -232.823007)
			(xy 377.194079 -232.789776) (xy 377.157827 -232.750705) (xy 377.127803 -232.706668) (xy 377.104677 -232.658647)
			(xy 377.088967 -232.607717) (xy 377.081024 -232.555013) (xy 376.852444 -232.555013) (xy 376.844501 -232.607717)
			(xy 376.828791 -232.658647) (xy 376.805665 -232.706668) (xy 376.775641 -232.750705) (xy 376.739389 -232.789776)
			(xy 376.697718 -232.823007) (xy 376.65156 -232.849656) (xy 376.601946 -232.869128) (xy 376.549984 -232.880988)
			(xy 376.496834 -232.884972) (xy 376.443684 -232.880988) (xy 376.391722 -232.869128) (xy 376.342108 -232.849656)
			(xy 376.29595 -232.823007) (xy 376.254279 -232.789776) (xy 376.218027 -232.750705) (xy 376.188003 -232.706668)
			(xy 376.164877 -232.658647) (xy 376.149167 -232.607717) (xy 376.141224 -232.555013) (xy 375.912644 -232.555013)
			(xy 375.904701 -232.607717) (xy 375.888991 -232.658647) (xy 375.865865 -232.706668) (xy 375.835841 -232.750705)
			(xy 375.799589 -232.789776) (xy 375.757918 -232.823007) (xy 375.71176 -232.849656) (xy 375.662146 -232.869128)
			(xy 375.610184 -232.880988) (xy 375.557034 -232.884972) (xy 375.503884 -232.880988) (xy 375.451922 -232.869128)
			(xy 375.402308 -232.849656) (xy 375.35615 -232.823007) (xy 375.314479 -232.789776) (xy 375.278227 -232.750705)
			(xy 375.248203 -232.706668) (xy 375.225077 -232.658647) (xy 375.209367 -232.607717) (xy 375.201424 -232.555013)
			(xy 374.97259 -232.555013) (xy 374.964647 -232.607717) (xy 374.948937 -232.658647) (xy 374.925811 -232.706668)
			(xy 374.895787 -232.750705) (xy 374.859535 -232.789776) (xy 374.817864 -232.823007) (xy 374.771706 -232.849656)
			(xy 374.722092 -232.869128) (xy 374.67013 -232.880988) (xy 374.61698 -232.884972) (xy 374.56383 -232.880988)
			(xy 374.511868 -232.869128) (xy 374.462254 -232.849656) (xy 374.416096 -232.823007) (xy 374.374425 -232.789776)
			(xy 374.338173 -232.750705) (xy 374.308149 -232.706668) (xy 374.285023 -232.658647) (xy 374.269313 -232.607717)
			(xy 374.26137 -232.555013) (xy 374.033044 -232.555013) (xy 374.025101 -232.607717) (xy 374.009391 -232.658647)
			(xy 373.986265 -232.706668) (xy 373.956241 -232.750705) (xy 373.919989 -232.789776) (xy 373.878318 -232.823007)
			(xy 373.83216 -232.849656) (xy 373.782546 -232.869128) (xy 373.730584 -232.880988) (xy 373.677434 -232.884972)
			(xy 373.624284 -232.880988) (xy 373.572322 -232.869128) (xy 373.522708 -232.849656) (xy 373.47655 -232.823007)
			(xy 373.434879 -232.789776) (xy 373.398627 -232.750705) (xy 373.368603 -232.706668) (xy 373.345477 -232.658647)
			(xy 373.329767 -232.607717) (xy 373.321824 -232.555013) (xy 373.093244 -232.555013) (xy 373.085301 -232.607717)
			(xy 373.069591 -232.658647) (xy 373.046465 -232.706668) (xy 373.016441 -232.750705) (xy 372.980189 -232.789776)
			(xy 372.938518 -232.823007) (xy 372.89236 -232.849656) (xy 372.842746 -232.869128) (xy 372.790784 -232.880988)
			(xy 372.737634 -232.884972) (xy 372.684484 -232.880988) (xy 372.632522 -232.869128) (xy 372.582908 -232.849656)
			(xy 372.53675 -232.823007) (xy 372.495079 -232.789776) (xy 372.458827 -232.750705) (xy 372.428803 -232.706668)
			(xy 372.405677 -232.658647) (xy 372.389967 -232.607717) (xy 372.382024 -232.555013) (xy 372.153444 -232.555013)
			(xy 372.145501 -232.607717) (xy 372.129791 -232.658647) (xy 372.106665 -232.706668) (xy 372.076641 -232.750705)
			(xy 372.040389 -232.789776) (xy 371.998718 -232.823007) (xy 371.95256 -232.849656) (xy 371.902946 -232.869128)
			(xy 371.850984 -232.880988) (xy 371.797834 -232.884972) (xy 371.744684 -232.880988) (xy 371.692722 -232.869128)
			(xy 371.643108 -232.849656) (xy 371.59695 -232.823007) (xy 371.555279 -232.789776) (xy 371.519027 -232.750705)
			(xy 371.489003 -232.706668) (xy 371.465877 -232.658647) (xy 371.450167 -232.607717) (xy 371.442224 -232.555013)
			(xy 371.213644 -232.555013) (xy 371.205701 -232.607717) (xy 371.189991 -232.658647) (xy 371.166865 -232.706668)
			(xy 371.136841 -232.750705) (xy 371.100589 -232.789776) (xy 371.058918 -232.823007) (xy 371.01276 -232.849656)
			(xy 370.963146 -232.869128) (xy 370.911184 -232.880988) (xy 370.858034 -232.884972) (xy 370.804884 -232.880988)
			(xy 370.752922 -232.869128) (xy 370.703308 -232.849656) (xy 370.65715 -232.823007) (xy 370.615479 -232.789776)
			(xy 370.579227 -232.750705) (xy 370.549203 -232.706668) (xy 370.526077 -232.658647) (xy 370.510367 -232.607717)
			(xy 370.502424 -232.555013) (xy 370.273844 -232.555013) (xy 370.265901 -232.607717) (xy 370.250191 -232.658647)
			(xy 370.227065 -232.706668) (xy 370.197041 -232.750705) (xy 370.160789 -232.789776) (xy 370.119118 -232.823007)
			(xy 370.07296 -232.849656) (xy 370.023346 -232.869128) (xy 369.971384 -232.880988) (xy 369.918234 -232.884972)
			(xy 369.865084 -232.880988) (xy 369.813122 -232.869128) (xy 369.763508 -232.849656) (xy 369.71735 -232.823007)
			(xy 369.675679 -232.789776) (xy 369.639427 -232.750705) (xy 369.609403 -232.706668) (xy 369.586277 -232.658647)
			(xy 369.570567 -232.607717) (xy 369.562624 -232.555013) (xy 369.334044 -232.555013) (xy 369.326101 -232.607717)
			(xy 369.310391 -232.658647) (xy 369.287265 -232.706668) (xy 369.257241 -232.750705) (xy 369.220989 -232.789776)
			(xy 369.179318 -232.823007) (xy 369.13316 -232.849656) (xy 369.083546 -232.869128) (xy 369.031584 -232.880988)
			(xy 368.978434 -232.884972) (xy 368.925284 -232.880988) (xy 368.873322 -232.869128) (xy 368.823708 -232.849656)
			(xy 368.77755 -232.823007) (xy 368.735879 -232.789776) (xy 368.699627 -232.750705) (xy 368.669603 -232.706668)
			(xy 368.646477 -232.658647) (xy 368.630767 -232.607717) (xy 368.622824 -232.555013) (xy 368.39399 -232.555013)
			(xy 368.386047 -232.607717) (xy 368.370337 -232.658647) (xy 368.347211 -232.706668) (xy 368.317187 -232.750705)
			(xy 368.280935 -232.789776) (xy 368.239264 -232.823007) (xy 368.193106 -232.849656) (xy 368.143492 -232.869128)
			(xy 368.09153 -232.880988) (xy 368.03838 -232.884972) (xy 367.98523 -232.880988) (xy 367.933268 -232.869128)
			(xy 367.883654 -232.849656) (xy 367.837496 -232.823007) (xy 367.795825 -232.789776) (xy 367.759573 -232.750705)
			(xy 367.729549 -232.706668) (xy 367.706423 -232.658647) (xy 367.690713 -232.607717) (xy 367.68277 -232.555013)
			(xy 367.454444 -232.555013) (xy 367.446501 -232.607717) (xy 367.430791 -232.658647) (xy 367.407665 -232.706668)
			(xy 367.377641 -232.750705) (xy 367.341389 -232.789776) (xy 367.299718 -232.823007) (xy 367.25356 -232.849656)
			(xy 367.203946 -232.869128) (xy 367.151984 -232.880988) (xy 367.098834 -232.884972) (xy 367.045684 -232.880988)
			(xy 366.993722 -232.869128) (xy 366.944108 -232.849656) (xy 366.89795 -232.823007) (xy 366.856279 -232.789776)
			(xy 366.820027 -232.750705) (xy 366.790003 -232.706668) (xy 366.766877 -232.658647) (xy 366.751167 -232.607717)
			(xy 366.743224 -232.555013) (xy 366.514644 -232.555013) (xy 366.506701 -232.607717) (xy 366.490991 -232.658647)
			(xy 366.467865 -232.706668) (xy 366.437841 -232.750705) (xy 366.401589 -232.789776) (xy 366.359918 -232.823007)
			(xy 366.31376 -232.849656) (xy 366.264146 -232.869128) (xy 366.212184 -232.880988) (xy 366.159034 -232.884972)
			(xy 366.105884 -232.880988) (xy 366.053922 -232.869128) (xy 366.004308 -232.849656) (xy 365.95815 -232.823007)
			(xy 365.916479 -232.789776) (xy 365.880227 -232.750705) (xy 365.850203 -232.706668) (xy 365.827077 -232.658647)
			(xy 365.811367 -232.607717) (xy 365.803424 -232.555013) (xy 365.574844 -232.555013) (xy 365.566901 -232.607717)
			(xy 365.551191 -232.658647) (xy 365.528065 -232.706668) (xy 365.498041 -232.750705) (xy 365.461789 -232.789776)
			(xy 365.420118 -232.823007) (xy 365.37396 -232.849656) (xy 365.324346 -232.869128) (xy 365.272384 -232.880988)
			(xy 365.219234 -232.884972) (xy 365.166084 -232.880988) (xy 365.114122 -232.869128) (xy 365.064508 -232.849656)
			(xy 365.01835 -232.823007) (xy 364.976679 -232.789776) (xy 364.940427 -232.750705) (xy 364.910403 -232.706668)
			(xy 364.887277 -232.658647) (xy 364.871567 -232.607717) (xy 364.863624 -232.555013) (xy 364.635044 -232.555013)
			(xy 364.627101 -232.607717) (xy 364.611391 -232.658647) (xy 364.588265 -232.706668) (xy 364.558241 -232.750705)
			(xy 364.521989 -232.789776) (xy 364.480318 -232.823007) (xy 364.43416 -232.849656) (xy 364.384546 -232.869128)
			(xy 364.332584 -232.880988) (xy 364.279434 -232.884972) (xy 364.226284 -232.880988) (xy 364.174322 -232.869128)
			(xy 364.124708 -232.849656) (xy 364.07855 -232.823007) (xy 364.036879 -232.789776) (xy 364.000627 -232.750705)
			(xy 363.970603 -232.706668) (xy 363.947477 -232.658647) (xy 363.931767 -232.607717) (xy 363.923824 -232.555013)
			(xy 363.695244 -232.555013) (xy 363.687301 -232.607717) (xy 363.671591 -232.658647) (xy 363.648465 -232.706668)
			(xy 363.618441 -232.750705) (xy 363.582189 -232.789776) (xy 363.540518 -232.823007) (xy 363.49436 -232.849656)
			(xy 363.444746 -232.869128) (xy 363.392784 -232.880988) (xy 363.339634 -232.884972) (xy 363.286484 -232.880988)
			(xy 363.234522 -232.869128) (xy 363.184908 -232.849656) (xy 363.13875 -232.823007) (xy 363.097079 -232.789776)
			(xy 363.060827 -232.750705) (xy 363.030803 -232.706668) (xy 363.007677 -232.658647) (xy 362.991967 -232.607717)
			(xy 362.984024 -232.555013) (xy 362.755444 -232.555013) (xy 362.747501 -232.607717) (xy 362.731791 -232.658647)
			(xy 362.708665 -232.706668) (xy 362.678641 -232.750705) (xy 362.642389 -232.789776) (xy 362.600718 -232.823007)
			(xy 362.55456 -232.849656) (xy 362.504946 -232.869128) (xy 362.452984 -232.880988) (xy 362.399834 -232.884972)
			(xy 362.346684 -232.880988) (xy 362.294722 -232.869128) (xy 362.245108 -232.849656) (xy 362.19895 -232.823007)
			(xy 362.157279 -232.789776) (xy 362.121027 -232.750705) (xy 362.091003 -232.706668) (xy 362.067877 -232.658647)
			(xy 362.052167 -232.607717) (xy 362.044224 -232.555013) (xy 361.815644 -232.555013) (xy 361.807701 -232.607717)
			(xy 361.791991 -232.658647) (xy 361.768865 -232.706668) (xy 361.738841 -232.750705) (xy 361.702589 -232.789776)
			(xy 361.660918 -232.823007) (xy 361.61476 -232.849656) (xy 361.565146 -232.869128) (xy 361.513184 -232.880988)
			(xy 361.460034 -232.884972) (xy 361.406884 -232.880988) (xy 361.354922 -232.869128) (xy 361.305308 -232.849656)
			(xy 361.25915 -232.823007) (xy 361.217479 -232.789776) (xy 361.181227 -232.750705) (xy 361.151203 -232.706668)
			(xy 361.128077 -232.658647) (xy 361.112367 -232.607717) (xy 361.104424 -232.555013) (xy 360.875844 -232.555013)
			(xy 360.867901 -232.607717) (xy 360.852191 -232.658647) (xy 360.829065 -232.706668) (xy 360.799041 -232.750705)
			(xy 360.762789 -232.789776) (xy 360.721118 -232.823007) (xy 360.67496 -232.849656) (xy 360.625346 -232.869128)
			(xy 360.573384 -232.880988) (xy 360.520234 -232.884972) (xy 360.467084 -232.880988) (xy 360.415122 -232.869128)
			(xy 360.365508 -232.849656) (xy 360.31935 -232.823007) (xy 360.277679 -232.789776) (xy 360.241427 -232.750705)
			(xy 360.211403 -232.706668) (xy 360.188277 -232.658647) (xy 360.172567 -232.607717) (xy 360.164624 -232.555013)
			(xy 359.936044 -232.555013) (xy 359.928101 -232.607717) (xy 359.912391 -232.658647) (xy 359.889265 -232.706668)
			(xy 359.859241 -232.750705) (xy 359.822989 -232.789776) (xy 359.781318 -232.823007) (xy 359.73516 -232.849656)
			(xy 359.685546 -232.869128) (xy 359.633584 -232.880988) (xy 359.580434 -232.884972) (xy 359.527284 -232.880988)
			(xy 359.475322 -232.869128) (xy 359.425708 -232.849656) (xy 359.37955 -232.823007) (xy 359.337879 -232.789776)
			(xy 359.301627 -232.750705) (xy 359.271603 -232.706668) (xy 359.248477 -232.658647) (xy 359.232767 -232.607717)
			(xy 359.224824 -232.555013) (xy 358.99625 -232.555013) (xy 358.996225 -232.556352) (xy 358.987474 -232.61164)
			(xy 358.970181 -232.664879) (xy 358.944774 -232.714756) (xy 358.911876 -232.760045) (xy 358.872299 -232.79963)
			(xy 358.827016 -232.832537) (xy 358.777143 -232.857954) (xy 358.723908 -232.875257) (xy 358.668622 -232.884019)
			(xy 358.640634 -232.884472) (xy 358.613412 -232.883957) (xy 358.559601 -232.875669) (xy 358.507681 -232.859282)
			(xy 358.458863 -232.835177) (xy 358.414286 -232.803918) (xy 358.374991 -232.766233) (xy 358.341894 -232.723003)
			(xy 358.315768 -232.675236) (xy 358.297223 -232.624047) (xy 358.291384 -232.597452) (xy 358.288307 -232.584016)
			(xy 358.276 -232.559366) (xy 358.257541 -232.538912) (xy 358.234278 -232.52415) (xy 358.20791 -232.516158)
			(xy 358.180366 -232.51552) (xy 358.153657 -232.522283) (xy 358.129736 -232.535952) (xy 358.11968 -232.545382)
			(xy 358.045258 -232.619804) (xy 358.041448 -232.631996) (xy 358.033792 -232.655733) (xy 358.012763 -232.700958)
			(xy 357.985628 -232.742806) (xy 357.952919 -232.780457) (xy 357.915276 -232.813176) (xy 357.873434 -232.84032)
			(xy 357.828214 -232.86136) (xy 357.804466 -232.868978) (xy 357.792274 -232.872788) (xy 357.525828 -233.139234)
			(xy 357.543862 -233.172508) (xy 357.557356 -233.198735) (xy 357.576497 -233.254519) (xy 357.586201 -233.312692)
			(xy 357.586788 -233.34218) (xy 357.586294 -233.368829) (xy 357.815124 -233.368829) (xy 357.815124 -233.315531)
			(xy 357.823067 -233.262827) (xy 357.838777 -233.211897) (xy 357.861903 -233.163876) (xy 357.891927 -233.119839)
			(xy 357.928179 -233.080768) (xy 357.96985 -233.047537) (xy 358.016008 -233.020888) (xy 358.065622 -233.001416)
			(xy 358.117584 -232.989556) (xy 358.170734 -232.985573) (xy 358.223884 -232.989556) (xy 358.275846 -233.001416)
			(xy 358.32546 -233.020888) (xy 358.371618 -233.047537) (xy 358.413289 -233.080768) (xy 358.449541 -233.119839)
			(xy 358.479565 -233.163876) (xy 358.502691 -233.211897) (xy 358.518401 -233.262827) (xy 358.526344 -233.315531)
			(xy 358.526842 -233.34218) (xy 358.526344 -233.368829) (xy 358.75467 -233.368829) (xy 358.75467 -233.315531)
			(xy 358.762613 -233.262827) (xy 358.778323 -233.211897) (xy 358.801449 -233.163876) (xy 358.831473 -233.119839)
			(xy 358.867725 -233.080768) (xy 358.909396 -233.047537) (xy 358.955554 -233.020888) (xy 359.005168 -233.001416)
			(xy 359.05713 -232.989556) (xy 359.11028 -232.985573) (xy 359.16343 -232.989556) (xy 359.215392 -233.001416)
			(xy 359.265006 -233.020888) (xy 359.311164 -233.047537) (xy 359.352835 -233.080768) (xy 359.389087 -233.119839)
			(xy 359.419111 -233.163876) (xy 359.442237 -233.211897) (xy 359.457947 -233.262827) (xy 359.46589 -233.315531)
			(xy 359.466388 -233.34218) (xy 359.46589 -233.368829) (xy 359.69447 -233.368829) (xy 359.69447 -233.315531)
			(xy 359.702413 -233.262827) (xy 359.718123 -233.211897) (xy 359.741249 -233.163876) (xy 359.771273 -233.119839)
			(xy 359.807525 -233.080768) (xy 359.849196 -233.047537) (xy 359.895354 -233.020888) (xy 359.944968 -233.001416)
			(xy 359.99693 -232.989556) (xy 360.05008 -232.985573) (xy 360.10323 -232.989556) (xy 360.155192 -233.001416)
			(xy 360.204806 -233.020888) (xy 360.250964 -233.047537) (xy 360.292635 -233.080768) (xy 360.328887 -233.119839)
			(xy 360.358911 -233.163876) (xy 360.382037 -233.211897) (xy 360.397747 -233.262827) (xy 360.40569 -233.315531)
			(xy 360.406188 -233.34218) (xy 360.40569 -233.368829) (xy 360.63427 -233.368829) (xy 360.63427 -233.315531)
			(xy 360.642213 -233.262827) (xy 360.657923 -233.211897) (xy 360.681049 -233.163876) (xy 360.711073 -233.119839)
			(xy 360.747325 -233.080768) (xy 360.788996 -233.047537) (xy 360.835154 -233.020888) (xy 360.884768 -233.001416)
			(xy 360.93673 -232.989556) (xy 360.98988 -232.985573) (xy 361.04303 -232.989556) (xy 361.094992 -233.001416)
			(xy 361.144606 -233.020888) (xy 361.190764 -233.047537) (xy 361.232435 -233.080768) (xy 361.268687 -233.119839)
			(xy 361.298711 -233.163876) (xy 361.321837 -233.211897) (xy 361.337547 -233.262827) (xy 361.34549 -233.315531)
			(xy 361.345988 -233.34218) (xy 361.34549 -233.368829) (xy 361.574324 -233.368829) (xy 361.574324 -233.315531)
			(xy 361.582267 -233.262827) (xy 361.597977 -233.211897) (xy 361.621103 -233.163876) (xy 361.651127 -233.119839)
			(xy 361.687379 -233.080768) (xy 361.72905 -233.047537) (xy 361.775208 -233.020888) (xy 361.824822 -233.001416)
			(xy 361.876784 -232.989556) (xy 361.929934 -232.985573) (xy 361.983084 -232.989556) (xy 362.035046 -233.001416)
			(xy 362.08466 -233.020888) (xy 362.130818 -233.047537) (xy 362.172489 -233.080768) (xy 362.208741 -233.119839)
			(xy 362.238765 -233.163876) (xy 362.261891 -233.211897) (xy 362.277601 -233.262827) (xy 362.285544 -233.315531)
			(xy 362.286042 -233.34218) (xy 362.285544 -233.368829) (xy 362.51387 -233.368829) (xy 362.51387 -233.315531)
			(xy 362.521813 -233.262827) (xy 362.537523 -233.211897) (xy 362.560649 -233.163876) (xy 362.590673 -233.119839)
			(xy 362.626925 -233.080768) (xy 362.668596 -233.047537) (xy 362.714754 -233.020888) (xy 362.764368 -233.001416)
			(xy 362.81633 -232.989556) (xy 362.86948 -232.985573) (xy 362.92263 -232.989556) (xy 362.974592 -233.001416)
			(xy 363.024206 -233.020888) (xy 363.070364 -233.047537) (xy 363.112035 -233.080768) (xy 363.148287 -233.119839)
			(xy 363.178311 -233.163876) (xy 363.201437 -233.211897) (xy 363.217147 -233.262827) (xy 363.22509 -233.315531)
			(xy 363.225588 -233.34218) (xy 363.22509 -233.368829) (xy 363.45367 -233.368829) (xy 363.45367 -233.315531)
			(xy 363.461613 -233.262827) (xy 363.477323 -233.211897) (xy 363.500449 -233.163876) (xy 363.530473 -233.119839)
			(xy 363.566725 -233.080768) (xy 363.608396 -233.047537) (xy 363.654554 -233.020888) (xy 363.704168 -233.001416)
			(xy 363.75613 -232.989556) (xy 363.80928 -232.985573) (xy 363.86243 -232.989556) (xy 363.914392 -233.001416)
			(xy 363.964006 -233.020888) (xy 364.010164 -233.047537) (xy 364.051835 -233.080768) (xy 364.088087 -233.119839)
			(xy 364.118111 -233.163876) (xy 364.141237 -233.211897) (xy 364.156947 -233.262827) (xy 364.16489 -233.315531)
			(xy 364.165388 -233.34218) (xy 364.16489 -233.368829) (xy 364.39347 -233.368829) (xy 364.39347 -233.315531)
			(xy 364.401413 -233.262827) (xy 364.417123 -233.211897) (xy 364.440249 -233.163876) (xy 364.470273 -233.119839)
			(xy 364.506525 -233.080768) (xy 364.548196 -233.047537) (xy 364.594354 -233.020888) (xy 364.643968 -233.001416)
			(xy 364.69593 -232.989556) (xy 364.74908 -232.985573) (xy 364.80223 -232.989556) (xy 364.854192 -233.001416)
			(xy 364.903806 -233.020888) (xy 364.949964 -233.047537) (xy 364.991635 -233.080768) (xy 365.027887 -233.119839)
			(xy 365.057911 -233.163876) (xy 365.081037 -233.211897) (xy 365.096747 -233.262827) (xy 365.10469 -233.315531)
			(xy 365.105188 -233.34218) (xy 365.10469 -233.368829) (xy 365.33327 -233.368829) (xy 365.33327 -233.315531)
			(xy 365.341213 -233.262827) (xy 365.356923 -233.211897) (xy 365.380049 -233.163876) (xy 365.410073 -233.119839)
			(xy 365.446325 -233.080768) (xy 365.487996 -233.047537) (xy 365.534154 -233.020888) (xy 365.583768 -233.001416)
			(xy 365.63573 -232.989556) (xy 365.68888 -232.985573) (xy 365.74203 -232.989556) (xy 365.793992 -233.001416)
			(xy 365.843606 -233.020888) (xy 365.889764 -233.047537) (xy 365.931435 -233.080768) (xy 365.967687 -233.119839)
			(xy 365.997711 -233.163876) (xy 366.020837 -233.211897) (xy 366.036547 -233.262827) (xy 366.04449 -233.315531)
			(xy 366.044988 -233.34218) (xy 366.04449 -233.368829) (xy 366.27307 -233.368829) (xy 366.27307 -233.315531)
			(xy 366.281013 -233.262827) (xy 366.296723 -233.211897) (xy 366.319849 -233.163876) (xy 366.349873 -233.119839)
			(xy 366.386125 -233.080768) (xy 366.427796 -233.047537) (xy 366.473954 -233.020888) (xy 366.523568 -233.001416)
			(xy 366.57553 -232.989556) (xy 366.62868 -232.985573) (xy 366.68183 -232.989556) (xy 366.733792 -233.001416)
			(xy 366.783406 -233.020888) (xy 366.829564 -233.047537) (xy 366.871235 -233.080768) (xy 366.907487 -233.119839)
			(xy 366.937511 -233.163876) (xy 366.960637 -233.211897) (xy 366.976347 -233.262827) (xy 366.98429 -233.315531)
			(xy 366.984788 -233.34218) (xy 366.98429 -233.368829) (xy 367.21287 -233.368829) (xy 367.21287 -233.315531)
			(xy 367.220813 -233.262827) (xy 367.236523 -233.211897) (xy 367.259649 -233.163876) (xy 367.289673 -233.119839)
			(xy 367.325925 -233.080768) (xy 367.367596 -233.047537) (xy 367.413754 -233.020888) (xy 367.463368 -233.001416)
			(xy 367.51533 -232.989556) (xy 367.56848 -232.985573) (xy 367.62163 -232.989556) (xy 367.673592 -233.001416)
			(xy 367.723206 -233.020888) (xy 367.769364 -233.047537) (xy 367.811035 -233.080768) (xy 367.847287 -233.119839)
			(xy 367.877311 -233.163876) (xy 367.900437 -233.211897) (xy 367.916147 -233.262827) (xy 367.92409 -233.315531)
			(xy 367.924588 -233.34218) (xy 367.92409 -233.368829) (xy 368.15267 -233.368829) (xy 368.15267 -233.315531)
			(xy 368.160613 -233.262827) (xy 368.176323 -233.211897) (xy 368.199449 -233.163876) (xy 368.229473 -233.119839)
			(xy 368.265725 -233.080768) (xy 368.307396 -233.047537) (xy 368.353554 -233.020888) (xy 368.403168 -233.001416)
			(xy 368.45513 -232.989556) (xy 368.50828 -232.985573) (xy 368.56143 -232.989556) (xy 368.613392 -233.001416)
			(xy 368.663006 -233.020888) (xy 368.709164 -233.047537) (xy 368.750835 -233.080768) (xy 368.787087 -233.119839)
			(xy 368.817111 -233.163876) (xy 368.840237 -233.211897) (xy 368.855947 -233.262827) (xy 368.86389 -233.315531)
			(xy 368.864388 -233.34218) (xy 368.86389 -233.368829) (xy 369.092724 -233.368829) (xy 369.092724 -233.315531)
			(xy 369.100667 -233.262827) (xy 369.116377 -233.211897) (xy 369.139503 -233.163876) (xy 369.169527 -233.119839)
			(xy 369.205779 -233.080768) (xy 369.24745 -233.047537) (xy 369.293608 -233.020888) (xy 369.343222 -233.001416)
			(xy 369.395184 -232.989556) (xy 369.448334 -232.985573) (xy 369.501484 -232.989556) (xy 369.553446 -233.001416)
			(xy 369.60306 -233.020888) (xy 369.649218 -233.047537) (xy 369.690889 -233.080768) (xy 369.727141 -233.119839)
			(xy 369.757165 -233.163876) (xy 369.780291 -233.211897) (xy 369.796001 -233.262827) (xy 369.803944 -233.315531)
			(xy 369.804442 -233.34218) (xy 369.803944 -233.368829) (xy 370.03227 -233.368829) (xy 370.03227 -233.315531)
			(xy 370.040213 -233.262827) (xy 370.055923 -233.211897) (xy 370.079049 -233.163876) (xy 370.109073 -233.119839)
			(xy 370.145325 -233.080768) (xy 370.186996 -233.047537) (xy 370.233154 -233.020888) (xy 370.282768 -233.001416)
			(xy 370.33473 -232.989556) (xy 370.38788 -232.985573) (xy 370.44103 -232.989556) (xy 370.492992 -233.001416)
			(xy 370.542606 -233.020888) (xy 370.588764 -233.047537) (xy 370.630435 -233.080768) (xy 370.666687 -233.119839)
			(xy 370.696711 -233.163876) (xy 370.719837 -233.211897) (xy 370.735547 -233.262827) (xy 370.74349 -233.315531)
			(xy 370.743988 -233.34218) (xy 370.74349 -233.368829) (xy 370.97207 -233.368829) (xy 370.97207 -233.315531)
			(xy 370.980013 -233.262827) (xy 370.995723 -233.211897) (xy 371.018849 -233.163876) (xy 371.048873 -233.119839)
			(xy 371.085125 -233.080768) (xy 371.126796 -233.047537) (xy 371.172954 -233.020888) (xy 371.222568 -233.001416)
			(xy 371.27453 -232.989556) (xy 371.32768 -232.985573) (xy 371.38083 -232.989556) (xy 371.432792 -233.001416)
			(xy 371.482406 -233.020888) (xy 371.528564 -233.047537) (xy 371.570235 -233.080768) (xy 371.606487 -233.119839)
			(xy 371.636511 -233.163876) (xy 371.659637 -233.211897) (xy 371.675347 -233.262827) (xy 371.68329 -233.315531)
			(xy 371.683788 -233.34218) (xy 371.68329 -233.368829) (xy 371.91187 -233.368829) (xy 371.91187 -233.315531)
			(xy 371.919813 -233.262827) (xy 371.935523 -233.211897) (xy 371.958649 -233.163876) (xy 371.988673 -233.119839)
			(xy 372.024925 -233.080768) (xy 372.066596 -233.047537) (xy 372.112754 -233.020888) (xy 372.162368 -233.001416)
			(xy 372.21433 -232.989556) (xy 372.26748 -232.985573) (xy 372.32063 -232.989556) (xy 372.372592 -233.001416)
			(xy 372.422206 -233.020888) (xy 372.468364 -233.047537) (xy 372.510035 -233.080768) (xy 372.546287 -233.119839)
			(xy 372.576311 -233.163876) (xy 372.599437 -233.211897) (xy 372.615147 -233.262827) (xy 372.62309 -233.315531)
			(xy 372.623588 -233.34218) (xy 372.62309 -233.368829) (xy 372.85167 -233.368829) (xy 372.85167 -233.315531)
			(xy 372.859613 -233.262827) (xy 372.875323 -233.211897) (xy 372.898449 -233.163876) (xy 372.928473 -233.119839)
			(xy 372.964725 -233.080768) (xy 373.006396 -233.047537) (xy 373.052554 -233.020888) (xy 373.102168 -233.001416)
			(xy 373.15413 -232.989556) (xy 373.20728 -232.985573) (xy 373.26043 -232.989556) (xy 373.312392 -233.001416)
			(xy 373.362006 -233.020888) (xy 373.408164 -233.047537) (xy 373.449835 -233.080768) (xy 373.486087 -233.119839)
			(xy 373.516111 -233.163876) (xy 373.539237 -233.211897) (xy 373.554947 -233.262827) (xy 373.56289 -233.315531)
			(xy 373.563388 -233.34218) (xy 373.56289 -233.368829) (xy 373.791724 -233.368829) (xy 373.791724 -233.315531)
			(xy 373.799667 -233.262827) (xy 373.815377 -233.211897) (xy 373.838503 -233.163876) (xy 373.868527 -233.119839)
			(xy 373.904779 -233.080768) (xy 373.94645 -233.047537) (xy 373.992608 -233.020888) (xy 374.042222 -233.001416)
			(xy 374.094184 -232.989556) (xy 374.147334 -232.985573) (xy 374.200484 -232.989556) (xy 374.252446 -233.001416)
			(xy 374.30206 -233.020888) (xy 374.348218 -233.047537) (xy 374.389889 -233.080768) (xy 374.426141 -233.119839)
			(xy 374.456165 -233.163876) (xy 374.479291 -233.211897) (xy 374.495001 -233.262827) (xy 374.502944 -233.315531)
			(xy 374.503442 -233.34218) (xy 374.502944 -233.368829) (xy 374.73127 -233.368829) (xy 374.73127 -233.315531)
			(xy 374.739213 -233.262827) (xy 374.754923 -233.211897) (xy 374.778049 -233.163876) (xy 374.808073 -233.119839)
			(xy 374.844325 -233.080768) (xy 374.885996 -233.047537) (xy 374.932154 -233.020888) (xy 374.981768 -233.001416)
			(xy 375.03373 -232.989556) (xy 375.08688 -232.985573) (xy 375.14003 -232.989556) (xy 375.191992 -233.001416)
			(xy 375.241606 -233.020888) (xy 375.287764 -233.047537) (xy 375.329435 -233.080768) (xy 375.365687 -233.119839)
			(xy 375.395711 -233.163876) (xy 375.418837 -233.211897) (xy 375.434547 -233.262827) (xy 375.44249 -233.315531)
			(xy 375.442988 -233.34218) (xy 375.44249 -233.368829) (xy 375.67107 -233.368829) (xy 375.67107 -233.315531)
			(xy 375.679013 -233.262827) (xy 375.694723 -233.211897) (xy 375.717849 -233.163876) (xy 375.747873 -233.119839)
			(xy 375.784125 -233.080768) (xy 375.825796 -233.047537) (xy 375.871954 -233.020888) (xy 375.921568 -233.001416)
			(xy 375.97353 -232.989556) (xy 376.02668 -232.985573) (xy 376.07983 -232.989556) (xy 376.131792 -233.001416)
			(xy 376.181406 -233.020888) (xy 376.227564 -233.047537) (xy 376.269235 -233.080768) (xy 376.305487 -233.119839)
			(xy 376.335511 -233.163876) (xy 376.358637 -233.211897) (xy 376.374347 -233.262827) (xy 376.38229 -233.315531)
			(xy 376.382788 -233.34218) (xy 376.38229 -233.368829) (xy 376.61087 -233.368829) (xy 376.61087 -233.315531)
			(xy 376.618813 -233.262827) (xy 376.634523 -233.211897) (xy 376.657649 -233.163876) (xy 376.687673 -233.119839)
			(xy 376.723925 -233.080768) (xy 376.765596 -233.047537) (xy 376.811754 -233.020888) (xy 376.861368 -233.001416)
			(xy 376.91333 -232.989556) (xy 376.96648 -232.985573) (xy 377.01963 -232.989556) (xy 377.071592 -233.001416)
			(xy 377.121206 -233.020888) (xy 377.167364 -233.047537) (xy 377.209035 -233.080768) (xy 377.245287 -233.119839)
			(xy 377.275311 -233.163876) (xy 377.298437 -233.211897) (xy 377.314147 -233.262827) (xy 377.32209 -233.315531)
			(xy 377.322588 -233.34218) (xy 377.32209 -233.368829) (xy 377.55067 -233.368829) (xy 377.55067 -233.315531)
			(xy 377.558613 -233.262827) (xy 377.574323 -233.211897) (xy 377.597449 -233.163876) (xy 377.627473 -233.119839)
			(xy 377.663725 -233.080768) (xy 377.705396 -233.047537) (xy 377.751554 -233.020888) (xy 377.801168 -233.001416)
			(xy 377.85313 -232.989556) (xy 377.90628 -232.985573) (xy 377.95943 -232.989556) (xy 378.011392 -233.001416)
			(xy 378.061006 -233.020888) (xy 378.107164 -233.047537) (xy 378.148835 -233.080768) (xy 378.185087 -233.119839)
			(xy 378.215111 -233.163876) (xy 378.238237 -233.211897) (xy 378.253947 -233.262827) (xy 378.26189 -233.315531)
			(xy 378.262388 -233.34218) (xy 378.26189 -233.368829) (xy 378.49047 -233.368829) (xy 378.49047 -233.315531)
			(xy 378.498413 -233.262827) (xy 378.514123 -233.211897) (xy 378.537249 -233.163876) (xy 378.567273 -233.119839)
			(xy 378.603525 -233.080768) (xy 378.645196 -233.047537) (xy 378.691354 -233.020888) (xy 378.740968 -233.001416)
			(xy 378.79293 -232.989556) (xy 378.84608 -232.985573) (xy 378.89923 -232.989556) (xy 378.951192 -233.001416)
			(xy 379.000806 -233.020888) (xy 379.046964 -233.047537) (xy 379.088635 -233.080768) (xy 379.124887 -233.119839)
			(xy 379.154911 -233.163876) (xy 379.178037 -233.211897) (xy 379.193747 -233.262827) (xy 379.20169 -233.315531)
			(xy 379.202188 -233.34218) (xy 379.20169 -233.368829) (xy 379.43027 -233.368829) (xy 379.43027 -233.315531)
			(xy 379.438213 -233.262827) (xy 379.453923 -233.211897) (xy 379.477049 -233.163876) (xy 379.507073 -233.119839)
			(xy 379.543325 -233.080768) (xy 379.584996 -233.047537) (xy 379.631154 -233.020888) (xy 379.680768 -233.001416)
			(xy 379.73273 -232.989556) (xy 379.78588 -232.985573) (xy 379.83903 -232.989556) (xy 379.890992 -233.001416)
			(xy 379.940606 -233.020888) (xy 379.986764 -233.047537) (xy 380.028435 -233.080768) (xy 380.064687 -233.119839)
			(xy 380.094711 -233.163876) (xy 380.117837 -233.211897) (xy 380.133547 -233.262827) (xy 380.14149 -233.315531)
			(xy 380.141988 -233.34218) (xy 380.14149 -233.368829) (xy 380.133547 -233.421533) (xy 380.117837 -233.472463)
			(xy 380.094711 -233.520484) (xy 380.064687 -233.564521) (xy 380.028435 -233.603592) (xy 379.986764 -233.636823)
			(xy 379.940606 -233.663472) (xy 379.890992 -233.682944) (xy 379.83903 -233.694804) (xy 379.78588 -233.698788)
			(xy 379.73273 -233.694804) (xy 379.680768 -233.682944) (xy 379.631154 -233.663472) (xy 379.584996 -233.636823)
			(xy 379.543325 -233.603592) (xy 379.507073 -233.564521) (xy 379.477049 -233.520484) (xy 379.453923 -233.472463)
			(xy 379.438213 -233.421533) (xy 379.43027 -233.368829) (xy 379.20169 -233.368829) (xy 379.193747 -233.421533)
			(xy 379.178037 -233.472463) (xy 379.154911 -233.520484) (xy 379.124887 -233.564521) (xy 379.088635 -233.603592)
			(xy 379.046964 -233.636823) (xy 379.000806 -233.663472) (xy 378.951192 -233.682944) (xy 378.89923 -233.694804)
			(xy 378.84608 -233.698788) (xy 378.79293 -233.694804) (xy 378.740968 -233.682944) (xy 378.691354 -233.663472)
			(xy 378.645196 -233.636823) (xy 378.603525 -233.603592) (xy 378.567273 -233.564521) (xy 378.537249 -233.520484)
			(xy 378.514123 -233.472463) (xy 378.498413 -233.421533) (xy 378.49047 -233.368829) (xy 378.26189 -233.368829)
			(xy 378.253947 -233.421533) (xy 378.238237 -233.472463) (xy 378.215111 -233.520484) (xy 378.185087 -233.564521)
			(xy 378.148835 -233.603592) (xy 378.107164 -233.636823) (xy 378.061006 -233.663472) (xy 378.011392 -233.682944)
			(xy 377.95943 -233.694804) (xy 377.90628 -233.698788) (xy 377.85313 -233.694804) (xy 377.801168 -233.682944)
			(xy 377.751554 -233.663472) (xy 377.705396 -233.636823) (xy 377.663725 -233.603592) (xy 377.627473 -233.564521)
			(xy 377.597449 -233.520484) (xy 377.574323 -233.472463) (xy 377.558613 -233.421533) (xy 377.55067 -233.368829)
			(xy 377.32209 -233.368829) (xy 377.314147 -233.421533) (xy 377.298437 -233.472463) (xy 377.275311 -233.520484)
			(xy 377.245287 -233.564521) (xy 377.209035 -233.603592) (xy 377.167364 -233.636823) (xy 377.121206 -233.663472)
			(xy 377.071592 -233.682944) (xy 377.01963 -233.694804) (xy 376.96648 -233.698788) (xy 376.91333 -233.694804)
			(xy 376.861368 -233.682944) (xy 376.811754 -233.663472) (xy 376.765596 -233.636823) (xy 376.723925 -233.603592)
			(xy 376.687673 -233.564521) (xy 376.657649 -233.520484) (xy 376.634523 -233.472463) (xy 376.618813 -233.421533)
			(xy 376.61087 -233.368829) (xy 376.38229 -233.368829) (xy 376.374347 -233.421533) (xy 376.358637 -233.472463)
			(xy 376.335511 -233.520484) (xy 376.305487 -233.564521) (xy 376.269235 -233.603592) (xy 376.227564 -233.636823)
			(xy 376.181406 -233.663472) (xy 376.131792 -233.682944) (xy 376.07983 -233.694804) (xy 376.02668 -233.698788)
			(xy 375.97353 -233.694804) (xy 375.921568 -233.682944) (xy 375.871954 -233.663472) (xy 375.825796 -233.636823)
			(xy 375.784125 -233.603592) (xy 375.747873 -233.564521) (xy 375.717849 -233.520484) (xy 375.694723 -233.472463)
			(xy 375.679013 -233.421533) (xy 375.67107 -233.368829) (xy 375.44249 -233.368829) (xy 375.434547 -233.421533)
			(xy 375.418837 -233.472463) (xy 375.395711 -233.520484) (xy 375.365687 -233.564521) (xy 375.329435 -233.603592)
			(xy 375.287764 -233.636823) (xy 375.241606 -233.663472) (xy 375.191992 -233.682944) (xy 375.14003 -233.694804)
			(xy 375.08688 -233.698788) (xy 375.03373 -233.694804) (xy 374.981768 -233.682944) (xy 374.932154 -233.663472)
			(xy 374.885996 -233.636823) (xy 374.844325 -233.603592) (xy 374.808073 -233.564521) (xy 374.778049 -233.520484)
			(xy 374.754923 -233.472463) (xy 374.739213 -233.421533) (xy 374.73127 -233.368829) (xy 374.502944 -233.368829)
			(xy 374.495001 -233.421533) (xy 374.479291 -233.472463) (xy 374.456165 -233.520484) (xy 374.426141 -233.564521)
			(xy 374.389889 -233.603592) (xy 374.348218 -233.636823) (xy 374.30206 -233.663472) (xy 374.252446 -233.682944)
			(xy 374.200484 -233.694804) (xy 374.147334 -233.698788) (xy 374.094184 -233.694804) (xy 374.042222 -233.682944)
			(xy 373.992608 -233.663472) (xy 373.94645 -233.636823) (xy 373.904779 -233.603592) (xy 373.868527 -233.564521)
			(xy 373.838503 -233.520484) (xy 373.815377 -233.472463) (xy 373.799667 -233.421533) (xy 373.791724 -233.368829)
			(xy 373.56289 -233.368829) (xy 373.554947 -233.421533) (xy 373.539237 -233.472463) (xy 373.516111 -233.520484)
			(xy 373.486087 -233.564521) (xy 373.449835 -233.603592) (xy 373.408164 -233.636823) (xy 373.362006 -233.663472)
			(xy 373.312392 -233.682944) (xy 373.26043 -233.694804) (xy 373.20728 -233.698788) (xy 373.15413 -233.694804)
			(xy 373.102168 -233.682944) (xy 373.052554 -233.663472) (xy 373.006396 -233.636823) (xy 372.964725 -233.603592)
			(xy 372.928473 -233.564521) (xy 372.898449 -233.520484) (xy 372.875323 -233.472463) (xy 372.859613 -233.421533)
			(xy 372.85167 -233.368829) (xy 372.62309 -233.368829) (xy 372.615147 -233.421533) (xy 372.599437 -233.472463)
			(xy 372.576311 -233.520484) (xy 372.546287 -233.564521) (xy 372.510035 -233.603592) (xy 372.468364 -233.636823)
			(xy 372.422206 -233.663472) (xy 372.372592 -233.682944) (xy 372.32063 -233.694804) (xy 372.26748 -233.698788)
			(xy 372.21433 -233.694804) (xy 372.162368 -233.682944) (xy 372.112754 -233.663472) (xy 372.066596 -233.636823)
			(xy 372.024925 -233.603592) (xy 371.988673 -233.564521) (xy 371.958649 -233.520484) (xy 371.935523 -233.472463)
			(xy 371.919813 -233.421533) (xy 371.91187 -233.368829) (xy 371.68329 -233.368829) (xy 371.675347 -233.421533)
			(xy 371.659637 -233.472463) (xy 371.636511 -233.520484) (xy 371.606487 -233.564521) (xy 371.570235 -233.603592)
			(xy 371.528564 -233.636823) (xy 371.482406 -233.663472) (xy 371.432792 -233.682944) (xy 371.38083 -233.694804)
			(xy 371.32768 -233.698788) (xy 371.27453 -233.694804) (xy 371.222568 -233.682944) (xy 371.172954 -233.663472)
			(xy 371.126796 -233.636823) (xy 371.085125 -233.603592) (xy 371.048873 -233.564521) (xy 371.018849 -233.520484)
			(xy 370.995723 -233.472463) (xy 370.980013 -233.421533) (xy 370.97207 -233.368829) (xy 370.74349 -233.368829)
			(xy 370.735547 -233.421533) (xy 370.719837 -233.472463) (xy 370.696711 -233.520484) (xy 370.666687 -233.564521)
			(xy 370.630435 -233.603592) (xy 370.588764 -233.636823) (xy 370.542606 -233.663472) (xy 370.492992 -233.682944)
			(xy 370.44103 -233.694804) (xy 370.38788 -233.698788) (xy 370.33473 -233.694804) (xy 370.282768 -233.682944)
			(xy 370.233154 -233.663472) (xy 370.186996 -233.636823) (xy 370.145325 -233.603592) (xy 370.109073 -233.564521)
			(xy 370.079049 -233.520484) (xy 370.055923 -233.472463) (xy 370.040213 -233.421533) (xy 370.03227 -233.368829)
			(xy 369.803944 -233.368829) (xy 369.796001 -233.421533) (xy 369.780291 -233.472463) (xy 369.757165 -233.520484)
			(xy 369.727141 -233.564521) (xy 369.690889 -233.603592) (xy 369.649218 -233.636823) (xy 369.60306 -233.663472)
			(xy 369.553446 -233.682944) (xy 369.501484 -233.694804) (xy 369.448334 -233.698788) (xy 369.395184 -233.694804)
			(xy 369.343222 -233.682944) (xy 369.293608 -233.663472) (xy 369.24745 -233.636823) (xy 369.205779 -233.603592)
			(xy 369.169527 -233.564521) (xy 369.139503 -233.520484) (xy 369.116377 -233.472463) (xy 369.100667 -233.421533)
			(xy 369.092724 -233.368829) (xy 368.86389 -233.368829) (xy 368.855947 -233.421533) (xy 368.840237 -233.472463)
			(xy 368.817111 -233.520484) (xy 368.787087 -233.564521) (xy 368.750835 -233.603592) (xy 368.709164 -233.636823)
			(xy 368.663006 -233.663472) (xy 368.613392 -233.682944) (xy 368.56143 -233.694804) (xy 368.50828 -233.698788)
			(xy 368.45513 -233.694804) (xy 368.403168 -233.682944) (xy 368.353554 -233.663472) (xy 368.307396 -233.636823)
			(xy 368.265725 -233.603592) (xy 368.229473 -233.564521) (xy 368.199449 -233.520484) (xy 368.176323 -233.472463)
			(xy 368.160613 -233.421533) (xy 368.15267 -233.368829) (xy 367.92409 -233.368829) (xy 367.916147 -233.421533)
			(xy 367.900437 -233.472463) (xy 367.877311 -233.520484) (xy 367.847287 -233.564521) (xy 367.811035 -233.603592)
			(xy 367.769364 -233.636823) (xy 367.723206 -233.663472) (xy 367.673592 -233.682944) (xy 367.62163 -233.694804)
			(xy 367.56848 -233.698788) (xy 367.51533 -233.694804) (xy 367.463368 -233.682944) (xy 367.413754 -233.663472)
			(xy 367.367596 -233.636823) (xy 367.325925 -233.603592) (xy 367.289673 -233.564521) (xy 367.259649 -233.520484)
			(xy 367.236523 -233.472463) (xy 367.220813 -233.421533) (xy 367.21287 -233.368829) (xy 366.98429 -233.368829)
			(xy 366.976347 -233.421533) (xy 366.960637 -233.472463) (xy 366.937511 -233.520484) (xy 366.907487 -233.564521)
			(xy 366.871235 -233.603592) (xy 366.829564 -233.636823) (xy 366.783406 -233.663472) (xy 366.733792 -233.682944)
			(xy 366.68183 -233.694804) (xy 366.62868 -233.698788) (xy 366.57553 -233.694804) (xy 366.523568 -233.682944)
			(xy 366.473954 -233.663472) (xy 366.427796 -233.636823) (xy 366.386125 -233.603592) (xy 366.349873 -233.564521)
			(xy 366.319849 -233.520484) (xy 366.296723 -233.472463) (xy 366.281013 -233.421533) (xy 366.27307 -233.368829)
			(xy 366.04449 -233.368829) (xy 366.036547 -233.421533) (xy 366.020837 -233.472463) (xy 365.997711 -233.520484)
			(xy 365.967687 -233.564521) (xy 365.931435 -233.603592) (xy 365.889764 -233.636823) (xy 365.843606 -233.663472)
			(xy 365.793992 -233.682944) (xy 365.74203 -233.694804) (xy 365.68888 -233.698788) (xy 365.63573 -233.694804)
			(xy 365.583768 -233.682944) (xy 365.534154 -233.663472) (xy 365.487996 -233.636823) (xy 365.446325 -233.603592)
			(xy 365.410073 -233.564521) (xy 365.380049 -233.520484) (xy 365.356923 -233.472463) (xy 365.341213 -233.421533)
			(xy 365.33327 -233.368829) (xy 365.10469 -233.368829) (xy 365.096747 -233.421533) (xy 365.081037 -233.472463)
			(xy 365.057911 -233.520484) (xy 365.027887 -233.564521) (xy 364.991635 -233.603592) (xy 364.949964 -233.636823)
			(xy 364.903806 -233.663472) (xy 364.854192 -233.682944) (xy 364.80223 -233.694804) (xy 364.74908 -233.698788)
			(xy 364.69593 -233.694804) (xy 364.643968 -233.682944) (xy 364.594354 -233.663472) (xy 364.548196 -233.636823)
			(xy 364.506525 -233.603592) (xy 364.470273 -233.564521) (xy 364.440249 -233.520484) (xy 364.417123 -233.472463)
			(xy 364.401413 -233.421533) (xy 364.39347 -233.368829) (xy 364.16489 -233.368829) (xy 364.156947 -233.421533)
			(xy 364.141237 -233.472463) (xy 364.118111 -233.520484) (xy 364.088087 -233.564521) (xy 364.051835 -233.603592)
			(xy 364.010164 -233.636823) (xy 363.964006 -233.663472) (xy 363.914392 -233.682944) (xy 363.86243 -233.694804)
			(xy 363.80928 -233.698788) (xy 363.75613 -233.694804) (xy 363.704168 -233.682944) (xy 363.654554 -233.663472)
			(xy 363.608396 -233.636823) (xy 363.566725 -233.603592) (xy 363.530473 -233.564521) (xy 363.500449 -233.520484)
			(xy 363.477323 -233.472463) (xy 363.461613 -233.421533) (xy 363.45367 -233.368829) (xy 363.22509 -233.368829)
			(xy 363.217147 -233.421533) (xy 363.201437 -233.472463) (xy 363.178311 -233.520484) (xy 363.148287 -233.564521)
			(xy 363.112035 -233.603592) (xy 363.070364 -233.636823) (xy 363.024206 -233.663472) (xy 362.974592 -233.682944)
			(xy 362.92263 -233.694804) (xy 362.86948 -233.698788) (xy 362.81633 -233.694804) (xy 362.764368 -233.682944)
			(xy 362.714754 -233.663472) (xy 362.668596 -233.636823) (xy 362.626925 -233.603592) (xy 362.590673 -233.564521)
			(xy 362.560649 -233.520484) (xy 362.537523 -233.472463) (xy 362.521813 -233.421533) (xy 362.51387 -233.368829)
			(xy 362.285544 -233.368829) (xy 362.277601 -233.421533) (xy 362.261891 -233.472463) (xy 362.238765 -233.520484)
			(xy 362.208741 -233.564521) (xy 362.172489 -233.603592) (xy 362.130818 -233.636823) (xy 362.08466 -233.663472)
			(xy 362.035046 -233.682944) (xy 361.983084 -233.694804) (xy 361.929934 -233.698788) (xy 361.876784 -233.694804)
			(xy 361.824822 -233.682944) (xy 361.775208 -233.663472) (xy 361.72905 -233.636823) (xy 361.687379 -233.603592)
			(xy 361.651127 -233.564521) (xy 361.621103 -233.520484) (xy 361.597977 -233.472463) (xy 361.582267 -233.421533)
			(xy 361.574324 -233.368829) (xy 361.34549 -233.368829) (xy 361.337547 -233.421533) (xy 361.321837 -233.472463)
			(xy 361.298711 -233.520484) (xy 361.268687 -233.564521) (xy 361.232435 -233.603592) (xy 361.190764 -233.636823)
			(xy 361.144606 -233.663472) (xy 361.094992 -233.682944) (xy 361.04303 -233.694804) (xy 360.98988 -233.698788)
			(xy 360.93673 -233.694804) (xy 360.884768 -233.682944) (xy 360.835154 -233.663472) (xy 360.788996 -233.636823)
			(xy 360.747325 -233.603592) (xy 360.711073 -233.564521) (xy 360.681049 -233.520484) (xy 360.657923 -233.472463)
			(xy 360.642213 -233.421533) (xy 360.63427 -233.368829) (xy 360.40569 -233.368829) (xy 360.397747 -233.421533)
			(xy 360.382037 -233.472463) (xy 360.358911 -233.520484) (xy 360.328887 -233.564521) (xy 360.292635 -233.603592)
			(xy 360.250964 -233.636823) (xy 360.204806 -233.663472) (xy 360.155192 -233.682944) (xy 360.10323 -233.694804)
			(xy 360.05008 -233.698788) (xy 359.99693 -233.694804) (xy 359.944968 -233.682944) (xy 359.895354 -233.663472)
			(xy 359.849196 -233.636823) (xy 359.807525 -233.603592) (xy 359.771273 -233.564521) (xy 359.741249 -233.520484)
			(xy 359.718123 -233.472463) (xy 359.702413 -233.421533) (xy 359.69447 -233.368829) (xy 359.46589 -233.368829)
			(xy 359.457947 -233.421533) (xy 359.442237 -233.472463) (xy 359.419111 -233.520484) (xy 359.389087 -233.564521)
			(xy 359.352835 -233.603592) (xy 359.311164 -233.636823) (xy 359.265006 -233.663472) (xy 359.215392 -233.682944)
			(xy 359.16343 -233.694804) (xy 359.11028 -233.698788) (xy 359.05713 -233.694804) (xy 359.005168 -233.682944)
			(xy 358.955554 -233.663472) (xy 358.909396 -233.636823) (xy 358.867725 -233.603592) (xy 358.831473 -233.564521)
			(xy 358.801449 -233.520484) (xy 358.778323 -233.472463) (xy 358.762613 -233.421533) (xy 358.75467 -233.368829)
			(xy 358.526344 -233.368829) (xy 358.518401 -233.421533) (xy 358.502691 -233.472463) (xy 358.479565 -233.520484)
			(xy 358.449541 -233.564521) (xy 358.413289 -233.603592) (xy 358.371618 -233.636823) (xy 358.32546 -233.663472)
			(xy 358.275846 -233.682944) (xy 358.223884 -233.694804) (xy 358.170734 -233.698788) (xy 358.117584 -233.694804)
			(xy 358.065622 -233.682944) (xy 358.016008 -233.663472) (xy 357.96985 -233.636823) (xy 357.928179 -233.603592)
			(xy 357.891927 -233.564521) (xy 357.861903 -233.520484) (xy 357.838777 -233.472463) (xy 357.823067 -233.421533)
			(xy 357.815124 -233.368829) (xy 357.586294 -233.368829) (xy 357.586269 -233.370166) (xy 357.577516 -233.425449)
			(xy 357.560221 -233.478681) (xy 357.534812 -233.528553) (xy 357.501913 -233.573835) (xy 357.462335 -233.613413)
			(xy 357.417053 -233.646312) (xy 357.367181 -233.671721) (xy 357.313949 -233.689016) (xy 357.258666 -233.697769)
			(xy 357.23068 -233.698288) (xy 357.201186 -233.697739) (xy 357.142999 -233.688065) (xy 357.087207 -233.668919)
			(xy 357.061008 -233.655362) (xy 357.027734 -233.637328) (xy 357.015034 -233.650028) (xy 356.470458 -233.650028)
			(xy 356.459028 -233.656124) (xy 356.436762 -233.667559) (xy 356.389759 -233.684769) (xy 356.340811 -233.695232)
			(xy 356.29088 -233.698743) (xy 356.240949 -233.695232) (xy 356.192001 -233.684769) (xy 356.144998 -233.667559)
			(xy 356.122732 -233.656124) (xy 356.111302 -233.650028) (xy 355.530658 -233.650028) (xy 355.519228 -233.656124)
			(xy 355.496962 -233.667559) (xy 355.449959 -233.684769) (xy 355.401011 -233.695232) (xy 355.35108 -233.698743)
			(xy 355.301149 -233.695232) (xy 355.252201 -233.684769) (xy 355.205198 -233.667559) (xy 355.182932 -233.656124)
			(xy 355.171502 -233.650028) (xy 354.590858 -233.650028) (xy 354.579428 -233.656124) (xy 354.557162 -233.667559)
			(xy 354.510159 -233.684769) (xy 354.461211 -233.695232) (xy 354.41128 -233.698743) (xy 354.361349 -233.695232)
			(xy 354.312401 -233.684769) (xy 354.265398 -233.667559) (xy 354.243132 -233.656124) (xy 354.231702 -233.650028)
			(xy 353.651312 -233.650028) (xy 353.639882 -233.656124) (xy 353.617616 -233.667559) (xy 353.570613 -233.684769)
			(xy 353.521665 -233.695232) (xy 353.471734 -233.698743) (xy 353.421803 -233.695232) (xy 353.372855 -233.684769)
			(xy 353.325852 -233.667559) (xy 353.303586 -233.656124) (xy 353.292156 -233.650028) (xy 352.711512 -233.650028)
			(xy 352.700082 -233.656124) (xy 352.677816 -233.667559) (xy 352.630813 -233.684769) (xy 352.581865 -233.695232)
			(xy 352.531934 -233.698743) (xy 352.482003 -233.695232) (xy 352.433055 -233.684769) (xy 352.386052 -233.667559)
			(xy 352.363786 -233.656124) (xy 352.352356 -233.650028) (xy 351.771458 -233.650028) (xy 351.760028 -233.656124)
			(xy 351.75825 -233.65714) (xy 351.751392 -233.660696) (xy 351.43313 -233.978958) (xy 351.447354 -234.010962)
			(xy 351.457155 -234.033915) (xy 351.47096 -234.081877) (xy 351.477935 -234.131296) (xy 351.478342 -234.15625)
			(xy 351.477815 -234.182899) (xy 351.706424 -234.182899) (xy 351.706424 -234.129601) (xy 351.714367 -234.076897)
			(xy 351.730077 -234.025967) (xy 351.753203 -233.977946) (xy 351.783227 -233.933909) (xy 351.819479 -233.894838)
			(xy 351.86115 -233.861607) (xy 351.907308 -233.834958) (xy 351.956922 -233.815486) (xy 352.008884 -233.803626)
			(xy 352.062034 -233.799643) (xy 352.115184 -233.803626) (xy 352.167146 -233.815486) (xy 352.21676 -233.834958)
			(xy 352.262918 -233.861607) (xy 352.304589 -233.894838) (xy 352.340841 -233.933909) (xy 352.370865 -233.977946)
			(xy 352.393991 -234.025967) (xy 352.409701 -234.076897) (xy 352.417644 -234.129601) (xy 352.418142 -234.15625)
			(xy 352.417644 -234.182899) (xy 353.586024 -234.182899) (xy 353.586024 -234.129601) (xy 353.593967 -234.076897)
			(xy 353.609677 -234.025967) (xy 353.632803 -233.977946) (xy 353.662827 -233.933909) (xy 353.699079 -233.894838)
			(xy 353.74075 -233.861607) (xy 353.786908 -233.834958) (xy 353.836522 -233.815486) (xy 353.888484 -233.803626)
			(xy 353.941634 -233.799643) (xy 353.994784 -233.803626) (xy 354.046746 -233.815486) (xy 354.09636 -233.834958)
			(xy 354.142518 -233.861607) (xy 354.184189 -233.894838) (xy 354.220441 -233.933909) (xy 354.250465 -233.977946)
			(xy 354.273591 -234.025967) (xy 354.289301 -234.076897) (xy 354.297244 -234.129601) (xy 354.297742 -234.15625)
			(xy 354.297244 -234.182899) (xy 354.525824 -234.182899) (xy 354.525824 -234.129601) (xy 354.533767 -234.076897)
			(xy 354.549477 -234.025967) (xy 354.572603 -233.977946) (xy 354.602627 -233.933909) (xy 354.638879 -233.894838)
			(xy 354.68055 -233.861607) (xy 354.726708 -233.834958) (xy 354.776322 -233.815486) (xy 354.828284 -233.803626)
			(xy 354.881434 -233.799643) (xy 354.934584 -233.803626) (xy 354.986546 -233.815486) (xy 355.03616 -233.834958)
			(xy 355.082318 -233.861607) (xy 355.123989 -233.894838) (xy 355.160241 -233.933909) (xy 355.190265 -233.977946)
			(xy 355.213391 -234.025967) (xy 355.229101 -234.076897) (xy 355.237044 -234.129601) (xy 355.237542 -234.15625)
			(xy 355.237044 -234.182899) (xy 355.465624 -234.182899) (xy 355.465624 -234.129601) (xy 355.473567 -234.076897)
			(xy 355.489277 -234.025967) (xy 355.512403 -233.977946) (xy 355.542427 -233.933909) (xy 355.578679 -233.894838)
			(xy 355.62035 -233.861607) (xy 355.666508 -233.834958) (xy 355.716122 -233.815486) (xy 355.768084 -233.803626)
			(xy 355.821234 -233.799643) (xy 355.874384 -233.803626) (xy 355.926346 -233.815486) (xy 355.97596 -233.834958)
			(xy 356.022118 -233.861607) (xy 356.063789 -233.894838) (xy 356.100041 -233.933909) (xy 356.130065 -233.977946)
			(xy 356.153191 -234.025967) (xy 356.168901 -234.076897) (xy 356.176844 -234.129601) (xy 356.177342 -234.15625)
			(xy 356.176844 -234.182899) (xy 356.405424 -234.182899) (xy 356.405424 -234.129601) (xy 356.413367 -234.076897)
			(xy 356.429077 -234.025967) (xy 356.452203 -233.977946) (xy 356.482227 -233.933909) (xy 356.518479 -233.894838)
			(xy 356.56015 -233.861607) (xy 356.606308 -233.834958) (xy 356.655922 -233.815486) (xy 356.707884 -233.803626)
			(xy 356.761034 -233.799643) (xy 356.814184 -233.803626) (xy 356.866146 -233.815486) (xy 356.91576 -233.834958)
			(xy 356.961918 -233.861607) (xy 357.003589 -233.894838) (xy 357.039841 -233.933909) (xy 357.069865 -233.977946)
			(xy 357.092991 -234.025967) (xy 357.108701 -234.076897) (xy 357.116644 -234.129601) (xy 357.117142 -234.15625)
			(xy 357.116644 -234.182899) (xy 357.345224 -234.182899) (xy 357.345224 -234.129601) (xy 357.353167 -234.076897)
			(xy 357.368877 -234.025967) (xy 357.392003 -233.977946) (xy 357.422027 -233.933909) (xy 357.458279 -233.894838)
			(xy 357.49995 -233.861607) (xy 357.546108 -233.834958) (xy 357.595722 -233.815486) (xy 357.647684 -233.803626)
			(xy 357.700834 -233.799643) (xy 357.753984 -233.803626) (xy 357.805946 -233.815486) (xy 357.85556 -233.834958)
			(xy 357.901718 -233.861607) (xy 357.943389 -233.894838) (xy 357.979641 -233.933909) (xy 358.009665 -233.977946)
			(xy 358.032791 -234.025967) (xy 358.048501 -234.076897) (xy 358.056444 -234.129601) (xy 358.056942 -234.15625)
			(xy 358.056444 -234.182899) (xy 358.285024 -234.182899) (xy 358.285024 -234.129601) (xy 358.292967 -234.076897)
			(xy 358.308677 -234.025967) (xy 358.331803 -233.977946) (xy 358.361827 -233.933909) (xy 358.398079 -233.894838)
			(xy 358.43975 -233.861607) (xy 358.485908 -233.834958) (xy 358.535522 -233.815486) (xy 358.587484 -233.803626)
			(xy 358.640634 -233.799643) (xy 358.693784 -233.803626) (xy 358.745746 -233.815486) (xy 358.79536 -233.834958)
			(xy 358.841518 -233.861607) (xy 358.883189 -233.894838) (xy 358.919441 -233.933909) (xy 358.949465 -233.977946)
			(xy 358.972591 -234.025967) (xy 358.988301 -234.076897) (xy 358.996244 -234.129601) (xy 358.996742 -234.15625)
			(xy 358.996244 -234.182899) (xy 359.224824 -234.182899) (xy 359.224824 -234.129601) (xy 359.232767 -234.076897)
			(xy 359.248477 -234.025967) (xy 359.271603 -233.977946) (xy 359.301627 -233.933909) (xy 359.337879 -233.894838)
			(xy 359.37955 -233.861607) (xy 359.425708 -233.834958) (xy 359.475322 -233.815486) (xy 359.527284 -233.803626)
			(xy 359.580434 -233.799643) (xy 359.633584 -233.803626) (xy 359.685546 -233.815486) (xy 359.73516 -233.834958)
			(xy 359.781318 -233.861607) (xy 359.822989 -233.894838) (xy 359.859241 -233.933909) (xy 359.889265 -233.977946)
			(xy 359.912391 -234.025967) (xy 359.928101 -234.076897) (xy 359.936044 -234.129601) (xy 359.936542 -234.15625)
			(xy 359.936044 -234.182899) (xy 360.164624 -234.182899) (xy 360.164624 -234.129601) (xy 360.172567 -234.076897)
			(xy 360.188277 -234.025967) (xy 360.211403 -233.977946) (xy 360.241427 -233.933909) (xy 360.277679 -233.894838)
			(xy 360.31935 -233.861607) (xy 360.365508 -233.834958) (xy 360.415122 -233.815486) (xy 360.467084 -233.803626)
			(xy 360.520234 -233.799643) (xy 360.573384 -233.803626) (xy 360.625346 -233.815486) (xy 360.67496 -233.834958)
			(xy 360.721118 -233.861607) (xy 360.762789 -233.894838) (xy 360.799041 -233.933909) (xy 360.829065 -233.977946)
			(xy 360.852191 -234.025967) (xy 360.867901 -234.076897) (xy 360.875844 -234.129601) (xy 360.876342 -234.15625)
			(xy 360.875844 -234.182899) (xy 361.104424 -234.182899) (xy 361.104424 -234.129601) (xy 361.112367 -234.076897)
			(xy 361.128077 -234.025967) (xy 361.151203 -233.977946) (xy 361.181227 -233.933909) (xy 361.217479 -233.894838)
			(xy 361.25915 -233.861607) (xy 361.305308 -233.834958) (xy 361.354922 -233.815486) (xy 361.406884 -233.803626)
			(xy 361.460034 -233.799643) (xy 361.513184 -233.803626) (xy 361.565146 -233.815486) (xy 361.61476 -233.834958)
			(xy 361.660918 -233.861607) (xy 361.702589 -233.894838) (xy 361.738841 -233.933909) (xy 361.768865 -233.977946)
			(xy 361.791991 -234.025967) (xy 361.807701 -234.076897) (xy 361.815644 -234.129601) (xy 361.816142 -234.15625)
			(xy 361.815644 -234.182899) (xy 362.044224 -234.182899) (xy 362.044224 -234.129601) (xy 362.052167 -234.076897)
			(xy 362.067877 -234.025967) (xy 362.091003 -233.977946) (xy 362.121027 -233.933909) (xy 362.157279 -233.894838)
			(xy 362.19895 -233.861607) (xy 362.245108 -233.834958) (xy 362.294722 -233.815486) (xy 362.346684 -233.803626)
			(xy 362.399834 -233.799643) (xy 362.452984 -233.803626) (xy 362.504946 -233.815486) (xy 362.55456 -233.834958)
			(xy 362.600718 -233.861607) (xy 362.642389 -233.894838) (xy 362.678641 -233.933909) (xy 362.708665 -233.977946)
			(xy 362.731791 -234.025967) (xy 362.747501 -234.076897) (xy 362.755444 -234.129601) (xy 362.755942 -234.15625)
			(xy 362.755444 -234.182899) (xy 362.984024 -234.182899) (xy 362.984024 -234.129601) (xy 362.991967 -234.076897)
			(xy 363.007677 -234.025967) (xy 363.030803 -233.977946) (xy 363.060827 -233.933909) (xy 363.097079 -233.894838)
			(xy 363.13875 -233.861607) (xy 363.184908 -233.834958) (xy 363.234522 -233.815486) (xy 363.286484 -233.803626)
			(xy 363.339634 -233.799643) (xy 363.392784 -233.803626) (xy 363.444746 -233.815486) (xy 363.49436 -233.834958)
			(xy 363.540518 -233.861607) (xy 363.582189 -233.894838) (xy 363.618441 -233.933909) (xy 363.648465 -233.977946)
			(xy 363.671591 -234.025967) (xy 363.687301 -234.076897) (xy 363.695244 -234.129601) (xy 363.695742 -234.15625)
			(xy 363.695244 -234.182899) (xy 363.923824 -234.182899) (xy 363.923824 -234.129601) (xy 363.931767 -234.076897)
			(xy 363.947477 -234.025967) (xy 363.970603 -233.977946) (xy 364.000627 -233.933909) (xy 364.036879 -233.894838)
			(xy 364.07855 -233.861607) (xy 364.124708 -233.834958) (xy 364.174322 -233.815486) (xy 364.226284 -233.803626)
			(xy 364.279434 -233.799643) (xy 364.332584 -233.803626) (xy 364.384546 -233.815486) (xy 364.43416 -233.834958)
			(xy 364.480318 -233.861607) (xy 364.521989 -233.894838) (xy 364.558241 -233.933909) (xy 364.588265 -233.977946)
			(xy 364.611391 -234.025967) (xy 364.627101 -234.076897) (xy 364.635044 -234.129601) (xy 364.635542 -234.15625)
			(xy 364.635044 -234.182899) (xy 364.863624 -234.182899) (xy 364.863624 -234.129601) (xy 364.871567 -234.076897)
			(xy 364.887277 -234.025967) (xy 364.910403 -233.977946) (xy 364.940427 -233.933909) (xy 364.976679 -233.894838)
			(xy 365.01835 -233.861607) (xy 365.064508 -233.834958) (xy 365.114122 -233.815486) (xy 365.166084 -233.803626)
			(xy 365.219234 -233.799643) (xy 365.272384 -233.803626) (xy 365.324346 -233.815486) (xy 365.37396 -233.834958)
			(xy 365.420118 -233.861607) (xy 365.461789 -233.894838) (xy 365.498041 -233.933909) (xy 365.528065 -233.977946)
			(xy 365.551191 -234.025967) (xy 365.566901 -234.076897) (xy 365.574844 -234.129601) (xy 365.575342 -234.15625)
			(xy 365.574844 -234.182899) (xy 365.803424 -234.182899) (xy 365.803424 -234.129601) (xy 365.811367 -234.076897)
			(xy 365.827077 -234.025967) (xy 365.850203 -233.977946) (xy 365.880227 -233.933909) (xy 365.916479 -233.894838)
			(xy 365.95815 -233.861607) (xy 366.004308 -233.834958) (xy 366.053922 -233.815486) (xy 366.105884 -233.803626)
			(xy 366.159034 -233.799643) (xy 366.212184 -233.803626) (xy 366.264146 -233.815486) (xy 366.31376 -233.834958)
			(xy 366.359918 -233.861607) (xy 366.401589 -233.894838) (xy 366.437841 -233.933909) (xy 366.467865 -233.977946)
			(xy 366.490991 -234.025967) (xy 366.506701 -234.076897) (xy 366.514644 -234.129601) (xy 366.515142 -234.15625)
			(xy 366.514644 -234.182899) (xy 366.743224 -234.182899) (xy 366.743224 -234.129601) (xy 366.751167 -234.076897)
			(xy 366.766877 -234.025967) (xy 366.790003 -233.977946) (xy 366.820027 -233.933909) (xy 366.856279 -233.894838)
			(xy 366.89795 -233.861607) (xy 366.944108 -233.834958) (xy 366.993722 -233.815486) (xy 367.045684 -233.803626)
			(xy 367.098834 -233.799643) (xy 367.151984 -233.803626) (xy 367.203946 -233.815486) (xy 367.25356 -233.834958)
			(xy 367.299718 -233.861607) (xy 367.341389 -233.894838) (xy 367.377641 -233.933909) (xy 367.407665 -233.977946)
			(xy 367.430791 -234.025967) (xy 367.446501 -234.076897) (xy 367.454444 -234.129601) (xy 367.454942 -234.15625)
			(xy 367.454444 -234.182899) (xy 367.683024 -234.182899) (xy 367.683024 -234.129601) (xy 367.690967 -234.076897)
			(xy 367.706677 -234.025967) (xy 367.729803 -233.977946) (xy 367.759827 -233.933909) (xy 367.796079 -233.894838)
			(xy 367.83775 -233.861607) (xy 367.883908 -233.834958) (xy 367.933522 -233.815486) (xy 367.985484 -233.803626)
			(xy 368.038634 -233.799643) (xy 368.091784 -233.803626) (xy 368.143746 -233.815486) (xy 368.19336 -233.834958)
			(xy 368.239518 -233.861607) (xy 368.281189 -233.894838) (xy 368.317441 -233.933909) (xy 368.347465 -233.977946)
			(xy 368.370591 -234.025967) (xy 368.386301 -234.076897) (xy 368.394244 -234.129601) (xy 368.394742 -234.15625)
			(xy 368.394244 -234.182899) (xy 368.62257 -234.182899) (xy 368.62257 -234.129601) (xy 368.630513 -234.076897)
			(xy 368.646223 -234.025967) (xy 368.669349 -233.977946) (xy 368.699373 -233.933909) (xy 368.735625 -233.894838)
			(xy 368.777296 -233.861607) (xy 368.823454 -233.834958) (xy 368.873068 -233.815486) (xy 368.92503 -233.803626)
			(xy 368.97818 -233.799643) (xy 369.03133 -233.803626) (xy 369.083292 -233.815486) (xy 369.132906 -233.834958)
			(xy 369.179064 -233.861607) (xy 369.220735 -233.894838) (xy 369.256987 -233.933909) (xy 369.287011 -233.977946)
			(xy 369.310137 -234.025967) (xy 369.325847 -234.076897) (xy 369.33379 -234.129601) (xy 369.334288 -234.15625)
			(xy 369.33379 -234.182899) (xy 369.562624 -234.182899) (xy 369.562624 -234.129601) (xy 369.570567 -234.076897)
			(xy 369.586277 -234.025967) (xy 369.609403 -233.977946) (xy 369.639427 -233.933909) (xy 369.675679 -233.894838)
			(xy 369.71735 -233.861607) (xy 369.763508 -233.834958) (xy 369.813122 -233.815486) (xy 369.865084 -233.803626)
			(xy 369.918234 -233.799643) (xy 369.971384 -233.803626) (xy 370.023346 -233.815486) (xy 370.07296 -233.834958)
			(xy 370.119118 -233.861607) (xy 370.160789 -233.894838) (xy 370.197041 -233.933909) (xy 370.227065 -233.977946)
			(xy 370.250191 -234.025967) (xy 370.265901 -234.076897) (xy 370.273844 -234.129601) (xy 370.274342 -234.15625)
			(xy 370.273844 -234.182899) (xy 370.50217 -234.182899) (xy 370.50217 -234.129601) (xy 370.510113 -234.076897)
			(xy 370.525823 -234.025967) (xy 370.548949 -233.977946) (xy 370.578973 -233.933909) (xy 370.615225 -233.894838)
			(xy 370.656896 -233.861607) (xy 370.703054 -233.834958) (xy 370.752668 -233.815486) (xy 370.80463 -233.803626)
			(xy 370.85778 -233.799643) (xy 370.91093 -233.803626) (xy 370.962892 -233.815486) (xy 371.012506 -233.834958)
			(xy 371.058664 -233.861607) (xy 371.100335 -233.894838) (xy 371.136587 -233.933909) (xy 371.166611 -233.977946)
			(xy 371.189737 -234.025967) (xy 371.205447 -234.076897) (xy 371.21339 -234.129601) (xy 371.213888 -234.15625)
			(xy 371.21339 -234.182899) (xy 371.442224 -234.182899) (xy 371.442224 -234.129601) (xy 371.450167 -234.076897)
			(xy 371.465877 -234.025967) (xy 371.489003 -233.977946) (xy 371.519027 -233.933909) (xy 371.555279 -233.894838)
			(xy 371.59695 -233.861607) (xy 371.643108 -233.834958) (xy 371.692722 -233.815486) (xy 371.744684 -233.803626)
			(xy 371.797834 -233.799643) (xy 371.850984 -233.803626) (xy 371.902946 -233.815486) (xy 371.95256 -233.834958)
			(xy 371.998718 -233.861607) (xy 372.040389 -233.894838) (xy 372.076641 -233.933909) (xy 372.106665 -233.977946)
			(xy 372.129791 -234.025967) (xy 372.145501 -234.076897) (xy 372.153444 -234.129601) (xy 372.153942 -234.15625)
			(xy 372.153444 -234.182899) (xy 372.382024 -234.182899) (xy 372.382024 -234.129601) (xy 372.389967 -234.076897)
			(xy 372.405677 -234.025967) (xy 372.428803 -233.977946) (xy 372.458827 -233.933909) (xy 372.495079 -233.894838)
			(xy 372.53675 -233.861607) (xy 372.582908 -233.834958) (xy 372.632522 -233.815486) (xy 372.684484 -233.803626)
			(xy 372.737634 -233.799643) (xy 372.790784 -233.803626) (xy 372.842746 -233.815486) (xy 372.89236 -233.834958)
			(xy 372.938518 -233.861607) (xy 372.980189 -233.894838) (xy 373.016441 -233.933909) (xy 373.046465 -233.977946)
			(xy 373.069591 -234.025967) (xy 373.085301 -234.076897) (xy 373.093244 -234.129601) (xy 373.093742 -234.15625)
			(xy 373.093244 -234.182899) (xy 373.321824 -234.182899) (xy 373.321824 -234.129601) (xy 373.329767 -234.076897)
			(xy 373.345477 -234.025967) (xy 373.368603 -233.977946) (xy 373.398627 -233.933909) (xy 373.434879 -233.894838)
			(xy 373.47655 -233.861607) (xy 373.522708 -233.834958) (xy 373.572322 -233.815486) (xy 373.624284 -233.803626)
			(xy 373.677434 -233.799643) (xy 373.730584 -233.803626) (xy 373.782546 -233.815486) (xy 373.83216 -233.834958)
			(xy 373.878318 -233.861607) (xy 373.919989 -233.894838) (xy 373.956241 -233.933909) (xy 373.986265 -233.977946)
			(xy 374.009391 -234.025967) (xy 374.025101 -234.076897) (xy 374.033044 -234.129601) (xy 374.033542 -234.15625)
			(xy 374.033044 -234.182899) (xy 374.261624 -234.182899) (xy 374.261624 -234.129601) (xy 374.269567 -234.076897)
			(xy 374.285277 -234.025967) (xy 374.308403 -233.977946) (xy 374.338427 -233.933909) (xy 374.374679 -233.894838)
			(xy 374.41635 -233.861607) (xy 374.462508 -233.834958) (xy 374.512122 -233.815486) (xy 374.564084 -233.803626)
			(xy 374.617234 -233.799643) (xy 374.670384 -233.803626) (xy 374.722346 -233.815486) (xy 374.77196 -233.834958)
			(xy 374.818118 -233.861607) (xy 374.859789 -233.894838) (xy 374.896041 -233.933909) (xy 374.926065 -233.977946)
			(xy 374.949191 -234.025967) (xy 374.964901 -234.076897) (xy 374.972844 -234.129601) (xy 374.973342 -234.15625)
			(xy 374.972844 -234.182899) (xy 375.201424 -234.182899) (xy 375.201424 -234.129601) (xy 375.209367 -234.076897)
			(xy 375.225077 -234.025967) (xy 375.248203 -233.977946) (xy 375.278227 -233.933909) (xy 375.314479 -233.894838)
			(xy 375.35615 -233.861607) (xy 375.402308 -233.834958) (xy 375.451922 -233.815486) (xy 375.503884 -233.803626)
			(xy 375.557034 -233.799643) (xy 375.610184 -233.803626) (xy 375.662146 -233.815486) (xy 375.71176 -233.834958)
			(xy 375.757918 -233.861607) (xy 375.799589 -233.894838) (xy 375.835841 -233.933909) (xy 375.865865 -233.977946)
			(xy 375.888991 -234.025967) (xy 375.904701 -234.076897) (xy 375.912644 -234.129601) (xy 375.913142 -234.15625)
			(xy 375.912644 -234.182899) (xy 376.141224 -234.182899) (xy 376.141224 -234.129601) (xy 376.149167 -234.076897)
			(xy 376.164877 -234.025967) (xy 376.188003 -233.977946) (xy 376.218027 -233.933909) (xy 376.254279 -233.894838)
			(xy 376.29595 -233.861607) (xy 376.342108 -233.834958) (xy 376.391722 -233.815486) (xy 376.443684 -233.803626)
			(xy 376.496834 -233.799643) (xy 376.549984 -233.803626) (xy 376.601946 -233.815486) (xy 376.65156 -233.834958)
			(xy 376.697718 -233.861607) (xy 376.739389 -233.894838) (xy 376.775641 -233.933909) (xy 376.805665 -233.977946)
			(xy 376.828791 -234.025967) (xy 376.844501 -234.076897) (xy 376.852444 -234.129601) (xy 376.852942 -234.15625)
			(xy 376.852444 -234.182899) (xy 377.08077 -234.182899) (xy 377.08077 -234.129601) (xy 377.088713 -234.076897)
			(xy 377.104423 -234.025967) (xy 377.127549 -233.977946) (xy 377.157573 -233.933909) (xy 377.193825 -233.894838)
			(xy 377.235496 -233.861607) (xy 377.281654 -233.834958) (xy 377.331268 -233.815486) (xy 377.38323 -233.803626)
			(xy 377.43638 -233.799643) (xy 377.48953 -233.803626) (xy 377.541492 -233.815486) (xy 377.591106 -233.834958)
			(xy 377.637264 -233.861607) (xy 377.678935 -233.894838) (xy 377.715187 -233.933909) (xy 377.745211 -233.977946)
			(xy 377.768337 -234.025967) (xy 377.784047 -234.076897) (xy 377.79199 -234.129601) (xy 377.792488 -234.15625)
			(xy 377.79199 -234.182899) (xy 378.020824 -234.182899) (xy 378.020824 -234.129601) (xy 378.028767 -234.076897)
			(xy 378.044477 -234.025967) (xy 378.067603 -233.977946) (xy 378.097627 -233.933909) (xy 378.133879 -233.894838)
			(xy 378.17555 -233.861607) (xy 378.221708 -233.834958) (xy 378.271322 -233.815486) (xy 378.323284 -233.803626)
			(xy 378.376434 -233.799643) (xy 378.429584 -233.803626) (xy 378.481546 -233.815486) (xy 378.53116 -233.834958)
			(xy 378.577318 -233.861607) (xy 378.618989 -233.894838) (xy 378.655241 -233.933909) (xy 378.685265 -233.977946)
			(xy 378.708391 -234.025967) (xy 378.724101 -234.076897) (xy 378.732044 -234.129601) (xy 378.732542 -234.15625)
			(xy 378.732044 -234.182899) (xy 378.960624 -234.182899) (xy 378.960624 -234.129601) (xy 378.968567 -234.076897)
			(xy 378.984277 -234.025967) (xy 379.007403 -233.977946) (xy 379.037427 -233.933909) (xy 379.073679 -233.894838)
			(xy 379.11535 -233.861607) (xy 379.161508 -233.834958) (xy 379.211122 -233.815486) (xy 379.263084 -233.803626)
			(xy 379.316234 -233.799643) (xy 379.369384 -233.803626) (xy 379.421346 -233.815486) (xy 379.47096 -233.834958)
			(xy 379.517118 -233.861607) (xy 379.558789 -233.894838) (xy 379.595041 -233.933909) (xy 379.625065 -233.977946)
			(xy 379.648191 -234.025967) (xy 379.663901 -234.076897) (xy 379.671844 -234.129601) (xy 379.672342 -234.15625)
			(xy 379.671844 -234.182899) (xy 379.900424 -234.182899) (xy 379.900424 -234.129601) (xy 379.908367 -234.076897)
			(xy 379.924077 -234.025967) (xy 379.947203 -233.977946) (xy 379.977227 -233.933909) (xy 380.013479 -233.894838)
			(xy 380.05515 -233.861607) (xy 380.101308 -233.834958) (xy 380.150922 -233.815486) (xy 380.202884 -233.803626)
			(xy 380.256034 -233.799643) (xy 380.309184 -233.803626) (xy 380.361146 -233.815486) (xy 380.41076 -233.834958)
			(xy 380.456918 -233.861607) (xy 380.498589 -233.894838) (xy 380.534841 -233.933909) (xy 380.564865 -233.977946)
			(xy 380.587991 -234.025967) (xy 380.603701 -234.076897) (xy 380.611644 -234.129601) (xy 380.612142 -234.15625)
			(xy 380.611644 -234.182899) (xy 380.603701 -234.235603) (xy 380.587991 -234.286533) (xy 380.564865 -234.334554)
			(xy 380.534841 -234.378591) (xy 380.498589 -234.417662) (xy 380.456918 -234.450893) (xy 380.41076 -234.477542)
			(xy 380.361146 -234.497014) (xy 380.309184 -234.508874) (xy 380.256034 -234.512858) (xy 380.202884 -234.508874)
			(xy 380.150922 -234.497014) (xy 380.101308 -234.477542) (xy 380.05515 -234.450893) (xy 380.013479 -234.417662)
			(xy 379.977227 -234.378591) (xy 379.947203 -234.334554) (xy 379.924077 -234.286533) (xy 379.908367 -234.235603)
			(xy 379.900424 -234.182899) (xy 379.671844 -234.182899) (xy 379.663901 -234.235603) (xy 379.648191 -234.286533)
			(xy 379.625065 -234.334554) (xy 379.595041 -234.378591) (xy 379.558789 -234.417662) (xy 379.517118 -234.450893)
			(xy 379.47096 -234.477542) (xy 379.421346 -234.497014) (xy 379.369384 -234.508874) (xy 379.316234 -234.512858)
			(xy 379.263084 -234.508874) (xy 379.211122 -234.497014) (xy 379.161508 -234.477542) (xy 379.11535 -234.450893)
			(xy 379.073679 -234.417662) (xy 379.037427 -234.378591) (xy 379.007403 -234.334554) (xy 378.984277 -234.286533)
			(xy 378.968567 -234.235603) (xy 378.960624 -234.182899) (xy 378.732044 -234.182899) (xy 378.724101 -234.235603)
			(xy 378.708391 -234.286533) (xy 378.685265 -234.334554) (xy 378.655241 -234.378591) (xy 378.618989 -234.417662)
			(xy 378.577318 -234.450893) (xy 378.53116 -234.477542) (xy 378.481546 -234.497014) (xy 378.429584 -234.508874)
			(xy 378.376434 -234.512858) (xy 378.323284 -234.508874) (xy 378.271322 -234.497014) (xy 378.221708 -234.477542)
			(xy 378.17555 -234.450893) (xy 378.133879 -234.417662) (xy 378.097627 -234.378591) (xy 378.067603 -234.334554)
			(xy 378.044477 -234.286533) (xy 378.028767 -234.235603) (xy 378.020824 -234.182899) (xy 377.79199 -234.182899)
			(xy 377.784047 -234.235603) (xy 377.768337 -234.286533) (xy 377.745211 -234.334554) (xy 377.715187 -234.378591)
			(xy 377.678935 -234.417662) (xy 377.637264 -234.450893) (xy 377.591106 -234.477542) (xy 377.541492 -234.497014)
			(xy 377.48953 -234.508874) (xy 377.43638 -234.512858) (xy 377.38323 -234.508874) (xy 377.331268 -234.497014)
			(xy 377.281654 -234.477542) (xy 377.235496 -234.450893) (xy 377.193825 -234.417662) (xy 377.157573 -234.378591)
			(xy 377.127549 -234.334554) (xy 377.104423 -234.286533) (xy 377.088713 -234.235603) (xy 377.08077 -234.182899)
			(xy 376.852444 -234.182899) (xy 376.844501 -234.235603) (xy 376.828791 -234.286533) (xy 376.805665 -234.334554)
			(xy 376.775641 -234.378591) (xy 376.739389 -234.417662) (xy 376.697718 -234.450893) (xy 376.65156 -234.477542)
			(xy 376.601946 -234.497014) (xy 376.549984 -234.508874) (xy 376.496834 -234.512858) (xy 376.443684 -234.508874)
			(xy 376.391722 -234.497014) (xy 376.342108 -234.477542) (xy 376.29595 -234.450893) (xy 376.254279 -234.417662)
			(xy 376.218027 -234.378591) (xy 376.188003 -234.334554) (xy 376.164877 -234.286533) (xy 376.149167 -234.235603)
			(xy 376.141224 -234.182899) (xy 375.912644 -234.182899) (xy 375.904701 -234.235603) (xy 375.888991 -234.286533)
			(xy 375.865865 -234.334554) (xy 375.835841 -234.378591) (xy 375.799589 -234.417662) (xy 375.757918 -234.450893)
			(xy 375.71176 -234.477542) (xy 375.662146 -234.497014) (xy 375.610184 -234.508874) (xy 375.557034 -234.512858)
			(xy 375.503884 -234.508874) (xy 375.451922 -234.497014) (xy 375.402308 -234.477542) (xy 375.35615 -234.450893)
			(xy 375.314479 -234.417662) (xy 375.278227 -234.378591) (xy 375.248203 -234.334554) (xy 375.225077 -234.286533)
			(xy 375.209367 -234.235603) (xy 375.201424 -234.182899) (xy 374.972844 -234.182899) (xy 374.964901 -234.235603)
			(xy 374.949191 -234.286533) (xy 374.926065 -234.334554) (xy 374.896041 -234.378591) (xy 374.859789 -234.417662)
			(xy 374.818118 -234.450893) (xy 374.77196 -234.477542) (xy 374.722346 -234.497014) (xy 374.670384 -234.508874)
			(xy 374.617234 -234.512858) (xy 374.564084 -234.508874) (xy 374.512122 -234.497014) (xy 374.462508 -234.477542)
			(xy 374.41635 -234.450893) (xy 374.374679 -234.417662) (xy 374.338427 -234.378591) (xy 374.308403 -234.334554)
			(xy 374.285277 -234.286533) (xy 374.269567 -234.235603) (xy 374.261624 -234.182899) (xy 374.033044 -234.182899)
			(xy 374.025101 -234.235603) (xy 374.009391 -234.286533) (xy 373.986265 -234.334554) (xy 373.956241 -234.378591)
			(xy 373.919989 -234.417662) (xy 373.878318 -234.450893) (xy 373.83216 -234.477542) (xy 373.782546 -234.497014)
			(xy 373.730584 -234.508874) (xy 373.677434 -234.512858) (xy 373.624284 -234.508874) (xy 373.572322 -234.497014)
			(xy 373.522708 -234.477542) (xy 373.47655 -234.450893) (xy 373.434879 -234.417662) (xy 373.398627 -234.378591)
			(xy 373.368603 -234.334554) (xy 373.345477 -234.286533) (xy 373.329767 -234.235603) (xy 373.321824 -234.182899)
			(xy 373.093244 -234.182899) (xy 373.085301 -234.235603) (xy 373.069591 -234.286533) (xy 373.046465 -234.334554)
			(xy 373.016441 -234.378591) (xy 372.980189 -234.417662) (xy 372.938518 -234.450893) (xy 372.89236 -234.477542)
			(xy 372.842746 -234.497014) (xy 372.790784 -234.508874) (xy 372.737634 -234.512858) (xy 372.684484 -234.508874)
			(xy 372.632522 -234.497014) (xy 372.582908 -234.477542) (xy 372.53675 -234.450893) (xy 372.495079 -234.417662)
			(xy 372.458827 -234.378591) (xy 372.428803 -234.334554) (xy 372.405677 -234.286533) (xy 372.389967 -234.235603)
			(xy 372.382024 -234.182899) (xy 372.153444 -234.182899) (xy 372.145501 -234.235603) (xy 372.129791 -234.286533)
			(xy 372.106665 -234.334554) (xy 372.076641 -234.378591) (xy 372.040389 -234.417662) (xy 371.998718 -234.450893)
			(xy 371.95256 -234.477542) (xy 371.902946 -234.497014) (xy 371.850984 -234.508874) (xy 371.797834 -234.512858)
			(xy 371.744684 -234.508874) (xy 371.692722 -234.497014) (xy 371.643108 -234.477542) (xy 371.59695 -234.450893)
			(xy 371.555279 -234.417662) (xy 371.519027 -234.378591) (xy 371.489003 -234.334554) (xy 371.465877 -234.286533)
			(xy 371.450167 -234.235603) (xy 371.442224 -234.182899) (xy 371.21339 -234.182899) (xy 371.205447 -234.235603)
			(xy 371.189737 -234.286533) (xy 371.166611 -234.334554) (xy 371.136587 -234.378591) (xy 371.100335 -234.417662)
			(xy 371.058664 -234.450893) (xy 371.012506 -234.477542) (xy 370.962892 -234.497014) (xy 370.91093 -234.508874)
			(xy 370.85778 -234.512858) (xy 370.80463 -234.508874) (xy 370.752668 -234.497014) (xy 370.703054 -234.477542)
			(xy 370.656896 -234.450893) (xy 370.615225 -234.417662) (xy 370.578973 -234.378591) (xy 370.548949 -234.334554)
			(xy 370.525823 -234.286533) (xy 370.510113 -234.235603) (xy 370.50217 -234.182899) (xy 370.273844 -234.182899)
			(xy 370.265901 -234.235603) (xy 370.250191 -234.286533) (xy 370.227065 -234.334554) (xy 370.197041 -234.378591)
			(xy 370.160789 -234.417662) (xy 370.119118 -234.450893) (xy 370.07296 -234.477542) (xy 370.023346 -234.497014)
			(xy 369.971384 -234.508874) (xy 369.918234 -234.512858) (xy 369.865084 -234.508874) (xy 369.813122 -234.497014)
			(xy 369.763508 -234.477542) (xy 369.71735 -234.450893) (xy 369.675679 -234.417662) (xy 369.639427 -234.378591)
			(xy 369.609403 -234.334554) (xy 369.586277 -234.286533) (xy 369.570567 -234.235603) (xy 369.562624 -234.182899)
			(xy 369.33379 -234.182899) (xy 369.325847 -234.235603) (xy 369.310137 -234.286533) (xy 369.287011 -234.334554)
			(xy 369.256987 -234.378591) (xy 369.220735 -234.417662) (xy 369.179064 -234.450893) (xy 369.132906 -234.477542)
			(xy 369.083292 -234.497014) (xy 369.03133 -234.508874) (xy 368.97818 -234.512858) (xy 368.92503 -234.508874)
			(xy 368.873068 -234.497014) (xy 368.823454 -234.477542) (xy 368.777296 -234.450893) (xy 368.735625 -234.417662)
			(xy 368.699373 -234.378591) (xy 368.669349 -234.334554) (xy 368.646223 -234.286533) (xy 368.630513 -234.235603)
			(xy 368.62257 -234.182899) (xy 368.394244 -234.182899) (xy 368.386301 -234.235603) (xy 368.370591 -234.286533)
			(xy 368.347465 -234.334554) (xy 368.317441 -234.378591) (xy 368.281189 -234.417662) (xy 368.239518 -234.450893)
			(xy 368.19336 -234.477542) (xy 368.143746 -234.497014) (xy 368.091784 -234.508874) (xy 368.038634 -234.512858)
			(xy 367.985484 -234.508874) (xy 367.933522 -234.497014) (xy 367.883908 -234.477542) (xy 367.83775 -234.450893)
			(xy 367.796079 -234.417662) (xy 367.759827 -234.378591) (xy 367.729803 -234.334554) (xy 367.706677 -234.286533)
			(xy 367.690967 -234.235603) (xy 367.683024 -234.182899) (xy 367.454444 -234.182899) (xy 367.446501 -234.235603)
			(xy 367.430791 -234.286533) (xy 367.407665 -234.334554) (xy 367.377641 -234.378591) (xy 367.341389 -234.417662)
			(xy 367.299718 -234.450893) (xy 367.25356 -234.477542) (xy 367.203946 -234.497014) (xy 367.151984 -234.508874)
			(xy 367.098834 -234.512858) (xy 367.045684 -234.508874) (xy 366.993722 -234.497014) (xy 366.944108 -234.477542)
			(xy 366.89795 -234.450893) (xy 366.856279 -234.417662) (xy 366.820027 -234.378591) (xy 366.790003 -234.334554)
			(xy 366.766877 -234.286533) (xy 366.751167 -234.235603) (xy 366.743224 -234.182899) (xy 366.514644 -234.182899)
			(xy 366.506701 -234.235603) (xy 366.490991 -234.286533) (xy 366.467865 -234.334554) (xy 366.437841 -234.378591)
			(xy 366.401589 -234.417662) (xy 366.359918 -234.450893) (xy 366.31376 -234.477542) (xy 366.264146 -234.497014)
			(xy 366.212184 -234.508874) (xy 366.159034 -234.512858) (xy 366.105884 -234.508874) (xy 366.053922 -234.497014)
			(xy 366.004308 -234.477542) (xy 365.95815 -234.450893) (xy 365.916479 -234.417662) (xy 365.880227 -234.378591)
			(xy 365.850203 -234.334554) (xy 365.827077 -234.286533) (xy 365.811367 -234.235603) (xy 365.803424 -234.182899)
			(xy 365.574844 -234.182899) (xy 365.566901 -234.235603) (xy 365.551191 -234.286533) (xy 365.528065 -234.334554)
			(xy 365.498041 -234.378591) (xy 365.461789 -234.417662) (xy 365.420118 -234.450893) (xy 365.37396 -234.477542)
			(xy 365.324346 -234.497014) (xy 365.272384 -234.508874) (xy 365.219234 -234.512858) (xy 365.166084 -234.508874)
			(xy 365.114122 -234.497014) (xy 365.064508 -234.477542) (xy 365.01835 -234.450893) (xy 364.976679 -234.417662)
			(xy 364.940427 -234.378591) (xy 364.910403 -234.334554) (xy 364.887277 -234.286533) (xy 364.871567 -234.235603)
			(xy 364.863624 -234.182899) (xy 364.635044 -234.182899) (xy 364.627101 -234.235603) (xy 364.611391 -234.286533)
			(xy 364.588265 -234.334554) (xy 364.558241 -234.378591) (xy 364.521989 -234.417662) (xy 364.480318 -234.450893)
			(xy 364.43416 -234.477542) (xy 364.384546 -234.497014) (xy 364.332584 -234.508874) (xy 364.279434 -234.512858)
			(xy 364.226284 -234.508874) (xy 364.174322 -234.497014) (xy 364.124708 -234.477542) (xy 364.07855 -234.450893)
			(xy 364.036879 -234.417662) (xy 364.000627 -234.378591) (xy 363.970603 -234.334554) (xy 363.947477 -234.286533)
			(xy 363.931767 -234.235603) (xy 363.923824 -234.182899) (xy 363.695244 -234.182899) (xy 363.687301 -234.235603)
			(xy 363.671591 -234.286533) (xy 363.648465 -234.334554) (xy 363.618441 -234.378591) (xy 363.582189 -234.417662)
			(xy 363.540518 -234.450893) (xy 363.49436 -234.477542) (xy 363.444746 -234.497014) (xy 363.392784 -234.508874)
			(xy 363.339634 -234.512858) (xy 363.286484 -234.508874) (xy 363.234522 -234.497014) (xy 363.184908 -234.477542)
			(xy 363.13875 -234.450893) (xy 363.097079 -234.417662) (xy 363.060827 -234.378591) (xy 363.030803 -234.334554)
			(xy 363.007677 -234.286533) (xy 362.991967 -234.235603) (xy 362.984024 -234.182899) (xy 362.755444 -234.182899)
			(xy 362.747501 -234.235603) (xy 362.731791 -234.286533) (xy 362.708665 -234.334554) (xy 362.678641 -234.378591)
			(xy 362.642389 -234.417662) (xy 362.600718 -234.450893) (xy 362.55456 -234.477542) (xy 362.504946 -234.497014)
			(xy 362.452984 -234.508874) (xy 362.399834 -234.512858) (xy 362.346684 -234.508874) (xy 362.294722 -234.497014)
			(xy 362.245108 -234.477542) (xy 362.19895 -234.450893) (xy 362.157279 -234.417662) (xy 362.121027 -234.378591)
			(xy 362.091003 -234.334554) (xy 362.067877 -234.286533) (xy 362.052167 -234.235603) (xy 362.044224 -234.182899)
			(xy 361.815644 -234.182899) (xy 361.807701 -234.235603) (xy 361.791991 -234.286533) (xy 361.768865 -234.334554)
			(xy 361.738841 -234.378591) (xy 361.702589 -234.417662) (xy 361.660918 -234.450893) (xy 361.61476 -234.477542)
			(xy 361.565146 -234.497014) (xy 361.513184 -234.508874) (xy 361.460034 -234.512858) (xy 361.406884 -234.508874)
			(xy 361.354922 -234.497014) (xy 361.305308 -234.477542) (xy 361.25915 -234.450893) (xy 361.217479 -234.417662)
			(xy 361.181227 -234.378591) (xy 361.151203 -234.334554) (xy 361.128077 -234.286533) (xy 361.112367 -234.235603)
			(xy 361.104424 -234.182899) (xy 360.875844 -234.182899) (xy 360.867901 -234.235603) (xy 360.852191 -234.286533)
			(xy 360.829065 -234.334554) (xy 360.799041 -234.378591) (xy 360.762789 -234.417662) (xy 360.721118 -234.450893)
			(xy 360.67496 -234.477542) (xy 360.625346 -234.497014) (xy 360.573384 -234.508874) (xy 360.520234 -234.512858)
			(xy 360.467084 -234.508874) (xy 360.415122 -234.497014) (xy 360.365508 -234.477542) (xy 360.31935 -234.450893)
			(xy 360.277679 -234.417662) (xy 360.241427 -234.378591) (xy 360.211403 -234.334554) (xy 360.188277 -234.286533)
			(xy 360.172567 -234.235603) (xy 360.164624 -234.182899) (xy 359.936044 -234.182899) (xy 359.928101 -234.235603)
			(xy 359.912391 -234.286533) (xy 359.889265 -234.334554) (xy 359.859241 -234.378591) (xy 359.822989 -234.417662)
			(xy 359.781318 -234.450893) (xy 359.73516 -234.477542) (xy 359.685546 -234.497014) (xy 359.633584 -234.508874)
			(xy 359.580434 -234.512858) (xy 359.527284 -234.508874) (xy 359.475322 -234.497014) (xy 359.425708 -234.477542)
			(xy 359.37955 -234.450893) (xy 359.337879 -234.417662) (xy 359.301627 -234.378591) (xy 359.271603 -234.334554)
			(xy 359.248477 -234.286533) (xy 359.232767 -234.235603) (xy 359.224824 -234.182899) (xy 358.996244 -234.182899)
			(xy 358.988301 -234.235603) (xy 358.972591 -234.286533) (xy 358.949465 -234.334554) (xy 358.919441 -234.378591)
			(xy 358.883189 -234.417662) (xy 358.841518 -234.450893) (xy 358.79536 -234.477542) (xy 358.745746 -234.497014)
			(xy 358.693784 -234.508874) (xy 358.640634 -234.512858) (xy 358.587484 -234.508874) (xy 358.535522 -234.497014)
			(xy 358.485908 -234.477542) (xy 358.43975 -234.450893) (xy 358.398079 -234.417662) (xy 358.361827 -234.378591)
			(xy 358.331803 -234.334554) (xy 358.308677 -234.286533) (xy 358.292967 -234.235603) (xy 358.285024 -234.182899)
			(xy 358.056444 -234.182899) (xy 358.048501 -234.235603) (xy 358.032791 -234.286533) (xy 358.009665 -234.334554)
			(xy 357.979641 -234.378591) (xy 357.943389 -234.417662) (xy 357.901718 -234.450893) (xy 357.85556 -234.477542)
			(xy 357.805946 -234.497014) (xy 357.753984 -234.508874) (xy 357.700834 -234.512858) (xy 357.647684 -234.508874)
			(xy 357.595722 -234.497014) (xy 357.546108 -234.477542) (xy 357.49995 -234.450893) (xy 357.458279 -234.417662)
			(xy 357.422027 -234.378591) (xy 357.392003 -234.334554) (xy 357.368877 -234.286533) (xy 357.353167 -234.235603)
			(xy 357.345224 -234.182899) (xy 357.116644 -234.182899) (xy 357.108701 -234.235603) (xy 357.092991 -234.286533)
			(xy 357.069865 -234.334554) (xy 357.039841 -234.378591) (xy 357.003589 -234.417662) (xy 356.961918 -234.450893)
			(xy 356.91576 -234.477542) (xy 356.866146 -234.497014) (xy 356.814184 -234.508874) (xy 356.761034 -234.512858)
			(xy 356.707884 -234.508874) (xy 356.655922 -234.497014) (xy 356.606308 -234.477542) (xy 356.56015 -234.450893)
			(xy 356.518479 -234.417662) (xy 356.482227 -234.378591) (xy 356.452203 -234.334554) (xy 356.429077 -234.286533)
			(xy 356.413367 -234.235603) (xy 356.405424 -234.182899) (xy 356.176844 -234.182899) (xy 356.168901 -234.235603)
			(xy 356.153191 -234.286533) (xy 356.130065 -234.334554) (xy 356.100041 -234.378591) (xy 356.063789 -234.417662)
			(xy 356.022118 -234.450893) (xy 355.97596 -234.477542) (xy 355.926346 -234.497014) (xy 355.874384 -234.508874)
			(xy 355.821234 -234.512858) (xy 355.768084 -234.508874) (xy 355.716122 -234.497014) (xy 355.666508 -234.477542)
			(xy 355.62035 -234.450893) (xy 355.578679 -234.417662) (xy 355.542427 -234.378591) (xy 355.512403 -234.334554)
			(xy 355.489277 -234.286533) (xy 355.473567 -234.235603) (xy 355.465624 -234.182899) (xy 355.237044 -234.182899)
			(xy 355.229101 -234.235603) (xy 355.213391 -234.286533) (xy 355.190265 -234.334554) (xy 355.160241 -234.378591)
			(xy 355.123989 -234.417662) (xy 355.082318 -234.450893) (xy 355.03616 -234.477542) (xy 354.986546 -234.497014)
			(xy 354.934584 -234.508874) (xy 354.881434 -234.512858) (xy 354.828284 -234.508874) (xy 354.776322 -234.497014)
			(xy 354.726708 -234.477542) (xy 354.68055 -234.450893) (xy 354.638879 -234.417662) (xy 354.602627 -234.378591)
			(xy 354.572603 -234.334554) (xy 354.549477 -234.286533) (xy 354.533767 -234.235603) (xy 354.525824 -234.182899)
			(xy 354.297244 -234.182899) (xy 354.289301 -234.235603) (xy 354.273591 -234.286533) (xy 354.250465 -234.334554)
			(xy 354.220441 -234.378591) (xy 354.184189 -234.417662) (xy 354.142518 -234.450893) (xy 354.09636 -234.477542)
			(xy 354.046746 -234.497014) (xy 353.994784 -234.508874) (xy 353.941634 -234.512858) (xy 353.888484 -234.508874)
			(xy 353.836522 -234.497014) (xy 353.786908 -234.477542) (xy 353.74075 -234.450893) (xy 353.699079 -234.417662)
			(xy 353.662827 -234.378591) (xy 353.632803 -234.334554) (xy 353.609677 -234.286533) (xy 353.593967 -234.235603)
			(xy 353.586024 -234.182899) (xy 352.417644 -234.182899) (xy 352.409701 -234.235603) (xy 352.393991 -234.286533)
			(xy 352.370865 -234.334554) (xy 352.340841 -234.378591) (xy 352.304589 -234.417662) (xy 352.262918 -234.450893)
			(xy 352.21676 -234.477542) (xy 352.167146 -234.497014) (xy 352.115184 -234.508874) (xy 352.062034 -234.512858)
			(xy 352.008884 -234.508874) (xy 351.956922 -234.497014) (xy 351.907308 -234.477542) (xy 351.86115 -234.450893)
			(xy 351.819479 -234.417662) (xy 351.783227 -234.378591) (xy 351.753203 -234.334554) (xy 351.730077 -234.286533)
			(xy 351.714367 -234.235603) (xy 351.706424 -234.182899) (xy 351.477815 -234.182899) (xy 351.477789 -234.184232)
			(xy 351.469028 -234.239505) (xy 351.45173 -234.292727) (xy 351.42632 -234.342589) (xy 351.393423 -234.387863)
			(xy 351.35385 -234.427434) (xy 351.308575 -234.460328) (xy 351.258712 -234.485736) (xy 351.205489 -234.503032)
			(xy 351.150216 -234.511791) (xy 351.122234 -234.512358) (xy 351.09728 -234.511941) (xy 351.047859 -234.504976)
			(xy 350.999896 -234.491178) (xy 350.976946 -234.48137) (xy 350.944942 -234.467146) (xy 350.379813 -235.032275)
			(xy 353.09809 -235.032275) (xy 353.09809 -234.978977) (xy 353.106033 -234.926273) (xy 353.121743 -234.875343)
			(xy 353.144869 -234.827322) (xy 353.174893 -234.783285) (xy 353.211145 -234.744214) (xy 353.252816 -234.710983)
			(xy 353.298974 -234.684334) (xy 353.348588 -234.664862) (xy 353.40055 -234.653002) (xy 353.4537 -234.649019)
			(xy 353.50685 -234.653002) (xy 353.558812 -234.664862) (xy 353.608426 -234.684334) (xy 353.654584 -234.710983)
			(xy 353.696255 -234.744214) (xy 353.732507 -234.783285) (xy 353.762531 -234.827322) (xy 353.785657 -234.875343)
			(xy 353.801367 -234.926273) (xy 353.80931 -234.978977) (xy 353.809808 -235.005626) (xy 353.80931 -235.032275)
			(xy 353.801367 -235.084979) (xy 353.785657 -235.135909) (xy 353.762531 -235.18393) (xy 353.732507 -235.227967)
			(xy 353.696255 -235.267038) (xy 353.657481 -235.297959) (xy 354.021888 -235.297959) (xy 354.021888 -235.244661)
			(xy 354.029831 -235.191957) (xy 354.045541 -235.141027) (xy 354.068667 -235.093006) (xy 354.098691 -235.048969)
			(xy 354.134943 -235.009898) (xy 354.176614 -234.976667) (xy 354.222772 -234.950018) (xy 354.272386 -234.930546)
			(xy 354.324348 -234.918686) (xy 354.377498 -234.914703) (xy 354.430648 -234.918686) (xy 354.48261 -234.930546)
			(xy 354.532224 -234.950018) (xy 354.578382 -234.976667) (xy 354.603522 -234.996715) (xy 356.87507 -234.996715)
			(xy 356.87507 -234.943417) (xy 356.883013 -234.890713) (xy 356.898723 -234.839783) (xy 356.921849 -234.791762)
			(xy 356.951873 -234.747725) (xy 356.988125 -234.708654) (xy 357.029796 -234.675423) (xy 357.075954 -234.648774)
			(xy 357.125568 -234.629302) (xy 357.17753 -234.617442) (xy 357.23068 -234.613459) (xy 357.28383 -234.617442)
			(xy 357.335792 -234.629302) (xy 357.385406 -234.648774) (xy 357.431564 -234.675423) (xy 357.473235 -234.708654)
			(xy 357.509487 -234.747725) (xy 357.539511 -234.791762) (xy 357.562637 -234.839783) (xy 357.578347 -234.890713)
			(xy 357.58629 -234.943417) (xy 357.586788 -234.970066) (xy 357.58629 -234.996715) (xy 357.815124 -234.996715)
			(xy 357.815124 -234.943417) (xy 357.823067 -234.890713) (xy 357.838777 -234.839783) (xy 357.861903 -234.791762)
			(xy 357.891927 -234.747725) (xy 357.928179 -234.708654) (xy 357.96985 -234.675423) (xy 358.016008 -234.648774)
			(xy 358.065622 -234.629302) (xy 358.117584 -234.617442) (xy 358.170734 -234.613459) (xy 358.223884 -234.617442)
			(xy 358.275846 -234.629302) (xy 358.32546 -234.648774) (xy 358.371618 -234.675423) (xy 358.413289 -234.708654)
			(xy 358.449541 -234.747725) (xy 358.479565 -234.791762) (xy 358.502691 -234.839783) (xy 358.518401 -234.890713)
			(xy 358.526344 -234.943417) (xy 358.526842 -234.970066) (xy 358.526344 -234.996715) (xy 358.75467 -234.996715)
			(xy 358.75467 -234.943417) (xy 358.762613 -234.890713) (xy 358.778323 -234.839783) (xy 358.801449 -234.791762)
			(xy 358.831473 -234.747725) (xy 358.867725 -234.708654) (xy 358.909396 -234.675423) (xy 358.955554 -234.648774)
			(xy 359.005168 -234.629302) (xy 359.05713 -234.617442) (xy 359.11028 -234.613459) (xy 359.16343 -234.617442)
			(xy 359.215392 -234.629302) (xy 359.265006 -234.648774) (xy 359.311164 -234.675423) (xy 359.352835 -234.708654)
			(xy 359.389087 -234.747725) (xy 359.419111 -234.791762) (xy 359.442237 -234.839783) (xy 359.457947 -234.890713)
			(xy 359.46589 -234.943417) (xy 359.466388 -234.970066) (xy 359.46589 -234.996715) (xy 359.69447 -234.996715)
			(xy 359.69447 -234.943417) (xy 359.702413 -234.890713) (xy 359.718123 -234.839783) (xy 359.741249 -234.791762)
			(xy 359.771273 -234.747725) (xy 359.807525 -234.708654) (xy 359.849196 -234.675423) (xy 359.895354 -234.648774)
			(xy 359.944968 -234.629302) (xy 359.99693 -234.617442) (xy 360.05008 -234.613459) (xy 360.10323 -234.617442)
			(xy 360.155192 -234.629302) (xy 360.204806 -234.648774) (xy 360.250964 -234.675423) (xy 360.292635 -234.708654)
			(xy 360.328887 -234.747725) (xy 360.358911 -234.791762) (xy 360.382037 -234.839783) (xy 360.397747 -234.890713)
			(xy 360.40569 -234.943417) (xy 360.406188 -234.970066) (xy 360.40569 -234.996715) (xy 360.63427 -234.996715)
			(xy 360.63427 -234.943417) (xy 360.642213 -234.890713) (xy 360.657923 -234.839783) (xy 360.681049 -234.791762)
			(xy 360.711073 -234.747725) (xy 360.747325 -234.708654) (xy 360.788996 -234.675423) (xy 360.835154 -234.648774)
			(xy 360.884768 -234.629302) (xy 360.93673 -234.617442) (xy 360.98988 -234.613459) (xy 361.04303 -234.617442)
			(xy 361.094992 -234.629302) (xy 361.144606 -234.648774) (xy 361.190764 -234.675423) (xy 361.232435 -234.708654)
			(xy 361.268687 -234.747725) (xy 361.298711 -234.791762) (xy 361.321837 -234.839783) (xy 361.337547 -234.890713)
			(xy 361.34549 -234.943417) (xy 361.345988 -234.970066) (xy 361.34549 -234.996715) (xy 361.574324 -234.996715)
			(xy 361.574324 -234.943417) (xy 361.582267 -234.890713) (xy 361.597977 -234.839783) (xy 361.621103 -234.791762)
			(xy 361.651127 -234.747725) (xy 361.687379 -234.708654) (xy 361.72905 -234.675423) (xy 361.775208 -234.648774)
			(xy 361.824822 -234.629302) (xy 361.876784 -234.617442) (xy 361.929934 -234.613459) (xy 361.983084 -234.617442)
			(xy 362.035046 -234.629302) (xy 362.08466 -234.648774) (xy 362.130818 -234.675423) (xy 362.172489 -234.708654)
			(xy 362.208741 -234.747725) (xy 362.238765 -234.791762) (xy 362.261891 -234.839783) (xy 362.277601 -234.890713)
			(xy 362.285544 -234.943417) (xy 362.286042 -234.970066) (xy 362.285544 -234.996715) (xy 369.09247 -234.996715)
			(xy 369.09247 -234.943417) (xy 369.100413 -234.890713) (xy 369.116123 -234.839783) (xy 369.139249 -234.791762)
			(xy 369.169273 -234.747725) (xy 369.205525 -234.708654) (xy 369.247196 -234.675423) (xy 369.293354 -234.648774)
			(xy 369.342968 -234.629302) (xy 369.39493 -234.617442) (xy 369.44808 -234.613459) (xy 369.50123 -234.617442)
			(xy 369.553192 -234.629302) (xy 369.602806 -234.648774) (xy 369.648964 -234.675423) (xy 369.690635 -234.708654)
			(xy 369.726887 -234.747725) (xy 369.756911 -234.791762) (xy 369.780037 -234.839783) (xy 369.795747 -234.890713)
			(xy 369.80369 -234.943417) (xy 369.804188 -234.970066) (xy 369.80369 -234.996715) (xy 370.03227 -234.996715)
			(xy 370.03227 -234.943417) (xy 370.040213 -234.890713) (xy 370.055923 -234.839783) (xy 370.079049 -234.791762)
			(xy 370.109073 -234.747725) (xy 370.145325 -234.708654) (xy 370.186996 -234.675423) (xy 370.233154 -234.648774)
			(xy 370.282768 -234.629302) (xy 370.33473 -234.617442) (xy 370.38788 -234.613459) (xy 370.44103 -234.617442)
			(xy 370.492992 -234.629302) (xy 370.542606 -234.648774) (xy 370.588764 -234.675423) (xy 370.630435 -234.708654)
			(xy 370.666687 -234.747725) (xy 370.696711 -234.791762) (xy 370.719837 -234.839783) (xy 370.735547 -234.890713)
			(xy 370.74349 -234.943417) (xy 370.743988 -234.970066) (xy 370.74349 -234.996715) (xy 370.97207 -234.996715)
			(xy 370.97207 -234.943417) (xy 370.980013 -234.890713) (xy 370.995723 -234.839783) (xy 371.018849 -234.791762)
			(xy 371.048873 -234.747725) (xy 371.085125 -234.708654) (xy 371.126796 -234.675423) (xy 371.172954 -234.648774)
			(xy 371.222568 -234.629302) (xy 371.27453 -234.617442) (xy 371.32768 -234.613459) (xy 371.38083 -234.617442)
			(xy 371.432792 -234.629302) (xy 371.482406 -234.648774) (xy 371.528564 -234.675423) (xy 371.570235 -234.708654)
			(xy 371.606487 -234.747725) (xy 371.636511 -234.791762) (xy 371.659637 -234.839783) (xy 371.675347 -234.890713)
			(xy 371.68329 -234.943417) (xy 371.683788 -234.970066) (xy 371.68329 -234.996715) (xy 371.91187 -234.996715)
			(xy 371.91187 -234.943417) (xy 371.919813 -234.890713) (xy 371.935523 -234.839783) (xy 371.958649 -234.791762)
			(xy 371.988673 -234.747725) (xy 372.024925 -234.708654) (xy 372.066596 -234.675423) (xy 372.112754 -234.648774)
			(xy 372.162368 -234.629302) (xy 372.21433 -234.617442) (xy 372.26748 -234.613459) (xy 372.32063 -234.617442)
			(xy 372.372592 -234.629302) (xy 372.422206 -234.648774) (xy 372.468364 -234.675423) (xy 372.510035 -234.708654)
			(xy 372.546287 -234.747725) (xy 372.576311 -234.791762) (xy 372.599437 -234.839783) (xy 372.615147 -234.890713)
			(xy 372.62309 -234.943417) (xy 372.623588 -234.970066) (xy 372.62309 -234.996715) (xy 372.851924 -234.996715)
			(xy 372.851924 -234.943417) (xy 372.859867 -234.890713) (xy 372.875577 -234.839783) (xy 372.898703 -234.791762)
			(xy 372.928727 -234.747725) (xy 372.964979 -234.708654) (xy 373.00665 -234.675423) (xy 373.052808 -234.648774)
			(xy 373.102422 -234.629302) (xy 373.154384 -234.617442) (xy 373.207534 -234.613459) (xy 373.260684 -234.617442)
			(xy 373.312646 -234.629302) (xy 373.36226 -234.648774) (xy 373.408418 -234.675423) (xy 373.450089 -234.708654)
			(xy 373.486341 -234.747725) (xy 373.516365 -234.791762) (xy 373.539491 -234.839783) (xy 373.555201 -234.890713)
			(xy 373.563144 -234.943417) (xy 373.563642 -234.970066) (xy 373.563144 -234.996715) (xy 373.79147 -234.996715)
			(xy 373.79147 -234.943417) (xy 373.799413 -234.890713) (xy 373.815123 -234.839783) (xy 373.838249 -234.791762)
			(xy 373.868273 -234.747725) (xy 373.904525 -234.708654) (xy 373.946196 -234.675423) (xy 373.992354 -234.648774)
			(xy 374.041968 -234.629302) (xy 374.09393 -234.617442) (xy 374.14708 -234.613459) (xy 374.20023 -234.617442)
			(xy 374.252192 -234.629302) (xy 374.301806 -234.648774) (xy 374.347964 -234.675423) (xy 374.389635 -234.708654)
			(xy 374.425887 -234.747725) (xy 374.455911 -234.791762) (xy 374.479037 -234.839783) (xy 374.494747 -234.890713)
			(xy 374.50269 -234.943417) (xy 374.503188 -234.970066) (xy 374.50269 -234.996715) (xy 374.73127 -234.996715)
			(xy 374.73127 -234.943417) (xy 374.739213 -234.890713) (xy 374.754923 -234.839783) (xy 374.778049 -234.791762)
			(xy 374.808073 -234.747725) (xy 374.844325 -234.708654) (xy 374.885996 -234.675423) (xy 374.932154 -234.648774)
			(xy 374.981768 -234.629302) (xy 375.03373 -234.617442) (xy 375.08688 -234.613459) (xy 375.14003 -234.617442)
			(xy 375.191992 -234.629302) (xy 375.241606 -234.648774) (xy 375.287764 -234.675423) (xy 375.329435 -234.708654)
			(xy 375.365687 -234.747725) (xy 375.395711 -234.791762) (xy 375.418837 -234.839783) (xy 375.434547 -234.890713)
			(xy 375.44249 -234.943417) (xy 375.442988 -234.970066) (xy 375.44249 -234.996715) (xy 375.67107 -234.996715)
			(xy 375.67107 -234.943417) (xy 375.679013 -234.890713) (xy 375.694723 -234.839783) (xy 375.717849 -234.791762)
			(xy 375.747873 -234.747725) (xy 375.784125 -234.708654) (xy 375.825796 -234.675423) (xy 375.871954 -234.648774)
			(xy 375.921568 -234.629302) (xy 375.97353 -234.617442) (xy 376.02668 -234.613459) (xy 376.07983 -234.617442)
			(xy 376.131792 -234.629302) (xy 376.181406 -234.648774) (xy 376.227564 -234.675423) (xy 376.269235 -234.708654)
			(xy 376.305487 -234.747725) (xy 376.335511 -234.791762) (xy 376.358637 -234.839783) (xy 376.374347 -234.890713)
			(xy 376.38229 -234.943417) (xy 376.382788 -234.970066) (xy 376.38229 -234.996715) (xy 376.61087 -234.996715)
			(xy 376.61087 -234.943417) (xy 376.618813 -234.890713) (xy 376.634523 -234.839783) (xy 376.657649 -234.791762)
			(xy 376.687673 -234.747725) (xy 376.723925 -234.708654) (xy 376.765596 -234.675423) (xy 376.811754 -234.648774)
			(xy 376.861368 -234.629302) (xy 376.91333 -234.617442) (xy 376.96648 -234.613459) (xy 377.01963 -234.617442)
			(xy 377.071592 -234.629302) (xy 377.121206 -234.648774) (xy 377.167364 -234.675423) (xy 377.209035 -234.708654)
			(xy 377.245287 -234.747725) (xy 377.275311 -234.791762) (xy 377.298437 -234.839783) (xy 377.314147 -234.890713)
			(xy 377.32209 -234.943417) (xy 377.322588 -234.970066) (xy 377.32209 -234.996715) (xy 377.55067 -234.996715)
			(xy 377.55067 -234.943417) (xy 377.558613 -234.890713) (xy 377.574323 -234.839783) (xy 377.597449 -234.791762)
			(xy 377.627473 -234.747725) (xy 377.663725 -234.708654) (xy 377.705396 -234.675423) (xy 377.751554 -234.648774)
			(xy 377.801168 -234.629302) (xy 377.85313 -234.617442) (xy 377.90628 -234.613459) (xy 377.95943 -234.617442)
			(xy 378.011392 -234.629302) (xy 378.061006 -234.648774) (xy 378.107164 -234.675423) (xy 378.148835 -234.708654)
			(xy 378.185087 -234.747725) (xy 378.215111 -234.791762) (xy 378.238237 -234.839783) (xy 378.253947 -234.890713)
			(xy 378.26189 -234.943417) (xy 378.262388 -234.970066) (xy 378.26189 -234.996715) (xy 378.49047 -234.996715)
			(xy 378.49047 -234.943417) (xy 378.498413 -234.890713) (xy 378.514123 -234.839783) (xy 378.537249 -234.791762)
			(xy 378.567273 -234.747725) (xy 378.603525 -234.708654) (xy 378.645196 -234.675423) (xy 378.691354 -234.648774)
			(xy 378.740968 -234.629302) (xy 378.79293 -234.617442) (xy 378.84608 -234.613459) (xy 378.89923 -234.617442)
			(xy 378.951192 -234.629302) (xy 379.000806 -234.648774) (xy 379.046964 -234.675423) (xy 379.088635 -234.708654)
			(xy 379.124887 -234.747725) (xy 379.154911 -234.791762) (xy 379.178037 -234.839783) (xy 379.193747 -234.890713)
			(xy 379.20169 -234.943417) (xy 379.202188 -234.970066) (xy 379.20169 -234.996715) (xy 379.430524 -234.996715)
			(xy 379.430524 -234.943417) (xy 379.438467 -234.890713) (xy 379.454177 -234.839783) (xy 379.477303 -234.791762)
			(xy 379.507327 -234.747725) (xy 379.543579 -234.708654) (xy 379.58525 -234.675423) (xy 379.631408 -234.648774)
			(xy 379.681022 -234.629302) (xy 379.732984 -234.617442) (xy 379.786134 -234.613459) (xy 379.839284 -234.617442)
			(xy 379.891246 -234.629302) (xy 379.94086 -234.648774) (xy 379.987018 -234.675423) (xy 380.028689 -234.708654)
			(xy 380.064941 -234.747725) (xy 380.094965 -234.791762) (xy 380.118091 -234.839783) (xy 380.133801 -234.890713)
			(xy 380.141744 -234.943417) (xy 380.142242 -234.970066) (xy 380.141744 -234.996715) (xy 380.133801 -235.049419)
			(xy 380.118091 -235.100349) (xy 380.094965 -235.14837) (xy 380.064941 -235.192407) (xy 380.028689 -235.231478)
			(xy 379.987018 -235.264709) (xy 379.94086 -235.291358) (xy 379.891246 -235.31083) (xy 379.839284 -235.32269)
			(xy 379.786134 -235.326674) (xy 379.732984 -235.32269) (xy 379.681022 -235.31083) (xy 379.631408 -235.291358)
			(xy 379.58525 -235.264709) (xy 379.543579 -235.231478) (xy 379.507327 -235.192407) (xy 379.477303 -235.14837)
			(xy 379.454177 -235.100349) (xy 379.438467 -235.049419) (xy 379.430524 -234.996715) (xy 379.20169 -234.996715)
			(xy 379.193747 -235.049419) (xy 379.178037 -235.100349) (xy 379.154911 -235.14837) (xy 379.124887 -235.192407)
			(xy 379.088635 -235.231478) (xy 379.046964 -235.264709) (xy 379.000806 -235.291358) (xy 378.951192 -235.31083)
			(xy 378.89923 -235.32269) (xy 378.84608 -235.326674) (xy 378.79293 -235.32269) (xy 378.740968 -235.31083)
			(xy 378.691354 -235.291358) (xy 378.645196 -235.264709) (xy 378.603525 -235.231478) (xy 378.567273 -235.192407)
			(xy 378.537249 -235.14837) (xy 378.514123 -235.100349) (xy 378.498413 -235.049419) (xy 378.49047 -234.996715)
			(xy 378.26189 -234.996715) (xy 378.253947 -235.049419) (xy 378.238237 -235.100349) (xy 378.215111 -235.14837)
			(xy 378.185087 -235.192407) (xy 378.148835 -235.231478) (xy 378.107164 -235.264709) (xy 378.061006 -235.291358)
			(xy 378.011392 -235.31083) (xy 377.95943 -235.32269) (xy 377.90628 -235.326674) (xy 377.85313 -235.32269)
			(xy 377.801168 -235.31083) (xy 377.751554 -235.291358) (xy 377.705396 -235.264709) (xy 377.663725 -235.231478)
			(xy 377.627473 -235.192407) (xy 377.597449 -235.14837) (xy 377.574323 -235.100349) (xy 377.558613 -235.049419)
			(xy 377.55067 -234.996715) (xy 377.32209 -234.996715) (xy 377.314147 -235.049419) (xy 377.298437 -235.100349)
			(xy 377.275311 -235.14837) (xy 377.245287 -235.192407) (xy 377.209035 -235.231478) (xy 377.167364 -235.264709)
			(xy 377.121206 -235.291358) (xy 377.071592 -235.31083) (xy 377.01963 -235.32269) (xy 376.96648 -235.326674)
			(xy 376.91333 -235.32269) (xy 376.861368 -235.31083) (xy 376.811754 -235.291358) (xy 376.765596 -235.264709)
			(xy 376.723925 -235.231478) (xy 376.687673 -235.192407) (xy 376.657649 -235.14837) (xy 376.634523 -235.100349)
			(xy 376.618813 -235.049419) (xy 376.61087 -234.996715) (xy 376.38229 -234.996715) (xy 376.374347 -235.049419)
			(xy 376.358637 -235.100349) (xy 376.335511 -235.14837) (xy 376.305487 -235.192407) (xy 376.269235 -235.231478)
			(xy 376.227564 -235.264709) (xy 376.181406 -235.291358) (xy 376.131792 -235.31083) (xy 376.07983 -235.32269)
			(xy 376.02668 -235.326674) (xy 375.97353 -235.32269) (xy 375.921568 -235.31083) (xy 375.871954 -235.291358)
			(xy 375.825796 -235.264709) (xy 375.784125 -235.231478) (xy 375.747873 -235.192407) (xy 375.717849 -235.14837)
			(xy 375.694723 -235.100349) (xy 375.679013 -235.049419) (xy 375.67107 -234.996715) (xy 375.44249 -234.996715)
			(xy 375.434547 -235.049419) (xy 375.418837 -235.100349) (xy 375.395711 -235.14837) (xy 375.365687 -235.192407)
			(xy 375.329435 -235.231478) (xy 375.287764 -235.264709) (xy 375.241606 -235.291358) (xy 375.191992 -235.31083)
			(xy 375.14003 -235.32269) (xy 375.08688 -235.326674) (xy 375.03373 -235.32269) (xy 374.981768 -235.31083)
			(xy 374.932154 -235.291358) (xy 374.885996 -235.264709) (xy 374.844325 -235.231478) (xy 374.808073 -235.192407)
			(xy 374.778049 -235.14837) (xy 374.754923 -235.100349) (xy 374.739213 -235.049419) (xy 374.73127 -234.996715)
			(xy 374.50269 -234.996715) (xy 374.494747 -235.049419) (xy 374.479037 -235.100349) (xy 374.455911 -235.14837)
			(xy 374.425887 -235.192407) (xy 374.389635 -235.231478) (xy 374.347964 -235.264709) (xy 374.301806 -235.291358)
			(xy 374.252192 -235.31083) (xy 374.20023 -235.32269) (xy 374.14708 -235.326674) (xy 374.09393 -235.32269)
			(xy 374.041968 -235.31083) (xy 373.992354 -235.291358) (xy 373.946196 -235.264709) (xy 373.904525 -235.231478)
			(xy 373.868273 -235.192407) (xy 373.838249 -235.14837) (xy 373.815123 -235.100349) (xy 373.799413 -235.049419)
			(xy 373.79147 -234.996715) (xy 373.563144 -234.996715) (xy 373.555201 -235.049419) (xy 373.539491 -235.100349)
			(xy 373.516365 -235.14837) (xy 373.486341 -235.192407) (xy 373.450089 -235.231478) (xy 373.408418 -235.264709)
			(xy 373.36226 -235.291358) (xy 373.312646 -235.31083) (xy 373.260684 -235.32269) (xy 373.207534 -235.326674)
			(xy 373.154384 -235.32269) (xy 373.102422 -235.31083) (xy 373.052808 -235.291358) (xy 373.00665 -235.264709)
			(xy 372.964979 -235.231478) (xy 372.928727 -235.192407) (xy 372.898703 -235.14837) (xy 372.875577 -235.100349)
			(xy 372.859867 -235.049419) (xy 372.851924 -234.996715) (xy 372.62309 -234.996715) (xy 372.615147 -235.049419)
			(xy 372.599437 -235.100349) (xy 372.576311 -235.14837) (xy 372.546287 -235.192407) (xy 372.510035 -235.231478)
			(xy 372.468364 -235.264709) (xy 372.422206 -235.291358) (xy 372.372592 -235.31083) (xy 372.32063 -235.32269)
			(xy 372.26748 -235.326674) (xy 372.21433 -235.32269) (xy 372.162368 -235.31083) (xy 372.112754 -235.291358)
			(xy 372.066596 -235.264709) (xy 372.024925 -235.231478) (xy 371.988673 -235.192407) (xy 371.958649 -235.14837)
			(xy 371.935523 -235.100349) (xy 371.919813 -235.049419) (xy 371.91187 -234.996715) (xy 371.68329 -234.996715)
			(xy 371.675347 -235.049419) (xy 371.659637 -235.100349) (xy 371.636511 -235.14837) (xy 371.606487 -235.192407)
			(xy 371.570235 -235.231478) (xy 371.528564 -235.264709) (xy 371.482406 -235.291358) (xy 371.432792 -235.31083)
			(xy 371.38083 -235.32269) (xy 371.32768 -235.326674) (xy 371.27453 -235.32269) (xy 371.222568 -235.31083)
			(xy 371.172954 -235.291358) (xy 371.126796 -235.264709) (xy 371.085125 -235.231478) (xy 371.048873 -235.192407)
			(xy 371.018849 -235.14837) (xy 370.995723 -235.100349) (xy 370.980013 -235.049419) (xy 370.97207 -234.996715)
			(xy 370.74349 -234.996715) (xy 370.735547 -235.049419) (xy 370.719837 -235.100349) (xy 370.696711 -235.14837)
			(xy 370.666687 -235.192407) (xy 370.630435 -235.231478) (xy 370.588764 -235.264709) (xy 370.542606 -235.291358)
			(xy 370.492992 -235.31083) (xy 370.44103 -235.32269) (xy 370.38788 -235.326674) (xy 370.33473 -235.32269)
			(xy 370.282768 -235.31083) (xy 370.233154 -235.291358) (xy 370.186996 -235.264709) (xy 370.145325 -235.231478)
			(xy 370.109073 -235.192407) (xy 370.079049 -235.14837) (xy 370.055923 -235.100349) (xy 370.040213 -235.049419)
			(xy 370.03227 -234.996715) (xy 369.80369 -234.996715) (xy 369.795747 -235.049419) (xy 369.780037 -235.100349)
			(xy 369.756911 -235.14837) (xy 369.726887 -235.192407) (xy 369.690635 -235.231478) (xy 369.648964 -235.264709)
			(xy 369.602806 -235.291358) (xy 369.553192 -235.31083) (xy 369.50123 -235.32269) (xy 369.44808 -235.326674)
			(xy 369.39493 -235.32269) (xy 369.342968 -235.31083) (xy 369.293354 -235.291358) (xy 369.247196 -235.264709)
			(xy 369.205525 -235.231478) (xy 369.169273 -235.192407) (xy 369.139249 -235.14837) (xy 369.116123 -235.100349)
			(xy 369.100413 -235.049419) (xy 369.09247 -234.996715) (xy 362.285544 -234.996715) (xy 362.277601 -235.049419)
			(xy 362.261891 -235.100349) (xy 362.238765 -235.14837) (xy 362.208741 -235.192407) (xy 362.172489 -235.231478)
			(xy 362.130818 -235.264709) (xy 362.08466 -235.291358) (xy 362.035046 -235.31083) (xy 361.983084 -235.32269)
			(xy 361.929934 -235.326674) (xy 361.876784 -235.32269) (xy 361.824822 -235.31083) (xy 361.775208 -235.291358)
			(xy 361.72905 -235.264709) (xy 361.687379 -235.231478) (xy 361.651127 -235.192407) (xy 361.621103 -235.14837)
			(xy 361.597977 -235.100349) (xy 361.582267 -235.049419) (xy 361.574324 -234.996715) (xy 361.34549 -234.996715)
			(xy 361.337547 -235.049419) (xy 361.321837 -235.100349) (xy 361.298711 -235.14837) (xy 361.268687 -235.192407)
			(xy 361.232435 -235.231478) (xy 361.190764 -235.264709) (xy 361.144606 -235.291358) (xy 361.094992 -235.31083)
			(xy 361.04303 -235.32269) (xy 360.98988 -235.326674) (xy 360.93673 -235.32269) (xy 360.884768 -235.31083)
			(xy 360.835154 -235.291358) (xy 360.788996 -235.264709) (xy 360.747325 -235.231478) (xy 360.711073 -235.192407)
			(xy 360.681049 -235.14837) (xy 360.657923 -235.100349) (xy 360.642213 -235.049419) (xy 360.63427 -234.996715)
			(xy 360.40569 -234.996715) (xy 360.397747 -235.049419) (xy 360.382037 -235.100349) (xy 360.358911 -235.14837)
			(xy 360.328887 -235.192407) (xy 360.292635 -235.231478) (xy 360.250964 -235.264709) (xy 360.204806 -235.291358)
			(xy 360.155192 -235.31083) (xy 360.10323 -235.32269) (xy 360.05008 -235.326674) (xy 359.99693 -235.32269)
			(xy 359.944968 -235.31083) (xy 359.895354 -235.291358) (xy 359.849196 -235.264709) (xy 359.807525 -235.231478)
			(xy 359.771273 -235.192407) (xy 359.741249 -235.14837) (xy 359.718123 -235.100349) (xy 359.702413 -235.049419)
			(xy 359.69447 -234.996715) (xy 359.46589 -234.996715) (xy 359.457947 -235.049419) (xy 359.442237 -235.100349)
			(xy 359.419111 -235.14837) (xy 359.389087 -235.192407) (xy 359.352835 -235.231478) (xy 359.311164 -235.264709)
			(xy 359.265006 -235.291358) (xy 359.215392 -235.31083) (xy 359.16343 -235.32269) (xy 359.11028 -235.326674)
			(xy 359.05713 -235.32269) (xy 359.005168 -235.31083) (xy 358.955554 -235.291358) (xy 358.909396 -235.264709)
			(xy 358.867725 -235.231478) (xy 358.831473 -235.192407) (xy 358.801449 -235.14837) (xy 358.778323 -235.100349)
			(xy 358.762613 -235.049419) (xy 358.75467 -234.996715) (xy 358.526344 -234.996715) (xy 358.518401 -235.049419)
			(xy 358.502691 -235.100349) (xy 358.479565 -235.14837) (xy 358.449541 -235.192407) (xy 358.413289 -235.231478)
			(xy 358.371618 -235.264709) (xy 358.32546 -235.291358) (xy 358.275846 -235.31083) (xy 358.223884 -235.32269)
			(xy 358.170734 -235.326674) (xy 358.117584 -235.32269) (xy 358.065622 -235.31083) (xy 358.016008 -235.291358)
			(xy 357.96985 -235.264709) (xy 357.928179 -235.231478) (xy 357.891927 -235.192407) (xy 357.861903 -235.14837)
			(xy 357.838777 -235.100349) (xy 357.823067 -235.049419) (xy 357.815124 -234.996715) (xy 357.58629 -234.996715)
			(xy 357.578347 -235.049419) (xy 357.562637 -235.100349) (xy 357.539511 -235.14837) (xy 357.509487 -235.192407)
			(xy 357.473235 -235.231478) (xy 357.431564 -235.264709) (xy 357.385406 -235.291358) (xy 357.335792 -235.31083)
			(xy 357.28383 -235.32269) (xy 357.23068 -235.326674) (xy 357.17753 -235.32269) (xy 357.125568 -235.31083)
			(xy 357.075954 -235.291358) (xy 357.029796 -235.264709) (xy 356.988125 -235.231478) (xy 356.951873 -235.192407)
			(xy 356.921849 -235.14837) (xy 356.898723 -235.100349) (xy 356.883013 -235.049419) (xy 356.87507 -234.996715)
			(xy 354.603522 -234.996715) (xy 354.620053 -235.009898) (xy 354.656305 -235.048969) (xy 354.686329 -235.093006)
			(xy 354.709455 -235.141027) (xy 354.725165 -235.191957) (xy 354.733108 -235.244661) (xy 354.733606 -235.27131)
			(xy 354.733108 -235.297959) (xy 354.725165 -235.350663) (xy 354.709455 -235.401593) (xy 354.686329 -235.449614)
			(xy 354.656305 -235.493651) (xy 354.652854 -235.49737) (xy 354.997004 -235.49737) (xy 354.997513 -235.469385)
			(xy 355.006273 -235.414106) (xy 355.023573 -235.360878) (xy 355.048985 -235.311011) (xy 355.081886 -235.265733)
			(xy 355.121465 -235.226159) (xy 355.166746 -235.193263) (xy 355.216616 -235.167856) (xy 355.269847 -235.150563)
			(xy 355.325127 -235.14181) (xy 355.353112 -235.141262) (xy 355.380432 -235.141786) (xy 355.434433 -235.150125)
			(xy 355.486529 -235.166606) (xy 355.535501 -235.190843) (xy 355.580201 -235.222268) (xy 355.600254 -235.24083)
			(xy 355.611876 -235.251227) (xy 355.63981 -235.265051) (xy 355.670612 -235.269807) (xy 355.701414 -235.265051)
			(xy 355.729348 -235.251227) (xy 355.74097 -235.24083) (xy 355.761008 -235.222245) (xy 355.805694 -235.190784)
			(xy 355.854666 -235.166528) (xy 355.906773 -235.150051) (xy 355.960787 -235.141738) (xy 355.988112 -235.141262)
			(xy 356.016094 -235.14183) (xy 356.071369 -235.150586) (xy 356.124593 -235.16788) (xy 356.174458 -235.193287)
			(xy 356.219734 -235.226181) (xy 356.259307 -235.265753) (xy 356.292204 -235.311027) (xy 356.317613 -235.36089)
			(xy 356.33491 -235.414114) (xy 356.343669 -235.469388) (xy 356.34422 -235.49737) (xy 356.343759 -235.523072)
			(xy 356.336367 -235.57394) (xy 356.321746 -235.62322) (xy 356.300198 -235.66989) (xy 356.286562 -235.69168)
			(xy 356.279149 -235.703918) (xy 356.270786 -235.73127) (xy 356.270325 -235.759868) (xy 356.277803 -235.787475)
			(xy 356.291784 -235.810531) (xy 357.345224 -235.810531) (xy 357.345224 -235.757233) (xy 357.353167 -235.704529)
			(xy 357.368877 -235.653599) (xy 357.392003 -235.605578) (xy 357.422027 -235.561541) (xy 357.458279 -235.52247)
			(xy 357.49995 -235.489239) (xy 357.546108 -235.46259) (xy 357.595722 -235.443118) (xy 357.647684 -235.431258)
			(xy 357.700834 -235.427275) (xy 357.753984 -235.431258) (xy 357.805946 -235.443118) (xy 357.85556 -235.46259)
			(xy 357.901718 -235.489239) (xy 357.943389 -235.52247) (xy 357.979641 -235.561541) (xy 358.009665 -235.605578)
			(xy 358.032791 -235.653599) (xy 358.048501 -235.704529) (xy 358.056444 -235.757233) (xy 358.056942 -235.783882)
			(xy 358.056444 -235.810531) (xy 358.285024 -235.810531) (xy 358.285024 -235.757233) (xy 358.292967 -235.704529)
			(xy 358.308677 -235.653599) (xy 358.331803 -235.605578) (xy 358.361827 -235.561541) (xy 358.398079 -235.52247)
			(xy 358.43975 -235.489239) (xy 358.485908 -235.46259) (xy 358.535522 -235.443118) (xy 358.587484 -235.431258)
			(xy 358.640634 -235.427275) (xy 358.693784 -235.431258) (xy 358.745746 -235.443118) (xy 358.79536 -235.46259)
			(xy 358.841518 -235.489239) (xy 358.883189 -235.52247) (xy 358.919441 -235.561541) (xy 358.949465 -235.605578)
			(xy 358.972591 -235.653599) (xy 358.988301 -235.704529) (xy 358.996244 -235.757233) (xy 358.996742 -235.783882)
			(xy 358.996244 -235.810531) (xy 359.224824 -235.810531) (xy 359.224824 -235.757233) (xy 359.232767 -235.704529)
			(xy 359.248477 -235.653599) (xy 359.271603 -235.605578) (xy 359.301627 -235.561541) (xy 359.337879 -235.52247)
			(xy 359.37955 -235.489239) (xy 359.425708 -235.46259) (xy 359.475322 -235.443118) (xy 359.527284 -235.431258)
			(xy 359.580434 -235.427275) (xy 359.633584 -235.431258) (xy 359.685546 -235.443118) (xy 359.73516 -235.46259)
			(xy 359.781318 -235.489239) (xy 359.822989 -235.52247) (xy 359.859241 -235.561541) (xy 359.889265 -235.605578)
			(xy 359.912391 -235.653599) (xy 359.928101 -235.704529) (xy 359.936044 -235.757233) (xy 359.936542 -235.783882)
			(xy 359.936044 -235.810531) (xy 360.164624 -235.810531) (xy 360.164624 -235.757233) (xy 360.172567 -235.704529)
			(xy 360.188277 -235.653599) (xy 360.211403 -235.605578) (xy 360.241427 -235.561541) (xy 360.277679 -235.52247)
			(xy 360.31935 -235.489239) (xy 360.365508 -235.46259) (xy 360.415122 -235.443118) (xy 360.467084 -235.431258)
			(xy 360.520234 -235.427275) (xy 360.573384 -235.431258) (xy 360.625346 -235.443118) (xy 360.67496 -235.46259)
			(xy 360.721118 -235.489239) (xy 360.762789 -235.52247) (xy 360.799041 -235.561541) (xy 360.829065 -235.605578)
			(xy 360.852191 -235.653599) (xy 360.867901 -235.704529) (xy 360.875844 -235.757233) (xy 360.876342 -235.783882)
			(xy 360.875844 -235.810531) (xy 361.104424 -235.810531) (xy 361.104424 -235.757233) (xy 361.112367 -235.704529)
			(xy 361.128077 -235.653599) (xy 361.151203 -235.605578) (xy 361.181227 -235.561541) (xy 361.217479 -235.52247)
			(xy 361.25915 -235.489239) (xy 361.305308 -235.46259) (xy 361.354922 -235.443118) (xy 361.406884 -235.431258)
			(xy 361.460034 -235.427275) (xy 361.513184 -235.431258) (xy 361.565146 -235.443118) (xy 361.61476 -235.46259)
			(xy 361.660918 -235.489239) (xy 361.702589 -235.52247) (xy 361.738841 -235.561541) (xy 361.768865 -235.605578)
			(xy 361.791991 -235.653599) (xy 361.807701 -235.704529) (xy 361.815644 -235.757233) (xy 361.816142 -235.783882)
			(xy 361.815644 -235.810531) (xy 362.044224 -235.810531) (xy 362.044224 -235.757233) (xy 362.052167 -235.704529)
			(xy 362.067877 -235.653599) (xy 362.091003 -235.605578) (xy 362.121027 -235.561541) (xy 362.157279 -235.52247)
			(xy 362.19895 -235.489239) (xy 362.245108 -235.46259) (xy 362.294722 -235.443118) (xy 362.346684 -235.431258)
			(xy 362.399834 -235.427275) (xy 362.452984 -235.431258) (xy 362.504946 -235.443118) (xy 362.55456 -235.46259)
			(xy 362.600718 -235.489239) (xy 362.642389 -235.52247) (xy 362.678641 -235.561541) (xy 362.708665 -235.605578)
			(xy 362.731791 -235.653599) (xy 362.747501 -235.704529) (xy 362.755444 -235.757233) (xy 362.755942 -235.783882)
			(xy 362.755633 -235.8004) (xy 364.178384 -235.8004) (xy 364.182367 -235.747253) (xy 364.194226 -235.695293)
			(xy 364.213695 -235.645681) (xy 364.240341 -235.599525) (xy 364.273569 -235.557855) (xy 364.312635 -235.521602)
			(xy 364.356668 -235.491576) (xy 364.404684 -235.468448) (xy 364.45561 -235.452734) (xy 364.50831 -235.444785)
			(xy 364.534958 -235.444284) (xy 364.559627 -235.444704) (xy 364.608495 -235.451505) (xy 364.655953 -235.464996)
			(xy 364.70109 -235.484919) (xy 364.74304 -235.51089) (xy 364.762288 -235.526326) (xy 364.773418 -235.534953)
			(xy 364.799178 -235.5463) (xy 364.827058 -235.550181) (xy 364.854938 -235.5463) (xy 364.880698 -235.534953)
			(xy 364.891828 -235.526326) (xy 364.913244 -235.509203) (xy 364.960301 -235.481064) (xy 365.011118 -235.460475)
			(xy 365.064491 -235.447923) (xy 365.119158 -235.443706) (xy 365.173825 -235.447923) (xy 365.227198 -235.460475)
			(xy 365.278015 -235.481064) (xy 365.325072 -235.509203) (xy 365.346488 -235.526326) (xy 365.357618 -235.534953)
			(xy 365.383378 -235.5463) (xy 365.411258 -235.550181) (xy 365.439138 -235.5463) (xy 365.464898 -235.534953)
			(xy 365.476028 -235.526326) (xy 365.497444 -235.509203) (xy 365.544501 -235.481064) (xy 365.595318 -235.460475)
			(xy 365.648691 -235.447923) (xy 365.703358 -235.443706) (xy 365.758025 -235.447923) (xy 365.811398 -235.460475)
			(xy 365.862215 -235.481064) (xy 365.909272 -235.509203) (xy 365.930688 -235.526326) (xy 365.941818 -235.534953)
			(xy 365.967578 -235.5463) (xy 365.995458 -235.550181) (xy 366.023338 -235.5463) (xy 366.049098 -235.534953)
			(xy 366.060228 -235.526326) (xy 366.081644 -235.509203) (xy 366.128701 -235.481064) (xy 366.179518 -235.460475)
			(xy 366.232891 -235.447923) (xy 366.287558 -235.443706) (xy 366.342225 -235.447923) (xy 366.395598 -235.460475)
			(xy 366.446415 -235.481064) (xy 366.493472 -235.509203) (xy 366.514888 -235.526326) (xy 366.526018 -235.534953)
			(xy 366.551778 -235.5463) (xy 366.579658 -235.550181) (xy 366.607538 -235.5463) (xy 366.633298 -235.534953)
			(xy 366.644428 -235.526326) (xy 366.665844 -235.509203) (xy 366.712901 -235.481064) (xy 366.763718 -235.460475)
			(xy 366.817091 -235.447923) (xy 366.871758 -235.443706) (xy 366.926425 -235.447923) (xy 366.979798 -235.460475)
			(xy 367.030615 -235.481064) (xy 367.077672 -235.509203) (xy 367.099088 -235.526326) (xy 367.110218 -235.534953)
			(xy 367.135978 -235.5463) (xy 367.163858 -235.550181) (xy 367.191738 -235.5463) (xy 367.217498 -235.534953)
			(xy 367.228628 -235.526326) (xy 367.247878 -235.510894) (xy 367.289834 -235.484936) (xy 367.334971 -235.465019)
			(xy 367.382426 -235.451523) (xy 367.43129 -235.444706) (xy 367.455958 -235.444284) (xy 367.482611 -235.44477)
			(xy 367.535321 -235.452709) (xy 367.58626 -235.468416) (xy 367.634288 -235.491541) (xy 367.678333 -235.521565)
			(xy 367.71741 -235.557819) (xy 367.750648 -235.599493) (xy 367.777302 -235.645656) (xy 367.796778 -235.695276)
			(xy 367.80864 -235.747244) (xy 367.812624 -235.8004) (xy 367.811865 -235.810531) (xy 369.562624 -235.810531)
			(xy 369.562624 -235.757233) (xy 369.570567 -235.704529) (xy 369.586277 -235.653599) (xy 369.609403 -235.605578)
			(xy 369.639427 -235.561541) (xy 369.675679 -235.52247) (xy 369.71735 -235.489239) (xy 369.763508 -235.46259)
			(xy 369.813122 -235.443118) (xy 369.865084 -235.431258) (xy 369.918234 -235.427275) (xy 369.971384 -235.431258)
			(xy 370.023346 -235.443118) (xy 370.07296 -235.46259) (xy 370.119118 -235.489239) (xy 370.160789 -235.52247)
			(xy 370.197041 -235.561541) (xy 370.227065 -235.605578) (xy 370.250191 -235.653599) (xy 370.265901 -235.704529)
			(xy 370.273844 -235.757233) (xy 370.274342 -235.783882) (xy 370.273844 -235.810531) (xy 370.502424 -235.810531)
			(xy 370.502424 -235.757233) (xy 370.510367 -235.704529) (xy 370.526077 -235.653599) (xy 370.549203 -235.605578)
			(xy 370.579227 -235.561541) (xy 370.615479 -235.52247) (xy 370.65715 -235.489239) (xy 370.703308 -235.46259)
			(xy 370.752922 -235.443118) (xy 370.804884 -235.431258) (xy 370.858034 -235.427275) (xy 370.911184 -235.431258)
			(xy 370.963146 -235.443118) (xy 371.01276 -235.46259) (xy 371.058918 -235.489239) (xy 371.100589 -235.52247)
			(xy 371.136841 -235.561541) (xy 371.166865 -235.605578) (xy 371.189991 -235.653599) (xy 371.205701 -235.704529)
			(xy 371.213644 -235.757233) (xy 371.214142 -235.783882) (xy 371.213644 -235.810531) (xy 371.442224 -235.810531)
			(xy 371.442224 -235.757233) (xy 371.450167 -235.704529) (xy 371.465877 -235.653599) (xy 371.489003 -235.605578)
			(xy 371.519027 -235.561541) (xy 371.555279 -235.52247) (xy 371.59695 -235.489239) (xy 371.643108 -235.46259)
			(xy 371.692722 -235.443118) (xy 371.744684 -235.431258) (xy 371.797834 -235.427275) (xy 371.850984 -235.431258)
			(xy 371.902946 -235.443118) (xy 371.95256 -235.46259) (xy 371.998718 -235.489239) (xy 372.040389 -235.52247)
			(xy 372.076641 -235.561541) (xy 372.106665 -235.605578) (xy 372.129791 -235.653599) (xy 372.145501 -235.704529)
			(xy 372.153444 -235.757233) (xy 372.153942 -235.783882) (xy 372.153444 -235.810531) (xy 372.382024 -235.810531)
			(xy 372.382024 -235.757233) (xy 372.389967 -235.704529) (xy 372.405677 -235.653599) (xy 372.428803 -235.605578)
			(xy 372.458827 -235.561541) (xy 372.495079 -235.52247) (xy 372.53675 -235.489239) (xy 372.582908 -235.46259)
			(xy 372.632522 -235.443118) (xy 372.684484 -235.431258) (xy 372.737634 -235.427275) (xy 372.790784 -235.431258)
			(xy 372.842746 -235.443118) (xy 372.89236 -235.46259) (xy 372.938518 -235.489239) (xy 372.980189 -235.52247)
			(xy 373.016441 -235.561541) (xy 373.046465 -235.605578) (xy 373.069591 -235.653599) (xy 373.085301 -235.704529)
			(xy 373.093244 -235.757233) (xy 373.093742 -235.783882) (xy 373.093244 -235.810531) (xy 373.32157 -235.810531)
			(xy 373.32157 -235.757233) (xy 373.329513 -235.704529) (xy 373.345223 -235.653599) (xy 373.368349 -235.605578)
			(xy 373.398373 -235.561541) (xy 373.434625 -235.52247) (xy 373.476296 -235.489239) (xy 373.522454 -235.46259)
			(xy 373.572068 -235.443118) (xy 373.62403 -235.431258) (xy 373.67718 -235.427275) (xy 373.73033 -235.431258)
			(xy 373.782292 -235.443118) (xy 373.831906 -235.46259) (xy 373.878064 -235.489239) (xy 373.919735 -235.52247)
			(xy 373.955987 -235.561541) (xy 373.986011 -235.605578) (xy 374.009137 -235.653599) (xy 374.024847 -235.704529)
			(xy 374.03279 -235.757233) (xy 374.033288 -235.783882) (xy 374.03279 -235.810531) (xy 374.261624 -235.810531)
			(xy 374.261624 -235.757233) (xy 374.269567 -235.704529) (xy 374.285277 -235.653599) (xy 374.308403 -235.605578)
			(xy 374.338427 -235.561541) (xy 374.374679 -235.52247) (xy 374.41635 -235.489239) (xy 374.462508 -235.46259)
			(xy 374.512122 -235.443118) (xy 374.564084 -235.431258) (xy 374.617234 -235.427275) (xy 374.670384 -235.431258)
			(xy 374.722346 -235.443118) (xy 374.77196 -235.46259) (xy 374.818118 -235.489239) (xy 374.859789 -235.52247)
			(xy 374.896041 -235.561541) (xy 374.926065 -235.605578) (xy 374.949191 -235.653599) (xy 374.964901 -235.704529)
			(xy 374.972844 -235.757233) (xy 374.973342 -235.783882) (xy 374.972844 -235.810531) (xy 375.201424 -235.810531)
			(xy 375.201424 -235.757233) (xy 375.209367 -235.704529) (xy 375.225077 -235.653599) (xy 375.248203 -235.605578)
			(xy 375.278227 -235.561541) (xy 375.314479 -235.52247) (xy 375.35615 -235.489239) (xy 375.402308 -235.46259)
			(xy 375.451922 -235.443118) (xy 375.503884 -235.431258) (xy 375.557034 -235.427275) (xy 375.610184 -235.431258)
			(xy 375.662146 -235.443118) (xy 375.71176 -235.46259) (xy 375.757918 -235.489239) (xy 375.799589 -235.52247)
			(xy 375.835841 -235.561541) (xy 375.865865 -235.605578) (xy 375.888991 -235.653599) (xy 375.904701 -235.704529)
			(xy 375.912644 -235.757233) (xy 375.913142 -235.783882) (xy 375.912644 -235.810531) (xy 376.141224 -235.810531)
			(xy 376.141224 -235.757233) (xy 376.149167 -235.704529) (xy 376.164877 -235.653599) (xy 376.188003 -235.605578)
			(xy 376.218027 -235.561541) (xy 376.254279 -235.52247) (xy 376.29595 -235.489239) (xy 376.342108 -235.46259)
			(xy 376.391722 -235.443118) (xy 376.443684 -235.431258) (xy 376.496834 -235.427275) (xy 376.549984 -235.431258)
			(xy 376.601946 -235.443118) (xy 376.65156 -235.46259) (xy 376.697718 -235.489239) (xy 376.739389 -235.52247)
			(xy 376.775641 -235.561541) (xy 376.805665 -235.605578) (xy 376.828791 -235.653599) (xy 376.844501 -235.704529)
			(xy 376.852444 -235.757233) (xy 376.852942 -235.783882) (xy 376.852444 -235.810531) (xy 377.081024 -235.810531)
			(xy 377.081024 -235.757233) (xy 377.088967 -235.704529) (xy 377.104677 -235.653599) (xy 377.127803 -235.605578)
			(xy 377.157827 -235.561541) (xy 377.194079 -235.52247) (xy 377.23575 -235.489239) (xy 377.281908 -235.46259)
			(xy 377.331522 -235.443118) (xy 377.383484 -235.431258) (xy 377.436634 -235.427275) (xy 377.489784 -235.431258)
			(xy 377.541746 -235.443118) (xy 377.59136 -235.46259) (xy 377.637518 -235.489239) (xy 377.679189 -235.52247)
			(xy 377.715441 -235.561541) (xy 377.745465 -235.605578) (xy 377.768591 -235.653599) (xy 377.784301 -235.704529)
			(xy 377.792244 -235.757233) (xy 377.792742 -235.783882) (xy 377.792244 -235.810531) (xy 378.020824 -235.810531)
			(xy 378.020824 -235.757233) (xy 378.028767 -235.704529) (xy 378.044477 -235.653599) (xy 378.067603 -235.605578)
			(xy 378.097627 -235.561541) (xy 378.133879 -235.52247) (xy 378.17555 -235.489239) (xy 378.221708 -235.46259)
			(xy 378.271322 -235.443118) (xy 378.323284 -235.431258) (xy 378.376434 -235.427275) (xy 378.429584 -235.431258)
			(xy 378.481546 -235.443118) (xy 378.53116 -235.46259) (xy 378.577318 -235.489239) (xy 378.618989 -235.52247)
			(xy 378.655241 -235.561541) (xy 378.685265 -235.605578) (xy 378.708391 -235.653599) (xy 378.724101 -235.704529)
			(xy 378.732044 -235.757233) (xy 378.732542 -235.783882) (xy 378.732044 -235.810531) (xy 378.960624 -235.810531)
			(xy 378.960624 -235.757233) (xy 378.968567 -235.704529) (xy 378.984277 -235.653599) (xy 379.007403 -235.605578)
			(xy 379.037427 -235.561541) (xy 379.073679 -235.52247) (xy 379.11535 -235.489239) (xy 379.161508 -235.46259)
			(xy 379.211122 -235.443118) (xy 379.263084 -235.431258) (xy 379.316234 -235.427275) (xy 379.369384 -235.431258)
			(xy 379.421346 -235.443118) (xy 379.47096 -235.46259) (xy 379.517118 -235.489239) (xy 379.558789 -235.52247)
			(xy 379.595041 -235.561541) (xy 379.625065 -235.605578) (xy 379.648191 -235.653599) (xy 379.663901 -235.704529)
			(xy 379.671844 -235.757233) (xy 379.672342 -235.783882) (xy 379.671844 -235.810531) (xy 379.90017 -235.810531)
			(xy 379.90017 -235.757233) (xy 379.908113 -235.704529) (xy 379.923823 -235.653599) (xy 379.946949 -235.605578)
			(xy 379.976973 -235.561541) (xy 380.013225 -235.52247) (xy 380.054896 -235.489239) (xy 380.101054 -235.46259)
			(xy 380.150668 -235.443118) (xy 380.20263 -235.431258) (xy 380.25578 -235.427275) (xy 380.30893 -235.431258)
			(xy 380.360892 -235.443118) (xy 380.410506 -235.46259) (xy 380.456664 -235.489239) (xy 380.498335 -235.52247)
			(xy 380.534587 -235.561541) (xy 380.564611 -235.605578) (xy 380.587737 -235.653599) (xy 380.603447 -235.704529)
			(xy 380.61139 -235.757233) (xy 380.611888 -235.783882) (xy 380.61139 -235.810531) (xy 380.603447 -235.863235)
			(xy 380.587737 -235.914165) (xy 380.564611 -235.962186) (xy 380.534587 -236.006223) (xy 380.498335 -236.045294)
			(xy 380.456664 -236.078525) (xy 380.410506 -236.105174) (xy 380.360892 -236.124646) (xy 380.30893 -236.136506)
			(xy 380.25578 -236.14049) (xy 380.20263 -236.136506) (xy 380.150668 -236.124646) (xy 380.101054 -236.105174)
			(xy 380.054896 -236.078525) (xy 380.013225 -236.045294) (xy 379.976973 -236.006223) (xy 379.946949 -235.962186)
			(xy 379.923823 -235.914165) (xy 379.908113 -235.863235) (xy 379.90017 -235.810531) (xy 379.671844 -235.810531)
			(xy 379.663901 -235.863235) (xy 379.648191 -235.914165) (xy 379.625065 -235.962186) (xy 379.595041 -236.006223)
			(xy 379.558789 -236.045294) (xy 379.517118 -236.078525) (xy 379.47096 -236.105174) (xy 379.421346 -236.124646)
			(xy 379.369384 -236.136506) (xy 379.316234 -236.14049) (xy 379.263084 -236.136506) (xy 379.211122 -236.124646)
			(xy 379.161508 -236.105174) (xy 379.11535 -236.078525) (xy 379.073679 -236.045294) (xy 379.037427 -236.006223)
			(xy 379.007403 -235.962186) (xy 378.984277 -235.914165) (xy 378.968567 -235.863235) (xy 378.960624 -235.810531)
			(xy 378.732044 -235.810531) (xy 378.724101 -235.863235) (xy 378.708391 -235.914165) (xy 378.685265 -235.962186)
			(xy 378.655241 -236.006223) (xy 378.618989 -236.045294) (xy 378.577318 -236.078525) (xy 378.53116 -236.105174)
			(xy 378.481546 -236.124646) (xy 378.429584 -236.136506) (xy 378.376434 -236.14049) (xy 378.323284 -236.136506)
			(xy 378.271322 -236.124646) (xy 378.221708 -236.105174) (xy 378.17555 -236.078525) (xy 378.133879 -236.045294)
			(xy 378.097627 -236.006223) (xy 378.067603 -235.962186) (xy 378.044477 -235.914165) (xy 378.028767 -235.863235)
			(xy 378.020824 -235.810531) (xy 377.792244 -235.810531) (xy 377.784301 -235.863235) (xy 377.768591 -235.914165)
			(xy 377.745465 -235.962186) (xy 377.715441 -236.006223) (xy 377.679189 -236.045294) (xy 377.637518 -236.078525)
			(xy 377.59136 -236.105174) (xy 377.541746 -236.124646) (xy 377.489784 -236.136506) (xy 377.436634 -236.14049)
			(xy 377.383484 -236.136506) (xy 377.331522 -236.124646) (xy 377.281908 -236.105174) (xy 377.23575 -236.078525)
			(xy 377.194079 -236.045294) (xy 377.157827 -236.006223) (xy 377.127803 -235.962186) (xy 377.104677 -235.914165)
			(xy 377.088967 -235.863235) (xy 377.081024 -235.810531) (xy 376.852444 -235.810531) (xy 376.844501 -235.863235)
			(xy 376.828791 -235.914165) (xy 376.805665 -235.962186) (xy 376.775641 -236.006223) (xy 376.739389 -236.045294)
			(xy 376.697718 -236.078525) (xy 376.65156 -236.105174) (xy 376.601946 -236.124646) (xy 376.549984 -236.136506)
			(xy 376.496834 -236.14049) (xy 376.443684 -236.136506) (xy 376.391722 -236.124646) (xy 376.342108 -236.105174)
			(xy 376.29595 -236.078525) (xy 376.254279 -236.045294) (xy 376.218027 -236.006223) (xy 376.188003 -235.962186)
			(xy 376.164877 -235.914165) (xy 376.149167 -235.863235) (xy 376.141224 -235.810531) (xy 375.912644 -235.810531)
			(xy 375.904701 -235.863235) (xy 375.888991 -235.914165) (xy 375.865865 -235.962186) (xy 375.835841 -236.006223)
			(xy 375.799589 -236.045294) (xy 375.757918 -236.078525) (xy 375.71176 -236.105174) (xy 375.662146 -236.124646)
			(xy 375.610184 -236.136506) (xy 375.557034 -236.14049) (xy 375.503884 -236.136506) (xy 375.451922 -236.124646)
			(xy 375.402308 -236.105174) (xy 375.35615 -236.078525) (xy 375.314479 -236.045294) (xy 375.278227 -236.006223)
			(xy 375.248203 -235.962186) (xy 375.225077 -235.914165) (xy 375.209367 -235.863235) (xy 375.201424 -235.810531)
			(xy 374.972844 -235.810531) (xy 374.964901 -235.863235) (xy 374.949191 -235.914165) (xy 374.926065 -235.962186)
			(xy 374.896041 -236.006223) (xy 374.859789 -236.045294) (xy 374.818118 -236.078525) (xy 374.77196 -236.105174)
			(xy 374.722346 -236.124646) (xy 374.670384 -236.136506) (xy 374.617234 -236.14049) (xy 374.564084 -236.136506)
			(xy 374.512122 -236.124646) (xy 374.462508 -236.105174) (xy 374.41635 -236.078525) (xy 374.374679 -236.045294)
			(xy 374.338427 -236.006223) (xy 374.308403 -235.962186) (xy 374.285277 -235.914165) (xy 374.269567 -235.863235)
			(xy 374.261624 -235.810531) (xy 374.03279 -235.810531) (xy 374.024847 -235.863235) (xy 374.009137 -235.914165)
			(xy 373.986011 -235.962186) (xy 373.955987 -236.006223) (xy 373.919735 -236.045294) (xy 373.878064 -236.078525)
			(xy 373.831906 -236.105174) (xy 373.782292 -236.124646) (xy 373.73033 -236.136506) (xy 373.67718 -236.14049)
			(xy 373.62403 -236.136506) (xy 373.572068 -236.124646) (xy 373.522454 -236.105174) (xy 373.476296 -236.078525)
			(xy 373.434625 -236.045294) (xy 373.398373 -236.006223) (xy 373.368349 -235.962186) (xy 373.345223 -235.914165)
			(xy 373.329513 -235.863235) (xy 373.32157 -235.810531) (xy 373.093244 -235.810531) (xy 373.085301 -235.863235)
			(xy 373.069591 -235.914165) (xy 373.046465 -235.962186) (xy 373.016441 -236.006223) (xy 372.980189 -236.045294)
			(xy 372.938518 -236.078525) (xy 372.89236 -236.105174) (xy 372.842746 -236.124646) (xy 372.790784 -236.136506)
			(xy 372.737634 -236.14049) (xy 372.684484 -236.136506) (xy 372.632522 -236.124646) (xy 372.582908 -236.105174)
			(xy 372.53675 -236.078525) (xy 372.495079 -236.045294) (xy 372.458827 -236.006223) (xy 372.428803 -235.962186)
			(xy 372.405677 -235.914165) (xy 372.389967 -235.863235) (xy 372.382024 -235.810531) (xy 372.153444 -235.810531)
			(xy 372.145501 -235.863235) (xy 372.129791 -235.914165) (xy 372.106665 -235.962186) (xy 372.076641 -236.006223)
			(xy 372.040389 -236.045294) (xy 371.998718 -236.078525) (xy 371.95256 -236.105174) (xy 371.902946 -236.124646)
			(xy 371.850984 -236.136506) (xy 371.797834 -236.14049) (xy 371.744684 -236.136506) (xy 371.692722 -236.124646)
			(xy 371.643108 -236.105174) (xy 371.59695 -236.078525) (xy 371.555279 -236.045294) (xy 371.519027 -236.006223)
			(xy 371.489003 -235.962186) (xy 371.465877 -235.914165) (xy 371.450167 -235.863235) (xy 371.442224 -235.810531)
			(xy 371.213644 -235.810531) (xy 371.205701 -235.863235) (xy 371.189991 -235.914165) (xy 371.166865 -235.962186)
			(xy 371.136841 -236.006223) (xy 371.100589 -236.045294) (xy 371.058918 -236.078525) (xy 371.01276 -236.105174)
			(xy 370.963146 -236.124646) (xy 370.911184 -236.136506) (xy 370.858034 -236.14049) (xy 370.804884 -236.136506)
			(xy 370.752922 -236.124646) (xy 370.703308 -236.105174) (xy 370.65715 -236.078525) (xy 370.615479 -236.045294)
			(xy 370.579227 -236.006223) (xy 370.549203 -235.962186) (xy 370.526077 -235.914165) (xy 370.510367 -235.863235)
			(xy 370.502424 -235.810531) (xy 370.273844 -235.810531) (xy 370.265901 -235.863235) (xy 370.250191 -235.914165)
			(xy 370.227065 -235.962186) (xy 370.197041 -236.006223) (xy 370.160789 -236.045294) (xy 370.119118 -236.078525)
			(xy 370.07296 -236.105174) (xy 370.023346 -236.124646) (xy 369.971384 -236.136506) (xy 369.918234 -236.14049)
			(xy 369.865084 -236.136506) (xy 369.813122 -236.124646) (xy 369.763508 -236.105174) (xy 369.71735 -236.078525)
			(xy 369.675679 -236.045294) (xy 369.639427 -236.006223) (xy 369.609403 -235.962186) (xy 369.586277 -235.914165)
			(xy 369.570567 -235.863235) (xy 369.562624 -235.810531) (xy 367.811865 -235.810531) (xy 367.80864 -235.853556)
			(xy 367.796778 -235.905524) (xy 367.777302 -235.955144) (xy 367.750648 -236.001307) (xy 367.71741 -236.042981)
			(xy 367.678333 -236.079235) (xy 367.634288 -236.109259) (xy 367.58626 -236.132384) (xy 367.535321 -236.148091)
			(xy 367.482611 -236.15603) (xy 367.455958 -236.1565) (xy 367.43129 -236.156052) (xy 367.382424 -236.149255)
			(xy 367.334967 -236.135769) (xy 367.289829 -236.115853) (xy 367.247878 -236.08989) (xy 367.228628 -236.074458)
			(xy 367.217498 -236.065831) (xy 367.191738 -236.054484) (xy 367.163858 -236.050603) (xy 367.135978 -236.054484)
			(xy 367.110218 -236.065831) (xy 367.099088 -236.074458) (xy 367.077672 -236.091581) (xy 367.030615 -236.11972)
			(xy 366.979798 -236.140309) (xy 366.926425 -236.152861) (xy 366.871758 -236.157078) (xy 366.817091 -236.152861)
			(xy 366.763718 -236.140309) (xy 366.712901 -236.11972) (xy 366.665844 -236.091581) (xy 366.644428 -236.074458)
			(xy 366.633298 -236.065831) (xy 366.607538 -236.054484) (xy 366.579658 -236.050603) (xy 366.551778 -236.054484)
			(xy 366.526018 -236.065831) (xy 366.514888 -236.074458) (xy 366.493472 -236.091581) (xy 366.446415 -236.11972)
			(xy 366.395598 -236.140309) (xy 366.342225 -236.152861) (xy 366.287558 -236.157078) (xy 366.232891 -236.152861)
			(xy 366.179518 -236.140309) (xy 366.128701 -236.11972) (xy 366.081644 -236.091581) (xy 366.060228 -236.074458)
			(xy 366.049098 -236.065831) (xy 366.023338 -236.054484) (xy 365.995458 -236.050603) (xy 365.967578 -236.054484)
			(xy 365.941818 -236.065831) (xy 365.930688 -236.074458) (xy 365.909272 -236.091581) (xy 365.862215 -236.11972)
			(xy 365.811398 -236.140309) (xy 365.758025 -236.152861) (xy 365.703358 -236.157078) (xy 365.648691 -236.152861)
			(xy 365.595318 -236.140309) (xy 365.544501 -236.11972) (xy 365.497444 -236.091581) (xy 365.476028 -236.074458)
			(xy 365.464898 -236.065831) (xy 365.439138 -236.054484) (xy 365.411258 -236.050603) (xy 365.383378 -236.054484)
			(xy 365.357618 -236.065831) (xy 365.346488 -236.074458) (xy 365.325072 -236.091581) (xy 365.278015 -236.11972)
			(xy 365.227198 -236.140309) (xy 365.173825 -236.152861) (xy 365.119158 -236.157078) (xy 365.064491 -236.152861)
			(xy 365.011118 -236.140309) (xy 364.960301 -236.11972) (xy 364.913244 -236.091581) (xy 364.891828 -236.074458)
			(xy 364.880698 -236.065831) (xy 364.854938 -236.054484) (xy 364.827058 -236.050603) (xy 364.799178 -236.054484)
			(xy 364.773418 -236.065831) (xy 364.762288 -236.074458) (xy 364.743031 -236.08988) (xy 364.701077 -236.11584)
			(xy 364.655941 -236.13576) (xy 364.608488 -236.149258) (xy 364.559626 -236.156077) (xy 364.534958 -236.1565)
			(xy 364.50831 -236.156015) (xy 364.45561 -236.148066) (xy 364.404684 -236.132352) (xy 364.356668 -236.109224)
			(xy 364.312635 -236.079198) (xy 364.273569 -236.042945) (xy 364.240341 -236.001275) (xy 364.213695 -235.955119)
			(xy 364.194226 -235.905507) (xy 364.182367 -235.853547) (xy 364.178384 -235.8004) (xy 362.755633 -235.8004)
			(xy 362.755444 -235.810531) (xy 362.747501 -235.863235) (xy 362.731791 -235.914165) (xy 362.708665 -235.962186)
			(xy 362.678641 -236.006223) (xy 362.642389 -236.045294) (xy 362.600718 -236.078525) (xy 362.55456 -236.105174)
			(xy 362.504946 -236.124646) (xy 362.452984 -236.136506) (xy 362.399834 -236.14049) (xy 362.346684 -236.136506)
			(xy 362.294722 -236.124646) (xy 362.245108 -236.105174) (xy 362.19895 -236.078525) (xy 362.157279 -236.045294)
			(xy 362.121027 -236.006223) (xy 362.091003 -235.962186) (xy 362.067877 -235.914165) (xy 362.052167 -235.863235)
			(xy 362.044224 -235.810531) (xy 361.815644 -235.810531) (xy 361.807701 -235.863235) (xy 361.791991 -235.914165)
			(xy 361.768865 -235.962186) (xy 361.738841 -236.006223) (xy 361.702589 -236.045294) (xy 361.660918 -236.078525)
			(xy 361.61476 -236.105174) (xy 361.565146 -236.124646) (xy 361.513184 -236.136506) (xy 361.460034 -236.14049)
			(xy 361.406884 -236.136506) (xy 361.354922 -236.124646) (xy 361.305308 -236.105174) (xy 361.25915 -236.078525)
			(xy 361.217479 -236.045294) (xy 361.181227 -236.006223) (xy 361.151203 -235.962186) (xy 361.128077 -235.914165)
			(xy 361.112367 -235.863235) (xy 361.104424 -235.810531) (xy 360.875844 -235.810531) (xy 360.867901 -235.863235)
			(xy 360.852191 -235.914165) (xy 360.829065 -235.962186) (xy 360.799041 -236.006223) (xy 360.762789 -236.045294)
			(xy 360.721118 -236.078525) (xy 360.67496 -236.105174) (xy 360.625346 -236.124646) (xy 360.573384 -236.136506)
			(xy 360.520234 -236.14049) (xy 360.467084 -236.136506) (xy 360.415122 -236.124646) (xy 360.365508 -236.105174)
			(xy 360.31935 -236.078525) (xy 360.277679 -236.045294) (xy 360.241427 -236.006223) (xy 360.211403 -235.962186)
			(xy 360.188277 -235.914165) (xy 360.172567 -235.863235) (xy 360.164624 -235.810531) (xy 359.936044 -235.810531)
			(xy 359.928101 -235.863235) (xy 359.912391 -235.914165) (xy 359.889265 -235.962186) (xy 359.859241 -236.006223)
			(xy 359.822989 -236.045294) (xy 359.781318 -236.078525) (xy 359.73516 -236.105174) (xy 359.685546 -236.124646)
			(xy 359.633584 -236.136506) (xy 359.580434 -236.14049) (xy 359.527284 -236.136506) (xy 359.475322 -236.124646)
			(xy 359.425708 -236.105174) (xy 359.37955 -236.078525) (xy 359.337879 -236.045294) (xy 359.301627 -236.006223)
			(xy 359.271603 -235.962186) (xy 359.248477 -235.914165) (xy 359.232767 -235.863235) (xy 359.224824 -235.810531)
			(xy 358.996244 -235.810531) (xy 358.988301 -235.863235) (xy 358.972591 -235.914165) (xy 358.949465 -235.962186)
			(xy 358.919441 -236.006223) (xy 358.883189 -236.045294) (xy 358.841518 -236.078525) (xy 358.79536 -236.105174)
			(xy 358.745746 -236.124646) (xy 358.693784 -236.136506) (xy 358.640634 -236.14049) (xy 358.587484 -236.136506)
			(xy 358.535522 -236.124646) (xy 358.485908 -236.105174) (xy 358.43975 -236.078525) (xy 358.398079 -236.045294)
			(xy 358.361827 -236.006223) (xy 358.331803 -235.962186) (xy 358.308677 -235.914165) (xy 358.292967 -235.863235)
			(xy 358.285024 -235.810531) (xy 358.056444 -235.810531) (xy 358.048501 -235.863235) (xy 358.032791 -235.914165)
			(xy 358.009665 -235.962186) (xy 357.979641 -236.006223) (xy 357.943389 -236.045294) (xy 357.901718 -236.078525)
			(xy 357.85556 -236.105174) (xy 357.805946 -236.124646) (xy 357.753984 -236.136506) (xy 357.700834 -236.14049)
			(xy 357.647684 -236.136506) (xy 357.595722 -236.124646) (xy 357.546108 -236.105174) (xy 357.49995 -236.078525)
			(xy 357.458279 -236.045294) (xy 357.422027 -236.006223) (xy 357.392003 -235.962186) (xy 357.368877 -235.914165)
			(xy 357.353167 -235.863235) (xy 357.345224 -235.810531) (xy 356.291784 -235.810531) (xy 356.292633 -235.811931)
			(xy 356.302818 -235.821982) (xy 356.3206 -235.838886) (xy 356.351776 -235.876769) (xy 356.377456 -235.918575)
			(xy 356.397151 -235.963511) (xy 356.41049 -236.010726) (xy 356.417219 -236.059325) (xy 356.417626 -236.083856)
			(xy 356.417047 -236.111839) (xy 356.408298 -236.167118) (xy 356.39101 -236.220347) (xy 356.365606 -236.270216)
			(xy 356.332714 -236.315497) (xy 356.293144 -236.355074) (xy 356.247869 -236.387974) (xy 356.198004 -236.413386)
			(xy 356.144778 -236.430684) (xy 356.089501 -236.439442) (xy 356.061518 -236.439964) (xy 356.034197 -236.439442)
			(xy 355.980195 -236.431106) (xy 355.928098 -236.414625) (xy 355.879127 -236.390388) (xy 355.834428 -236.35896)
			(xy 355.814376 -236.340396) (xy 355.802754 -236.329999) (xy 355.77482 -236.316175) (xy 355.744018 -236.311419)
			(xy 355.713216 -236.316175) (xy 355.685282 -236.329999) (xy 355.67366 -236.340396) (xy 355.653656 -236.359019)
			(xy 355.60896 -236.390474) (xy 355.559979 -236.414722) (xy 355.507865 -236.431191) (xy 355.453846 -236.439494)
			(xy 355.426518 -236.439964) (xy 355.398531 -236.439471) (xy 355.343246 -236.430716) (xy 355.290011 -236.41342)
			(xy 355.240138 -236.388008) (xy 355.194854 -236.355107) (xy 355.155276 -236.315526) (xy 355.122378 -236.27024)
			(xy 355.09697 -236.220365) (xy 355.079678 -236.167129) (xy 355.070927 -236.111843) (xy 355.07041 -236.083856)
			(xy 355.070847 -236.058154) (xy 355.078248 -236.007284) (xy 355.092877 -235.958005) (xy 355.114429 -235.911336)
			(xy 355.128068 -235.889546) (xy 355.135449 -235.87729) (xy 355.143813 -235.849946) (xy 355.144279 -235.821354)
			(xy 355.13681 -235.793752) (xy 355.121991 -235.769296) (xy 355.111812 -235.759244) (xy 355.094048 -235.742322)
			(xy 355.062869 -235.704443) (xy 355.037187 -235.662641) (xy 355.017488 -235.617709) (xy 355.004145 -235.570497)
			(xy 354.997413 -235.5219) (xy 354.997004 -235.49737) (xy 354.652854 -235.49737) (xy 354.620053 -235.532722)
			(xy 354.578382 -235.565953) (xy 354.532224 -235.592602) (xy 354.48261 -235.612074) (xy 354.430648 -235.623934)
			(xy 354.377498 -235.627918) (xy 354.324348 -235.623934) (xy 354.272386 -235.612074) (xy 354.222772 -235.592602)
			(xy 354.176614 -235.565953) (xy 354.134943 -235.532722) (xy 354.098691 -235.493651) (xy 354.068667 -235.449614)
			(xy 354.045541 -235.401593) (xy 354.029831 -235.350663) (xy 354.021888 -235.297959) (xy 353.657481 -235.297959)
			(xy 353.654584 -235.300269) (xy 353.608426 -235.326918) (xy 353.558812 -235.34639) (xy 353.50685 -235.35825)
			(xy 353.4537 -235.362234) (xy 353.40055 -235.35825) (xy 353.348588 -235.34639) (xy 353.298974 -235.326918)
			(xy 353.252816 -235.300269) (xy 353.211145 -235.267038) (xy 353.174893 -235.227967) (xy 353.144869 -235.18393)
			(xy 353.121743 -235.135909) (xy 353.106033 -235.084979) (xy 353.09809 -235.032275) (xy 350.379813 -235.032275)
			(xy 350.15551 -235.256578) (xy 350.145698 -235.267085) (xy 350.131842 -235.292259) (xy 350.125551 -235.320297)
			(xy 350.127325 -235.348978) (xy 350.137022 -235.376028) (xy 350.153875 -235.399303) (xy 350.176546 -235.416958)
			(xy 350.203241 -235.427595) (xy 350.217486 -235.429552) (xy 350.243537 -235.432599) (xy 350.294409 -235.445364)
			(xy 350.342858 -235.465451) (xy 350.387839 -235.492426) (xy 350.428377 -235.525706) (xy 350.463596 -235.56457)
			(xy 350.492735 -235.60818) (xy 350.515164 -235.655591) (xy 350.530397 -235.705779) (xy 350.530786 -235.7084)
			(xy 350.876937 -235.7084) (xy 350.880919 -235.655258) (xy 350.892777 -235.603304) (xy 350.912246 -235.553697)
			(xy 350.938891 -235.507545) (xy 350.972116 -235.46588) (xy 351.01118 -235.429633) (xy 351.05521 -235.399612)
			(xy 351.103223 -235.376489) (xy 351.154146 -235.360779) (xy 351.206841 -235.352835) (xy 351.233486 -235.352336)
			(xy 351.260406 -235.352854) (xy 351.31363 -235.360969) (xy 351.365028 -235.377) (xy 351.413427 -235.400583)
			(xy 351.457727 -235.43118) (xy 351.496919 -235.468096) (xy 351.513902 -235.488988) (xy 351.523002 -235.499874)
			(xy 351.545959 -235.516529) (xy 351.572611 -235.526232) (xy 351.600903 -235.528234) (xy 351.628655 -235.522382)
			(xy 351.64141 -235.516166) (xy 351.66719 -235.503146) (xy 351.721917 -235.484705) (xy 351.778905 -235.475343)
			(xy 351.80778 -235.474764) (xy 351.83443 -235.475292) (xy 351.887135 -235.483233) (xy 351.938068 -235.498941)
			(xy 351.98609 -235.522065) (xy 352.03013 -235.552089) (xy 352.069203 -235.588341) (xy 352.102436 -235.630012)
			(xy 352.129087 -235.67617) (xy 352.14856 -235.725785) (xy 352.160421 -235.777749) (xy 352.164404 -235.8309)
			(xy 352.160421 -235.884051) (xy 352.14856 -235.936015) (xy 352.129087 -235.98563) (xy 352.102436 -236.031788)
			(xy 352.069203 -236.073459) (xy 352.03013 -236.109711) (xy 351.98609 -236.139735) (xy 351.938068 -236.162859)
			(xy 351.887135 -236.178567) (xy 351.83443 -236.186508) (xy 351.80778 -236.18698) (xy 351.780858 -236.186518)
			(xy 351.727629 -236.178396) (xy 351.676229 -236.162356) (xy 351.627829 -236.138763) (xy 351.583531 -236.108154)
			(xy 351.544344 -236.071226) (xy 351.527364 -236.050328) (xy 351.518205 -236.039496) (xy 351.495266 -236.022835)
			(xy 351.468631 -236.013123) (xy 351.440352 -236.011107) (xy 351.412609 -236.016943) (xy 351.399856 -236.02315)
			(xy 351.374083 -236.036183) (xy 351.319352 -236.054619) (xy 351.262362 -236.063975) (xy 351.233486 -236.064552)
			(xy 351.206841 -236.063965) (xy 351.154146 -236.056021) (xy 351.103223 -236.040311) (xy 351.05521 -236.017188)
			(xy 351.01118 -235.987167) (xy 350.972116 -235.95092) (xy 350.938891 -235.909255) (xy 350.912246 -235.863103)
			(xy 350.892777 -235.813496) (xy 350.880919 -235.761542) (xy 350.876937 -235.7084) (xy 350.530786 -235.7084)
			(xy 350.538106 -235.757658) (xy 350.538542 -235.783882) (xy 350.537994 -235.811867) (xy 350.529242 -235.867148)
			(xy 350.511949 -235.92038) (xy 350.486543 -235.970251) (xy 350.453647 -236.015534) (xy 350.414074 -236.055114)
			(xy 350.368796 -236.088015) (xy 350.318928 -236.113429) (xy 350.265699 -236.13073) (xy 350.210419 -236.13949)
			(xy 350.182434 -236.13999) (xy 350.156209 -236.139526) (xy 350.104327 -236.131835) (xy 350.054134 -236.116614)
			(xy 350.006718 -236.094194) (xy 349.963105 -236.065059) (xy 349.924239 -236.02984) (xy 349.890961 -235.9893)
			(xy 349.863992 -235.944315) (xy 349.843916 -235.89586) (xy 349.831166 -235.844984) (xy 349.828104 -235.818934)
			(xy 349.826206 -235.804681) (xy 349.815539 -235.777994) (xy 349.797864 -235.755331) (xy 349.774579 -235.738485)
			(xy 349.747524 -235.728786) (xy 349.71884 -235.727002) (xy 349.690792 -235.733274) (xy 349.665599 -235.747105)
			(xy 349.65513 -235.756958) (xy 349.59798 -235.814108) (xy 349.595694 -235.831126) (xy 349.591813 -235.85667)
			(xy 349.577638 -235.906355) (xy 349.556433 -235.95347) (xy 349.528645 -235.997028) (xy 349.494856 -236.036115)
			(xy 349.455775 -236.06991) (xy 349.412222 -236.097706) (xy 349.36511 -236.118918) (xy 349.315428 -236.133101)
			(xy 349.289878 -236.136942) (xy 349.27286 -236.139228) (xy 349.046038 -236.36605) (xy 349.068898 -236.400848)
			(xy 349.082997 -236.422852) (xy 349.105291 -236.470116) (xy 349.120437 -236.520131) (xy 349.128111 -236.571823)
			(xy 349.128588 -236.597952) (xy 349.128096 -236.624601) (xy 349.35667 -236.624601) (xy 349.35667 -236.571303)
			(xy 349.364613 -236.518599) (xy 349.380323 -236.467669) (xy 349.403449 -236.419648) (xy 349.433473 -236.375611)
			(xy 349.469725 -236.33654) (xy 349.511396 -236.303309) (xy 349.557554 -236.27666) (xy 349.607168 -236.257188)
			(xy 349.65913 -236.245328) (xy 349.71228 -236.241345) (xy 349.76543 -236.245328) (xy 349.817392 -236.257188)
			(xy 349.867006 -236.27666) (xy 349.913164 -236.303309) (xy 349.954835 -236.33654) (xy 349.991087 -236.375611)
			(xy 350.021111 -236.419648) (xy 350.037001 -236.452643) (xy 350.466396 -236.452643) (xy 350.466396 -236.399345)
			(xy 350.474339 -236.346641) (xy 350.490049 -236.295711) (xy 350.513175 -236.24769) (xy 350.543199 -236.203653)
			(xy 350.579451 -236.164582) (xy 350.621122 -236.131351) (xy 350.66728 -236.104702) (xy 350.716894 -236.08523)
			(xy 350.768856 -236.07337) (xy 350.822006 -236.069387) (xy 350.875156 -236.07337) (xy 350.927118 -236.08523)
			(xy 350.976732 -236.104702) (xy 351.02289 -236.131351) (xy 351.064561 -236.164582) (xy 351.100813 -236.203653)
			(xy 351.130837 -236.24769) (xy 351.153963 -236.295711) (xy 351.169673 -236.346641) (xy 351.177616 -236.399345)
			(xy 351.178114 -236.425994) (xy 351.177616 -236.452643) (xy 351.169673 -236.505347) (xy 351.153963 -236.556277)
			(xy 351.130837 -236.604298) (xy 351.100813 -236.648335) (xy 351.064561 -236.687406) (xy 351.02289 -236.720637)
			(xy 350.976732 -236.747286) (xy 350.927118 -236.766758) (xy 350.875156 -236.778618) (xy 350.822006 -236.782602)
			(xy 350.768856 -236.778618) (xy 350.716894 -236.766758) (xy 350.66728 -236.747286) (xy 350.621122 -236.720637)
			(xy 350.579451 -236.687406) (xy 350.543199 -236.648335) (xy 350.513175 -236.604298) (xy 350.490049 -236.556277)
			(xy 350.474339 -236.505347) (xy 350.466396 -236.452643) (xy 350.037001 -236.452643) (xy 350.044237 -236.467669)
			(xy 350.059947 -236.518599) (xy 350.06789 -236.571303) (xy 350.068388 -236.597952) (xy 350.06789 -236.624601)
			(xy 350.059947 -236.677305) (xy 350.044237 -236.728235) (xy 350.021111 -236.776256) (xy 349.991087 -236.820293)
			(xy 349.954835 -236.859364) (xy 349.913164 -236.892595) (xy 349.867006 -236.919244) (xy 349.817392 -236.938716)
			(xy 349.76543 -236.950576) (xy 349.71228 -236.95456) (xy 349.65913 -236.950576) (xy 349.607168 -236.938716)
			(xy 349.557554 -236.919244) (xy 349.511396 -236.892595) (xy 349.469725 -236.859364) (xy 349.433473 -236.820293)
			(xy 349.403449 -236.776256) (xy 349.380323 -236.728235) (xy 349.364613 -236.677305) (xy 349.35667 -236.624601)
			(xy 349.128096 -236.624601) (xy 349.128071 -236.625939) (xy 349.119321 -236.681225) (xy 349.102029 -236.734462)
			(xy 349.076621 -236.784337) (xy 349.043723 -236.829623) (xy 349.004145 -236.869205) (xy 348.958861 -236.902107)
			(xy 348.908988 -236.927518) (xy 348.855753 -236.944815) (xy 348.800467 -236.953569) (xy 348.77248 -236.95406)
			(xy 348.747449 -236.953634) (xy 348.697881 -236.946621) (xy 348.649783 -236.932735) (xy 348.604103 -236.912251)
			(xy 348.561742 -236.885572) (xy 348.542356 -236.869732) (xy 348.465394 -236.946694) (xy 348.454859 -236.957978)
			(xy 348.440535 -236.985307) (xy 348.435028 -237.015668) (xy 348.438843 -237.046288) (xy 348.451629 -237.07437)
			(xy 348.472221 -237.09735) (xy 348.485206 -237.105698) (xy 348.507539 -237.11957) (xy 348.548238 -237.15285)
			(xy 348.583603 -237.19175) (xy 348.612867 -237.235426) (xy 348.635393 -237.282929) (xy 348.650692 -237.333227)
			(xy 348.658432 -237.385228) (xy 348.658942 -237.411514) (xy 348.658418 -237.438163) (xy 348.887024 -237.438163)
			(xy 348.887024 -237.384865) (xy 348.894967 -237.332161) (xy 348.910677 -237.281231) (xy 348.933803 -237.23321)
			(xy 348.963827 -237.189173) (xy 349.000079 -237.150102) (xy 349.04175 -237.116871) (xy 349.087908 -237.090222)
			(xy 349.137522 -237.07075) (xy 349.189484 -237.05889) (xy 349.242634 -237.054907) (xy 349.295784 -237.05889)
			(xy 349.347746 -237.07075) (xy 349.39736 -237.090222) (xy 349.443518 -237.116871) (xy 349.485189 -237.150102)
			(xy 349.521441 -237.189173) (xy 349.551465 -237.23321) (xy 349.574591 -237.281231) (xy 349.590301 -237.332161)
			(xy 349.598244 -237.384865) (xy 349.598742 -237.4115) (xy 349.825782 -237.4115) (xy 349.829766 -237.358346)
			(xy 349.841627 -237.306379) (xy 349.861103 -237.25676) (xy 349.887756 -237.210599) (xy 349.920992 -237.168926)
			(xy 349.960068 -237.132673) (xy 350.004111 -237.102648) (xy 350.052137 -237.079524) (xy 350.103073 -237.063817)
			(xy 350.155782 -237.055877) (xy 350.182434 -237.055406) (xy 350.210399 -237.056016) (xy 350.265641 -237.064764)
			(xy 350.318837 -237.082041) (xy 350.368677 -237.107421) (xy 350.413938 -237.14028) (xy 350.453505 -237.179811)
			(xy 350.486406 -237.225041) (xy 350.511832 -237.274858) (xy 350.521016 -237.301278) (xy 350.525914 -237.315035)
			(xy 350.542412 -237.339122) (xy 350.565053 -237.357552) (xy 350.591986 -237.368819) (xy 350.621007 -237.371999)
			(xy 350.649741 -237.366833) (xy 350.663002 -237.360714) (xy 350.687825 -237.348889) (xy 350.740195 -237.332149)
			(xy 350.794516 -237.323655) (xy 350.822006 -237.323122) (xy 350.849993 -237.323607) (xy 350.905278 -237.332364)
			(xy 350.958512 -237.349663) (xy 351.008384 -237.375076) (xy 351.053667 -237.407979) (xy 351.093244 -237.447561)
			(xy 351.126143 -237.492847) (xy 351.151551 -237.542722) (xy 351.168844 -237.595957) (xy 351.177596 -237.651243)
			(xy 351.178114 -237.67923) (xy 351.177736 -237.703901) (xy 351.170925 -237.75277) (xy 351.157424 -237.800229)
			(xy 351.137492 -237.845365) (xy 351.111512 -237.887313) (xy 351.096072 -237.90656) (xy 351.087416 -237.917669)
			(xy 351.076072 -237.943437) (xy 351.072197 -237.971323) (xy 351.076085 -237.999208) (xy 351.08744 -238.02497)
			(xy 351.096072 -238.0361) (xy 351.111491 -238.05536) (xy 351.137451 -238.097313) (xy 351.157371 -238.142448)
			(xy 351.17087 -238.189901) (xy 351.17769 -238.238762) (xy 351.178114 -238.26343) (xy 351.177616 -238.290079)
			(xy 351.169673 -238.342783) (xy 351.153963 -238.393713) (xy 351.130837 -238.441734) (xy 351.100813 -238.485771)
			(xy 351.064561 -238.524842) (xy 351.02289 -238.558073) (xy 350.976732 -238.584722) (xy 350.927118 -238.604194)
			(xy 350.875156 -238.616054) (xy 350.822006 -238.620038) (xy 350.768856 -238.616054) (xy 350.716894 -238.604194)
			(xy 350.66728 -238.584722) (xy 350.621122 -238.558073) (xy 350.579451 -238.524842) (xy 350.543199 -238.485771)
			(xy 350.513175 -238.441734) (xy 350.490049 -238.393713) (xy 350.474339 -238.342783) (xy 350.466396 -238.290079)
			(xy 350.465898 -238.26343) (xy 350.46633 -238.238761) (xy 350.473131 -238.189895) (xy 350.486621 -238.142438)
			(xy 350.50654 -238.0973) (xy 350.532506 -238.055349) (xy 350.54794 -238.0361) (xy 350.556538 -238.02495)
			(xy 350.567888 -237.999197) (xy 350.571774 -237.971323) (xy 350.5679 -237.943448) (xy 350.556562 -237.91769)
			(xy 350.54794 -237.90656) (xy 350.533883 -237.889087) (xy 350.509816 -237.851246) (xy 350.490689 -237.810683)
			(xy 350.483424 -237.789466) (xy 350.478457 -237.775736) (xy 350.461977 -237.75165) (xy 350.439351 -237.733217)
			(xy 350.412431 -237.721945) (xy 350.383421 -237.718757) (xy 350.354696 -237.723915) (xy 350.341438 -237.73003)
			(xy 350.316623 -237.741872) (xy 350.264249 -237.758607) (xy 350.209925 -237.767093) (xy 350.182434 -237.767622)
			(xy 350.155782 -237.767123) (xy 350.103073 -237.759183) (xy 350.052137 -237.743476) (xy 350.004111 -237.720352)
			(xy 349.960068 -237.690327) (xy 349.920992 -237.654074) (xy 349.887756 -237.612401) (xy 349.861103 -237.56624)
			(xy 349.841627 -237.516621) (xy 349.829766 -237.464654) (xy 349.825782 -237.4115) (xy 349.598742 -237.4115)
			(xy 349.598742 -237.411514) (xy 349.598244 -237.438163) (xy 349.590301 -237.490867) (xy 349.574591 -237.541797)
			(xy 349.551465 -237.589818) (xy 349.521441 -237.633855) (xy 349.485189 -237.672926) (xy 349.443518 -237.706157)
			(xy 349.39736 -237.732806) (xy 349.347746 -237.752278) (xy 349.295784 -237.764138) (xy 349.242634 -237.768122)
			(xy 349.189484 -237.764138) (xy 349.137522 -237.752278) (xy 349.087908 -237.732806) (xy 349.04175 -237.706157)
			(xy 349.000079 -237.672926) (xy 348.963827 -237.633855) (xy 348.933803 -237.589818) (xy 348.910677 -237.541797)
			(xy 348.894967 -237.490867) (xy 348.887024 -237.438163) (xy 348.658418 -237.438163) (xy 348.658392 -237.439497)
			(xy 348.649635 -237.494775) (xy 348.63234 -237.548002) (xy 348.606932 -237.597869) (xy 348.574036 -237.643147)
			(xy 348.534463 -237.682723) (xy 348.489186 -237.715621) (xy 348.439321 -237.741032) (xy 348.386094 -237.758331)
			(xy 348.330817 -237.76709) (xy 348.302834 -237.767622) (xy 348.276579 -237.767155) (xy 348.224637 -237.759442)
			(xy 348.174393 -237.74418) (xy 348.126938 -237.721699) (xy 348.083302 -237.692487) (xy 348.063566 -237.675166)
			(xy 348.052362 -237.665644) (xy 348.025887 -237.652884) (xy 347.996875 -237.648183) (xy 347.967725 -237.651931)
			(xy 347.940845 -237.663817) (xy 347.918458 -237.682859) (xy 347.902414 -237.707484) (xy 347.894038 -237.735655)
			(xy 347.89364 -237.75035) (xy 347.89364 -237.872524) (xy 347.93047 -237.883192) (xy 347.95638 -237.891117)
			(xy 348.005624 -237.913714) (xy 348.050876 -237.94351) (xy 348.091092 -237.979817) (xy 348.125344 -238.021798)
			(xy 348.15284 -238.068483) (xy 348.172947 -238.118794) (xy 348.1852 -238.171571) (xy 348.189317 -238.225596)
			(xy 348.187288 -238.252233) (xy 348.41687 -238.252233) (xy 348.41687 -238.198935) (xy 348.424813 -238.146231)
			(xy 348.440523 -238.095301) (xy 348.463649 -238.04728) (xy 348.493673 -238.003243) (xy 348.529925 -237.964172)
			(xy 348.571596 -237.930941) (xy 348.617754 -237.904292) (xy 348.667368 -237.88482) (xy 348.71933 -237.87296)
			(xy 348.77248 -237.868977) (xy 348.82563 -237.87296) (xy 348.877592 -237.88482) (xy 348.927206 -237.904292)
			(xy 348.973364 -237.930941) (xy 349.015035 -237.964172) (xy 349.051287 -238.003243) (xy 349.081311 -238.04728)
			(xy 349.104437 -238.095301) (xy 349.120147 -238.146231) (xy 349.12809 -238.198935) (xy 349.128588 -238.225584)
			(xy 349.12809 -238.252233) (xy 349.35667 -238.252233) (xy 349.35667 -238.198935) (xy 349.364613 -238.146231)
			(xy 349.380323 -238.095301) (xy 349.403449 -238.04728) (xy 349.433473 -238.003243) (xy 349.469725 -237.964172)
			(xy 349.511396 -237.930941) (xy 349.557554 -237.904292) (xy 349.607168 -237.88482) (xy 349.65913 -237.87296)
			(xy 349.71228 -237.868977) (xy 349.76543 -237.87296) (xy 349.817392 -237.88482) (xy 349.867006 -237.904292)
			(xy 349.913164 -237.930941) (xy 349.954835 -237.964172) (xy 349.991087 -238.003243) (xy 350.021111 -238.04728)
			(xy 350.044237 -238.095301) (xy 350.059947 -238.146231) (xy 350.06789 -238.198935) (xy 350.068388 -238.225584)
			(xy 350.06789 -238.252233) (xy 350.059947 -238.304937) (xy 350.044237 -238.355867) (xy 350.021111 -238.403888)
			(xy 349.991087 -238.447925) (xy 349.954835 -238.486996) (xy 349.913164 -238.520227) (xy 349.867006 -238.546876)
			(xy 349.817392 -238.566348) (xy 349.76543 -238.578208) (xy 349.71228 -238.582192) (xy 349.65913 -238.578208)
			(xy 349.607168 -238.566348) (xy 349.557554 -238.546876) (xy 349.511396 -238.520227) (xy 349.469725 -238.486996)
			(xy 349.433473 -238.447925) (xy 349.403449 -238.403888) (xy 349.380323 -238.355867) (xy 349.364613 -238.304937)
			(xy 349.35667 -238.252233) (xy 349.12809 -238.252233) (xy 349.120147 -238.304937) (xy 349.104437 -238.355867)
			(xy 349.081311 -238.403888) (xy 349.051287 -238.447925) (xy 349.015035 -238.486996) (xy 348.973364 -238.520227)
			(xy 348.927206 -238.546876) (xy 348.877592 -238.566348) (xy 348.82563 -238.578208) (xy 348.77248 -238.582192)
			(xy 348.71933 -238.578208) (xy 348.667368 -238.566348) (xy 348.617754 -238.546876) (xy 348.571596 -238.520227)
			(xy 348.529925 -238.486996) (xy 348.493673 -238.447925) (xy 348.463649 -238.403888) (xy 348.440523 -238.355867)
			(xy 348.424813 -238.304937) (xy 348.41687 -238.252233) (xy 348.187288 -238.252233) (xy 348.185202 -238.27962)
			(xy 348.17295 -238.332397) (xy 348.152844 -238.382709) (xy 348.125349 -238.429395) (xy 348.091098 -238.471377)
			(xy 348.050883 -238.507685) (xy 348.005632 -238.537482) (xy 347.956388 -238.56008) (xy 347.93047 -238.567976)
			(xy 347.89364 -238.578644) (xy 347.89364 -238.700564) (xy 347.894123 -238.715254) (xy 347.902477 -238.743422)
			(xy 347.918504 -238.768046) (xy 347.940877 -238.787089) (xy 347.967746 -238.798974) (xy 347.996886 -238.80272)
			(xy 348.025887 -238.798014) (xy 348.052349 -238.785248) (xy 348.063566 -238.775748) (xy 348.083315 -238.758441)
			(xy 348.126948 -238.729226) (xy 348.174399 -238.706738) (xy 348.22464 -238.691467) (xy 348.276579 -238.683742)
			(xy 348.302834 -238.683292) (xy 348.329482 -238.683792) (xy 348.382181 -238.69174) (xy 348.433107 -238.707453)
			(xy 348.481123 -238.73058) (xy 348.525156 -238.760605) (xy 348.564223 -238.796857) (xy 348.59745 -238.838527)
			(xy 348.624096 -238.884683) (xy 348.643566 -238.934294) (xy 348.655425 -238.986254) (xy 348.659408 -239.0394)
			(xy 348.657411 -239.066049) (xy 348.88677 -239.066049) (xy 348.88677 -239.012751) (xy 348.894713 -238.960047)
			(xy 348.910423 -238.909117) (xy 348.933549 -238.861096) (xy 348.963573 -238.817059) (xy 348.999825 -238.777988)
			(xy 349.041496 -238.744757) (xy 349.087654 -238.718108) (xy 349.137268 -238.698636) (xy 349.18923 -238.686776)
			(xy 349.24238 -238.682793) (xy 349.29553 -238.686776) (xy 349.347492 -238.698636) (xy 349.397106 -238.718108)
			(xy 349.443264 -238.744757) (xy 349.484935 -238.777988) (xy 349.521187 -238.817059) (xy 349.551211 -238.861096)
			(xy 349.574337 -238.909117) (xy 349.590047 -238.960047) (xy 349.59799 -239.012751) (xy 349.598488 -239.0394)
			(xy 349.59799 -239.066049) (xy 349.590047 -239.118753) (xy 349.574337 -239.169683) (xy 349.551211 -239.217704)
			(xy 349.521187 -239.261741) (xy 349.484935 -239.300812) (xy 349.443264 -239.334043) (xy 349.397106 -239.360692)
			(xy 349.347492 -239.380164) (xy 349.29553 -239.392024) (xy 349.24238 -239.396008) (xy 349.18923 -239.392024)
			(xy 349.137268 -239.380164) (xy 349.087654 -239.360692) (xy 349.041496 -239.334043) (xy 348.999825 -239.300812)
			(xy 348.963573 -239.261741) (xy 348.933549 -239.217704) (xy 348.910423 -239.169683) (xy 348.894713 -239.118753)
			(xy 348.88677 -239.066049) (xy 348.657411 -239.066049) (xy 348.655425 -239.092546) (xy 348.643566 -239.144506)
			(xy 348.624096 -239.194117) (xy 348.59745 -239.240273) (xy 348.564223 -239.281943) (xy 348.525156 -239.318195)
			(xy 348.481123 -239.34822) (xy 348.433107 -239.371347) (xy 348.382181 -239.38706) (xy 348.329482 -239.395008)
			(xy 348.302834 -239.395508) (xy 348.276579 -239.395041) (xy 348.224637 -239.387328) (xy 348.174394 -239.372065)
			(xy 348.126939 -239.349583) (xy 348.083304 -239.320371) (xy 348.063566 -239.303052) (xy 348.052368 -239.293524)
			(xy 348.025897 -239.280754) (xy 347.996887 -239.276047) (xy 347.967737 -239.279793) (xy 347.940859 -239.291683)
			(xy 347.918479 -239.310732) (xy 347.902447 -239.335364) (xy 347.89409 -239.363541) (xy 347.89364 -239.378236)
			(xy 347.89364 -239.500156) (xy 347.93047 -239.510824) (xy 347.956378 -239.518749) (xy 348.005617 -239.541345)
			(xy 348.050864 -239.571139) (xy 348.091076 -239.607445) (xy 348.125323 -239.649423) (xy 348.152817 -239.696104)
			(xy 348.172921 -239.746412) (xy 348.185171 -239.799185) (xy 348.189286 -239.853204) (xy 348.187255 -239.879865)
			(xy 348.41687 -239.879865) (xy 348.41687 -239.826567) (xy 348.424813 -239.773863) (xy 348.440523 -239.722933)
			(xy 348.463649 -239.674912) (xy 348.493673 -239.630875) (xy 348.529925 -239.591804) (xy 348.571596 -239.558573)
			(xy 348.617754 -239.531924) (xy 348.667368 -239.512452) (xy 348.71933 -239.500592) (xy 348.77248 -239.496609)
			(xy 348.82563 -239.500592) (xy 348.877592 -239.512452) (xy 348.927206 -239.531924) (xy 348.973364 -239.558573)
			(xy 349.015035 -239.591804) (xy 349.051287 -239.630875) (xy 349.081311 -239.674912) (xy 349.104437 -239.722933)
			(xy 349.120147 -239.773863) (xy 349.12809 -239.826567) (xy 349.128588 -239.853216) (xy 349.12809 -239.879865)
			(xy 349.120147 -239.932569) (xy 349.104437 -239.983499) (xy 349.081311 -240.03152) (xy 349.051287 -240.075557)
			(xy 349.015035 -240.114628) (xy 348.973364 -240.147859) (xy 348.927206 -240.174508) (xy 348.877592 -240.19398)
			(xy 348.82563 -240.20584) (xy 348.77248 -240.209824) (xy 348.71933 -240.20584) (xy 348.667368 -240.19398)
			(xy 348.617754 -240.174508) (xy 348.571596 -240.147859) (xy 348.529925 -240.114628) (xy 348.493673 -240.075557)
			(xy 348.463649 -240.03152) (xy 348.440523 -239.983499) (xy 348.424813 -239.932569) (xy 348.41687 -239.879865)
			(xy 348.187255 -239.879865) (xy 348.18517 -239.907224) (xy 348.172918 -239.959996) (xy 348.152813 -240.010304)
			(xy 348.125318 -240.056985) (xy 348.09107 -240.098962) (xy 348.050857 -240.135266) (xy 348.005609 -240.165059)
			(xy 347.95637 -240.187654) (xy 347.93047 -240.195608) (xy 347.89364 -240.206276) (xy 347.89364 -240.32845)
			(xy 347.894121 -240.343142) (xy 347.902473 -240.371313) (xy 347.918499 -240.395941) (xy 347.940874 -240.414987)
			(xy 347.967745 -240.426874) (xy 347.996888 -240.43062) (xy 348.025892 -240.425913) (xy 348.052356 -240.413143)
			(xy 348.063566 -240.403634) (xy 348.083315 -240.386328) (xy 348.126948 -240.357114) (xy 348.1744 -240.334627)
			(xy 348.22464 -240.319356) (xy 348.276579 -240.311632) (xy 348.302834 -240.311178) (xy 348.329483 -240.311678)
			(xy 348.382184 -240.319626) (xy 348.433113 -240.33534) (xy 348.48113 -240.358468) (xy 348.525165 -240.388494)
			(xy 348.564233 -240.424748) (xy 348.597462 -240.466419) (xy 348.624109 -240.512576) (xy 348.64358 -240.56219)
			(xy 348.655439 -240.614152) (xy 348.659422 -240.6673) (xy 348.657426 -240.693935) (xy 348.887024 -240.693935)
			(xy 348.887024 -240.640637) (xy 348.894967 -240.587933) (xy 348.910677 -240.537003) (xy 348.933803 -240.488982)
			(xy 348.963827 -240.444945) (xy 349.000079 -240.405874) (xy 349.04175 -240.372643) (xy 349.087908 -240.345994)
			(xy 349.137522 -240.326522) (xy 349.189484 -240.314662) (xy 349.242634 -240.310679) (xy 349.295784 -240.314662)
			(xy 349.347746 -240.326522) (xy 349.39736 -240.345994) (xy 349.443518 -240.372643) (xy 349.485189 -240.405874)
			(xy 349.521441 -240.444945) (xy 349.551465 -240.488982) (xy 349.574591 -240.537003) (xy 349.590301 -240.587933)
			(xy 349.598244 -240.640637) (xy 349.598742 -240.667286) (xy 349.598244 -240.693935) (xy 349.590301 -240.746639)
			(xy 349.574591 -240.797569) (xy 349.551465 -240.84559) (xy 349.521441 -240.889627) (xy 349.485189 -240.928698)
			(xy 349.443518 -240.961929) (xy 349.39736 -240.988578) (xy 349.347746 -241.00805) (xy 349.295784 -241.01991)
			(xy 349.242634 -241.023894) (xy 349.189484 -241.01991) (xy 349.137522 -241.00805) (xy 349.087908 -240.988578)
			(xy 349.04175 -240.961929) (xy 349.000079 -240.928698) (xy 348.963827 -240.889627) (xy 348.933803 -240.84559)
			(xy 348.910677 -240.797569) (xy 348.894967 -240.746639) (xy 348.887024 -240.693935) (xy 348.657426 -240.693935)
			(xy 348.655439 -240.720448) (xy 348.64358 -240.77241) (xy 348.624109 -240.822024) (xy 348.597462 -240.868181)
			(xy 348.564233 -240.909852) (xy 348.525165 -240.946106) (xy 348.48113 -240.976132) (xy 348.433113 -240.99926)
			(xy 348.382184 -241.014974) (xy 348.329483 -241.022922) (xy 348.302834 -241.023394) (xy 348.276579 -241.022927)
			(xy 348.224638 -241.015214) (xy 348.174395 -240.99995) (xy 348.12694 -240.977468) (xy 348.083306 -240.948255)
			(xy 348.063566 -240.930938) (xy 348.052367 -240.921411) (xy 348.025896 -240.908642) (xy 347.996885 -240.903937)
			(xy 347.967735 -240.907683) (xy 347.940857 -240.919572) (xy 347.918475 -240.93862) (xy 347.902441 -240.963251)
			(xy 347.894082 -240.991427) (xy 347.89364 -241.006122) (xy 347.89364 -241.128042) (xy 347.93047 -241.13871)
			(xy 347.956379 -241.146635) (xy 348.00562 -241.169231) (xy 348.050869 -241.199026) (xy 348.091083 -241.235333)
			(xy 348.125332 -241.277312) (xy 348.152827 -241.323995) (xy 348.172932 -241.374304) (xy 348.185184 -241.427079)
			(xy 348.1893 -241.481101) (xy 348.187269 -241.507751) (xy 348.417124 -241.507751) (xy 348.417124 -241.454453)
			(xy 348.425067 -241.401749) (xy 348.440777 -241.350819) (xy 348.463903 -241.302798) (xy 348.493927 -241.258761)
			(xy 348.530179 -241.21969) (xy 348.57185 -241.186459) (xy 348.618008 -241.15981) (xy 348.667622 -241.140338)
			(xy 348.719584 -241.128478) (xy 348.772734 -241.124495) (xy 348.825884 -241.128478) (xy 348.877846 -241.140338)
			(xy 348.92746 -241.15981) (xy 348.973618 -241.186459) (xy 349.015289 -241.21969) (xy 349.051541 -241.258761)
			(xy 349.081565 -241.302798) (xy 349.104691 -241.350819) (xy 349.120401 -241.401749) (xy 349.128344 -241.454453)
			(xy 349.128842 -241.481102) (xy 349.128344 -241.507751) (xy 349.120401 -241.560455) (xy 349.104691 -241.611385)
			(xy 349.081565 -241.659406) (xy 349.051541 -241.703443) (xy 349.015289 -241.742514) (xy 348.973618 -241.775745)
			(xy 348.92746 -241.802394) (xy 348.877846 -241.821866) (xy 348.825884 -241.833726) (xy 348.772734 -241.83771)
			(xy 348.719584 -241.833726) (xy 348.667622 -241.821866) (xy 348.618008 -241.802394) (xy 348.57185 -241.775745)
			(xy 348.530179 -241.742514) (xy 348.493927 -241.703443) (xy 348.463903 -241.659406) (xy 348.440777 -241.611385)
			(xy 348.425067 -241.560455) (xy 348.417124 -241.507751) (xy 348.187269 -241.507751) (xy 348.185184 -241.535122)
			(xy 348.172932 -241.587897) (xy 348.152827 -241.638206) (xy 348.125332 -241.684889) (xy 348.091082 -241.726868)
			(xy 348.050868 -241.763174) (xy 348.005619 -241.792969) (xy 347.956378 -241.815565) (xy 347.93047 -241.823494)
			(xy 347.89364 -241.834162) (xy 347.89364 -241.956082) (xy 347.894126 -241.97077) (xy 347.902482 -241.998933)
			(xy 347.918509 -242.023552) (xy 347.940881 -242.042591) (xy 347.967747 -242.054475) (xy 347.996884 -242.05822)
			(xy 348.025881 -242.053516) (xy 348.05234 -242.040754) (xy 348.063566 -242.031266) (xy 348.083315 -242.013958)
			(xy 348.126947 -241.984742) (xy 348.174398 -241.962253) (xy 348.224639 -241.94698) (xy 348.276579 -241.939255)
			(xy 348.302834 -241.93881) (xy 348.32948 -241.939311) (xy 348.382177 -241.947258) (xy 348.433101 -241.96297)
			(xy 348.481114 -241.986096) (xy 348.525145 -242.01612) (xy 348.564209 -242.05237) (xy 348.597435 -242.094037)
			(xy 348.62408 -242.140191) (xy 348.643549 -242.1898) (xy 348.655407 -242.241756) (xy 348.659389 -242.2949)
			(xy 348.655407 -242.348044) (xy 348.643549 -242.4) (xy 348.62408 -242.449609) (xy 348.597435 -242.495763)
			(xy 348.564209 -242.53743) (xy 348.525145 -242.57368) (xy 348.481114 -242.603704) (xy 348.433101 -242.62683)
			(xy 348.382177 -242.642542) (xy 348.32948 -242.650489) (xy 348.302834 -242.651026) (xy 348.276578 -242.650559)
			(xy 348.224637 -242.642846) (xy 348.174393 -242.627584) (xy 348.126938 -242.605103) (xy 348.083302 -242.575892)
			(xy 348.063566 -242.55857) (xy 348.052363 -242.549048) (xy 348.025887 -242.536287) (xy 347.996876 -242.531586)
			(xy 347.967725 -242.535334) (xy 347.940846 -242.54722) (xy 347.918459 -242.566262) (xy 347.902415 -242.590887)
			(xy 347.894041 -242.619059) (xy 347.89364 -242.633754) (xy 347.89364 -242.755928) (xy 347.93047 -242.766596)
			(xy 347.95638 -242.774521) (xy 348.005623 -242.797118) (xy 348.050875 -242.826913) (xy 348.09109 -242.863221)
			(xy 348.125341 -242.905201) (xy 348.152837 -242.951885) (xy 348.172944 -243.002197) (xy 348.185197 -243.054973)
			(xy 348.189313 -243.108997) (xy 348.187284 -243.135637) (xy 348.41687 -243.135637) (xy 348.41687 -243.082339)
			(xy 348.424813 -243.029635) (xy 348.440523 -242.978705) (xy 348.463649 -242.930684) (xy 348.493673 -242.886647)
			(xy 348.529925 -242.847576) (xy 348.571596 -242.814345) (xy 348.617754 -242.787696) (xy 348.667368 -242.768224)
			(xy 348.71933 -242.756364) (xy 348.77248 -242.752381) (xy 348.82563 -242.756364) (xy 348.877592 -242.768224)
			(xy 348.927206 -242.787696) (xy 348.973364 -242.814345) (xy 349.015035 -242.847576) (xy 349.051287 -242.886647)
			(xy 349.081311 -242.930684) (xy 349.104437 -242.978705) (xy 349.120147 -243.029635) (xy 349.12809 -243.082339)
			(xy 349.128588 -243.108988) (xy 349.12809 -243.135637) (xy 349.35667 -243.135637) (xy 349.35667 -243.082339)
			(xy 349.364613 -243.029635) (xy 349.380323 -242.978705) (xy 349.403449 -242.930684) (xy 349.433473 -242.886647)
			(xy 349.469725 -242.847576) (xy 349.511396 -242.814345) (xy 349.557554 -242.787696) (xy 349.607168 -242.768224)
			(xy 349.65913 -242.756364) (xy 349.71228 -242.752381) (xy 349.76543 -242.756364) (xy 349.817392 -242.768224)
			(xy 349.867006 -242.787696) (xy 349.913164 -242.814345) (xy 349.954835 -242.847576) (xy 349.991087 -242.886647)
			(xy 350.021111 -242.930684) (xy 350.044237 -242.978705) (xy 350.059947 -243.029635) (xy 350.06789 -243.082339)
			(xy 350.068388 -243.108988) (xy 350.06789 -243.135637) (xy 350.059947 -243.188341) (xy 350.044237 -243.239271)
			(xy 350.021111 -243.287292) (xy 349.991087 -243.331329) (xy 349.954835 -243.3704) (xy 349.913164 -243.403631)
			(xy 349.867006 -243.43028) (xy 349.817392 -243.449752) (xy 349.76543 -243.461612) (xy 349.71228 -243.465596)
			(xy 349.65913 -243.461612) (xy 349.607168 -243.449752) (xy 349.557554 -243.43028) (xy 349.511396 -243.403631)
			(xy 349.469725 -243.3704) (xy 349.433473 -243.331329) (xy 349.403449 -243.287292) (xy 349.380323 -243.239271)
			(xy 349.364613 -243.188341) (xy 349.35667 -243.135637) (xy 349.12809 -243.135637) (xy 349.120147 -243.188341)
			(xy 349.104437 -243.239271) (xy 349.081311 -243.287292) (xy 349.051287 -243.331329) (xy 349.015035 -243.3704)
			(xy 348.973364 -243.403631) (xy 348.927206 -243.43028) (xy 348.877592 -243.449752) (xy 348.82563 -243.461612)
			(xy 348.77248 -243.465596) (xy 348.71933 -243.461612) (xy 348.667368 -243.449752) (xy 348.617754 -243.43028)
			(xy 348.571596 -243.403631) (xy 348.529925 -243.3704) (xy 348.493673 -243.331329) (xy 348.463649 -243.287292)
			(xy 348.440523 -243.239271) (xy 348.424813 -243.188341) (xy 348.41687 -243.135637) (xy 348.187284 -243.135637)
			(xy 348.185198 -243.16302) (xy 348.172946 -243.215797) (xy 348.15284 -243.266109) (xy 348.125345 -243.312794)
			(xy 348.091095 -243.354775) (xy 348.05088 -243.391082) (xy 348.005629 -243.420879) (xy 347.956386 -243.443477)
			(xy 347.93047 -243.45138) (xy 347.89364 -243.462048) (xy 347.89364 -243.583968) (xy 347.894124 -243.598658)
			(xy 347.902478 -243.626824) (xy 347.918505 -243.651447) (xy 347.940878 -243.670489) (xy 347.967746 -243.682374)
			(xy 347.996886 -243.68612) (xy 348.025886 -243.681415) (xy 348.052347 -243.668649) (xy 348.063566 -243.659152)
			(xy 348.083315 -243.641845) (xy 348.126948 -243.612629) (xy 348.174399 -243.590142) (xy 348.22464 -243.57487)
			(xy 348.276579 -243.567145) (xy 348.302834 -243.566696) (xy 348.329481 -243.567196) (xy 348.38218 -243.575144)
			(xy 348.433106 -243.590857) (xy 348.481121 -243.613984) (xy 348.525154 -243.644008) (xy 348.56422 -243.68026)
			(xy 348.597447 -243.721929) (xy 348.624093 -243.768084) (xy 348.643563 -243.817695) (xy 348.655421 -243.869654)
			(xy 348.659404 -243.9228) (xy 348.657407 -243.949453) (xy 348.88677 -243.949453) (xy 348.88677 -243.896155)
			(xy 348.894713 -243.843451) (xy 348.910423 -243.792521) (xy 348.933549 -243.7445) (xy 348.963573 -243.700463)
			(xy 348.999825 -243.661392) (xy 349.041496 -243.628161) (xy 349.087654 -243.601512) (xy 349.137268 -243.58204)
			(xy 349.18923 -243.57018) (xy 349.24238 -243.566197) (xy 349.29553 -243.57018) (xy 349.347492 -243.58204)
			(xy 349.397106 -243.601512) (xy 349.443264 -243.628161) (xy 349.484935 -243.661392) (xy 349.521187 -243.700463)
			(xy 349.551211 -243.7445) (xy 349.574337 -243.792521) (xy 349.590047 -243.843451) (xy 349.59799 -243.896155)
			(xy 349.598488 -243.922804) (xy 349.59799 -243.949453) (xy 349.826824 -243.949453) (xy 349.826824 -243.896155)
			(xy 349.834767 -243.843451) (xy 349.850477 -243.792521) (xy 349.873603 -243.7445) (xy 349.903627 -243.700463)
			(xy 349.939879 -243.661392) (xy 349.98155 -243.628161) (xy 350.027708 -243.601512) (xy 350.077322 -243.58204)
			(xy 350.129284 -243.57018) (xy 350.182434 -243.566197) (xy 350.235584 -243.57018) (xy 350.287546 -243.58204)
			(xy 350.33716 -243.601512) (xy 350.383318 -243.628161) (xy 350.424989 -243.661392) (xy 350.461241 -243.700463)
			(xy 350.491265 -243.7445) (xy 350.514391 -243.792521) (xy 350.530101 -243.843451) (xy 350.538044 -243.896155)
			(xy 350.538542 -243.922804) (xy 350.538044 -243.949453) (xy 350.530101 -244.002157) (xy 350.514391 -244.053087)
			(xy 350.491265 -244.101108) (xy 350.461241 -244.145145) (xy 350.424989 -244.184216) (xy 350.383318 -244.217447)
			(xy 350.33716 -244.244096) (xy 350.287546 -244.263568) (xy 350.235584 -244.275428) (xy 350.182434 -244.279412)
			(xy 350.129284 -244.275428) (xy 350.077322 -244.263568) (xy 350.027708 -244.244096) (xy 349.98155 -244.217447)
			(xy 349.939879 -244.184216) (xy 349.903627 -244.145145) (xy 349.873603 -244.101108) (xy 349.850477 -244.053087)
			(xy 349.834767 -244.002157) (xy 349.826824 -243.949453) (xy 349.59799 -243.949453) (xy 349.590047 -244.002157)
			(xy 349.574337 -244.053087) (xy 349.551211 -244.101108) (xy 349.521187 -244.145145) (xy 349.484935 -244.184216)
			(xy 349.443264 -244.217447) (xy 349.397106 -244.244096) (xy 349.347492 -244.263568) (xy 349.29553 -244.275428)
			(xy 349.24238 -244.279412) (xy 349.18923 -244.275428) (xy 349.137268 -244.263568) (xy 349.087654 -244.244096)
			(xy 349.041496 -244.217447) (xy 348.999825 -244.184216) (xy 348.963573 -244.145145) (xy 348.933549 -244.101108)
			(xy 348.910423 -244.053087) (xy 348.894713 -244.002157) (xy 348.88677 -243.949453) (xy 348.657407 -243.949453)
			(xy 348.655421 -243.975946) (xy 348.643563 -244.027905) (xy 348.624093 -244.077516) (xy 348.597447 -244.123671)
			(xy 348.56422 -244.16534) (xy 348.525154 -244.201592) (xy 348.481121 -244.231616) (xy 348.433106 -244.254743)
			(xy 348.38218 -244.270456) (xy 348.329481 -244.278404) (xy 348.302834 -244.278912) (xy 348.276579 -244.278445)
			(xy 348.224637 -244.270732) (xy 348.174394 -244.255469) (xy 348.126939 -244.232988) (xy 348.083304 -244.203776)
			(xy 348.063566 -244.186456) (xy 348.052368 -244.176929) (xy 348.025898 -244.164158) (xy 347.996887 -244.15945)
			(xy 347.967738 -244.163197) (xy 347.94086 -244.175087) (xy 347.91848 -244.194136) (xy 347.902449 -244.218768)
			(xy 347.894093 -244.246945) (xy 347.89364 -244.26164) (xy 347.89364 -244.38356) (xy 347.93047 -244.394228)
			(xy 347.956377 -244.402153) (xy 348.005616 -244.424749) (xy 348.050863 -244.454543) (xy 348.091074 -244.490848)
			(xy 348.125321 -244.532826) (xy 348.152814 -244.579507) (xy 348.172917 -244.629814) (xy 348.185168 -244.682586)
			(xy 348.189282 -244.736605) (xy 348.18725 -244.763269) (xy 348.41687 -244.763269) (xy 348.41687 -244.709971)
			(xy 348.424813 -244.657267) (xy 348.440523 -244.606337) (xy 348.463649 -244.558316) (xy 348.493673 -244.514279)
			(xy 348.529925 -244.475208) (xy 348.571596 -244.441977) (xy 348.617754 -244.415328) (xy 348.667368 -244.395856)
			(xy 348.71933 -244.383996) (xy 348.77248 -244.380013) (xy 348.82563 -244.383996) (xy 348.877592 -244.395856)
			(xy 348.927206 -244.415328) (xy 348.973364 -244.441977) (xy 349.015035 -244.475208) (xy 349.051287 -244.514279)
			(xy 349.081311 -244.558316) (xy 349.104437 -244.606337) (xy 349.120147 -244.657267) (xy 349.12809 -244.709971)
			(xy 349.128588 -244.73662) (xy 349.12809 -244.763269) (xy 349.35667 -244.763269) (xy 349.35667 -244.709971)
			(xy 349.364613 -244.657267) (xy 349.380323 -244.606337) (xy 349.403449 -244.558316) (xy 349.433473 -244.514279)
			(xy 349.469725 -244.475208) (xy 349.511396 -244.441977) (xy 349.557554 -244.415328) (xy 349.607168 -244.395856)
			(xy 349.65913 -244.383996) (xy 349.71228 -244.380013) (xy 349.76543 -244.383996) (xy 349.817392 -244.395856)
			(xy 349.867006 -244.415328) (xy 349.913164 -244.441977) (xy 349.954835 -244.475208) (xy 349.991087 -244.514279)
			(xy 350.021111 -244.558316) (xy 350.044237 -244.606337) (xy 350.059947 -244.657267) (xy 350.06789 -244.709971)
			(xy 350.068388 -244.73662) (xy 350.06789 -244.763269) (xy 350.059947 -244.815973) (xy 350.044237 -244.866903)
			(xy 350.021111 -244.914924) (xy 349.991087 -244.958961) (xy 349.954835 -244.998032) (xy 349.913164 -245.031263)
			(xy 349.867006 -245.057912) (xy 349.817392 -245.077384) (xy 349.76543 -245.089244) (xy 349.71228 -245.093228)
			(xy 349.65913 -245.089244) (xy 349.607168 -245.077384) (xy 349.557554 -245.057912) (xy 349.511396 -245.031263)
			(xy 349.469725 -244.998032) (xy 349.433473 -244.958961) (xy 349.403449 -244.914924) (xy 349.380323 -244.866903)
			(xy 349.364613 -244.815973) (xy 349.35667 -244.763269) (xy 349.12809 -244.763269) (xy 349.120147 -244.815973)
			(xy 349.104437 -244.866903) (xy 349.081311 -244.914924) (xy 349.051287 -244.958961) (xy 349.015035 -244.998032)
			(xy 348.973364 -245.031263) (xy 348.927206 -245.057912) (xy 348.877592 -245.077384) (xy 348.82563 -245.089244)
			(xy 348.77248 -245.093228) (xy 348.71933 -245.089244) (xy 348.667368 -245.077384) (xy 348.617754 -245.057912)
			(xy 348.571596 -245.031263) (xy 348.529925 -244.998032) (xy 348.493673 -244.958961) (xy 348.463649 -244.914924)
			(xy 348.440523 -244.866903) (xy 348.424813 -244.815973) (xy 348.41687 -244.763269) (xy 348.18725 -244.763269)
			(xy 348.185166 -244.790624) (xy 348.172914 -244.843396) (xy 348.152809 -244.893703) (xy 348.125315 -244.940383)
			(xy 348.091066 -244.98236) (xy 348.050854 -245.018664) (xy 348.005606 -245.048456) (xy 347.956367 -245.071051)
			(xy 347.93047 -245.079012) (xy 347.89364 -245.08968) (xy 347.89364 -245.211854) (xy 347.894122 -245.226545)
			(xy 347.902474 -245.254716) (xy 347.918501 -245.279342) (xy 347.940875 -245.298387) (xy 347.967745 -245.310274)
			(xy 347.996888 -245.31402) (xy 348.025891 -245.309313) (xy 348.052354 -245.296545) (xy 348.063566 -245.287038)
			(xy 348.083315 -245.269731) (xy 348.126948 -245.240517) (xy 348.1744 -245.21803) (xy 348.22464 -245.202759)
			(xy 348.276579 -245.195035) (xy 348.302834 -245.194582) (xy 348.329482 -245.195082) (xy 348.382183 -245.20303)
			(xy 348.433111 -245.218744) (xy 348.481128 -245.241872) (xy 348.525163 -245.271897) (xy 348.56423 -245.30815)
			(xy 348.597459 -245.349821) (xy 348.624105 -245.395978) (xy 348.643576 -245.445591) (xy 348.655435 -245.497552)
			(xy 348.659418 -245.5507) (xy 348.657422 -245.577339) (xy 348.887024 -245.577339) (xy 348.887024 -245.524041)
			(xy 348.894967 -245.471337) (xy 348.910677 -245.420407) (xy 348.933803 -245.372386) (xy 348.963827 -245.328349)
			(xy 349.000079 -245.289278) (xy 349.04175 -245.256047) (xy 349.087908 -245.229398) (xy 349.137522 -245.209926)
			(xy 349.189484 -245.198066) (xy 349.242634 -245.194083) (xy 349.295784 -245.198066) (xy 349.347746 -245.209926)
			(xy 349.39736 -245.229398) (xy 349.443518 -245.256047) (xy 349.485189 -245.289278) (xy 349.521441 -245.328349)
			(xy 349.551465 -245.372386) (xy 349.574591 -245.420407) (xy 349.590301 -245.471337) (xy 349.598244 -245.524041)
			(xy 349.598742 -245.55069) (xy 349.598742 -245.5507) (xy 349.825758 -245.5507) (xy 349.829742 -245.497542)
			(xy 349.841605 -245.445572) (xy 349.861081 -245.39595) (xy 349.887736 -245.349786) (xy 349.920974 -245.30811)
			(xy 349.960053 -245.271854) (xy 350.004099 -245.241828) (xy 350.052128 -245.218702) (xy 350.103068 -245.202993)
			(xy 350.15578 -245.195053) (xy 350.182434 -245.194582) (xy 350.206678 -245.194976) (xy 350.254715 -245.201571)
			(xy 350.301411 -245.214632) (xy 350.345898 -245.233919) (xy 350.366838 -245.246144) (xy 350.379547 -245.253245)
			(xy 350.407679 -245.260687) (xy 350.436768 -245.259904) (xy 350.464459 -245.25096) (xy 350.48851 -245.234579)
			(xy 350.506975 -245.212088) (xy 350.513142 -245.1989) (xy 350.52368 -245.175087) (xy 350.550714 -245.130581)
			(xy 350.56699 -245.110254) (xy 350.575635 -245.099136) (xy 350.586985 -245.073372) (xy 350.590865 -245.045488)
			(xy 350.586978 -245.017604) (xy 350.575622 -244.991843) (xy 350.56699 -244.980714) (xy 350.551587 -244.961442)
			(xy 350.525623 -244.919493) (xy 350.505699 -244.874361) (xy 350.492196 -244.826911) (xy 350.485374 -244.778051)
			(xy 350.484948 -244.753384) (xy 350.485446 -244.726735) (xy 350.493389 -244.674031) (xy 350.509099 -244.623101)
			(xy 350.532225 -244.57508) (xy 350.562249 -244.531043) (xy 350.598501 -244.491972) (xy 350.640172 -244.458741)
			(xy 350.68633 -244.432092) (xy 350.735944 -244.41262) (xy 350.787906 -244.40076) (xy 350.841056 -244.396777)
			(xy 350.894206 -244.40076) (xy 350.946168 -244.41262) (xy 350.995782 -244.432092) (xy 351.04194 -244.458741)
			(xy 351.083611 -244.491972) (xy 351.119863 -244.531043) (xy 351.149887 -244.57508) (xy 351.173013 -244.623101)
			(xy 351.188723 -244.674031) (xy 351.196666 -244.726735) (xy 351.197164 -244.753384) (xy 351.196748 -244.778053)
			(xy 351.189944 -244.826921) (xy 351.176452 -244.874378) (xy 351.156528 -244.919516) (xy 351.130558 -244.961466)
			(xy 351.115122 -244.980714) (xy 351.106514 -244.991856) (xy 351.095169 -245.017612) (xy 351.091288 -245.045488)
			(xy 351.095163 -245.073364) (xy 351.1065 -245.099123) (xy 351.115122 -245.110254) (xy 351.130558 -245.129501)
			(xy 351.156517 -245.171457) (xy 351.176434 -245.216595) (xy 351.189929 -245.264051) (xy 351.196743 -245.312915)
			(xy 351.197164 -245.337584) (xy 351.196673 -245.365571) (xy 351.187918 -245.420856) (xy 351.170621 -245.474091)
			(xy 351.145209 -245.523964) (xy 351.112308 -245.569248) (xy 351.072726 -245.608826) (xy 351.02744 -245.641724)
			(xy 350.977565 -245.667132) (xy 350.924329 -245.684424) (xy 350.869043 -245.693175) (xy 350.841056 -245.693692)
			(xy 350.816812 -245.693306) (xy 350.768774 -245.68671) (xy 350.722078 -245.673646) (xy 350.677591 -245.654357)
			(xy 350.656652 -245.64213) (xy 350.643944 -245.635029) (xy 350.615812 -245.627592) (xy 350.586724 -245.628378)
			(xy 350.559034 -245.637321) (xy 350.534983 -245.6537) (xy 350.516517 -245.676187) (xy 350.510348 -245.689374)
			(xy 350.499791 -245.713213) (xy 350.472715 -245.757767) (xy 350.439429 -245.797895) (xy 350.400645 -245.832736)
			(xy 350.357192 -245.861547) (xy 350.310001 -245.88371) (xy 350.260082 -245.89875) (xy 350.208502 -245.906347)
			(xy 350.182434 -245.906798) (xy 350.15578 -245.906347) (xy 350.103068 -245.898407) (xy 350.052128 -245.882698)
			(xy 350.004099 -245.859572) (xy 349.960053 -245.829546) (xy 349.920974 -245.79329) (xy 349.887736 -245.751614)
			(xy 349.861081 -245.70545) (xy 349.841605 -245.655828) (xy 349.829742 -245.603858) (xy 349.825758 -245.5507)
			(xy 349.598742 -245.5507) (xy 349.598244 -245.577339) (xy 349.590301 -245.630043) (xy 349.574591 -245.680973)
			(xy 349.551465 -245.728994) (xy 349.521441 -245.773031) (xy 349.485189 -245.812102) (xy 349.443518 -245.845333)
			(xy 349.39736 -245.871982) (xy 349.347746 -245.891454) (xy 349.295784 -245.903314) (xy 349.242634 -245.907298)
			(xy 349.189484 -245.903314) (xy 349.137522 -245.891454) (xy 349.087908 -245.871982) (xy 349.04175 -245.845333)
			(xy 349.000079 -245.812102) (xy 348.963827 -245.773031) (xy 348.933803 -245.728994) (xy 348.910677 -245.680973)
			(xy 348.894967 -245.630043) (xy 348.887024 -245.577339) (xy 348.657422 -245.577339) (xy 348.655435 -245.603848)
			(xy 348.643576 -245.655809) (xy 348.624105 -245.705422) (xy 348.597459 -245.751579) (xy 348.56423 -245.79325)
			(xy 348.525163 -245.829503) (xy 348.481128 -245.859528) (xy 348.433111 -245.882656) (xy 348.382183 -245.89837)
			(xy 348.329482 -245.906318) (xy 348.302834 -245.906798) (xy 348.276579 -245.906331) (xy 348.224638 -245.898618)
			(xy 348.174394 -245.883355) (xy 348.12694 -245.860872) (xy 348.083306 -245.831659) (xy 348.063566 -245.814342)
			(xy 348.052367 -245.804815) (xy 348.025896 -245.792046) (xy 347.996885 -245.78734) (xy 347.967735 -245.791086)
			(xy 347.940858 -245.802975) (xy 347.918476 -245.822024) (xy 347.902443 -245.846655) (xy 347.894084 -245.874831)
			(xy 347.89364 -245.889526) (xy 347.89364 -246.011446) (xy 347.93047 -246.022114) (xy 347.956379 -246.030039)
			(xy 348.005619 -246.052635) (xy 348.050868 -246.08243) (xy 348.091081 -246.118736) (xy 348.12533 -246.160715)
			(xy 348.152824 -246.207398) (xy 348.172929 -246.257707) (xy 348.18518 -246.310481) (xy 348.189296 -246.364502)
			(xy 348.187265 -246.391155) (xy 348.417124 -246.391155) (xy 348.417124 -246.337857) (xy 348.425067 -246.285153)
			(xy 348.440777 -246.234223) (xy 348.463903 -246.186202) (xy 348.493927 -246.142165) (xy 348.530179 -246.103094)
			(xy 348.57185 -246.069863) (xy 348.618008 -246.043214) (xy 348.667622 -246.023742) (xy 348.719584 -246.011882)
			(xy 348.772734 -246.007899) (xy 348.825884 -246.011882) (xy 348.877846 -246.023742) (xy 348.92746 -246.043214)
			(xy 348.973618 -246.069863) (xy 349.015289 -246.103094) (xy 349.051541 -246.142165) (xy 349.081565 -246.186202)
			(xy 349.104691 -246.234223) (xy 349.120401 -246.285153) (xy 349.128344 -246.337857) (xy 349.128842 -246.364506)
			(xy 349.128344 -246.391155) (xy 349.35667 -246.391155) (xy 349.35667 -246.337857) (xy 349.364613 -246.285153)
			(xy 349.380323 -246.234223) (xy 349.403449 -246.186202) (xy 349.433473 -246.142165) (xy 349.469725 -246.103094)
			(xy 349.511396 -246.069863) (xy 349.557554 -246.043214) (xy 349.607168 -246.023742) (xy 349.65913 -246.011882)
			(xy 349.71228 -246.007899) (xy 349.76543 -246.011882) (xy 349.817392 -246.023742) (xy 349.867006 -246.043214)
			(xy 349.913164 -246.069863) (xy 349.954835 -246.103094) (xy 349.991087 -246.142165) (xy 350.021111 -246.186202)
			(xy 350.044237 -246.234223) (xy 350.059947 -246.285153) (xy 350.06789 -246.337857) (xy 350.068388 -246.364506)
			(xy 350.06789 -246.391155) (xy 350.059947 -246.443859) (xy 350.044237 -246.494789) (xy 350.021111 -246.54281)
			(xy 349.991087 -246.586847) (xy 349.954835 -246.625918) (xy 349.913164 -246.659149) (xy 349.867006 -246.685798)
			(xy 349.817392 -246.70527) (xy 349.76543 -246.71713) (xy 349.71228 -246.721114) (xy 349.65913 -246.71713)
			(xy 349.607168 -246.70527) (xy 349.557554 -246.685798) (xy 349.511396 -246.659149) (xy 349.469725 -246.625918)
			(xy 349.433473 -246.586847) (xy 349.403449 -246.54281) (xy 349.380323 -246.494789) (xy 349.364613 -246.443859)
			(xy 349.35667 -246.391155) (xy 349.128344 -246.391155) (xy 349.120401 -246.443859) (xy 349.104691 -246.494789)
			(xy 349.081565 -246.54281) (xy 349.051541 -246.586847) (xy 349.015289 -246.625918) (xy 348.973618 -246.659149)
			(xy 348.92746 -246.685798) (xy 348.877846 -246.70527) (xy 348.825884 -246.71713) (xy 348.772734 -246.721114)
			(xy 348.719584 -246.71713) (xy 348.667622 -246.70527) (xy 348.618008 -246.685798) (xy 348.57185 -246.659149)
			(xy 348.530179 -246.625918) (xy 348.493927 -246.586847) (xy 348.463903 -246.54281) (xy 348.440777 -246.494789)
			(xy 348.425067 -246.443859) (xy 348.417124 -246.391155) (xy 348.187265 -246.391155) (xy 348.18518 -246.418523)
			(xy 348.172928 -246.471297) (xy 348.152823 -246.521605) (xy 348.125328 -246.568288) (xy 348.091079 -246.610266)
			(xy 348.050865 -246.646572) (xy 348.005616 -246.676366) (xy 347.956375 -246.698962) (xy 347.93047 -246.706898)
			(xy 347.89364 -246.717566) (xy 347.89364 -246.839486) (xy 347.894126 -246.854174) (xy 347.902483 -246.882336)
			(xy 347.918511 -246.906954) (xy 347.940882 -246.925992) (xy 347.967747 -246.937875) (xy 347.996883 -246.94162)
			(xy 348.02588 -246.936917) (xy 348.052338 -246.924155) (xy 348.063566 -246.91467) (xy 348.083315 -246.897362)
			(xy 348.126947 -246.868145) (xy 348.174398 -246.845656) (xy 348.224639 -246.830383) (xy 348.276579 -246.822658)
			(xy 348.302834 -246.822214) (xy 348.32948 -246.822715) (xy 348.382176 -246.830662) (xy 348.433099 -246.846374)
			(xy 348.481112 -246.8695) (xy 348.525142 -246.899523) (xy 348.564206 -246.935772) (xy 348.597432 -246.977439)
			(xy 348.624076 -247.023592) (xy 348.643545 -247.073201) (xy 348.655403 -247.125157) (xy 348.659385 -247.1783)
			(xy 348.657387 -247.204971) (xy 348.887024 -247.204971) (xy 348.887024 -247.151673) (xy 348.894967 -247.098969)
			(xy 348.910677 -247.048039) (xy 348.933803 -247.000018) (xy 348.963827 -246.955981) (xy 349.000079 -246.91691)
			(xy 349.04175 -246.883679) (xy 349.087908 -246.85703) (xy 349.137522 -246.837558) (xy 349.189484 -246.825698)
			(xy 349.242634 -246.821715) (xy 349.295784 -246.825698) (xy 349.347746 -246.837558) (xy 349.39736 -246.85703)
			(xy 349.443518 -246.883679) (xy 349.485189 -246.91691) (xy 349.521441 -246.955981) (xy 349.551465 -247.000018)
			(xy 349.574591 -247.048039) (xy 349.590301 -247.098969) (xy 349.598244 -247.151673) (xy 349.598742 -247.178322)
			(xy 349.598244 -247.204971) (xy 349.826824 -247.204971) (xy 349.826824 -247.151673) (xy 349.834767 -247.098969)
			(xy 349.850477 -247.048039) (xy 349.873603 -247.000018) (xy 349.903627 -246.955981) (xy 349.939879 -246.91691)
			(xy 349.98155 -246.883679) (xy 350.027708 -246.85703) (xy 350.077322 -246.837558) (xy 350.129284 -246.825698)
			(xy 350.182434 -246.821715) (xy 350.235584 -246.825698) (xy 350.287546 -246.837558) (xy 350.33716 -246.85703)
			(xy 350.383318 -246.883679) (xy 350.424989 -246.91691) (xy 350.461241 -246.955981) (xy 350.491265 -247.000018)
			(xy 350.514391 -247.048039) (xy 350.530101 -247.098969) (xy 350.538044 -247.151673) (xy 350.538542 -247.178322)
			(xy 350.538044 -247.204971) (xy 350.530101 -247.257675) (xy 350.514391 -247.308605) (xy 350.491265 -247.356626)
			(xy 350.461241 -247.400663) (xy 350.424989 -247.439734) (xy 350.383318 -247.472965) (xy 350.33716 -247.499614)
			(xy 350.287546 -247.519086) (xy 350.235584 -247.530946) (xy 350.182434 -247.53493) (xy 350.129284 -247.530946)
			(xy 350.077322 -247.519086) (xy 350.027708 -247.499614) (xy 349.98155 -247.472965) (xy 349.939879 -247.439734)
			(xy 349.903627 -247.400663) (xy 349.873603 -247.356626) (xy 349.850477 -247.308605) (xy 349.834767 -247.257675)
			(xy 349.826824 -247.204971) (xy 349.598244 -247.204971) (xy 349.590301 -247.257675) (xy 349.574591 -247.308605)
			(xy 349.551465 -247.356626) (xy 349.521441 -247.400663) (xy 349.485189 -247.439734) (xy 349.443518 -247.472965)
			(xy 349.39736 -247.499614) (xy 349.347746 -247.519086) (xy 349.295784 -247.530946) (xy 349.242634 -247.53493)
			(xy 349.189484 -247.530946) (xy 349.137522 -247.519086) (xy 349.087908 -247.499614) (xy 349.04175 -247.472965)
			(xy 349.000079 -247.439734) (xy 348.963827 -247.400663) (xy 348.933803 -247.356626) (xy 348.910677 -247.308605)
			(xy 348.894967 -247.257675) (xy 348.887024 -247.204971) (xy 348.657387 -247.204971) (xy 348.655403 -247.231443)
			(xy 348.643545 -247.283399) (xy 348.624076 -247.333008) (xy 348.597432 -247.379161) (xy 348.564206 -247.420828)
			(xy 348.525142 -247.457077) (xy 348.481112 -247.4871) (xy 348.433099 -247.510226) (xy 348.382176 -247.525938)
			(xy 348.32948 -247.533885) (xy 348.302834 -247.53443) (xy 348.276578 -247.533963) (xy 348.224637 -247.526251)
			(xy 348.174393 -247.510988) (xy 348.126937 -247.488508) (xy 348.083301 -247.459297) (xy 348.063566 -247.441974)
			(xy 348.052363 -247.432452) (xy 348.025888 -247.41969) (xy 347.996876 -247.414989) (xy 347.967726 -247.418737)
			(xy 347.940846 -247.430623) (xy 347.91846 -247.449666) (xy 347.902417 -247.474291) (xy 347.894043 -247.502463)
			(xy 347.89364 -247.517158) (xy 347.89364 -247.639078) (xy 347.93047 -247.649746) (xy 347.956376 -247.657671)
			(xy 348.005612 -247.680266) (xy 348.050856 -247.71006) (xy 348.091065 -247.746364) (xy 348.12531 -247.78834)
			(xy 348.1528 -247.835019) (xy 348.172902 -247.885324) (xy 348.185151 -247.938094) (xy 348.189265 -247.99211)
			(xy 348.187232 -248.018787) (xy 348.41687 -248.018787) (xy 348.41687 -247.965489) (xy 348.424813 -247.912785)
			(xy 348.440523 -247.861855) (xy 348.463649 -247.813834) (xy 348.493673 -247.769797) (xy 348.529925 -247.730726)
			(xy 348.571596 -247.697495) (xy 348.617754 -247.670846) (xy 348.667368 -247.651374) (xy 348.71933 -247.639514)
			(xy 348.77248 -247.635531) (xy 348.82563 -247.639514) (xy 348.877592 -247.651374) (xy 348.927206 -247.670846)
			(xy 348.973364 -247.697495) (xy 349.015035 -247.730726) (xy 349.051287 -247.769797) (xy 349.081311 -247.813834)
			(xy 349.104437 -247.861855) (xy 349.120147 -247.912785) (xy 349.12809 -247.965489) (xy 349.128588 -247.992138)
			(xy 349.12809 -248.018787) (xy 349.35667 -248.018787) (xy 349.35667 -247.965489) (xy 349.364613 -247.912785)
			(xy 349.380323 -247.861855) (xy 349.403449 -247.813834) (xy 349.433473 -247.769797) (xy 349.469725 -247.730726)
			(xy 349.511396 -247.697495) (xy 349.557554 -247.670846) (xy 349.607168 -247.651374) (xy 349.65913 -247.639514)
			(xy 349.71228 -247.635531) (xy 349.76543 -247.639514) (xy 349.817392 -247.651374) (xy 349.867006 -247.670846)
			(xy 349.913164 -247.697495) (xy 349.954835 -247.730726) (xy 349.991087 -247.769797) (xy 350.021111 -247.813834)
			(xy 350.044237 -247.861855) (xy 350.059947 -247.912785) (xy 350.06789 -247.965489) (xy 350.068388 -247.992138)
			(xy 350.06789 -248.018787) (xy 350.059947 -248.071491) (xy 350.044237 -248.122421) (xy 350.021111 -248.170442)
			(xy 349.991087 -248.214479) (xy 349.954835 -248.25355) (xy 349.913164 -248.286781) (xy 349.867006 -248.31343)
			(xy 349.817392 -248.332902) (xy 349.76543 -248.344762) (xy 349.71228 -248.348746) (xy 349.65913 -248.344762)
			(xy 349.607168 -248.332902) (xy 349.557554 -248.31343) (xy 349.511396 -248.286781) (xy 349.469725 -248.25355)
			(xy 349.433473 -248.214479) (xy 349.403449 -248.170442) (xy 349.380323 -248.122421) (xy 349.364613 -248.071491)
			(xy 349.35667 -248.018787) (xy 349.12809 -248.018787) (xy 349.120147 -248.071491) (xy 349.104437 -248.122421)
			(xy 349.081311 -248.170442) (xy 349.051287 -248.214479) (xy 349.015035 -248.25355) (xy 348.973364 -248.286781)
			(xy 348.927206 -248.31343) (xy 348.877592 -248.332902) (xy 348.82563 -248.344762) (xy 348.77248 -248.348746)
			(xy 348.71933 -248.344762) (xy 348.667368 -248.332902) (xy 348.617754 -248.31343) (xy 348.571596 -248.286781)
			(xy 348.529925 -248.25355) (xy 348.493673 -248.214479) (xy 348.463649 -248.170442) (xy 348.440523 -248.122421)
			(xy 348.424813 -248.071491) (xy 348.41687 -248.018787) (xy 348.187232 -248.018787) (xy 348.185148 -248.046127)
			(xy 348.172896 -248.098896) (xy 348.152791 -248.1492) (xy 348.125298 -248.195877) (xy 348.09105 -248.237851)
			(xy 348.050839 -248.274153) (xy 348.005593 -248.303944) (xy 347.956357 -248.326536) (xy 347.93047 -248.33453)
			(xy 347.89364 -248.345198) (xy 347.89364 -248.467372) (xy 347.894124 -248.482061) (xy 347.902479 -248.510227)
			(xy 347.918506 -248.534849) (xy 347.940879 -248.55389) (xy 347.967746 -248.565775) (xy 347.996885 -248.56952)
			(xy 348.025885 -248.564815) (xy 348.052345 -248.55205) (xy 348.063566 -248.542556) (xy 348.083315 -248.525249)
			(xy 348.126947 -248.496033) (xy 348.174399 -248.473545) (xy 348.22464 -248.458273) (xy 348.276579 -248.450548)
			(xy 348.302834 -248.4501) (xy 348.329481 -248.4506) (xy 348.382179 -248.458548) (xy 348.433105 -248.47426)
			(xy 348.481119 -248.497387) (xy 348.525151 -248.527411) (xy 348.564217 -248.563663) (xy 348.597444 -248.605331)
			(xy 348.624089 -248.651486) (xy 348.643559 -248.701097) (xy 348.655417 -248.753055) (xy 348.6594 -248.8062)
			(xy 348.657402 -248.832857) (xy 348.88677 -248.832857) (xy 348.88677 -248.779559) (xy 348.894713 -248.726855)
			(xy 348.910423 -248.675925) (xy 348.933549 -248.627904) (xy 348.963573 -248.583867) (xy 348.999825 -248.544796)
			(xy 349.041496 -248.511565) (xy 349.087654 -248.484916) (xy 349.137268 -248.465444) (xy 349.18923 -248.453584)
			(xy 349.24238 -248.449601) (xy 349.29553 -248.453584) (xy 349.347492 -248.465444) (xy 349.397106 -248.484916)
			(xy 349.443264 -248.511565) (xy 349.484935 -248.544796) (xy 349.521187 -248.583867) (xy 349.551211 -248.627904)
			(xy 349.574337 -248.675925) (xy 349.590047 -248.726855) (xy 349.59799 -248.779559) (xy 349.598488 -248.8062)
			(xy 349.825776 -248.8062) (xy 349.82976 -248.753045) (xy 349.841622 -248.701077) (xy 349.861097 -248.651458)
			(xy 349.887751 -248.605296) (xy 349.920987 -248.563622) (xy 349.960064 -248.527368) (xy 350.004108 -248.497343)
			(xy 350.052135 -248.474219) (xy 350.103072 -248.458511) (xy 350.155782 -248.450571) (xy 350.182434 -248.4501)
			(xy 350.211256 -248.450674) (xy 350.268148 -248.459956) (xy 350.322799 -248.478289) (xy 350.34855 -248.491248)
			(xy 350.361932 -248.497705) (xy 350.391094 -248.503339) (xy 350.420645 -248.500353) (xy 350.448091 -248.488999)
			(xy 350.471115 -248.470236) (xy 350.479868 -248.458228) (xy 350.494148 -248.437928) (xy 350.527464 -248.401138)
			(xy 350.565561 -248.369324) (xy 350.607701 -248.343101) (xy 350.65307 -248.322976) (xy 350.700793 -248.309337)
			(xy 350.749946 -248.302449) (xy 350.774762 -248.302018) (xy 350.802748 -248.302548) (xy 350.85803 -248.311299)
			(xy 350.911263 -248.328591) (xy 350.961135 -248.353999) (xy 351.006418 -248.386896) (xy 351.045996 -248.426473)
			(xy 351.078895 -248.471754) (xy 351.104305 -248.521626) (xy 351.121599 -248.574858) (xy 351.130351 -248.63014)
			(xy 351.13087 -248.658126) (xy 351.130477 -248.682796) (xy 351.123668 -248.731664) (xy 351.11017 -248.779122)
			(xy 351.090241 -248.824259) (xy 351.064266 -248.866209) (xy 351.048828 -248.885456) (xy 351.040179 -248.896569)
			(xy 351.02884 -248.922336) (xy 351.024965 -248.95022) (xy 351.028851 -248.978103) (xy 351.0402 -249.003865)
			(xy 351.048828 -249.014996) (xy 351.064238 -249.034263) (xy 351.0902 -249.076213) (xy 351.110123 -249.121347)
			(xy 351.123624 -249.168798) (xy 351.130445 -249.217659) (xy 351.13087 -249.242326) (xy 351.130412 -249.270314)
			(xy 351.121651 -249.3256) (xy 351.104349 -249.378835) (xy 351.078932 -249.428708) (xy 351.046027 -249.473991)
			(xy 351.006442 -249.513568) (xy 350.961153 -249.546466) (xy 350.911276 -249.571874) (xy 350.858038 -249.589166)
			(xy 350.80275 -249.597917) (xy 350.774762 -249.598434) (xy 350.74683 -249.5979) (xy 350.691651 -249.589171)
			(xy 350.638512 -249.571935) (xy 350.588716 -249.546613) (xy 350.543485 -249.513826) (xy 350.503927 -249.47438)
			(xy 350.471013 -249.429241) (xy 350.445551 -249.379516) (xy 350.428164 -249.326426) (xy 350.419281 -249.271273)
			(xy 350.418654 -249.243342) (xy 350.418159 -249.229773) (xy 350.410917 -249.203616) (xy 350.39704 -249.180291)
			(xy 350.377509 -249.161446) (xy 350.353703 -249.148411) (xy 350.327304 -249.142108) (xy 350.300177 -249.142982)
			(xy 350.287082 -249.146568) (xy 350.261551 -249.153939) (xy 350.209004 -249.161849) (xy 350.182434 -249.162316)
			(xy 350.155782 -249.161829) (xy 350.103072 -249.153889) (xy 350.052135 -249.138181) (xy 350.004108 -249.115057)
			(xy 349.960064 -249.085032) (xy 349.920987 -249.048778) (xy 349.887751 -249.007104) (xy 349.861097 -248.960942)
			(xy 349.841622 -248.911323) (xy 349.82976 -248.859355) (xy 349.825776 -248.8062) (xy 349.598488 -248.8062)
			(xy 349.598488 -248.806208) (xy 349.59799 -248.832857) (xy 349.590047 -248.885561) (xy 349.574337 -248.936491)
			(xy 349.551211 -248.984512) (xy 349.521187 -249.028549) (xy 349.484935 -249.06762) (xy 349.443264 -249.100851)
			(xy 349.397106 -249.1275) (xy 349.347492 -249.146972) (xy 349.29553 -249.158832) (xy 349.24238 -249.162816)
			(xy 349.18923 -249.158832) (xy 349.137268 -249.146972) (xy 349.087654 -249.1275) (xy 349.041496 -249.100851)
			(xy 348.999825 -249.06762) (xy 348.963573 -249.028549) (xy 348.933549 -248.984512) (xy 348.910423 -248.936491)
			(xy 348.894713 -248.885561) (xy 348.88677 -248.832857) (xy 348.657402 -248.832857) (xy 348.655417 -248.859345)
			(xy 348.643559 -248.911303) (xy 348.624089 -248.960914) (xy 348.597444 -249.007069) (xy 348.564217 -249.048737)
			(xy 348.525151 -249.084989) (xy 348.481119 -249.115013) (xy 348.433105 -249.13814) (xy 348.382179 -249.153852)
			(xy 348.329481 -249.1618) (xy 348.302834 -249.162316) (xy 348.276579 -249.161849) (xy 348.224637 -249.154136)
			(xy 348.174394 -249.138874) (xy 348.126939 -249.116392) (xy 348.083303 -249.08718) (xy 348.063566 -249.06986)
			(xy 348.052362 -249.060339) (xy 348.025886 -249.047579) (xy 347.996874 -249.042879) (xy 347.967724 -249.046626)
			(xy 347.940844 -249.058512) (xy 347.918457 -249.077554) (xy 347.902412 -249.102178) (xy 347.894035 -249.130349)
			(xy 347.89364 -249.145044) (xy 347.89364 -249.266964) (xy 347.93047 -249.277632) (xy 347.956377 -249.285557)
			(xy 348.005615 -249.308153) (xy 348.050861 -249.337947) (xy 348.091072 -249.374252) (xy 348.125318 -249.416229)
			(xy 348.152811 -249.46291) (xy 348.172914 -249.513216) (xy 348.185164 -249.565988) (xy 348.189279 -249.620007)
			(xy 348.187247 -249.646673) (xy 348.41687 -249.646673) (xy 348.41687 -249.593375) (xy 348.424813 -249.540671)
			(xy 348.440523 -249.489741) (xy 348.463649 -249.44172) (xy 348.493673 -249.397683) (xy 348.529925 -249.358612)
			(xy 348.571596 -249.325381) (xy 348.617754 -249.298732) (xy 348.667368 -249.27926) (xy 348.71933 -249.2674)
			(xy 348.77248 -249.263417) (xy 348.82563 -249.2674) (xy 348.877592 -249.27926) (xy 348.927206 -249.298732)
			(xy 348.973364 -249.325381) (xy 349.015035 -249.358612) (xy 349.051287 -249.397683) (xy 349.081311 -249.44172)
			(xy 349.104437 -249.489741) (xy 349.120147 -249.540671) (xy 349.12809 -249.593375) (xy 349.128588 -249.620024)
			(xy 349.12809 -249.646673) (xy 349.35667 -249.646673) (xy 349.35667 -249.593375) (xy 349.364613 -249.540671)
			(xy 349.380323 -249.489741) (xy 349.403449 -249.44172) (xy 349.433473 -249.397683) (xy 349.469725 -249.358612)
			(xy 349.511396 -249.325381) (xy 349.557554 -249.298732) (xy 349.607168 -249.27926) (xy 349.65913 -249.2674)
			(xy 349.71228 -249.263417) (xy 349.76543 -249.2674) (xy 349.817392 -249.27926) (xy 349.867006 -249.298732)
			(xy 349.913164 -249.325381) (xy 349.954835 -249.358612) (xy 349.991087 -249.397683) (xy 350.021111 -249.44172)
			(xy 350.044237 -249.489741) (xy 350.059947 -249.540671) (xy 350.06789 -249.593375) (xy 350.068388 -249.620024)
			(xy 350.06789 -249.646673) (xy 350.059947 -249.699377) (xy 350.044237 -249.750307) (xy 350.021111 -249.798328)
			(xy 349.991087 -249.842365) (xy 349.954835 -249.881436) (xy 349.913164 -249.914667) (xy 349.867006 -249.941316)
			(xy 349.817392 -249.960788) (xy 349.76543 -249.972648) (xy 349.71228 -249.976632) (xy 349.65913 -249.972648)
			(xy 349.607168 -249.960788) (xy 349.557554 -249.941316) (xy 349.511396 -249.914667) (xy 349.469725 -249.881436)
			(xy 349.433473 -249.842365) (xy 349.403449 -249.798328) (xy 349.380323 -249.750307) (xy 349.364613 -249.699377)
			(xy 349.35667 -249.646673) (xy 349.12809 -249.646673) (xy 349.120147 -249.699377) (xy 349.104437 -249.750307)
			(xy 349.081311 -249.798328) (xy 349.051287 -249.842365) (xy 349.015035 -249.881436) (xy 348.973364 -249.914667)
			(xy 348.927206 -249.941316) (xy 348.877592 -249.960788) (xy 348.82563 -249.972648) (xy 348.77248 -249.976632)
			(xy 348.71933 -249.972648) (xy 348.667368 -249.960788) (xy 348.617754 -249.941316) (xy 348.571596 -249.914667)
			(xy 348.529925 -249.881436) (xy 348.493673 -249.842365) (xy 348.463649 -249.798328) (xy 348.440523 -249.750307)
			(xy 348.424813 -249.699377) (xy 348.41687 -249.646673) (xy 348.187247 -249.646673) (xy 348.185162 -249.674025)
			(xy 348.17291 -249.726796) (xy 348.152805 -249.777102) (xy 348.125311 -249.823782) (xy 348.091063 -249.865758)
			(xy 348.050851 -249.902061) (xy 348.005603 -249.931854) (xy 347.956365 -249.954448) (xy 347.93047 -249.962416)
			(xy 347.89364 -249.973084) (xy 347.89364 -251.135134) (xy 350.418654 -251.135134) (xy 350.419076 -251.110465)
			(xy 350.425878 -251.061598) (xy 350.439369 -251.01414) (xy 350.459291 -250.969002) (xy 350.485261 -250.927052)
			(xy 350.500696 -250.907804) (xy 350.509293 -250.896652) (xy 350.520649 -250.870901) (xy 350.524537 -250.843026)
			(xy 350.520663 -250.81515) (xy 350.509321 -250.789392) (xy 350.500696 -250.778264) (xy 350.485271 -250.759009)
			(xy 350.45931 -250.717055) (xy 350.43939 -250.671919) (xy 350.425893 -250.624465) (xy 350.419076 -250.575602)
			(xy 350.418654 -250.550934) (xy 350.419152 -250.524285) (xy 350.427095 -250.471581) (xy 350.442805 -250.420651)
			(xy 350.465931 -250.37263) (xy 350.495955 -250.328593) (xy 350.532207 -250.289522) (xy 350.573878 -250.256291)
			(xy 350.620036 -250.229642) (xy 350.66965 -250.21017) (xy 350.721612 -250.19831) (xy 350.774762 -250.194327)
			(xy 350.827912 -250.19831) (xy 350.879874 -250.21017) (xy 350.929488 -250.229642) (xy 350.975646 -250.256291)
			(xy 351.017317 -250.289522) (xy 351.053569 -250.328593) (xy 351.083593 -250.37263) (xy 351.106719 -250.420651)
			(xy 351.122429 -250.471581) (xy 351.130372 -250.524285) (xy 351.13087 -250.550934) (xy 351.130424 -250.575602)
			(xy 351.123628 -250.624468) (xy 351.110141 -250.671926) (xy 351.090225 -250.717063) (xy 351.064261 -250.759015)
			(xy 351.048828 -250.778264) (xy 351.040172 -250.789372) (xy 351.028833 -250.815141) (xy 351.02496 -250.843026)
			(xy 351.028847 -250.87091) (xy 351.040199 -250.896673) (xy 351.048828 -250.907804) (xy 351.064242 -250.927068)
			(xy 351.090204 -250.969019) (xy 351.110125 -251.014153) (xy 351.123626 -251.061605) (xy 351.130445 -251.110467)
			(xy 351.13087 -251.135134) (xy 351.130372 -251.161783) (xy 351.122429 -251.214487) (xy 351.106719 -251.265417)
			(xy 351.083593 -251.313438) (xy 351.053569 -251.357475) (xy 351.017317 -251.396546) (xy 350.975646 -251.429777)
			(xy 350.929488 -251.456426) (xy 350.879874 -251.475898) (xy 350.827912 -251.487758) (xy 350.774762 -251.491742)
			(xy 350.721612 -251.487758) (xy 350.66965 -251.475898) (xy 350.620036 -251.456426) (xy 350.573878 -251.429777)
			(xy 350.532207 -251.396546) (xy 350.495955 -251.357475) (xy 350.465931 -251.313438) (xy 350.442805 -251.265417)
			(xy 350.427095 -251.214487) (xy 350.419152 -251.161783) (xy 350.418654 -251.135134) (xy 347.89364 -251.135134)
			(xy 347.89364 -252.798834) (xy 350.479614 -252.798834) (xy 350.480045 -252.774165) (xy 350.486845 -252.725299)
			(xy 350.500335 -252.677841) (xy 350.520255 -252.632704) (xy 350.546222 -252.590753) (xy 350.561656 -252.571504)
			(xy 350.570249 -252.56035) (xy 350.581597 -252.534598) (xy 350.585484 -252.506726) (xy 350.581612 -252.478852)
			(xy 350.570276 -252.453094) (xy 350.561656 -252.441964) (xy 350.546225 -252.422714) (xy 350.520266 -252.380758)
			(xy 350.500348 -252.335621) (xy 350.486852 -252.288166) (xy 350.480036 -252.239302) (xy 350.479614 -252.214634)
			(xy 350.480112 -252.187985) (xy 350.488055 -252.135281) (xy 350.503765 -252.084351) (xy 350.526891 -252.03633)
			(xy 350.556915 -251.992293) (xy 350.593167 -251.953222) (xy 350.634838 -251.919991) (xy 350.680996 -251.893342)
			(xy 350.73061 -251.87387) (xy 350.782572 -251.86201) (xy 350.835722 -251.858027) (xy 350.888872 -251.86201)
			(xy 350.940834 -251.87387) (xy 350.990448 -251.893342) (xy 351.036606 -251.919991) (xy 351.078277 -251.953222)
			(xy 351.114529 -251.992293) (xy 351.144553 -252.03633) (xy 351.167679 -252.084351) (xy 351.183389 -252.135281)
			(xy 351.191332 -252.187985) (xy 351.19183 -252.214634) (xy 351.191393 -252.239303) (xy 351.184596 -252.288169)
			(xy 351.171108 -252.335627) (xy 351.151189 -252.380765) (xy 351.125222 -252.422716) (xy 351.109788 -252.441964)
			(xy 351.101128 -252.45307) (xy 351.089782 -252.478839) (xy 351.085907 -252.506726) (xy 351.089797 -252.534612)
			(xy 351.101155 -252.560375) (xy 351.109788 -252.571504) (xy 351.125211 -252.590761) (xy 351.15117 -252.632715)
			(xy 351.171089 -252.677851) (xy 351.184587 -252.725304) (xy 351.191406 -252.774166) (xy 351.19183 -252.798834)
			(xy 351.191332 -252.825483) (xy 351.183389 -252.878187) (xy 351.167679 -252.929117) (xy 351.144553 -252.977138)
			(xy 351.114529 -253.021175) (xy 351.078277 -253.060246) (xy 351.036606 -253.093477) (xy 350.990448 -253.120126)
			(xy 350.940834 -253.139598) (xy 350.888872 -253.151458) (xy 350.835722 -253.155442) (xy 350.782572 -253.151458)
			(xy 350.73061 -253.139598) (xy 350.680996 -253.120126) (xy 350.634838 -253.093477) (xy 350.593167 -253.060246)
			(xy 350.556915 -253.021175) (xy 350.526891 -252.977138) (xy 350.503765 -252.929117) (xy 350.488055 -252.878187)
			(xy 350.480112 -252.825483) (xy 350.479614 -252.798834) (xy 347.89364 -252.798834) (xy 347.89364 -253.946385)
			(xy 348.057206 -253.946385) (xy 348.057206 -253.893087) (xy 348.065149 -253.840383) (xy 348.080859 -253.789453)
			(xy 348.103985 -253.741432) (xy 348.134009 -253.697395) (xy 348.170261 -253.658324) (xy 348.211932 -253.625093)
			(xy 348.25809 -253.598444) (xy 348.307704 -253.578972) (xy 348.359666 -253.567112) (xy 348.412816 -253.563129)
			(xy 348.465966 -253.567112) (xy 348.517928 -253.578972) (xy 348.567542 -253.598444) (xy 348.6137 -253.625093)
			(xy 348.655371 -253.658324) (xy 348.691623 -253.697395) (xy 348.721647 -253.741432) (xy 348.744773 -253.789453)
			(xy 348.760483 -253.840383) (xy 348.768426 -253.893087) (xy 348.768924 -253.919736) (xy 348.768426 -253.946385)
			(xy 348.997006 -253.946385) (xy 348.997006 -253.893087) (xy 349.004949 -253.840383) (xy 349.020659 -253.789453)
			(xy 349.043785 -253.741432) (xy 349.073809 -253.697395) (xy 349.110061 -253.658324) (xy 349.151732 -253.625093)
			(xy 349.19789 -253.598444) (xy 349.247504 -253.578972) (xy 349.299466 -253.567112) (xy 349.352616 -253.563129)
			(xy 349.405766 -253.567112) (xy 349.457728 -253.578972) (xy 349.507342 -253.598444) (xy 349.5535 -253.625093)
			(xy 349.595171 -253.658324) (xy 349.631423 -253.697395) (xy 349.661447 -253.741432) (xy 349.684573 -253.789453)
			(xy 349.700283 -253.840383) (xy 349.708226 -253.893087) (xy 349.708724 -253.919736) (xy 349.708226 -253.946385)
			(xy 349.936806 -253.946385) (xy 349.936806 -253.893087) (xy 349.944749 -253.840383) (xy 349.960459 -253.789453)
			(xy 349.983585 -253.741432) (xy 350.013609 -253.697395) (xy 350.049861 -253.658324) (xy 350.091532 -253.625093)
			(xy 350.13769 -253.598444) (xy 350.187304 -253.578972) (xy 350.239266 -253.567112) (xy 350.292416 -253.563129)
			(xy 350.345566 -253.567112) (xy 350.397528 -253.578972) (xy 350.447142 -253.598444) (xy 350.4933 -253.625093)
			(xy 350.534971 -253.658324) (xy 350.571223 -253.697395) (xy 350.601247 -253.741432) (xy 350.624373 -253.789453)
			(xy 350.640083 -253.840383) (xy 350.648026 -253.893087) (xy 350.648524 -253.919736) (xy 350.648026 -253.946385)
			(xy 350.640083 -253.999089) (xy 350.624373 -254.050019) (xy 350.601247 -254.09804) (xy 350.571223 -254.142077)
			(xy 350.534971 -254.181148) (xy 350.4933 -254.214379) (xy 350.447142 -254.241028) (xy 350.397528 -254.2605)
			(xy 350.345566 -254.27236) (xy 350.292416 -254.276344) (xy 350.239266 -254.27236) (xy 350.187304 -254.2605)
			(xy 350.13769 -254.241028) (xy 350.091532 -254.214379) (xy 350.049861 -254.181148) (xy 350.013609 -254.142077)
			(xy 349.983585 -254.09804) (xy 349.960459 -254.050019) (xy 349.944749 -253.999089) (xy 349.936806 -253.946385)
			(xy 349.708226 -253.946385) (xy 349.700283 -253.999089) (xy 349.684573 -254.050019) (xy 349.661447 -254.09804)
			(xy 349.631423 -254.142077) (xy 349.595171 -254.181148) (xy 349.5535 -254.214379) (xy 349.507342 -254.241028)
			(xy 349.457728 -254.2605) (xy 349.405766 -254.27236) (xy 349.352616 -254.276344) (xy 349.299466 -254.27236)
			(xy 349.247504 -254.2605) (xy 349.19789 -254.241028) (xy 349.151732 -254.214379) (xy 349.110061 -254.181148)
			(xy 349.073809 -254.142077) (xy 349.043785 -254.09804) (xy 349.020659 -254.050019) (xy 349.004949 -253.999089)
			(xy 348.997006 -253.946385) (xy 348.768426 -253.946385) (xy 348.760483 -253.999089) (xy 348.744773 -254.050019)
			(xy 348.721647 -254.09804) (xy 348.691623 -254.142077) (xy 348.655371 -254.181148) (xy 348.6137 -254.214379)
			(xy 348.567542 -254.241028) (xy 348.517928 -254.2605) (xy 348.465966 -254.27236) (xy 348.412816 -254.276344)
			(xy 348.359666 -254.27236) (xy 348.307704 -254.2605) (xy 348.25809 -254.241028) (xy 348.211932 -254.214379)
			(xy 348.170261 -254.181148) (xy 348.134009 -254.142077) (xy 348.103985 -254.09804) (xy 348.080859 -254.050019)
			(xy 348.065149 -253.999089) (xy 348.057206 -253.946385) (xy 347.89364 -253.946385) (xy 347.89364 -254.326644)
			(xy 347.89413 -254.336611) (xy 347.901752 -254.355033) (xy 347.915825 -254.369153) (xy 347.934221 -254.376836)
			(xy 347.944186 -254.377444) (xy 347.970766 -254.378047) (xy 348.023307 -254.38617) (xy 348.074057 -254.402012)
			(xy 348.121888 -254.425222) (xy 348.165737 -254.455284) (xy 348.204631 -254.49153) (xy 348.237704 -254.533156)
			(xy 348.264222 -254.579235) (xy 348.283597 -254.628744) (xy 348.295396 -254.680583) (xy 348.299359 -254.7336)
			(xy 348.297371 -254.760201) (xy 348.526852 -254.760201) (xy 348.526852 -254.706903) (xy 348.534795 -254.654199)
			(xy 348.550505 -254.603269) (xy 348.573631 -254.555248) (xy 348.603655 -254.511211) (xy 348.639907 -254.47214)
			(xy 348.681578 -254.438909) (xy 348.727736 -254.41226) (xy 348.77735 -254.392788) (xy 348.829312 -254.380928)
			(xy 348.882462 -254.376945) (xy 348.935612 -254.380928) (xy 348.987574 -254.392788) (xy 349.037188 -254.41226)
			(xy 349.083346 -254.438909) (xy 349.125017 -254.47214) (xy 349.161269 -254.511211) (xy 349.191293 -254.555248)
			(xy 349.214419 -254.603269) (xy 349.230129 -254.654199) (xy 349.238072 -254.706903) (xy 349.23857 -254.733552)
			(xy 349.238072 -254.760201) (xy 349.466652 -254.760201) (xy 349.466652 -254.706903) (xy 349.474595 -254.654199)
			(xy 349.490305 -254.603269) (xy 349.513431 -254.555248) (xy 349.543455 -254.511211) (xy 349.579707 -254.47214)
			(xy 349.621378 -254.438909) (xy 349.667536 -254.41226) (xy 349.71715 -254.392788) (xy 349.769112 -254.380928)
			(xy 349.822262 -254.376945) (xy 349.875412 -254.380928) (xy 349.927374 -254.392788) (xy 349.976988 -254.41226)
			(xy 350.023146 -254.438909) (xy 350.064817 -254.47214) (xy 350.101069 -254.511211) (xy 350.131093 -254.555248)
			(xy 350.154219 -254.603269) (xy 350.169929 -254.654199) (xy 350.177872 -254.706903) (xy 350.17837 -254.733552)
			(xy 350.177872 -254.760201) (xy 350.169929 -254.812905) (xy 350.154219 -254.863835) (xy 350.131093 -254.911856)
			(xy 350.101069 -254.955893) (xy 350.064817 -254.994964) (xy 350.023146 -255.028195) (xy 349.976988 -255.054844)
			(xy 349.927374 -255.074316) (xy 349.875412 -255.086176) (xy 349.822262 -255.09016) (xy 349.769112 -255.086176)
			(xy 349.71715 -255.074316) (xy 349.667536 -255.054844) (xy 349.621378 -255.028195) (xy 349.579707 -254.994964)
			(xy 349.543455 -254.955893) (xy 349.513431 -254.911856) (xy 349.490305 -254.863835) (xy 349.474595 -254.812905)
			(xy 349.466652 -254.760201) (xy 349.238072 -254.760201) (xy 349.230129 -254.812905) (xy 349.214419 -254.863835)
			(xy 349.191293 -254.911856) (xy 349.161269 -254.955893) (xy 349.125017 -254.994964) (xy 349.083346 -255.028195)
			(xy 349.037188 -255.054844) (xy 348.987574 -255.074316) (xy 348.935612 -255.086176) (xy 348.882462 -255.09016)
			(xy 348.829312 -255.086176) (xy 348.77735 -255.074316) (xy 348.727736 -255.054844) (xy 348.681578 -255.028195)
			(xy 348.639907 -254.994964) (xy 348.603655 -254.955893) (xy 348.573631 -254.911856) (xy 348.550505 -254.863835)
			(xy 348.534795 -254.812905) (xy 348.526852 -254.760201) (xy 348.297371 -254.760201) (xy 348.295396 -254.786617)
			(xy 348.283597 -254.838456) (xy 348.264223 -254.887965) (xy 348.237704 -254.934044) (xy 348.204631 -254.975669)
			(xy 348.165737 -255.011916) (xy 348.121888 -255.041978) (xy 348.074057 -255.065188) (xy 348.023307 -255.08103)
			(xy 347.970767 -255.089153) (xy 347.944186 -255.08966) (xy 347.934204 -255.090184) (xy 347.915778 -255.09788)
			(xy 347.901683 -255.112024) (xy 347.89405 -255.130476) (xy 347.89364 -255.14046) (xy 347.89364 -255.574271)
			(xy 348.057206 -255.574271) (xy 348.057206 -255.520973) (xy 348.065149 -255.468269) (xy 348.080859 -255.417339)
			(xy 348.103985 -255.369318) (xy 348.134009 -255.325281) (xy 348.170261 -255.28621) (xy 348.211932 -255.252979)
			(xy 348.25809 -255.22633) (xy 348.307704 -255.206858) (xy 348.359666 -255.194998) (xy 348.412816 -255.191015)
			(xy 348.465966 -255.194998) (xy 348.517928 -255.206858) (xy 348.567542 -255.22633) (xy 348.6137 -255.252979)
			(xy 348.655371 -255.28621) (xy 348.691623 -255.325281) (xy 348.721647 -255.369318) (xy 348.744773 -255.417339)
			(xy 348.760483 -255.468269) (xy 348.768426 -255.520973) (xy 348.768924 -255.547622) (xy 348.768426 -255.574271)
			(xy 348.997006 -255.574271) (xy 348.997006 -255.520973) (xy 349.004949 -255.468269) (xy 349.020659 -255.417339)
			(xy 349.043785 -255.369318) (xy 349.073809 -255.325281) (xy 349.110061 -255.28621) (xy 349.151732 -255.252979)
			(xy 349.19789 -255.22633) (xy 349.247504 -255.206858) (xy 349.299466 -255.194998) (xy 349.352616 -255.191015)
			(xy 349.405766 -255.194998) (xy 349.457728 -255.206858) (xy 349.507342 -255.22633) (xy 349.5535 -255.252979)
			(xy 349.595171 -255.28621) (xy 349.631423 -255.325281) (xy 349.661447 -255.369318) (xy 349.684573 -255.417339)
			(xy 349.700283 -255.468269) (xy 349.708226 -255.520973) (xy 349.708724 -255.5476) (xy 349.93579 -255.5476)
			(xy 349.939773 -255.494449) (xy 349.951634 -255.442484) (xy 349.971107 -255.392869) (xy 349.997758 -255.346709)
			(xy 350.030992 -255.305038) (xy 350.070064 -255.268785) (xy 350.114104 -255.238761) (xy 350.162127 -255.215637)
			(xy 350.21306 -255.199928) (xy 350.265766 -255.191986) (xy 350.292416 -255.191514) (xy 350.319047 -255.191999)
			(xy 350.371718 -255.19991) (xy 350.397318 -255.207262) (xy 350.410436 -255.210865) (xy 350.437613 -255.211801)
			(xy 350.46407 -255.205516) (xy 350.487923 -255.192458) (xy 350.507473 -255.173557) (xy 350.521328 -255.150158)
			(xy 350.525334 -255.137158) (xy 350.532552 -255.112393) (xy 350.553239 -255.06514) (xy 350.580527 -255.021366)
			(xy 350.613845 -254.981986) (xy 350.652497 -254.947826) (xy 350.695672 -254.9196) (xy 350.742468 -254.897898)
			(xy 350.791906 -254.883175) (xy 350.84295 -254.875738) (xy 350.868742 -254.875284) (xy 350.896726 -254.875802)
			(xy 350.952004 -254.884563) (xy 351.005231 -254.901863) (xy 351.055096 -254.927276) (xy 351.100373 -254.960175)
			(xy 351.139947 -254.999753) (xy 351.172842 -255.045033) (xy 351.19825 -255.094901) (xy 351.215545 -255.148129)
			(xy 351.2243 -255.203408) (xy 351.22485 -255.231392) (xy 351.224429 -255.256224) (xy 351.217528 -255.305407)
			(xy 351.203859 -255.353153) (xy 351.183687 -255.398537) (xy 351.157404 -255.440676) (xy 351.141792 -255.459992)
			(xy 351.133132 -255.471166) (xy 351.121674 -255.496997) (xy 351.117713 -255.524976) (xy 351.121551 -255.552972)
			(xy 351.132896 -255.578853) (xy 351.141538 -255.59004) (xy 351.157024 -255.609292) (xy 351.183064 -255.651281)
			(xy 351.203044 -255.696469) (xy 351.21658 -255.743987) (xy 351.223413 -255.79292) (xy 351.223834 -255.817624)
			(xy 351.223281 -255.845606) (xy 351.214523 -255.900882) (xy 351.197227 -255.954107) (xy 351.171818 -256.003972)
			(xy 351.138923 -256.049248) (xy 351.099349 -256.088821) (xy 351.054073 -256.121717) (xy 351.004209 -256.147126)
			(xy 350.950984 -256.164423) (xy 350.895708 -256.173181) (xy 350.867726 -256.173732) (xy 350.840864 -256.173228)
			(xy 350.787748 -256.165175) (xy 350.736444 -256.149232) (xy 350.688119 -256.125761) (xy 350.643869 -256.095296)
			(xy 350.604699 -256.058528) (xy 350.571498 -256.016292) (xy 350.54502 -255.969546) (xy 350.534986 -255.944624)
			(xy 350.528894 -255.930216) (xy 350.50942 -255.905754) (xy 350.483471 -255.88831) (xy 350.453467 -255.879512)
			(xy 350.422207 -255.88018) (xy 350.407224 -255.88468) (xy 350.379356 -255.893562) (xy 350.321659 -255.90314)
			(xy 350.292416 -255.90373) (xy 350.265766 -255.903214) (xy 350.21306 -255.895272) (xy 350.162127 -255.879563)
			(xy 350.114104 -255.856439) (xy 350.070064 -255.826415) (xy 350.030992 -255.790162) (xy 349.997758 -255.748491)
			(xy 349.971107 -255.702331) (xy 349.951634 -255.652716) (xy 349.939773 -255.600751) (xy 349.93579 -255.5476)
			(xy 349.708724 -255.5476) (xy 349.708724 -255.547622) (xy 349.708226 -255.574271) (xy 349.700283 -255.626975)
			(xy 349.684573 -255.677905) (xy 349.661447 -255.725926) (xy 349.631423 -255.769963) (xy 349.595171 -255.809034)
			(xy 349.5535 -255.842265) (xy 349.507342 -255.868914) (xy 349.457728 -255.888386) (xy 349.405766 -255.900246)
			(xy 349.352616 -255.90423) (xy 349.299466 -255.900246) (xy 349.247504 -255.888386) (xy 349.19789 -255.868914)
			(xy 349.151732 -255.842265) (xy 349.110061 -255.809034) (xy 349.073809 -255.769963) (xy 349.043785 -255.725926)
			(xy 349.020659 -255.677905) (xy 349.004949 -255.626975) (xy 348.997006 -255.574271) (xy 348.768426 -255.574271)
			(xy 348.760483 -255.626975) (xy 348.744773 -255.677905) (xy 348.721647 -255.725926) (xy 348.691623 -255.769963)
			(xy 348.655371 -255.809034) (xy 348.6137 -255.842265) (xy 348.567542 -255.868914) (xy 348.517928 -255.888386)
			(xy 348.465966 -255.900246) (xy 348.412816 -255.90423) (xy 348.359666 -255.900246) (xy 348.307704 -255.888386)
			(xy 348.25809 -255.868914) (xy 348.211932 -255.842265) (xy 348.170261 -255.809034) (xy 348.134009 -255.769963)
			(xy 348.103985 -255.725926) (xy 348.080859 -255.677905) (xy 348.065149 -255.626975) (xy 348.057206 -255.574271)
			(xy 347.89364 -255.574271) (xy 347.89364 -255.95453) (xy 347.894128 -255.964499) (xy 347.901747 -255.982925)
			(xy 347.915821 -255.99705) (xy 347.934219 -256.004736) (xy 347.944186 -256.00533) (xy 347.97076 -256.005934)
			(xy 348.023288 -256.014054) (xy 348.074025 -256.029892) (xy 348.121845 -256.053097) (xy 348.165683 -256.083152)
			(xy 348.204567 -256.119389) (xy 348.237633 -256.161005) (xy 348.264145 -256.207072) (xy 348.283514 -256.25657)
			(xy 348.295311 -256.308396) (xy 348.299272 -256.3614) (xy 348.297278 -256.388087) (xy 348.527106 -256.388087)
			(xy 348.527106 -256.334789) (xy 348.535049 -256.282085) (xy 348.550759 -256.231155) (xy 348.573885 -256.183134)
			(xy 348.603909 -256.139097) (xy 348.640161 -256.100026) (xy 348.681832 -256.066795) (xy 348.72799 -256.040146)
			(xy 348.777604 -256.020674) (xy 348.829566 -256.008814) (xy 348.882716 -256.004831) (xy 348.935866 -256.008814)
			(xy 348.987828 -256.020674) (xy 349.037442 -256.040146) (xy 349.0836 -256.066795) (xy 349.125271 -256.100026)
			(xy 349.161523 -256.139097) (xy 349.191547 -256.183134) (xy 349.214673 -256.231155) (xy 349.230383 -256.282085)
			(xy 349.238326 -256.334789) (xy 349.238824 -256.361438) (xy 349.238326 -256.388087) (xy 349.466652 -256.388087)
			(xy 349.466652 -256.334789) (xy 349.474595 -256.282085) (xy 349.490305 -256.231155) (xy 349.513431 -256.183134)
			(xy 349.543455 -256.139097) (xy 349.579707 -256.100026) (xy 349.621378 -256.066795) (xy 349.667536 -256.040146)
			(xy 349.71715 -256.020674) (xy 349.769112 -256.008814) (xy 349.822262 -256.004831) (xy 349.875412 -256.008814)
			(xy 349.927374 -256.020674) (xy 349.976988 -256.040146) (xy 350.023146 -256.066795) (xy 350.064817 -256.100026)
			(xy 350.101069 -256.139097) (xy 350.131093 -256.183134) (xy 350.154219 -256.231155) (xy 350.169929 -256.282085)
			(xy 350.177872 -256.334789) (xy 350.17837 -256.361438) (xy 350.177872 -256.388087) (xy 350.169929 -256.440791)
			(xy 350.154219 -256.491721) (xy 350.131093 -256.539742) (xy 350.101069 -256.583779) (xy 350.064817 -256.62285)
			(xy 350.023146 -256.656081) (xy 349.976988 -256.68273) (xy 349.927374 -256.702202) (xy 349.875412 -256.714062)
			(xy 349.822262 -256.718046) (xy 349.769112 -256.714062) (xy 349.71715 -256.702202) (xy 349.667536 -256.68273)
			(xy 349.621378 -256.656081) (xy 349.579707 -256.62285) (xy 349.543455 -256.583779) (xy 349.513431 -256.539742)
			(xy 349.490305 -256.491721) (xy 349.474595 -256.440791) (xy 349.466652 -256.388087) (xy 349.238326 -256.388087)
			(xy 349.230383 -256.440791) (xy 349.214673 -256.491721) (xy 349.191547 -256.539742) (xy 349.161523 -256.583779)
			(xy 349.125271 -256.62285) (xy 349.0836 -256.656081) (xy 349.037442 -256.68273) (xy 348.987828 -256.702202)
			(xy 348.935866 -256.714062) (xy 348.882716 -256.718046) (xy 348.829566 -256.714062) (xy 348.777604 -256.702202)
			(xy 348.72799 -256.68273) (xy 348.681832 -256.656081) (xy 348.640161 -256.62285) (xy 348.603909 -256.583779)
			(xy 348.573885 -256.539742) (xy 348.550759 -256.491721) (xy 348.535049 -256.440791) (xy 348.527106 -256.388087)
			(xy 348.297278 -256.388087) (xy 348.295311 -256.414404) (xy 348.283514 -256.466231) (xy 348.264145 -256.515728)
			(xy 348.237633 -256.561796) (xy 348.204567 -256.603411) (xy 348.165683 -256.639648) (xy 348.121844 -256.669703)
			(xy 348.074025 -256.692908) (xy 348.023287 -256.708746) (xy 347.970759 -256.716866) (xy 347.944186 -256.717546)
			(xy 347.93421 -256.718072) (xy 347.9158 -256.725771) (xy 347.901725 -256.739918) (xy 347.89412 -256.758368)
			(xy 347.89364 -256.768346) (xy 347.89364 -257.201903) (xy 348.057206 -257.201903) (xy 348.057206 -257.148605)
			(xy 348.065149 -257.095901) (xy 348.080859 -257.044971) (xy 348.103985 -256.99695) (xy 348.134009 -256.952913)
			(xy 348.170261 -256.913842) (xy 348.211932 -256.880611) (xy 348.25809 -256.853962) (xy 348.307704 -256.83449)
			(xy 348.359666 -256.82263) (xy 348.412816 -256.818647) (xy 348.465966 -256.82263) (xy 348.517928 -256.83449)
			(xy 348.567542 -256.853962) (xy 348.6137 -256.880611) (xy 348.655371 -256.913842) (xy 348.691623 -256.952913)
			(xy 348.721647 -256.99695) (xy 348.744773 -257.044971) (xy 348.760483 -257.095901) (xy 348.768426 -257.148605)
			(xy 348.768924 -257.175254) (xy 348.768426 -257.201903) (xy 348.997006 -257.201903) (xy 348.997006 -257.148605)
			(xy 349.004949 -257.095901) (xy 349.020659 -257.044971) (xy 349.043785 -256.99695) (xy 349.073809 -256.952913)
			(xy 349.110061 -256.913842) (xy 349.151732 -256.880611) (xy 349.19789 -256.853962) (xy 349.247504 -256.83449)
			(xy 349.299466 -256.82263) (xy 349.352616 -256.818647) (xy 349.405766 -256.82263) (xy 349.457728 -256.83449)
			(xy 349.507342 -256.853962) (xy 349.5535 -256.880611) (xy 349.595171 -256.913842) (xy 349.631423 -256.952913)
			(xy 349.661447 -256.99695) (xy 349.684573 -257.044971) (xy 349.700283 -257.095901) (xy 349.708226 -257.148605)
			(xy 349.708724 -257.175254) (xy 349.708226 -257.201903) (xy 349.936806 -257.201903) (xy 349.936806 -257.148605)
			(xy 349.944749 -257.095901) (xy 349.960459 -257.044971) (xy 349.983585 -256.99695) (xy 350.013609 -256.952913)
			(xy 350.049861 -256.913842) (xy 350.091532 -256.880611) (xy 350.13769 -256.853962) (xy 350.187304 -256.83449)
			(xy 350.239266 -256.82263) (xy 350.292416 -256.818647) (xy 350.345566 -256.82263) (xy 350.397528 -256.83449)
			(xy 350.447142 -256.853962) (xy 350.4933 -256.880611) (xy 350.534971 -256.913842) (xy 350.571223 -256.952913)
			(xy 350.601247 -256.99695) (xy 350.624373 -257.044971) (xy 350.640083 -257.095901) (xy 350.648026 -257.148605)
			(xy 350.648524 -257.175254) (xy 350.648026 -257.201903) (xy 350.640083 -257.254607) (xy 350.624373 -257.305537)
			(xy 350.601247 -257.353558) (xy 350.571223 -257.397595) (xy 350.534971 -257.436666) (xy 350.4933 -257.469897)
			(xy 350.447142 -257.496546) (xy 350.397528 -257.516018) (xy 350.345566 -257.527878) (xy 350.292416 -257.531862)
			(xy 350.239266 -257.527878) (xy 350.187304 -257.516018) (xy 350.13769 -257.496546) (xy 350.091532 -257.469897)
			(xy 350.049861 -257.436666) (xy 350.013609 -257.397595) (xy 349.983585 -257.353558) (xy 349.960459 -257.305537)
			(xy 349.944749 -257.254607) (xy 349.936806 -257.201903) (xy 349.708226 -257.201903) (xy 349.700283 -257.254607)
			(xy 349.684573 -257.305537) (xy 349.661447 -257.353558) (xy 349.631423 -257.397595) (xy 349.595171 -257.436666)
			(xy 349.5535 -257.469897) (xy 349.507342 -257.496546) (xy 349.457728 -257.516018) (xy 349.405766 -257.527878)
			(xy 349.352616 -257.531862) (xy 349.299466 -257.527878) (xy 349.247504 -257.516018) (xy 349.19789 -257.496546)
			(xy 349.151732 -257.469897) (xy 349.110061 -257.436666) (xy 349.073809 -257.397595) (xy 349.043785 -257.353558)
			(xy 349.020659 -257.305537) (xy 349.004949 -257.254607) (xy 348.997006 -257.201903) (xy 348.768426 -257.201903)
			(xy 348.760483 -257.254607) (xy 348.744773 -257.305537) (xy 348.721647 -257.353558) (xy 348.691623 -257.397595)
			(xy 348.655371 -257.436666) (xy 348.6137 -257.469897) (xy 348.567542 -257.496546) (xy 348.517928 -257.516018)
			(xy 348.465966 -257.527878) (xy 348.412816 -257.531862) (xy 348.359666 -257.527878) (xy 348.307704 -257.516018)
			(xy 348.25809 -257.496546) (xy 348.211932 -257.469897) (xy 348.170261 -257.436666) (xy 348.134009 -257.397595)
			(xy 348.103985 -257.353558) (xy 348.080859 -257.305537) (xy 348.065149 -257.254607) (xy 348.057206 -257.201903)
			(xy 347.89364 -257.201903) (xy 347.89364 -257.582162) (xy 347.894116 -257.59214) (xy 347.901723 -257.610589)
			(xy 347.915799 -257.624735) (xy 347.93421 -257.632434) (xy 347.944186 -257.632962) (xy 347.970765 -257.633565)
			(xy 348.023303 -257.641687) (xy 348.07405 -257.657529) (xy 348.121879 -257.680737) (xy 348.165726 -257.710798)
			(xy 348.204617 -257.747043) (xy 348.237689 -257.788666) (xy 348.264206 -257.834743) (xy 348.283579 -257.884249)
			(xy 348.295378 -257.936086) (xy 348.299341 -257.9891) (xy 348.297351 -258.015719) (xy 348.526852 -258.015719)
			(xy 348.526852 -257.962421) (xy 348.534795 -257.909717) (xy 348.550505 -257.858787) (xy 348.573631 -257.810766)
			(xy 348.603655 -257.766729) (xy 348.639907 -257.727658) (xy 348.681578 -257.694427) (xy 348.727736 -257.667778)
			(xy 348.77735 -257.648306) (xy 348.829312 -257.636446) (xy 348.882462 -257.632463) (xy 348.935612 -257.636446)
			(xy 348.987574 -257.648306) (xy 349.037188 -257.667778) (xy 349.083346 -257.694427) (xy 349.125017 -257.727658)
			(xy 349.161269 -257.766729) (xy 349.191293 -257.810766) (xy 349.214419 -257.858787) (xy 349.230129 -257.909717)
			(xy 349.238072 -257.962421) (xy 349.23857 -257.98907) (xy 349.238072 -258.015719) (xy 349.466652 -258.015719)
			(xy 349.466652 -257.962421) (xy 349.474595 -257.909717) (xy 349.490305 -257.858787) (xy 349.513431 -257.810766)
			(xy 349.543455 -257.766729) (xy 349.579707 -257.727658) (xy 349.621378 -257.694427) (xy 349.667536 -257.667778)
			(xy 349.71715 -257.648306) (xy 349.769112 -257.636446) (xy 349.822262 -257.632463) (xy 349.875412 -257.636446)
			(xy 349.927374 -257.648306) (xy 349.976988 -257.667778) (xy 350.023146 -257.694427) (xy 350.064817 -257.727658)
			(xy 350.101069 -257.766729) (xy 350.131093 -257.810766) (xy 350.154219 -257.858787) (xy 350.169929 -257.909717)
			(xy 350.177872 -257.962421) (xy 350.17837 -257.98907) (xy 350.177872 -258.015719) (xy 350.169929 -258.068423)
			(xy 350.154219 -258.119353) (xy 350.131093 -258.167374) (xy 350.101069 -258.211411) (xy 350.064817 -258.250482)
			(xy 350.023146 -258.283713) (xy 349.976988 -258.310362) (xy 349.927374 -258.329834) (xy 349.875412 -258.341694)
			(xy 349.822262 -258.345678) (xy 349.769112 -258.341694) (xy 349.71715 -258.329834) (xy 349.667536 -258.310362)
			(xy 349.621378 -258.283713) (xy 349.579707 -258.250482) (xy 349.543455 -258.211411) (xy 349.513431 -258.167374)
			(xy 349.490305 -258.119353) (xy 349.474595 -258.068423) (xy 349.466652 -258.015719) (xy 349.238072 -258.015719)
			(xy 349.230129 -258.068423) (xy 349.214419 -258.119353) (xy 349.191293 -258.167374) (xy 349.161269 -258.211411)
			(xy 349.125017 -258.250482) (xy 349.083346 -258.283713) (xy 349.037188 -258.310362) (xy 348.987574 -258.329834)
			(xy 348.935612 -258.341694) (xy 348.882462 -258.345678) (xy 348.829312 -258.341694) (xy 348.77735 -258.329834)
			(xy 348.727736 -258.310362) (xy 348.681578 -258.283713) (xy 348.639907 -258.250482) (xy 348.603655 -258.211411)
			(xy 348.573631 -258.167374) (xy 348.550505 -258.119353) (xy 348.534795 -258.068423) (xy 348.526852 -258.015719)
			(xy 348.297351 -258.015719) (xy 348.295378 -258.042114) (xy 348.28358 -258.093951) (xy 348.264206 -258.143457)
			(xy 348.237689 -258.189534) (xy 348.204618 -258.231157) (xy 348.165726 -258.267402) (xy 348.121879 -258.297462)
			(xy 348.07405 -258.320671) (xy 348.023303 -258.336513) (xy 347.970765 -258.344635) (xy 347.944186 -258.345178)
			(xy 347.934205 -258.345702) (xy 347.915783 -258.353399) (xy 347.901691 -258.367544) (xy 347.894064 -258.385995)
			(xy 347.89364 -258.395978) (xy 347.89364 -258.829789) (xy 348.057206 -258.829789) (xy 348.057206 -258.776491)
			(xy 348.065149 -258.723787) (xy 348.080859 -258.672857) (xy 348.103985 -258.624836) (xy 348.134009 -258.580799)
			(xy 348.170261 -258.541728) (xy 348.211932 -258.508497) (xy 348.25809 -258.481848) (xy 348.307704 -258.462376)
			(xy 348.359666 -258.450516) (xy 348.412816 -258.446533) (xy 348.465966 -258.450516) (xy 348.517928 -258.462376)
			(xy 348.567542 -258.481848) (xy 348.6137 -258.508497) (xy 348.655371 -258.541728) (xy 348.691623 -258.580799)
			(xy 348.721647 -258.624836) (xy 348.744773 -258.672857) (xy 348.760483 -258.723787) (xy 348.768426 -258.776491)
			(xy 348.768924 -258.80314) (xy 348.768426 -258.829789) (xy 348.996752 -258.829789) (xy 348.996752 -258.776491)
			(xy 349.004695 -258.723787) (xy 349.020405 -258.672857) (xy 349.043531 -258.624836) (xy 349.073555 -258.580799)
			(xy 349.109807 -258.541728) (xy 349.151478 -258.508497) (xy 349.197636 -258.481848) (xy 349.24725 -258.462376)
			(xy 349.299212 -258.450516) (xy 349.352362 -258.446533) (xy 349.405512 -258.450516) (xy 349.457474 -258.462376)
			(xy 349.507088 -258.481848) (xy 349.553246 -258.508497) (xy 349.594917 -258.541728) (xy 349.631169 -258.580799)
			(xy 349.661193 -258.624836) (xy 349.684319 -258.672857) (xy 349.700029 -258.723787) (xy 349.707972 -258.776491)
			(xy 349.70847 -258.80314) (xy 349.707972 -258.829789) (xy 349.700029 -258.882493) (xy 349.684319 -258.933423)
			(xy 349.661193 -258.981444) (xy 349.631169 -259.025481) (xy 349.594917 -259.064552) (xy 349.553246 -259.097783)
			(xy 349.507088 -259.124432) (xy 349.457474 -259.143904) (xy 349.405512 -259.155764) (xy 349.352362 -259.159748)
			(xy 349.299212 -259.155764) (xy 349.24725 -259.143904) (xy 349.197636 -259.124432) (xy 349.151478 -259.097783)
			(xy 349.109807 -259.064552) (xy 349.073555 -259.025481) (xy 349.043531 -258.981444) (xy 349.020405 -258.933423)
			(xy 349.004695 -258.882493) (xy 348.996752 -258.829789) (xy 348.768426 -258.829789) (xy 348.760483 -258.882493)
			(xy 348.744773 -258.933423) (xy 348.721647 -258.981444) (xy 348.691623 -259.025481) (xy 348.655371 -259.064552)
			(xy 348.6137 -259.097783) (xy 348.567542 -259.124432) (xy 348.517928 -259.143904) (xy 348.465966 -259.155764)
			(xy 348.412816 -259.159748) (xy 348.359666 -259.155764) (xy 348.307704 -259.143904) (xy 348.25809 -259.124432)
			(xy 348.211932 -259.097783) (xy 348.170261 -259.064552) (xy 348.134009 -259.025481) (xy 348.103985 -258.981444)
			(xy 348.080859 -258.933423) (xy 348.065149 -258.882493) (xy 348.057206 -258.829789) (xy 347.89364 -258.829789)
			(xy 347.89364 -259.210048) (xy 347.894131 -259.220015) (xy 347.901753 -259.238435) (xy 347.915826 -259.252554)
			(xy 347.934221 -259.260236) (xy 347.944186 -259.260848) (xy 347.970766 -259.261451) (xy 348.023306 -259.269574)
			(xy 348.074055 -259.285415) (xy 348.121886 -259.308625) (xy 348.165735 -259.338687) (xy 348.204628 -259.374933)
			(xy 348.237701 -259.416558) (xy 348.264219 -259.462636) (xy 348.283593 -259.512145) (xy 348.295392 -259.563983)
			(xy 348.299355 -259.617) (xy 348.297366 -259.643605) (xy 348.526852 -259.643605) (xy 348.526852 -259.590307)
			(xy 348.534795 -259.537603) (xy 348.550505 -259.486673) (xy 348.573631 -259.438652) (xy 348.603655 -259.394615)
			(xy 348.639907 -259.355544) (xy 348.681578 -259.322313) (xy 348.727736 -259.295664) (xy 348.77735 -259.276192)
			(xy 348.829312 -259.264332) (xy 348.882462 -259.260349) (xy 348.935612 -259.264332) (xy 348.987574 -259.276192)
			(xy 349.037188 -259.295664) (xy 349.083346 -259.322313) (xy 349.125017 -259.355544) (xy 349.161269 -259.394615)
			(xy 349.191293 -259.438652) (xy 349.214419 -259.486673) (xy 349.230129 -259.537603) (xy 349.238072 -259.590307)
			(xy 349.23857 -259.616956) (xy 349.238072 -259.643605) (xy 349.230129 -259.696309) (xy 349.221863 -259.723107)
			(xy 350.450902 -259.723107) (xy 350.450902 -259.669809) (xy 350.458845 -259.617105) (xy 350.474555 -259.566175)
			(xy 350.497681 -259.518154) (xy 350.527705 -259.474117) (xy 350.563957 -259.435046) (xy 350.605628 -259.401815)
			(xy 350.651786 -259.375166) (xy 350.7014 -259.355694) (xy 350.753362 -259.343834) (xy 350.806512 -259.339851)
			(xy 350.859662 -259.343834) (xy 350.911624 -259.355694) (xy 350.961238 -259.375166) (xy 351.007396 -259.401815)
			(xy 351.049067 -259.435046) (xy 351.085319 -259.474117) (xy 351.115343 -259.518154) (xy 351.138469 -259.566175)
			(xy 351.154179 -259.617105) (xy 351.162122 -259.669809) (xy 351.16262 -259.696458) (xy 351.162122 -259.723107)
			(xy 351.154179 -259.775811) (xy 351.138469 -259.826741) (xy 351.115343 -259.874762) (xy 351.085319 -259.918799)
			(xy 351.049067 -259.95787) (xy 351.007396 -259.991101) (xy 350.961238 -260.01775) (xy 350.911624 -260.037222)
			(xy 350.859662 -260.049082) (xy 350.806512 -260.053066) (xy 350.753362 -260.049082) (xy 350.7014 -260.037222)
			(xy 350.651786 -260.01775) (xy 350.605628 -259.991101) (xy 350.563957 -259.95787) (xy 350.527705 -259.918799)
			(xy 350.497681 -259.874762) (xy 350.474555 -259.826741) (xy 350.458845 -259.775811) (xy 350.450902 -259.723107)
			(xy 349.221863 -259.723107) (xy 349.214419 -259.747239) (xy 349.191293 -259.79526) (xy 349.161269 -259.839297)
			(xy 349.125017 -259.878368) (xy 349.083346 -259.911599) (xy 349.037188 -259.938248) (xy 348.987574 -259.95772)
			(xy 348.935612 -259.96958) (xy 348.882462 -259.973564) (xy 348.829312 -259.96958) (xy 348.77735 -259.95772)
			(xy 348.727736 -259.938248) (xy 348.681578 -259.911599) (xy 348.639907 -259.878368) (xy 348.603655 -259.839297)
			(xy 348.573631 -259.79526) (xy 348.550505 -259.747239) (xy 348.534795 -259.696309) (xy 348.526852 -259.643605)
			(xy 348.297366 -259.643605) (xy 348.295392 -259.670016) (xy 348.283593 -259.721855) (xy 348.264219 -259.771363)
			(xy 348.237701 -259.817442) (xy 348.204628 -259.859067) (xy 348.165735 -259.895313) (xy 348.121886 -259.925375)
			(xy 348.074056 -259.948584) (xy 348.023306 -259.964426) (xy 347.970766 -259.972549) (xy 347.944186 -259.973064)
			(xy 347.934204 -259.973588) (xy 347.915779 -259.981285) (xy 347.901685 -259.995429) (xy 347.894053 -260.01388)
			(xy 347.89364 -260.023864) (xy 347.89364 -260.198108) (xy 347.953838 -260.258306) (xy 347.964986 -260.268664)
			(xy 347.991865 -260.282897) (xy 348.021742 -260.288585) (xy 348.05197 -260.285227) (xy 348.07987 -260.273118)
			(xy 348.102969 -260.253332) (xy 348.111572 -260.24078) (xy 348.125634 -260.219313) (xy 348.15895 -260.180281)
			(xy 348.197525 -260.146437) (xy 348.24056 -260.118483) (xy 348.287164 -260.096999) (xy 348.33637 -260.08243)
			(xy 348.387157 -260.075077) (xy 348.412816 -260.074664) (xy 348.440799 -260.075214) (xy 348.496076 -260.083971)
			(xy 348.549303 -260.101267) (xy 348.599169 -260.126675) (xy 348.644446 -260.159571) (xy 348.684021 -260.199144)
			(xy 348.716919 -260.244421) (xy 348.742329 -260.294286) (xy 348.759626 -260.347512) (xy 348.768385 -260.402789)
			(xy 348.768924 -260.430772) (xy 348.768508 -260.456205) (xy 348.761299 -260.506558) (xy 348.746995 -260.555372)
			(xy 348.725888 -260.601652) (xy 348.712536 -260.623304) (xy 348.705545 -260.634992) (xy 348.697411 -260.660974)
			(xy 348.696436 -260.688182) (xy 348.702689 -260.714679) (xy 348.715726 -260.738581) (xy 348.734617 -260.758185)
			(xy 348.75802 -260.772096) (xy 348.784268 -260.779325) (xy 348.79788 -260.779768) (xy 350.45269 -260.779768)
			(xy 350.461072 -260.739382) (xy 350.467106 -260.713066) (xy 350.486047 -260.662507) (xy 350.512403 -260.615388)
			(xy 350.545571 -260.572788) (xy 350.584789 -260.535683) (xy 350.62916 -260.504923) (xy 350.677666 -260.481215)
			(xy 350.729194 -260.465101) (xy 350.782565 -260.45695) (xy 350.836555 -260.45695) (xy 350.889926 -260.465101)
			(xy 350.941454 -260.481215) (xy 350.98996 -260.504923) (xy 351.034331 -260.535683) (xy 351.073549 -260.572788)
			(xy 351.106717 -260.615388) (xy 351.133073 -260.662507) (xy 351.152014 -260.713066) (xy 351.158048 -260.739382)
			(xy 351.16643 -260.779768) (xy 351.37598 -260.779768) (xy 352.80854 -259.347208) (xy 352.80854 -258.104894)
			(xy 352.80805 -258.090201) (xy 352.79968 -258.062032) (xy 352.783634 -258.037414) (xy 352.761242 -258.018384)
			(xy 352.734357 -258.006519) (xy 352.705207 -258.002802) (xy 352.676205 -258.007541) (xy 352.662744 -258.013454)
			(xy 352.638473 -258.024672) (xy 352.587403 -258.040507) (xy 352.534538 -258.048515) (xy 352.507804 -258.049014)
			(xy 352.483135 -258.048595) (xy 352.434268 -258.041784) (xy 352.38681 -258.028293) (xy 352.341668 -258.00838)
			(xy 352.299708 -257.982425) (xy 352.280474 -257.966972) (xy 352.269344 -257.958345) (xy 352.243584 -257.946998)
			(xy 352.215704 -257.943117) (xy 352.187824 -257.946998) (xy 352.162064 -257.958345) (xy 352.150934 -257.966972)
			(xy 352.129518 -257.984095) (xy 352.082461 -258.012234) (xy 352.031644 -258.032823) (xy 351.978271 -258.045375)
			(xy 351.923604 -258.049592) (xy 351.868937 -258.045375) (xy 351.815564 -258.032823) (xy 351.764747 -258.012234)
			(xy 351.71769 -257.984095) (xy 351.696274 -257.966972) (xy 351.685144 -257.958345) (xy 351.659384 -257.946998)
			(xy 351.631504 -257.943117) (xy 351.603624 -257.946998) (xy 351.577864 -257.958345) (xy 351.566734 -257.966972)
			(xy 351.547487 -257.982411) (xy 351.505538 -258.008387) (xy 351.460401 -258.028316) (xy 351.412943 -258.041813)
			(xy 351.364074 -258.048621) (xy 351.339404 -258.049014) (xy 351.312752 -258.048541) (xy 351.260044 -258.040597)
			(xy 351.209108 -258.024886) (xy 351.161083 -258.001759) (xy 351.117042 -257.971732) (xy 351.077967 -257.935477)
			(xy 351.044733 -257.893803) (xy 351.018081 -257.84764) (xy 350.998607 -257.798022) (xy 350.986745 -257.746055)
			(xy 350.982762 -257.6929) (xy 350.986745 -257.639745) (xy 350.998607 -257.587778) (xy 351.018081 -257.53816)
			(xy 351.044733 -257.491997) (xy 351.077967 -257.450323) (xy 351.117042 -257.414068) (xy 351.161083 -257.384041)
			(xy 351.209108 -257.360914) (xy 351.260044 -257.345203) (xy 351.312752 -257.337259) (xy 351.339404 -257.336798)
			(xy 351.364073 -257.337218) (xy 351.412939 -257.344029) (xy 351.460397 -257.357522) (xy 351.505537 -257.377437)
			(xy 351.547496 -257.403392) (xy 351.566734 -257.41884) (xy 351.577864 -257.427467) (xy 351.603624 -257.438814)
			(xy 351.631504 -257.442695) (xy 351.659384 -257.438814) (xy 351.685144 -257.427467) (xy 351.696274 -257.41884)
			(xy 351.71769 -257.401717) (xy 351.764747 -257.373578) (xy 351.815564 -257.352989) (xy 351.868937 -257.340437)
			(xy 351.923604 -257.33622) (xy 351.978271 -257.340437) (xy 352.031644 -257.352989) (xy 352.082461 -257.373578)
			(xy 352.129518 -257.401717) (xy 352.150934 -257.41884) (xy 352.162064 -257.427467) (xy 352.187824 -257.438814)
			(xy 352.215704 -257.442695) (xy 352.243584 -257.438814) (xy 352.269344 -257.427467) (xy 352.280474 -257.41884)
			(xy 352.299722 -257.403405) (xy 352.341673 -257.377435) (xy 352.38681 -257.357513) (xy 352.434268 -257.34402)
			(xy 352.483135 -257.337215) (xy 352.507804 -257.336798) (xy 352.534537 -257.337297) (xy 352.5874 -257.34532)
			(xy 352.638473 -257.361141) (xy 352.662744 -257.372358) (xy 352.676184 -257.378304) (xy 352.705179 -257.383018)
			(xy 352.734317 -257.379284) (xy 352.761187 -257.36741) (xy 352.783566 -257.348379) (xy 352.799602 -257.323766)
			(xy 352.807969 -257.295606) (xy 352.80854 -257.280918) (xy 352.80854 -254.477266) (xy 352.808088 -254.463538)
			(xy 352.800771 -254.437074) (xy 352.786673 -254.413512) (xy 352.766813 -254.394553) (xy 352.742623 -254.381564)
			(xy 352.715849 -254.375483) (xy 352.702114 -254.375666) (xy 352.685604 -254.376174) (xy 352.660935 -254.375754)
			(xy 352.612069 -254.368943) (xy 352.564611 -254.355451) (xy 352.519471 -254.335535) (xy 352.477513 -254.309579)
			(xy 352.458274 -254.294132) (xy 352.447144 -254.285505) (xy 352.421384 -254.274158) (xy 352.393504 -254.270277)
			(xy 352.365624 -254.274158) (xy 352.339864 -254.285505) (xy 352.328734 -254.294132) (xy 352.309486 -254.309569)
			(xy 352.267536 -254.335541) (xy 352.222399 -254.355466) (xy 352.174941 -254.368961) (xy 352.126074 -254.375768)
			(xy 352.101404 -254.376174) (xy 352.074755 -254.375701) (xy 352.022053 -254.367758) (xy 351.971123 -254.352049)
			(xy 351.923103 -254.328924) (xy 351.879067 -254.298901) (xy 351.839996 -254.26265) (xy 351.806766 -254.22098)
			(xy 351.780117 -254.174823) (xy 351.760645 -254.12521) (xy 351.748785 -254.073249) (xy 351.744802 -254.0201)
			(xy 351.748785 -253.966951) (xy 351.760645 -253.91499) (xy 351.780117 -253.865377) (xy 351.806766 -253.81922)
			(xy 351.839996 -253.77755) (xy 351.879067 -253.741299) (xy 351.923103 -253.711276) (xy 351.971123 -253.688151)
			(xy 352.022053 -253.672442) (xy 352.074755 -253.664499) (xy 352.101404 -253.663958) (xy 352.126073 -253.664378)
			(xy 352.174938 -253.671191) (xy 352.222394 -253.684685) (xy 352.267533 -253.704603) (xy 352.309489 -253.730562)
			(xy 352.328734 -253.746) (xy 352.339864 -253.754627) (xy 352.365624 -253.765974) (xy 352.393504 -253.769855)
			(xy 352.421384 -253.765974) (xy 352.447144 -253.754627) (xy 352.458274 -253.746) (xy 352.477522 -253.730563)
			(xy 352.519471 -253.704589) (xy 352.564608 -253.684663) (xy 352.612066 -253.671168) (xy 352.660934 -253.664362)
			(xy 352.685604 -253.663958) (xy 352.702114 -253.664466) (xy 352.715853 -253.664676) (xy 352.742646 -253.658627)
			(xy 352.766852 -253.645645) (xy 352.786715 -253.626673) (xy 352.800792 -253.603088) (xy 352.808063 -253.576601)
			(xy 352.80854 -253.562866) (xy 352.80854 -250.801632) (xy 352.808082 -250.787828) (xy 352.800681 -250.761232)
			(xy 352.786414 -250.737597) (xy 352.766327 -250.718659) (xy 352.741894 -250.705806) (xy 352.714908 -250.699983)
			(xy 352.701098 -250.700286) (xy 352.680524 -250.700794) (xy 352.655857 -250.700369) (xy 352.606996 -250.693549)
			(xy 352.559544 -250.680048) (xy 352.51441 -250.660126) (xy 352.472458 -250.634165) (xy 352.453194 -250.618752)
			(xy 352.442064 -250.610125) (xy 352.416304 -250.598778) (xy 352.388424 -250.594897) (xy 352.360544 -250.598778)
			(xy 352.334784 -250.610125) (xy 352.323654 -250.618752) (xy 352.304406 -250.634189) (xy 352.262456 -250.660162)
			(xy 352.217319 -250.680089) (xy 352.169862 -250.693586) (xy 352.120994 -250.700395) (xy 352.096324 -250.700794)
			(xy 352.069673 -250.700323) (xy 352.016965 -250.692381) (xy 351.96603 -250.676673) (xy 351.918005 -250.653548)
			(xy 351.873963 -250.623524) (xy 351.834888 -250.58727) (xy 351.801654 -250.545598) (xy 351.775001 -250.499437)
			(xy 351.755527 -250.449819) (xy 351.743665 -250.397853) (xy 351.739682 -250.3447) (xy 351.743665 -250.291547)
			(xy 351.755527 -250.239581) (xy 351.775001 -250.189963) (xy 351.801654 -250.143802) (xy 351.834888 -250.10213)
			(xy 351.873963 -250.065876) (xy 351.918005 -250.035852) (xy 351.96603 -250.012727) (xy 352.016965 -249.997019)
			(xy 352.069673 -249.989077) (xy 352.096324 -249.988578) (xy 352.120993 -249.988999) (xy 352.169858 -249.995813)
			(xy 352.217314 -250.009307) (xy 352.262453 -250.029223) (xy 352.304411 -250.055179) (xy 352.323654 -250.07062)
			(xy 352.334784 -250.079247) (xy 352.360544 -250.090594) (xy 352.388424 -250.094475) (xy 352.416304 -250.090594)
			(xy 352.442064 -250.079247) (xy 352.453194 -250.07062) (xy 352.472442 -250.055183) (xy 352.514391 -250.02921)
			(xy 352.559528 -250.009286) (xy 352.606986 -249.995792) (xy 352.655854 -249.988989) (xy 352.680524 -249.988578)
			(xy 352.701098 -249.989086) (xy 352.714902 -249.989416) (xy 352.741874 -249.983555) (xy 352.766292 -249.970685)
			(xy 352.786371 -249.951747) (xy 352.800646 -249.928123) (xy 352.808074 -249.90154) (xy 352.80854 -249.88774)
			(xy 352.80854 -245.067328) (xy 351.24136 -243.500148) (xy 351.24136 -241.280696) (xy 351.240848 -241.266288)
			(xy 351.232783 -241.238624) (xy 351.217321 -241.214307) (xy 351.19569 -241.195268) (xy 351.169607 -241.183018)
			(xy 351.141143 -241.178529) (xy 351.112556 -241.182157) (xy 351.086115 -241.193615) (xy 351.074736 -241.202464)
			(xy 351.055467 -241.217986) (xy 351.013449 -241.244112) (xy 350.968215 -241.264161) (xy 350.920638 -241.277746)
			(xy 350.871637 -241.284604) (xy 350.846898 -241.285014) (xy 350.818915 -241.284465) (xy 350.763638 -241.27571)
			(xy 350.71041 -241.258415) (xy 350.660544 -241.233007) (xy 350.615266 -241.200111) (xy 350.575692 -241.160537)
			(xy 350.542795 -241.115259) (xy 350.517387 -241.065393) (xy 350.500091 -241.012166) (xy 350.491335 -240.956889)
			(xy 350.49079 -240.928906) (xy 350.491209 -240.904237) (xy 350.498019 -240.85537) (xy 350.51151 -240.807911)
			(xy 350.531424 -240.76277) (xy 350.557379 -240.720809) (xy 350.572832 -240.701576) (xy 350.58146 -240.690446)
			(xy 350.592808 -240.664685) (xy 350.596691 -240.636805) (xy 350.592811 -240.608923) (xy 350.581464 -240.583162)
			(xy 350.572832 -240.572036) (xy 350.557393 -240.552789) (xy 350.531416 -240.510841) (xy 350.511487 -240.465704)
			(xy 350.497989 -240.418245) (xy 350.491181 -240.369376) (xy 350.49079 -240.344706) (xy 350.49131 -240.31672)
			(xy 350.500065 -240.261438) (xy 350.51736 -240.208205) (xy 350.54277 -240.158334) (xy 350.575668 -240.113052)
			(xy 350.615246 -240.073474) (xy 350.660527 -240.040574) (xy 350.710398 -240.015163) (xy 350.76363 -239.997866)
			(xy 350.818912 -239.98911) (xy 350.846898 -239.988598) (xy 350.871632 -239.989048) (xy 350.92062 -239.995938)
			(xy 350.968185 -240.009532) (xy 351.013416 -240.029568) (xy 351.055443 -240.055662) (xy 351.074736 -240.071148)
			(xy 351.086139 -240.079977) (xy 351.112571 -240.091478) (xy 351.141163 -240.095136) (xy 351.16964 -240.09066)
			(xy 351.195731 -240.078407) (xy 351.217361 -240.059353) (xy 351.232806 -240.035014) (xy 351.240836 -240.007329)
			(xy 351.24136 -239.992916) (xy 351.24136 -239.584484) (xy 351.233665 -239.578054) (xy 351.218926 -239.564456)
			(xy 351.211896 -239.557306) (xy 351.204442 -239.550253) (xy 351.185571 -239.542241) (xy 351.165069 -239.542241)
			(xy 351.146198 -239.550253) (xy 351.138744 -239.557306) (xy 351.118489 -239.577392) (xy 351.072764 -239.611492)
			(xy 351.022186 -239.637863) (xy 350.968049 -239.655828) (xy 350.91174 -239.664929) (xy 350.88322 -239.66551)
			(xy 350.856568 -239.665038) (xy 350.803858 -239.657096) (xy 350.752921 -239.641387) (xy 350.704895 -239.618261)
			(xy 350.660851 -239.588235) (xy 350.621775 -239.55198) (xy 350.588539 -239.510305) (xy 350.561886 -239.464143)
			(xy 350.542411 -239.414523) (xy 350.53055 -239.362555) (xy 350.526566 -239.3094) (xy 350.53055 -239.256245)
			(xy 350.542411 -239.204277) (xy 350.561886 -239.154657) (xy 350.588539 -239.108495) (xy 350.621775 -239.06682)
			(xy 350.660851 -239.030565) (xy 350.704895 -239.000539) (xy 350.752921 -238.977413) (xy 350.803858 -238.961704)
			(xy 350.856568 -238.953762) (xy 350.88322 -238.953294) (xy 350.91174 -238.95386) (xy 350.96805 -238.962963)
			(xy 351.022186 -238.980934) (xy 351.072762 -239.007311) (xy 351.118481 -239.041419) (xy 351.138744 -239.061498)
			(xy 351.146198 -239.068551) (xy 351.165069 -239.076563) (xy 351.185571 -239.076563) (xy 351.204442 -239.068551)
			(xy 351.211896 -239.061498) (xy 351.21892 -239.054341) (xy 351.233659 -239.040742) (xy 351.24136 -239.03432)
			(xy 351.24136 -238.544608) (xy 353.086162 -236.699806) (xy 356.772972 -236.699806) (xy 356.786299 -236.699414)
			(xy 356.812045 -236.692522) (xy 356.835129 -236.6792) (xy 356.853979 -236.660357) (xy 356.867308 -236.637276)
			(xy 356.874209 -236.611532) (xy 356.874572 -236.598206) (xy 356.874572 -236.597952) (xy 356.87507 -236.571303)
			(xy 356.883013 -236.518599) (xy 356.898723 -236.467669) (xy 356.921849 -236.419648) (xy 356.951873 -236.375611)
			(xy 356.988125 -236.33654) (xy 357.029796 -236.303309) (xy 357.075954 -236.27666) (xy 357.125568 -236.257188)
			(xy 357.17753 -236.245328) (xy 357.23068 -236.241345) (xy 357.28383 -236.245328) (xy 357.335792 -236.257188)
			(xy 357.385406 -236.27666) (xy 357.431564 -236.303309) (xy 357.473235 -236.33654) (xy 357.509487 -236.375611)
			(xy 357.539511 -236.419648) (xy 357.562637 -236.467669) (xy 357.578347 -236.518599) (xy 357.58629 -236.571303)
			(xy 357.586788 -236.597952) (xy 357.586788 -236.598206) (xy 357.587223 -236.611525) (xy 357.594118 -236.637254)
			(xy 357.607437 -236.660323) (xy 357.626272 -236.679159) (xy 357.64934 -236.692479) (xy 357.675069 -236.699376)
			(xy 357.688388 -236.699806) (xy 357.713026 -236.699806) (xy 357.726343 -236.699368) (xy 357.752067 -236.69247)
			(xy 357.775131 -236.67915) (xy 357.793962 -236.660315) (xy 357.807278 -236.637249) (xy 357.814171 -236.611523)
			(xy 357.814626 -236.598206) (xy 357.814626 -236.597952) (xy 357.815124 -236.571303) (xy 357.823067 -236.518599)
			(xy 357.838777 -236.467669) (xy 357.861903 -236.419648) (xy 357.891927 -236.375611) (xy 357.928179 -236.33654)
			(xy 357.96985 -236.303309) (xy 358.016008 -236.27666) (xy 358.065622 -236.257188) (xy 358.117584 -236.245328)
			(xy 358.170734 -236.241345) (xy 358.223884 -236.245328) (xy 358.275846 -236.257188) (xy 358.32546 -236.27666)
			(xy 358.371618 -236.303309) (xy 358.413289 -236.33654) (xy 358.449541 -236.375611) (xy 358.479565 -236.419648)
			(xy 358.502691 -236.467669) (xy 358.518401 -236.518599) (xy 358.526344 -236.571303) (xy 358.526842 -236.597952)
			(xy 358.526842 -236.598206) (xy 358.527239 -236.611527) (xy 358.534137 -236.637261) (xy 358.547463 -236.660332)
			(xy 358.566306 -236.679167) (xy 358.589383 -236.692481) (xy 358.615121 -236.699368) (xy 358.628442 -236.699806)
			(xy 358.652572 -236.699806) (xy 358.665899 -236.699414) (xy 358.691645 -236.692522) (xy 358.714729 -236.6792)
			(xy 358.733579 -236.660357) (xy 358.746908 -236.637276) (xy 358.753809 -236.611532) (xy 358.754172 -236.598206)
			(xy 358.754172 -236.597952) (xy 358.75467 -236.571303) (xy 358.762613 -236.518599) (xy 358.778323 -236.467669)
			(xy 358.801449 -236.419648) (xy 358.831473 -236.375611) (xy 358.867725 -236.33654) (xy 358.909396 -236.303309)
			(xy 358.955554 -236.27666) (xy 359.005168 -236.257188) (xy 359.05713 -236.245328) (xy 359.11028 -236.241345)
			(xy 359.16343 -236.245328) (xy 359.215392 -236.257188) (xy 359.265006 -236.27666) (xy 359.311164 -236.303309)
			(xy 359.352835 -236.33654) (xy 359.389087 -236.375611) (xy 359.419111 -236.419648) (xy 359.442237 -236.467669)
			(xy 359.457947 -236.518599) (xy 359.46589 -236.571303) (xy 359.466388 -236.597952) (xy 359.466388 -236.598206)
			(xy 359.466823 -236.611525) (xy 359.473718 -236.637254) (xy 359.487037 -236.660323) (xy 359.505872 -236.679159)
			(xy 359.52894 -236.692479) (xy 359.554669 -236.699376) (xy 359.567988 -236.699806) (xy 359.592372 -236.699806)
			(xy 359.605699 -236.699414) (xy 359.631445 -236.692522) (xy 359.654529 -236.6792) (xy 359.673379 -236.660357)
			(xy 359.686708 -236.637276) (xy 359.693609 -236.611532) (xy 359.693972 -236.598206) (xy 359.693972 -236.597952)
			(xy 359.69447 -236.571303) (xy 359.702413 -236.518599) (xy 359.718123 -236.467669) (xy 359.741249 -236.419648)
			(xy 359.771273 -236.375611) (xy 359.807525 -236.33654) (xy 359.849196 -236.303309) (xy 359.895354 -236.27666)
			(xy 359.944968 -236.257188) (xy 359.99693 -236.245328) (xy 360.05008 -236.241345) (xy 360.10323 -236.245328)
			(xy 360.155192 -236.257188) (xy 360.204806 -236.27666) (xy 360.250964 -236.303309) (xy 360.292635 -236.33654)
			(xy 360.328887 -236.375611) (xy 360.358911 -236.419648) (xy 360.382037 -236.467669) (xy 360.397747 -236.518599)
			(xy 360.40569 -236.571303) (xy 360.406188 -236.597952) (xy 360.406188 -236.598206) (xy 360.406623 -236.611525)
			(xy 360.413518 -236.637254) (xy 360.426837 -236.660323) (xy 360.445672 -236.679159) (xy 360.46874 -236.692479)
			(xy 360.494469 -236.699376) (xy 360.507788 -236.699806) (xy 360.532172 -236.699806) (xy 360.545499 -236.699414)
			(xy 360.571245 -236.692522) (xy 360.594329 -236.6792) (xy 360.613179 -236.660357) (xy 360.626508 -236.637276)
			(xy 360.633409 -236.611532) (xy 360.633772 -236.598206) (xy 360.633772 -236.597952) (xy 360.63427 -236.571303)
			(xy 360.642213 -236.518599) (xy 360.657923 -236.467669) (xy 360.681049 -236.419648) (xy 360.711073 -236.375611)
			(xy 360.747325 -236.33654) (xy 360.788996 -236.303309) (xy 360.835154 -236.27666) (xy 360.884768 -236.257188)
			(xy 360.93673 -236.245328) (xy 360.98988 -236.241345) (xy 361.04303 -236.245328) (xy 361.094992 -236.257188)
			(xy 361.144606 -236.27666) (xy 361.190764 -236.303309) (xy 361.232435 -236.33654) (xy 361.268687 -236.375611)
			(xy 361.298711 -236.419648) (xy 361.321837 -236.467669) (xy 361.337547 -236.518599) (xy 361.34549 -236.571303)
			(xy 361.345988 -236.597952) (xy 361.345988 -236.598206) (xy 361.346423 -236.611525) (xy 361.353318 -236.637254)
			(xy 361.366637 -236.660323) (xy 361.385472 -236.679159) (xy 361.40854 -236.692479) (xy 361.434269 -236.699376)
			(xy 361.447588 -236.699806) (xy 361.472226 -236.699806) (xy 361.485543 -236.699368) (xy 361.511267 -236.69247)
			(xy 361.534331 -236.67915) (xy 361.553162 -236.660315) (xy 361.566478 -236.637249) (xy 361.573371 -236.611523)
			(xy 361.573826 -236.598206) (xy 361.573826 -236.597952) (xy 361.574324 -236.571303) (xy 361.582267 -236.518599)
			(xy 361.597977 -236.467669) (xy 361.621103 -236.419648) (xy 361.651127 -236.375611) (xy 361.687379 -236.33654)
			(xy 361.72905 -236.303309) (xy 361.775208 -236.27666) (xy 361.824822 -236.257188) (xy 361.876784 -236.245328)
			(xy 361.929934 -236.241345) (xy 361.983084 -236.245328) (xy 362.035046 -236.257188) (xy 362.08466 -236.27666)
			(xy 362.130818 -236.303309) (xy 362.172489 -236.33654) (xy 362.208741 -236.375611) (xy 362.238765 -236.419648)
			(xy 362.261891 -236.467669) (xy 362.277601 -236.518599) (xy 362.285544 -236.571303) (xy 362.286042 -236.597952)
			(xy 362.286042 -236.598206) (xy 362.286439 -236.611527) (xy 362.293337 -236.637261) (xy 362.306663 -236.660332)
			(xy 362.325506 -236.679167) (xy 362.348583 -236.692481) (xy 362.374321 -236.699368) (xy 362.387642 -236.699806)
			(xy 362.825538 -236.699806) (xy 362.839476 -236.699368) (xy 362.866312 -236.691819) (xy 362.890107 -236.677296)
			(xy 362.909088 -236.656879) (xy 362.921841 -236.63209) (xy 362.927417 -236.604777) (xy 362.926884 -236.59084)
			(xy 362.925868 -236.564932) (xy 362.926366 -236.538283) (xy 362.934309 -236.485579) (xy 362.950019 -236.434649)
			(xy 362.973145 -236.386628) (xy 363.003169 -236.342591) (xy 363.039421 -236.30352) (xy 363.081092 -236.270289)
			(xy 363.12725 -236.24364) (xy 363.176864 -236.224168) (xy 363.228826 -236.212308) (xy 363.281976 -236.208325)
			(xy 363.335126 -236.212308) (xy 363.387088 -236.224168) (xy 363.436702 -236.24364) (xy 363.450663 -236.2517)
			(xy 368.559618 -236.2517) (xy 368.563601 -236.198554) (xy 368.57546 -236.146595) (xy 368.594931 -236.096984)
			(xy 368.621579 -236.050829) (xy 368.654808 -236.009161) (xy 368.693877 -235.972912) (xy 368.737911 -235.94289)
			(xy 368.785929 -235.919766) (xy 368.836856 -235.904057) (xy 368.889556 -235.896115) (xy 368.916204 -235.895642)
			(xy 368.942799 -235.896074) (xy 368.995396 -235.903986) (xy 369.046232 -235.919633) (xy 369.094176 -235.942667)
			(xy 369.13816 -235.972575) (xy 369.177207 -236.008693) (xy 369.210447 -236.050216) (xy 369.237142 -236.096222)
			(xy 369.256697 -236.145686) (xy 369.263168 -236.171486) (xy 369.267197 -236.186575) (xy 369.283088 -236.213444)
			(xy 369.306362 -236.234249) (xy 369.334838 -236.24704) (xy 369.365849 -236.250619) (xy 369.381278 -236.248194)
			(xy 369.397945 -236.245209) (xy 369.431657 -236.242032) (xy 369.448588 -236.241844) (xy 369.475236 -236.242412)
			(xy 369.527937 -236.250354) (xy 369.578866 -236.266062) (xy 369.626885 -236.289185) (xy 369.670921 -236.319207)
			(xy 369.709991 -236.355457) (xy 369.743221 -236.397125) (xy 369.76987 -236.443281) (xy 369.789341 -236.492893)
			(xy 369.801201 -236.544853) (xy 369.805184 -236.598) (xy 369.80319 -236.624601) (xy 370.03227 -236.624601)
			(xy 370.03227 -236.571303) (xy 370.040213 -236.518599) (xy 370.055923 -236.467669) (xy 370.079049 -236.419648)
			(xy 370.109073 -236.375611) (xy 370.145325 -236.33654) (xy 370.186996 -236.303309) (xy 370.233154 -236.27666)
			(xy 370.282768 -236.257188) (xy 370.33473 -236.245328) (xy 370.38788 -236.241345) (xy 370.44103 -236.245328)
			(xy 370.492992 -236.257188) (xy 370.542606 -236.27666) (xy 370.588764 -236.303309) (xy 370.630435 -236.33654)
			(xy 370.666687 -236.375611) (xy 370.696711 -236.419648) (xy 370.719837 -236.467669) (xy 370.735547 -236.518599)
			(xy 370.74349 -236.571303) (xy 370.743988 -236.597952) (xy 370.74349 -236.624601) (xy 370.97207 -236.624601)
			(xy 370.97207 -236.571303) (xy 370.980013 -236.518599) (xy 370.995723 -236.467669) (xy 371.018849 -236.419648)
			(xy 371.048873 -236.375611) (xy 371.085125 -236.33654) (xy 371.126796 -236.303309) (xy 371.172954 -236.27666)
			(xy 371.222568 -236.257188) (xy 371.27453 -236.245328) (xy 371.32768 -236.241345) (xy 371.38083 -236.245328)
			(xy 371.432792 -236.257188) (xy 371.482406 -236.27666) (xy 371.528564 -236.303309) (xy 371.570235 -236.33654)
			(xy 371.606487 -236.375611) (xy 371.636511 -236.419648) (xy 371.659637 -236.467669) (xy 371.675347 -236.518599)
			(xy 371.68329 -236.571303) (xy 371.683788 -236.597952) (xy 371.68329 -236.624601) (xy 371.91187 -236.624601)
			(xy 371.91187 -236.571303) (xy 371.919813 -236.518599) (xy 371.935523 -236.467669) (xy 371.958649 -236.419648)
			(xy 371.988673 -236.375611) (xy 372.024925 -236.33654) (xy 372.066596 -236.303309) (xy 372.112754 -236.27666)
			(xy 372.162368 -236.257188) (xy 372.21433 -236.245328) (xy 372.26748 -236.241345) (xy 372.32063 -236.245328)
			(xy 372.372592 -236.257188) (xy 372.422206 -236.27666) (xy 372.468364 -236.303309) (xy 372.510035 -236.33654)
			(xy 372.546287 -236.375611) (xy 372.576311 -236.419648) (xy 372.599437 -236.467669) (xy 372.615147 -236.518599)
			(xy 372.62309 -236.571303) (xy 372.623588 -236.597952) (xy 372.62309 -236.624601) (xy 372.85167 -236.624601)
			(xy 372.85167 -236.571303) (xy 372.859613 -236.518599) (xy 372.875323 -236.467669) (xy 372.898449 -236.419648)
			(xy 372.928473 -236.375611) (xy 372.964725 -236.33654) (xy 373.006396 -236.303309) (xy 373.052554 -236.27666)
			(xy 373.102168 -236.257188) (xy 373.15413 -236.245328) (xy 373.20728 -236.241345) (xy 373.26043 -236.245328)
			(xy 373.312392 -236.257188) (xy 373.362006 -236.27666) (xy 373.408164 -236.303309) (xy 373.449835 -236.33654)
			(xy 373.486087 -236.375611) (xy 373.516111 -236.419648) (xy 373.539237 -236.467669) (xy 373.554947 -236.518599)
			(xy 373.56289 -236.571303) (xy 373.563388 -236.597952) (xy 373.56289 -236.624601) (xy 373.79147 -236.624601)
			(xy 373.79147 -236.571303) (xy 373.799413 -236.518599) (xy 373.815123 -236.467669) (xy 373.838249 -236.419648)
			(xy 373.868273 -236.375611) (xy 373.904525 -236.33654) (xy 373.946196 -236.303309) (xy 373.992354 -236.27666)
			(xy 374.041968 -236.257188) (xy 374.09393 -236.245328) (xy 374.14708 -236.241345) (xy 374.20023 -236.245328)
			(xy 374.252192 -236.257188) (xy 374.301806 -236.27666) (xy 374.347964 -236.303309) (xy 374.389635 -236.33654)
			(xy 374.425887 -236.375611) (xy 374.455911 -236.419648) (xy 374.479037 -236.467669) (xy 374.494747 -236.518599)
			(xy 374.50269 -236.571303) (xy 374.503188 -236.597952) (xy 374.50269 -236.624601) (xy 374.73127 -236.624601)
			(xy 374.73127 -236.571303) (xy 374.739213 -236.518599) (xy 374.754923 -236.467669) (xy 374.778049 -236.419648)
			(xy 374.808073 -236.375611) (xy 374.844325 -236.33654) (xy 374.885996 -236.303309) (xy 374.932154 -236.27666)
			(xy 374.981768 -236.257188) (xy 375.03373 -236.245328) (xy 375.08688 -236.241345) (xy 375.14003 -236.245328)
			(xy 375.191992 -236.257188) (xy 375.241606 -236.27666) (xy 375.287764 -236.303309) (xy 375.329435 -236.33654)
			(xy 375.365687 -236.375611) (xy 375.395711 -236.419648) (xy 375.418837 -236.467669) (xy 375.434547 -236.518599)
			(xy 375.44249 -236.571303) (xy 375.442988 -236.597952) (xy 375.44249 -236.624601) (xy 375.67107 -236.624601)
			(xy 375.67107 -236.571303) (xy 375.679013 -236.518599) (xy 375.694723 -236.467669) (xy 375.717849 -236.419648)
			(xy 375.747873 -236.375611) (xy 375.784125 -236.33654) (xy 375.825796 -236.303309) (xy 375.871954 -236.27666)
			(xy 375.921568 -236.257188) (xy 375.97353 -236.245328) (xy 376.02668 -236.241345) (xy 376.07983 -236.245328)
			(xy 376.131792 -236.257188) (xy 376.181406 -236.27666) (xy 376.227564 -236.303309) (xy 376.269235 -236.33654)
			(xy 376.305487 -236.375611) (xy 376.335511 -236.419648) (xy 376.358637 -236.467669) (xy 376.374347 -236.518599)
			(xy 376.38229 -236.571303) (xy 376.382788 -236.597952) (xy 376.38229 -236.624601) (xy 376.611124 -236.624601)
			(xy 376.611124 -236.571303) (xy 376.619067 -236.518599) (xy 376.634777 -236.467669) (xy 376.657903 -236.419648)
			(xy 376.687927 -236.375611) (xy 376.724179 -236.33654) (xy 376.76585 -236.303309) (xy 376.812008 -236.27666)
			(xy 376.861622 -236.257188) (xy 376.913584 -236.245328) (xy 376.966734 -236.241345) (xy 377.019884 -236.245328)
			(xy 377.071846 -236.257188) (xy 377.12146 -236.27666) (xy 377.167618 -236.303309) (xy 377.209289 -236.33654)
			(xy 377.245541 -236.375611) (xy 377.275565 -236.419648) (xy 377.298691 -236.467669) (xy 377.314401 -236.518599)
			(xy 377.322344 -236.571303) (xy 377.322842 -236.597952) (xy 377.322344 -236.624601) (xy 377.55067 -236.624601)
			(xy 377.55067 -236.571303) (xy 377.558613 -236.518599) (xy 377.574323 -236.467669) (xy 377.597449 -236.419648)
			(xy 377.627473 -236.375611) (xy 377.663725 -236.33654) (xy 377.705396 -236.303309) (xy 377.751554 -236.27666)
			(xy 377.801168 -236.257188) (xy 377.85313 -236.245328) (xy 377.90628 -236.241345) (xy 377.95943 -236.245328)
			(xy 378.011392 -236.257188) (xy 378.061006 -236.27666) (xy 378.107164 -236.303309) (xy 378.148835 -236.33654)
			(xy 378.185087 -236.375611) (xy 378.215111 -236.419648) (xy 378.238237 -236.467669) (xy 378.253947 -236.518599)
			(xy 378.26189 -236.571303) (xy 378.262388 -236.597952) (xy 378.26189 -236.624601) (xy 378.49047 -236.624601)
			(xy 378.49047 -236.571303) (xy 378.498413 -236.518599) (xy 378.514123 -236.467669) (xy 378.537249 -236.419648)
			(xy 378.567273 -236.375611) (xy 378.603525 -236.33654) (xy 378.645196 -236.303309) (xy 378.691354 -236.27666)
			(xy 378.740968 -236.257188) (xy 378.79293 -236.245328) (xy 378.84608 -236.241345) (xy 378.89923 -236.245328)
			(xy 378.951192 -236.257188) (xy 379.000806 -236.27666) (xy 379.046964 -236.303309) (xy 379.088635 -236.33654)
			(xy 379.124887 -236.375611) (xy 379.154911 -236.419648) (xy 379.178037 -236.467669) (xy 379.193747 -236.518599)
			(xy 379.20169 -236.571303) (xy 379.202188 -236.597952) (xy 379.20169 -236.624601) (xy 379.43027 -236.624601)
			(xy 379.43027 -236.571303) (xy 379.438213 -236.518599) (xy 379.453923 -236.467669) (xy 379.477049 -236.419648)
			(xy 379.507073 -236.375611) (xy 379.543325 -236.33654) (xy 379.584996 -236.303309) (xy 379.631154 -236.27666)
			(xy 379.680768 -236.257188) (xy 379.73273 -236.245328) (xy 379.78588 -236.241345) (xy 379.83903 -236.245328)
			(xy 379.890992 -236.257188) (xy 379.940606 -236.27666) (xy 379.986764 -236.303309) (xy 380.028435 -236.33654)
			(xy 380.064687 -236.375611) (xy 380.094711 -236.419648) (xy 380.117837 -236.467669) (xy 380.133547 -236.518599)
			(xy 380.14149 -236.571303) (xy 380.141988 -236.597952) (xy 380.14149 -236.624601) (xy 380.133547 -236.677305)
			(xy 380.117837 -236.728235) (xy 380.094711 -236.776256) (xy 380.064687 -236.820293) (xy 380.028435 -236.859364)
			(xy 379.986764 -236.892595) (xy 379.940606 -236.919244) (xy 379.890992 -236.938716) (xy 379.83903 -236.950576)
			(xy 379.78588 -236.95456) (xy 379.73273 -236.950576) (xy 379.680768 -236.938716) (xy 379.631154 -236.919244)
			(xy 379.584996 -236.892595) (xy 379.543325 -236.859364) (xy 379.507073 -236.820293) (xy 379.477049 -236.776256)
			(xy 379.453923 -236.728235) (xy 379.438213 -236.677305) (xy 379.43027 -236.624601) (xy 379.20169 -236.624601)
			(xy 379.193747 -236.677305) (xy 379.178037 -236.728235) (xy 379.154911 -236.776256) (xy 379.124887 -236.820293)
			(xy 379.088635 -236.859364) (xy 379.046964 -236.892595) (xy 379.000806 -236.919244) (xy 378.951192 -236.938716)
			(xy 378.89923 -236.950576) (xy 378.84608 -236.95456) (xy 378.79293 -236.950576) (xy 378.740968 -236.938716)
			(xy 378.691354 -236.919244) (xy 378.645196 -236.892595) (xy 378.603525 -236.859364) (xy 378.567273 -236.820293)
			(xy 378.537249 -236.776256) (xy 378.514123 -236.728235) (xy 378.498413 -236.677305) (xy 378.49047 -236.624601)
			(xy 378.26189 -236.624601) (xy 378.253947 -236.677305) (xy 378.238237 -236.728235) (xy 378.215111 -236.776256)
			(xy 378.185087 -236.820293) (xy 378.148835 -236.859364) (xy 378.107164 -236.892595) (xy 378.061006 -236.919244)
			(xy 378.011392 -236.938716) (xy 377.95943 -236.950576) (xy 377.90628 -236.95456) (xy 377.85313 -236.950576)
			(xy 377.801168 -236.938716) (xy 377.751554 -236.919244) (xy 377.705396 -236.892595) (xy 377.663725 -236.859364)
			(xy 377.627473 -236.820293) (xy 377.597449 -236.776256) (xy 377.574323 -236.728235) (xy 377.558613 -236.677305)
			(xy 377.55067 -236.624601) (xy 377.322344 -236.624601) (xy 377.314401 -236.677305) (xy 377.298691 -236.728235)
			(xy 377.275565 -236.776256) (xy 377.245541 -236.820293) (xy 377.209289 -236.859364) (xy 377.167618 -236.892595)
			(xy 377.12146 -236.919244) (xy 377.071846 -236.938716) (xy 377.019884 -236.950576) (xy 376.966734 -236.95456)
			(xy 376.913584 -236.950576) (xy 376.861622 -236.938716) (xy 376.812008 -236.919244) (xy 376.76585 -236.892595)
			(xy 376.724179 -236.859364) (xy 376.687927 -236.820293) (xy 376.657903 -236.776256) (xy 376.634777 -236.728235)
			(xy 376.619067 -236.677305) (xy 376.611124 -236.624601) (xy 376.38229 -236.624601) (xy 376.374347 -236.677305)
			(xy 376.358637 -236.728235) (xy 376.335511 -236.776256) (xy 376.305487 -236.820293) (xy 376.269235 -236.859364)
			(xy 376.227564 -236.892595) (xy 376.181406 -236.919244) (xy 376.131792 -236.938716) (xy 376.07983 -236.950576)
			(xy 376.02668 -236.95456) (xy 375.97353 -236.950576) (xy 375.921568 -236.938716) (xy 375.871954 -236.919244)
			(xy 375.825796 -236.892595) (xy 375.784125 -236.859364) (xy 375.747873 -236.820293) (xy 375.717849 -236.776256)
			(xy 375.694723 -236.728235) (xy 375.679013 -236.677305) (xy 375.67107 -236.624601) (xy 375.44249 -236.624601)
			(xy 375.434547 -236.677305) (xy 375.418837 -236.728235) (xy 375.395711 -236.776256) (xy 375.365687 -236.820293)
			(xy 375.329435 -236.859364) (xy 375.287764 -236.892595) (xy 375.241606 -236.919244) (xy 375.191992 -236.938716)
			(xy 375.14003 -236.950576) (xy 375.08688 -236.95456) (xy 375.03373 -236.950576) (xy 374.981768 -236.938716)
			(xy 374.932154 -236.919244) (xy 374.885996 -236.892595) (xy 374.844325 -236.859364) (xy 374.808073 -236.820293)
			(xy 374.778049 -236.776256) (xy 374.754923 -236.728235) (xy 374.739213 -236.677305) (xy 374.73127 -236.624601)
			(xy 374.50269 -236.624601) (xy 374.494747 -236.677305) (xy 374.479037 -236.728235) (xy 374.455911 -236.776256)
			(xy 374.425887 -236.820293) (xy 374.389635 -236.859364) (xy 374.347964 -236.892595) (xy 374.301806 -236.919244)
			(xy 374.252192 -236.938716) (xy 374.20023 -236.950576) (xy 374.14708 -236.95456) (xy 374.09393 -236.950576)
			(xy 374.041968 -236.938716) (xy 373.992354 -236.919244) (xy 373.946196 -236.892595) (xy 373.904525 -236.859364)
			(xy 373.868273 -236.820293) (xy 373.838249 -236.776256) (xy 373.815123 -236.728235) (xy 373.799413 -236.677305)
			(xy 373.79147 -236.624601) (xy 373.56289 -236.624601) (xy 373.554947 -236.677305) (xy 373.539237 -236.728235)
			(xy 373.516111 -236.776256) (xy 373.486087 -236.820293) (xy 373.449835 -236.859364) (xy 373.408164 -236.892595)
			(xy 373.362006 -236.919244) (xy 373.312392 -236.938716) (xy 373.26043 -236.950576) (xy 373.20728 -236.95456)
			(xy 373.15413 -236.950576) (xy 373.102168 -236.938716) (xy 373.052554 -236.919244) (xy 373.006396 -236.892595)
			(xy 372.964725 -236.859364) (xy 372.928473 -236.820293) (xy 372.898449 -236.776256) (xy 372.875323 -236.728235)
			(xy 372.859613 -236.677305) (xy 372.85167 -236.624601) (xy 372.62309 -236.624601) (xy 372.615147 -236.677305)
			(xy 372.599437 -236.728235) (xy 372.576311 -236.776256) (xy 372.546287 -236.820293) (xy 372.510035 -236.859364)
			(xy 372.468364 -236.892595) (xy 372.422206 -236.919244) (xy 372.372592 -236.938716) (xy 372.32063 -236.950576)
			(xy 372.26748 -236.95456) (xy 372.21433 -236.950576) (xy 372.162368 -236.938716) (xy 372.112754 -236.919244)
			(xy 372.066596 -236.892595) (xy 372.024925 -236.859364) (xy 371.988673 -236.820293) (xy 371.958649 -236.776256)
			(xy 371.935523 -236.728235) (xy 371.919813 -236.677305) (xy 371.91187 -236.624601) (xy 371.68329 -236.624601)
			(xy 371.675347 -236.677305) (xy 371.659637 -236.728235) (xy 371.636511 -236.776256) (xy 371.606487 -236.820293)
			(xy 371.570235 -236.859364) (xy 371.528564 -236.892595) (xy 371.482406 -236.919244) (xy 371.432792 -236.938716)
			(xy 371.38083 -236.950576) (xy 371.32768 -236.95456) (xy 371.27453 -236.950576) (xy 371.222568 -236.938716)
			(xy 371.172954 -236.919244) (xy 371.126796 -236.892595) (xy 371.085125 -236.859364) (xy 371.048873 -236.820293)
			(xy 371.018849 -236.776256) (xy 370.995723 -236.728235) (xy 370.980013 -236.677305) (xy 370.97207 -236.624601)
			(xy 370.74349 -236.624601) (xy 370.735547 -236.677305) (xy 370.719837 -236.728235) (xy 370.696711 -236.776256)
			(xy 370.666687 -236.820293) (xy 370.630435 -236.859364) (xy 370.588764 -236.892595) (xy 370.542606 -236.919244)
			(xy 370.492992 -236.938716) (xy 370.44103 -236.950576) (xy 370.38788 -236.95456) (xy 370.33473 -236.950576)
			(xy 370.282768 -236.938716) (xy 370.233154 -236.919244) (xy 370.186996 -236.892595) (xy 370.145325 -236.859364)
			(xy 370.109073 -236.820293) (xy 370.079049 -236.776256) (xy 370.055923 -236.728235) (xy 370.040213 -236.677305)
			(xy 370.03227 -236.624601) (xy 369.80319 -236.624601) (xy 369.801201 -236.651147) (xy 369.789341 -236.703107)
			(xy 369.76987 -236.752719) (xy 369.743221 -236.798875) (xy 369.709991 -236.840543) (xy 369.670921 -236.876793)
			(xy 369.626885 -236.906815) (xy 369.578866 -236.929938) (xy 369.527937 -236.945646) (xy 369.475236 -236.953588)
			(xy 369.448588 -236.95406) (xy 369.421996 -236.953543) (xy 369.369402 -236.945644) (xy 369.318568 -236.93001)
			(xy 369.270625 -236.906988) (xy 369.226641 -236.877091) (xy 369.187593 -236.840983) (xy 369.154351 -236.799468)
			(xy 369.127654 -236.75347) (xy 369.108097 -236.704013) (xy 369.101624 -236.678216) (xy 369.097602 -236.663125)
			(xy 369.08171 -236.636254) (xy 369.058435 -236.615449) (xy 369.029957 -236.602659) (xy 368.998944 -236.599082)
			(xy 368.983514 -236.601508) (xy 368.966848 -236.604494) (xy 368.933135 -236.60767) (xy 368.916204 -236.607858)
			(xy 368.889556 -236.607285) (xy 368.836856 -236.599343) (xy 368.785929 -236.583634) (xy 368.737911 -236.56051)
			(xy 368.693877 -236.530488) (xy 368.654808 -236.494239) (xy 368.621579 -236.452571) (xy 368.594931 -236.406416)
			(xy 368.57546 -236.356805) (xy 368.563601 -236.304846) (xy 368.559618 -236.2517) (xy 363.450663 -236.2517)
			(xy 363.48286 -236.270289) (xy 363.524531 -236.30352) (xy 363.560783 -236.342591) (xy 363.590807 -236.386628)
			(xy 363.613933 -236.434649) (xy 363.629643 -236.485579) (xy 363.637586 -236.538283) (xy 363.638084 -236.564932)
			(xy 363.637068 -236.59084) (xy 363.636491 -236.604777) (xy 363.642069 -236.632098) (xy 363.654829 -236.656891)
			(xy 363.67382 -236.677309) (xy 363.697626 -236.691828) (xy 363.724472 -236.699367) (xy 363.738414 -236.699806)
			(xy 366.940338 -236.699806) (xy 367.687331 -237.446799) (xy 368.560594 -237.446799) (xy 368.560594 -237.393501)
			(xy 368.568537 -237.340797) (xy 368.584247 -237.289867) (xy 368.607373 -237.241846) (xy 368.637397 -237.197809)
			(xy 368.673649 -237.158738) (xy 368.71532 -237.125507) (xy 368.761478 -237.098858) (xy 368.811092 -237.079386)
			(xy 368.863054 -237.067526) (xy 368.916204 -237.063543) (xy 368.969354 -237.067526) (xy 369.021316 -237.079386)
			(xy 369.07093 -237.098858) (xy 369.117088 -237.125507) (xy 369.158759 -237.158738) (xy 369.195011 -237.197809)
			(xy 369.225035 -237.241846) (xy 369.248161 -237.289867) (xy 369.263871 -237.340797) (xy 369.271814 -237.393501)
			(xy 369.272312 -237.42015) (xy 369.271975 -237.438163) (xy 369.562624 -237.438163) (xy 369.562624 -237.384865)
			(xy 369.570567 -237.332161) (xy 369.586277 -237.281231) (xy 369.609403 -237.23321) (xy 369.639427 -237.189173)
			(xy 369.675679 -237.150102) (xy 369.71735 -237.116871) (xy 369.763508 -237.090222) (xy 369.813122 -237.07075)
			(xy 369.865084 -237.05889) (xy 369.918234 -237.054907) (xy 369.971384 -237.05889) (xy 370.023346 -237.07075)
			(xy 370.07296 -237.090222) (xy 370.119118 -237.116871) (xy 370.160789 -237.150102) (xy 370.197041 -237.189173)
			(xy 370.227065 -237.23321) (xy 370.250191 -237.281231) (xy 370.265901 -237.332161) (xy 370.273844 -237.384865)
			(xy 370.274342 -237.411514) (xy 370.273844 -237.438163) (xy 370.502424 -237.438163) (xy 370.502424 -237.384865)
			(xy 370.510367 -237.332161) (xy 370.526077 -237.281231) (xy 370.549203 -237.23321) (xy 370.579227 -237.189173)
			(xy 370.615479 -237.150102) (xy 370.65715 -237.116871) (xy 370.703308 -237.090222) (xy 370.752922 -237.07075)
			(xy 370.804884 -237.05889) (xy 370.858034 -237.054907) (xy 370.911184 -237.05889) (xy 370.963146 -237.07075)
			(xy 371.01276 -237.090222) (xy 371.058918 -237.116871) (xy 371.100589 -237.150102) (xy 371.136841 -237.189173)
			(xy 371.166865 -237.23321) (xy 371.189991 -237.281231) (xy 371.205701 -237.332161) (xy 371.213644 -237.384865)
			(xy 371.214142 -237.411514) (xy 371.213644 -237.438163) (xy 371.442224 -237.438163) (xy 371.442224 -237.384865)
			(xy 371.450167 -237.332161) (xy 371.465877 -237.281231) (xy 371.489003 -237.23321) (xy 371.519027 -237.189173)
			(xy 371.555279 -237.150102) (xy 371.59695 -237.116871) (xy 371.643108 -237.090222) (xy 371.692722 -237.07075)
			(xy 371.744684 -237.05889) (xy 371.797834 -237.054907) (xy 371.850984 -237.05889) (xy 371.902946 -237.07075)
			(xy 371.95256 -237.090222) (xy 371.998718 -237.116871) (xy 372.040389 -237.150102) (xy 372.076641 -237.189173)
			(xy 372.106665 -237.23321) (xy 372.129791 -237.281231) (xy 372.145501 -237.332161) (xy 372.153444 -237.384865)
			(xy 372.153942 -237.411514) (xy 372.153444 -237.438163) (xy 372.382024 -237.438163) (xy 372.382024 -237.384865)
			(xy 372.389967 -237.332161) (xy 372.405677 -237.281231) (xy 372.428803 -237.23321) (xy 372.458827 -237.189173)
			(xy 372.495079 -237.150102) (xy 372.53675 -237.116871) (xy 372.582908 -237.090222) (xy 372.632522 -237.07075)
			(xy 372.684484 -237.05889) (xy 372.737634 -237.054907) (xy 372.790784 -237.05889) (xy 372.842746 -237.07075)
			(xy 372.89236 -237.090222) (xy 372.938518 -237.116871) (xy 372.980189 -237.150102) (xy 373.016441 -237.189173)
			(xy 373.046465 -237.23321) (xy 373.069591 -237.281231) (xy 373.085301 -237.332161) (xy 373.093244 -237.384865)
			(xy 373.093742 -237.411514) (xy 373.093244 -237.438163) (xy 373.321824 -237.438163) (xy 373.321824 -237.384865)
			(xy 373.329767 -237.332161) (xy 373.345477 -237.281231) (xy 373.368603 -237.23321) (xy 373.398627 -237.189173)
			(xy 373.434879 -237.150102) (xy 373.47655 -237.116871) (xy 373.522708 -237.090222) (xy 373.572322 -237.07075)
			(xy 373.624284 -237.05889) (xy 373.677434 -237.054907) (xy 373.730584 -237.05889) (xy 373.782546 -237.07075)
			(xy 373.83216 -237.090222) (xy 373.878318 -237.116871) (xy 373.919989 -237.150102) (xy 373.956241 -237.189173)
			(xy 373.986265 -237.23321) (xy 374.009391 -237.281231) (xy 374.025101 -237.332161) (xy 374.033044 -237.384865)
			(xy 374.033542 -237.411514) (xy 374.033044 -237.438163) (xy 374.261624 -237.438163) (xy 374.261624 -237.384865)
			(xy 374.269567 -237.332161) (xy 374.285277 -237.281231) (xy 374.308403 -237.23321) (xy 374.338427 -237.189173)
			(xy 374.374679 -237.150102) (xy 374.41635 -237.116871) (xy 374.462508 -237.090222) (xy 374.512122 -237.07075)
			(xy 374.564084 -237.05889) (xy 374.617234 -237.054907) (xy 374.670384 -237.05889) (xy 374.722346 -237.07075)
			(xy 374.77196 -237.090222) (xy 374.818118 -237.116871) (xy 374.859789 -237.150102) (xy 374.896041 -237.189173)
			(xy 374.926065 -237.23321) (xy 374.949191 -237.281231) (xy 374.964901 -237.332161) (xy 374.972844 -237.384865)
			(xy 374.973342 -237.411514) (xy 374.972844 -237.438163) (xy 375.201424 -237.438163) (xy 375.201424 -237.384865)
			(xy 375.209367 -237.332161) (xy 375.225077 -237.281231) (xy 375.248203 -237.23321) (xy 375.278227 -237.189173)
			(xy 375.314479 -237.150102) (xy 375.35615 -237.116871) (xy 375.402308 -237.090222) (xy 375.451922 -237.07075)
			(xy 375.503884 -237.05889) (xy 375.557034 -237.054907) (xy 375.610184 -237.05889) (xy 375.662146 -237.07075)
			(xy 375.71176 -237.090222) (xy 375.757918 -237.116871) (xy 375.799589 -237.150102) (xy 375.835841 -237.189173)
			(xy 375.865865 -237.23321) (xy 375.888991 -237.281231) (xy 375.904701 -237.332161) (xy 375.912644 -237.384865)
			(xy 375.913142 -237.411514) (xy 375.912644 -237.438163) (xy 376.141224 -237.438163) (xy 376.141224 -237.384865)
			(xy 376.149167 -237.332161) (xy 376.164877 -237.281231) (xy 376.188003 -237.23321) (xy 376.218027 -237.189173)
			(xy 376.254279 -237.150102) (xy 376.29595 -237.116871) (xy 376.342108 -237.090222) (xy 376.391722 -237.07075)
			(xy 376.443684 -237.05889) (xy 376.496834 -237.054907) (xy 376.549984 -237.05889) (xy 376.601946 -237.07075)
			(xy 376.65156 -237.090222) (xy 376.697718 -237.116871) (xy 376.739389 -237.150102) (xy 376.775641 -237.189173)
			(xy 376.805665 -237.23321) (xy 376.828791 -237.281231) (xy 376.844501 -237.332161) (xy 376.852444 -237.384865)
			(xy 376.852942 -237.411514) (xy 376.852444 -237.438163) (xy 377.081024 -237.438163) (xy 377.081024 -237.384865)
			(xy 377.088967 -237.332161) (xy 377.104677 -237.281231) (xy 377.127803 -237.23321) (xy 377.157827 -237.189173)
			(xy 377.194079 -237.150102) (xy 377.23575 -237.116871) (xy 377.281908 -237.090222) (xy 377.331522 -237.07075)
			(xy 377.383484 -237.05889) (xy 377.436634 -237.054907) (xy 377.489784 -237.05889) (xy 377.541746 -237.07075)
			(xy 377.59136 -237.090222) (xy 377.637518 -237.116871) (xy 377.679189 -237.150102) (xy 377.715441 -237.189173)
			(xy 377.745465 -237.23321) (xy 377.768591 -237.281231) (xy 377.784301 -237.332161) (xy 377.792244 -237.384865)
			(xy 377.792742 -237.411514) (xy 377.792244 -237.438163) (xy 378.020824 -237.438163) (xy 378.020824 -237.384865)
			(xy 378.028767 -237.332161) (xy 378.044477 -237.281231) (xy 378.067603 -237.23321) (xy 378.097627 -237.189173)
			(xy 378.133879 -237.150102) (xy 378.17555 -237.116871) (xy 378.221708 -237.090222) (xy 378.271322 -237.07075)
			(xy 378.323284 -237.05889) (xy 378.376434 -237.054907) (xy 378.429584 -237.05889) (xy 378.481546 -237.07075)
			(xy 378.53116 -237.090222) (xy 378.577318 -237.116871) (xy 378.618989 -237.150102) (xy 378.655241 -237.189173)
			(xy 378.685265 -237.23321) (xy 378.708391 -237.281231) (xy 378.724101 -237.332161) (xy 378.732044 -237.384865)
			(xy 378.732542 -237.411514) (xy 378.732044 -237.438163) (xy 378.960624 -237.438163) (xy 378.960624 -237.384865)
			(xy 378.968567 -237.332161) (xy 378.984277 -237.281231) (xy 379.007403 -237.23321) (xy 379.037427 -237.189173)
			(xy 379.073679 -237.150102) (xy 379.11535 -237.116871) (xy 379.161508 -237.090222) (xy 379.211122 -237.07075)
			(xy 379.263084 -237.05889) (xy 379.316234 -237.054907) (xy 379.369384 -237.05889) (xy 379.421346 -237.07075)
			(xy 379.47096 -237.090222) (xy 379.517118 -237.116871) (xy 379.558789 -237.150102) (xy 379.595041 -237.189173)
			(xy 379.625065 -237.23321) (xy 379.648191 -237.281231) (xy 379.663901 -237.332161) (xy 379.671844 -237.384865)
			(xy 379.672342 -237.411514) (xy 379.671844 -237.438163) (xy 379.900424 -237.438163) (xy 379.900424 -237.384865)
			(xy 379.908367 -237.332161) (xy 379.924077 -237.281231) (xy 379.947203 -237.23321) (xy 379.977227 -237.189173)
			(xy 380.013479 -237.150102) (xy 380.05515 -237.116871) (xy 380.101308 -237.090222) (xy 380.150922 -237.07075)
			(xy 380.202884 -237.05889) (xy 380.256034 -237.054907) (xy 380.309184 -237.05889) (xy 380.361146 -237.07075)
			(xy 380.41076 -237.090222) (xy 380.456918 -237.116871) (xy 380.498589 -237.150102) (xy 380.534841 -237.189173)
			(xy 380.564865 -237.23321) (xy 380.587991 -237.281231) (xy 380.603701 -237.332161) (xy 380.611644 -237.384865)
			(xy 380.612142 -237.411514) (xy 380.611644 -237.438163) (xy 380.603701 -237.490867) (xy 380.587991 -237.541797)
			(xy 380.564865 -237.589818) (xy 380.534841 -237.633855) (xy 380.498589 -237.672926) (xy 380.456918 -237.706157)
			(xy 380.41076 -237.732806) (xy 380.361146 -237.752278) (xy 380.309184 -237.764138) (xy 380.256034 -237.768122)
			(xy 380.202884 -237.764138) (xy 380.150922 -237.752278) (xy 380.101308 -237.732806) (xy 380.05515 -237.706157)
			(xy 380.013479 -237.672926) (xy 379.977227 -237.633855) (xy 379.947203 -237.589818) (xy 379.924077 -237.541797)
			(xy 379.908367 -237.490867) (xy 379.900424 -237.438163) (xy 379.671844 -237.438163) (xy 379.663901 -237.490867)
			(xy 379.648191 -237.541797) (xy 379.625065 -237.589818) (xy 379.595041 -237.633855) (xy 379.558789 -237.672926)
			(xy 379.517118 -237.706157) (xy 379.47096 -237.732806) (xy 379.421346 -237.752278) (xy 379.369384 -237.764138)
			(xy 379.316234 -237.768122) (xy 379.263084 -237.764138) (xy 379.211122 -237.752278) (xy 379.161508 -237.732806)
			(xy 379.11535 -237.706157) (xy 379.073679 -237.672926) (xy 379.037427 -237.633855) (xy 379.007403 -237.589818)
			(xy 378.984277 -237.541797) (xy 378.968567 -237.490867) (xy 378.960624 -237.438163) (xy 378.732044 -237.438163)
			(xy 378.724101 -237.490867) (xy 378.708391 -237.541797) (xy 378.685265 -237.589818) (xy 378.655241 -237.633855)
			(xy 378.618989 -237.672926) (xy 378.577318 -237.706157) (xy 378.53116 -237.732806) (xy 378.481546 -237.752278)
			(xy 378.429584 -237.764138) (xy 378.376434 -237.768122) (xy 378.323284 -237.764138) (xy 378.271322 -237.752278)
			(xy 378.221708 -237.732806) (xy 378.17555 -237.706157) (xy 378.133879 -237.672926) (xy 378.097627 -237.633855)
			(xy 378.067603 -237.589818) (xy 378.044477 -237.541797) (xy 378.028767 -237.490867) (xy 378.020824 -237.438163)
			(xy 377.792244 -237.438163) (xy 377.784301 -237.490867) (xy 377.768591 -237.541797) (xy 377.745465 -237.589818)
			(xy 377.715441 -237.633855) (xy 377.679189 -237.672926) (xy 377.637518 -237.706157) (xy 377.59136 -237.732806)
			(xy 377.541746 -237.752278) (xy 377.489784 -237.764138) (xy 377.436634 -237.768122) (xy 377.383484 -237.764138)
			(xy 377.331522 -237.752278) (xy 377.281908 -237.732806) (xy 377.23575 -237.706157) (xy 377.194079 -237.672926)
			(xy 377.157827 -237.633855) (xy 377.127803 -237.589818) (xy 377.104677 -237.541797) (xy 377.088967 -237.490867)
			(xy 377.081024 -237.438163) (xy 376.852444 -237.438163) (xy 376.844501 -237.490867) (xy 376.828791 -237.541797)
			(xy 376.805665 -237.589818) (xy 376.775641 -237.633855) (xy 376.739389 -237.672926) (xy 376.697718 -237.706157)
			(xy 376.65156 -237.732806) (xy 376.601946 -237.752278) (xy 376.549984 -237.764138) (xy 376.496834 -237.768122)
			(xy 376.443684 -237.764138) (xy 376.391722 -237.752278) (xy 376.342108 -237.732806) (xy 376.29595 -237.706157)
			(xy 376.254279 -237.672926) (xy 376.218027 -237.633855) (xy 376.188003 -237.589818) (xy 376.164877 -237.541797)
			(xy 376.149167 -237.490867) (xy 376.141224 -237.438163) (xy 375.912644 -237.438163) (xy 375.904701 -237.490867)
			(xy 375.888991 -237.541797) (xy 375.865865 -237.589818) (xy 375.835841 -237.633855) (xy 375.799589 -237.672926)
			(xy 375.757918 -237.706157) (xy 375.71176 -237.732806) (xy 375.662146 -237.752278) (xy 375.610184 -237.764138)
			(xy 375.557034 -237.768122) (xy 375.503884 -237.764138) (xy 375.451922 -237.752278) (xy 375.402308 -237.732806)
			(xy 375.35615 -237.706157) (xy 375.314479 -237.672926) (xy 375.278227 -237.633855) (xy 375.248203 -237.589818)
			(xy 375.225077 -237.541797) (xy 375.209367 -237.490867) (xy 375.201424 -237.438163) (xy 374.972844 -237.438163)
			(xy 374.964901 -237.490867) (xy 374.949191 -237.541797) (xy 374.926065 -237.589818) (xy 374.896041 -237.633855)
			(xy 374.859789 -237.672926) (xy 374.818118 -237.706157) (xy 374.77196 -237.732806) (xy 374.722346 -237.752278)
			(xy 374.670384 -237.764138) (xy 374.617234 -237.768122) (xy 374.564084 -237.764138) (xy 374.512122 -237.752278)
			(xy 374.462508 -237.732806) (xy 374.41635 -237.706157) (xy 374.374679 -237.672926) (xy 374.338427 -237.633855)
			(xy 374.308403 -237.589818) (xy 374.285277 -237.541797) (xy 374.269567 -237.490867) (xy 374.261624 -237.438163)
			(xy 374.033044 -237.438163) (xy 374.025101 -237.490867) (xy 374.009391 -237.541797) (xy 373.986265 -237.589818)
			(xy 373.956241 -237.633855) (xy 373.919989 -237.672926) (xy 373.878318 -237.706157) (xy 373.83216 -237.732806)
			(xy 373.782546 -237.752278) (xy 373.730584 -237.764138) (xy 373.677434 -237.768122) (xy 373.624284 -237.764138)
			(xy 373.572322 -237.752278) (xy 373.522708 -237.732806) (xy 373.47655 -237.706157) (xy 373.434879 -237.672926)
			(xy 373.398627 -237.633855) (xy 373.368603 -237.589818) (xy 373.345477 -237.541797) (xy 373.329767 -237.490867)
			(xy 373.321824 -237.438163) (xy 373.093244 -237.438163) (xy 373.085301 -237.490867) (xy 373.069591 -237.541797)
			(xy 373.046465 -237.589818) (xy 373.016441 -237.633855) (xy 372.980189 -237.672926) (xy 372.938518 -237.706157)
			(xy 372.89236 -237.732806) (xy 372.842746 -237.752278) (xy 372.790784 -237.764138) (xy 372.737634 -237.768122)
			(xy 372.684484 -237.764138) (xy 372.632522 -237.752278) (xy 372.582908 -237.732806) (xy 372.53675 -237.706157)
			(xy 372.495079 -237.672926) (xy 372.458827 -237.633855) (xy 372.428803 -237.589818) (xy 372.405677 -237.541797)
			(xy 372.389967 -237.490867) (xy 372.382024 -237.438163) (xy 372.153444 -237.438163) (xy 372.145501 -237.490867)
			(xy 372.129791 -237.541797) (xy 372.106665 -237.589818) (xy 372.076641 -237.633855) (xy 372.040389 -237.672926)
			(xy 371.998718 -237.706157) (xy 371.95256 -237.732806) (xy 371.902946 -237.752278) (xy 371.850984 -237.764138)
			(xy 371.797834 -237.768122) (xy 371.744684 -237.764138) (xy 371.692722 -237.752278) (xy 371.643108 -237.732806)
			(xy 371.59695 -237.706157) (xy 371.555279 -237.672926) (xy 371.519027 -237.633855) (xy 371.489003 -237.589818)
			(xy 371.465877 -237.541797) (xy 371.450167 -237.490867) (xy 371.442224 -237.438163) (xy 371.213644 -237.438163)
			(xy 371.205701 -237.490867) (xy 371.189991 -237.541797) (xy 371.166865 -237.589818) (xy 371.136841 -237.633855)
			(xy 371.100589 -237.672926) (xy 371.058918 -237.706157) (xy 371.01276 -237.732806) (xy 370.963146 -237.752278)
			(xy 370.911184 -237.764138) (xy 370.858034 -237.768122) (xy 370.804884 -237.764138) (xy 370.752922 -237.752278)
			(xy 370.703308 -237.732806) (xy 370.65715 -237.706157) (xy 370.615479 -237.672926) (xy 370.579227 -237.633855)
			(xy 370.549203 -237.589818) (xy 370.526077 -237.541797) (xy 370.510367 -237.490867) (xy 370.502424 -237.438163)
			(xy 370.273844 -237.438163) (xy 370.265901 -237.490867) (xy 370.250191 -237.541797) (xy 370.227065 -237.589818)
			(xy 370.197041 -237.633855) (xy 370.160789 -237.672926) (xy 370.119118 -237.706157) (xy 370.07296 -237.732806)
			(xy 370.023346 -237.752278) (xy 369.971384 -237.764138) (xy 369.918234 -237.768122) (xy 369.865084 -237.764138)
			(xy 369.813122 -237.752278) (xy 369.763508 -237.732806) (xy 369.71735 -237.706157) (xy 369.675679 -237.672926)
			(xy 369.639427 -237.633855) (xy 369.609403 -237.589818) (xy 369.586277 -237.541797) (xy 369.570567 -237.490867)
			(xy 369.562624 -237.438163) (xy 369.271975 -237.438163) (xy 369.271814 -237.446799) (xy 369.263871 -237.499503)
			(xy 369.248161 -237.550433) (xy 369.225035 -237.598454) (xy 369.195011 -237.642491) (xy 369.158759 -237.681562)
			(xy 369.117088 -237.714793) (xy 369.07093 -237.741442) (xy 369.021316 -237.760914) (xy 368.969354 -237.772774)
			(xy 368.916204 -237.776758) (xy 368.863054 -237.772774) (xy 368.811092 -237.760914) (xy 368.761478 -237.741442)
			(xy 368.71532 -237.714793) (xy 368.673649 -237.681562) (xy 368.637397 -237.642491) (xy 368.607373 -237.598454)
			(xy 368.584247 -237.550433) (xy 368.568537 -237.499503) (xy 368.560594 -237.446799) (xy 367.687331 -237.446799)
			(xy 368.40668 -238.166148) (xy 368.40668 -238.252233) (xy 369.09247 -238.252233) (xy 369.09247 -238.198935)
			(xy 369.100413 -238.146231) (xy 369.116123 -238.095301) (xy 369.139249 -238.04728) (xy 369.169273 -238.003243)
			(xy 369.205525 -237.964172) (xy 369.247196 -237.930941) (xy 369.293354 -237.904292) (xy 369.342968 -237.88482)
			(xy 369.39493 -237.87296) (xy 369.44808 -237.868977) (xy 369.50123 -237.87296) (xy 369.553192 -237.88482)
			(xy 369.602806 -237.904292) (xy 369.648964 -237.930941) (xy 369.690635 -237.964172) (xy 369.726887 -238.003243)
			(xy 369.756911 -238.04728) (xy 369.780037 -238.095301) (xy 369.795747 -238.146231) (xy 369.80369 -238.198935)
			(xy 369.804188 -238.225584) (xy 369.80369 -238.252233) (xy 370.03227 -238.252233) (xy 370.03227 -238.198935)
			(xy 370.040213 -238.146231) (xy 370.055923 -238.095301) (xy 370.079049 -238.04728) (xy 370.109073 -238.003243)
			(xy 370.145325 -237.964172) (xy 370.186996 -237.930941) (xy 370.233154 -237.904292) (xy 370.282768 -237.88482)
			(xy 370.33473 -237.87296) (xy 370.38788 -237.868977) (xy 370.44103 -237.87296) (xy 370.492992 -237.88482)
			(xy 370.542606 -237.904292) (xy 370.588764 -237.930941) (xy 370.630435 -237.964172) (xy 370.666687 -238.003243)
			(xy 370.696711 -238.04728) (xy 370.719837 -238.095301) (xy 370.735547 -238.146231) (xy 370.74349 -238.198935)
			(xy 370.743988 -238.225584) (xy 370.74349 -238.252233) (xy 370.97207 -238.252233) (xy 370.97207 -238.198935)
			(xy 370.980013 -238.146231) (xy 370.995723 -238.095301) (xy 371.018849 -238.04728) (xy 371.048873 -238.003243)
			(xy 371.085125 -237.964172) (xy 371.126796 -237.930941) (xy 371.172954 -237.904292) (xy 371.222568 -237.88482)
			(xy 371.27453 -237.87296) (xy 371.32768 -237.868977) (xy 371.38083 -237.87296) (xy 371.432792 -237.88482)
			(xy 371.482406 -237.904292) (xy 371.528564 -237.930941) (xy 371.570235 -237.964172) (xy 371.606487 -238.003243)
			(xy 371.636511 -238.04728) (xy 371.659637 -238.095301) (xy 371.675347 -238.146231) (xy 371.68329 -238.198935)
			(xy 371.683788 -238.225584) (xy 371.68329 -238.252233) (xy 371.91187 -238.252233) (xy 371.91187 -238.198935)
			(xy 371.919813 -238.146231) (xy 371.935523 -238.095301) (xy 371.958649 -238.04728) (xy 371.988673 -238.003243)
			(xy 372.024925 -237.964172) (xy 372.066596 -237.930941) (xy 372.112754 -237.904292) (xy 372.162368 -237.88482)
			(xy 372.21433 -237.87296) (xy 372.26748 -237.868977) (xy 372.32063 -237.87296) (xy 372.372592 -237.88482)
			(xy 372.422206 -237.904292) (xy 372.468364 -237.930941) (xy 372.510035 -237.964172) (xy 372.546287 -238.003243)
			(xy 372.576311 -238.04728) (xy 372.599437 -238.095301) (xy 372.615147 -238.146231) (xy 372.62309 -238.198935)
			(xy 372.623588 -238.225584) (xy 372.62309 -238.252233) (xy 372.85167 -238.252233) (xy 372.85167 -238.198935)
			(xy 372.859613 -238.146231) (xy 372.875323 -238.095301) (xy 372.898449 -238.04728) (xy 372.928473 -238.003243)
			(xy 372.964725 -237.964172) (xy 373.006396 -237.930941) (xy 373.052554 -237.904292) (xy 373.102168 -237.88482)
			(xy 373.15413 -237.87296) (xy 373.20728 -237.868977) (xy 373.26043 -237.87296) (xy 373.312392 -237.88482)
			(xy 373.362006 -237.904292) (xy 373.408164 -237.930941) (xy 373.449835 -237.964172) (xy 373.486087 -238.003243)
			(xy 373.516111 -238.04728) (xy 373.539237 -238.095301) (xy 373.554947 -238.146231) (xy 373.56289 -238.198935)
			(xy 373.563388 -238.225584) (xy 373.56289 -238.252233) (xy 373.791724 -238.252233) (xy 373.791724 -238.198935)
			(xy 373.799667 -238.146231) (xy 373.815377 -238.095301) (xy 373.838503 -238.04728) (xy 373.868527 -238.003243)
			(xy 373.904779 -237.964172) (xy 373.94645 -237.930941) (xy 373.992608 -237.904292) (xy 374.042222 -237.88482)
			(xy 374.094184 -237.87296) (xy 374.147334 -237.868977) (xy 374.200484 -237.87296) (xy 374.252446 -237.88482)
			(xy 374.30206 -237.904292) (xy 374.348218 -237.930941) (xy 374.389889 -237.964172) (xy 374.426141 -238.003243)
			(xy 374.456165 -238.04728) (xy 374.479291 -238.095301) (xy 374.495001 -238.146231) (xy 374.502944 -238.198935)
			(xy 374.503442 -238.225584) (xy 374.502944 -238.252233) (xy 374.73127 -238.252233) (xy 374.73127 -238.198935)
			(xy 374.739213 -238.146231) (xy 374.754923 -238.095301) (xy 374.778049 -238.04728) (xy 374.808073 -238.003243)
			(xy 374.844325 -237.964172) (xy 374.885996 -237.930941) (xy 374.932154 -237.904292) (xy 374.981768 -237.88482)
			(xy 375.03373 -237.87296) (xy 375.08688 -237.868977) (xy 375.14003 -237.87296) (xy 375.191992 -237.88482)
			(xy 375.241606 -237.904292) (xy 375.287764 -237.930941) (xy 375.329435 -237.964172) (xy 375.365687 -238.003243)
			(xy 375.395711 -238.04728) (xy 375.418837 -238.095301) (xy 375.434547 -238.146231) (xy 375.44249 -238.198935)
			(xy 375.442988 -238.225584) (xy 375.44249 -238.252233) (xy 375.67107 -238.252233) (xy 375.67107 -238.198935)
			(xy 375.679013 -238.146231) (xy 375.694723 -238.095301) (xy 375.717849 -238.04728) (xy 375.747873 -238.003243)
			(xy 375.784125 -237.964172) (xy 375.825796 -237.930941) (xy 375.871954 -237.904292) (xy 375.921568 -237.88482)
			(xy 375.97353 -237.87296) (xy 376.02668 -237.868977) (xy 376.07983 -237.87296) (xy 376.131792 -237.88482)
			(xy 376.181406 -237.904292) (xy 376.227564 -237.930941) (xy 376.269235 -237.964172) (xy 376.305487 -238.003243)
			(xy 376.335511 -238.04728) (xy 376.358637 -238.095301) (xy 376.374347 -238.146231) (xy 376.38229 -238.198935)
			(xy 376.382788 -238.225584) (xy 376.38229 -238.252233) (xy 376.61087 -238.252233) (xy 376.61087 -238.198935)
			(xy 376.618813 -238.146231) (xy 376.634523 -238.095301) (xy 376.657649 -238.04728) (xy 376.687673 -238.003243)
			(xy 376.723925 -237.964172) (xy 376.765596 -237.930941) (xy 376.811754 -237.904292) (xy 376.861368 -237.88482)
			(xy 376.91333 -237.87296) (xy 376.96648 -237.868977) (xy 377.01963 -237.87296) (xy 377.071592 -237.88482)
			(xy 377.121206 -237.904292) (xy 377.167364 -237.930941) (xy 377.209035 -237.964172) (xy 377.245287 -238.003243)
			(xy 377.275311 -238.04728) (xy 377.298437 -238.095301) (xy 377.314147 -238.146231) (xy 377.32209 -238.198935)
			(xy 377.322588 -238.225584) (xy 377.32209 -238.252233) (xy 377.55067 -238.252233) (xy 377.55067 -238.198935)
			(xy 377.558613 -238.146231) (xy 377.574323 -238.095301) (xy 377.597449 -238.04728) (xy 377.627473 -238.003243)
			(xy 377.663725 -237.964172) (xy 377.705396 -237.930941) (xy 377.751554 -237.904292) (xy 377.801168 -237.88482)
			(xy 377.85313 -237.87296) (xy 377.90628 -237.868977) (xy 377.95943 -237.87296) (xy 378.011392 -237.88482)
			(xy 378.061006 -237.904292) (xy 378.107164 -237.930941) (xy 378.148835 -237.964172) (xy 378.185087 -238.003243)
			(xy 378.215111 -238.04728) (xy 378.238237 -238.095301) (xy 378.253947 -238.146231) (xy 378.26189 -238.198935)
			(xy 378.262388 -238.225584) (xy 378.26189 -238.252233) (xy 378.49047 -238.252233) (xy 378.49047 -238.198935)
			(xy 378.498413 -238.146231) (xy 378.514123 -238.095301) (xy 378.537249 -238.04728) (xy 378.567273 -238.003243)
			(xy 378.603525 -237.964172) (xy 378.645196 -237.930941) (xy 378.691354 -237.904292) (xy 378.740968 -237.88482)
			(xy 378.79293 -237.87296) (xy 378.84608 -237.868977) (xy 378.89923 -237.87296) (xy 378.951192 -237.88482)
			(xy 379.000806 -237.904292) (xy 379.046964 -237.930941) (xy 379.088635 -237.964172) (xy 379.124887 -238.003243)
			(xy 379.154911 -238.04728) (xy 379.178037 -238.095301) (xy 379.193747 -238.146231) (xy 379.20169 -238.198935)
			(xy 379.202188 -238.225584) (xy 379.20169 -238.252233) (xy 379.43027 -238.252233) (xy 379.43027 -238.198935)
			(xy 379.438213 -238.146231) (xy 379.453923 -238.095301) (xy 379.477049 -238.04728) (xy 379.507073 -238.003243)
			(xy 379.543325 -237.964172) (xy 379.584996 -237.930941) (xy 379.631154 -237.904292) (xy 379.680768 -237.88482)
			(xy 379.73273 -237.87296) (xy 379.78588 -237.868977) (xy 379.83903 -237.87296) (xy 379.890992 -237.88482)
			(xy 379.940606 -237.904292) (xy 379.986764 -237.930941) (xy 380.028435 -237.964172) (xy 380.064687 -238.003243)
			(xy 380.094711 -238.04728) (xy 380.117837 -238.095301) (xy 380.133547 -238.146231) (xy 380.14149 -238.198935)
			(xy 380.141988 -238.225584) (xy 380.14149 -238.252233) (xy 380.133547 -238.304937) (xy 380.117837 -238.355867)
			(xy 380.094711 -238.403888) (xy 380.064687 -238.447925) (xy 380.028435 -238.486996) (xy 379.986764 -238.520227)
			(xy 379.940606 -238.546876) (xy 379.890992 -238.566348) (xy 379.83903 -238.578208) (xy 379.78588 -238.582192)
			(xy 379.73273 -238.578208) (xy 379.680768 -238.566348) (xy 379.631154 -238.546876) (xy 379.584996 -238.520227)
			(xy 379.543325 -238.486996) (xy 379.507073 -238.447925) (xy 379.477049 -238.403888) (xy 379.453923 -238.355867)
			(xy 379.438213 -238.304937) (xy 379.43027 -238.252233) (xy 379.20169 -238.252233) (xy 379.193747 -238.304937)
			(xy 379.178037 -238.355867) (xy 379.154911 -238.403888) (xy 379.124887 -238.447925) (xy 379.088635 -238.486996)
			(xy 379.046964 -238.520227) (xy 379.000806 -238.546876) (xy 378.951192 -238.566348) (xy 378.89923 -238.578208)
			(xy 378.84608 -238.582192) (xy 378.79293 -238.578208) (xy 378.740968 -238.566348) (xy 378.691354 -238.546876)
			(xy 378.645196 -238.520227) (xy 378.603525 -238.486996) (xy 378.567273 -238.447925) (xy 378.537249 -238.403888)
			(xy 378.514123 -238.355867) (xy 378.498413 -238.304937) (xy 378.49047 -238.252233) (xy 378.26189 -238.252233)
			(xy 378.253947 -238.304937) (xy 378.238237 -238.355867) (xy 378.215111 -238.403888) (xy 378.185087 -238.447925)
			(xy 378.148835 -238.486996) (xy 378.107164 -238.520227) (xy 378.061006 -238.546876) (xy 378.011392 -238.566348)
			(xy 377.95943 -238.578208) (xy 377.90628 -238.582192) (xy 377.85313 -238.578208) (xy 377.801168 -238.566348)
			(xy 377.751554 -238.546876) (xy 377.705396 -238.520227) (xy 377.663725 -238.486996) (xy 377.627473 -238.447925)
			(xy 377.597449 -238.403888) (xy 377.574323 -238.355867) (xy 377.558613 -238.304937) (xy 377.55067 -238.252233)
			(xy 377.32209 -238.252233) (xy 377.314147 -238.304937) (xy 377.298437 -238.355867) (xy 377.275311 -238.403888)
			(xy 377.245287 -238.447925) (xy 377.209035 -238.486996) (xy 377.167364 -238.520227) (xy 377.121206 -238.546876)
			(xy 377.071592 -238.566348) (xy 377.01963 -238.578208) (xy 376.96648 -238.582192) (xy 376.91333 -238.578208)
			(xy 376.861368 -238.566348) (xy 376.811754 -238.546876) (xy 376.765596 -238.520227) (xy 376.723925 -238.486996)
			(xy 376.687673 -238.447925) (xy 376.657649 -238.403888) (xy 376.634523 -238.355867) (xy 376.618813 -238.304937)
			(xy 376.61087 -238.252233) (xy 376.38229 -238.252233) (xy 376.374347 -238.304937) (xy 376.358637 -238.355867)
			(xy 376.335511 -238.403888) (xy 376.305487 -238.447925) (xy 376.269235 -238.486996) (xy 376.227564 -238.520227)
			(xy 376.181406 -238.546876) (xy 376.131792 -238.566348) (xy 376.07983 -238.578208) (xy 376.02668 -238.582192)
			(xy 375.97353 -238.578208) (xy 375.921568 -238.566348) (xy 375.871954 -238.546876) (xy 375.825796 -238.520227)
			(xy 375.784125 -238.486996) (xy 375.747873 -238.447925) (xy 375.717849 -238.403888) (xy 375.694723 -238.355867)
			(xy 375.679013 -238.304937) (xy 375.67107 -238.252233) (xy 375.44249 -238.252233) (xy 375.434547 -238.304937)
			(xy 375.418837 -238.355867) (xy 375.395711 -238.403888) (xy 375.365687 -238.447925) (xy 375.329435 -238.486996)
			(xy 375.287764 -238.520227) (xy 375.241606 -238.546876) (xy 375.191992 -238.566348) (xy 375.14003 -238.578208)
			(xy 375.08688 -238.582192) (xy 375.03373 -238.578208) (xy 374.981768 -238.566348) (xy 374.932154 -238.546876)
			(xy 374.885996 -238.520227) (xy 374.844325 -238.486996) (xy 374.808073 -238.447925) (xy 374.778049 -238.403888)
			(xy 374.754923 -238.355867) (xy 374.739213 -238.304937) (xy 374.73127 -238.252233) (xy 374.502944 -238.252233)
			(xy 374.495001 -238.304937) (xy 374.479291 -238.355867) (xy 374.456165 -238.403888) (xy 374.426141 -238.447925)
			(xy 374.389889 -238.486996) (xy 374.348218 -238.520227) (xy 374.30206 -238.546876) (xy 374.252446 -238.566348)
			(xy 374.200484 -238.578208) (xy 374.147334 -238.582192) (xy 374.094184 -238.578208) (xy 374.042222 -238.566348)
			(xy 373.992608 -238.546876) (xy 373.94645 -238.520227) (xy 373.904779 -238.486996) (xy 373.868527 -238.447925)
			(xy 373.838503 -238.403888) (xy 373.815377 -238.355867) (xy 373.799667 -238.304937) (xy 373.791724 -238.252233)
			(xy 373.56289 -238.252233) (xy 373.554947 -238.304937) (xy 373.539237 -238.355867) (xy 373.516111 -238.403888)
			(xy 373.486087 -238.447925) (xy 373.449835 -238.486996) (xy 373.408164 -238.520227) (xy 373.362006 -238.546876)
			(xy 373.312392 -238.566348) (xy 373.26043 -238.578208) (xy 373.20728 -238.582192) (xy 373.15413 -238.578208)
			(xy 373.102168 -238.566348) (xy 373.052554 -238.546876) (xy 373.006396 -238.520227) (xy 372.964725 -238.486996)
			(xy 372.928473 -238.447925) (xy 372.898449 -238.403888) (xy 372.875323 -238.355867) (xy 372.859613 -238.304937)
			(xy 372.85167 -238.252233) (xy 372.62309 -238.252233) (xy 372.615147 -238.304937) (xy 372.599437 -238.355867)
			(xy 372.576311 -238.403888) (xy 372.546287 -238.447925) (xy 372.510035 -238.486996) (xy 372.468364 -238.520227)
			(xy 372.422206 -238.546876) (xy 372.372592 -238.566348) (xy 372.32063 -238.578208) (xy 372.26748 -238.582192)
			(xy 372.21433 -238.578208) (xy 372.162368 -238.566348) (xy 372.112754 -238.546876) (xy 372.066596 -238.520227)
			(xy 372.024925 -238.486996) (xy 371.988673 -238.447925) (xy 371.958649 -238.403888) (xy 371.935523 -238.355867)
			(xy 371.919813 -238.304937) (xy 371.91187 -238.252233) (xy 371.68329 -238.252233) (xy 371.675347 -238.304937)
			(xy 371.659637 -238.355867) (xy 371.636511 -238.403888) (xy 371.606487 -238.447925) (xy 371.570235 -238.486996)
			(xy 371.528564 -238.520227) (xy 371.482406 -238.546876) (xy 371.432792 -238.566348) (xy 371.38083 -238.578208)
			(xy 371.32768 -238.582192) (xy 371.27453 -238.578208) (xy 371.222568 -238.566348) (xy 371.172954 -238.546876)
			(xy 371.126796 -238.520227) (xy 371.085125 -238.486996) (xy 371.048873 -238.447925) (xy 371.018849 -238.403888)
			(xy 370.995723 -238.355867) (xy 370.980013 -238.304937) (xy 370.97207 -238.252233) (xy 370.74349 -238.252233)
			(xy 370.735547 -238.304937) (xy 370.719837 -238.355867) (xy 370.696711 -238.403888) (xy 370.666687 -238.447925)
			(xy 370.630435 -238.486996) (xy 370.588764 -238.520227) (xy 370.542606 -238.546876) (xy 370.492992 -238.566348)
			(xy 370.44103 -238.578208) (xy 370.38788 -238.582192) (xy 370.33473 -238.578208) (xy 370.282768 -238.566348)
			(xy 370.233154 -238.546876) (xy 370.186996 -238.520227) (xy 370.145325 -238.486996) (xy 370.109073 -238.447925)
			(xy 370.079049 -238.403888) (xy 370.055923 -238.355867) (xy 370.040213 -238.304937) (xy 370.03227 -238.252233)
			(xy 369.80369 -238.252233) (xy 369.795747 -238.304937) (xy 369.780037 -238.355867) (xy 369.756911 -238.403888)
			(xy 369.726887 -238.447925) (xy 369.690635 -238.486996) (xy 369.648964 -238.520227) (xy 369.602806 -238.546876)
			(xy 369.553192 -238.566348) (xy 369.50123 -238.578208) (xy 369.44808 -238.582192) (xy 369.39493 -238.578208)
			(xy 369.342968 -238.566348) (xy 369.293354 -238.546876) (xy 369.247196 -238.520227) (xy 369.205525 -238.486996)
			(xy 369.169273 -238.447925) (xy 369.139249 -238.403888) (xy 369.116123 -238.355867) (xy 369.100413 -238.304937)
			(xy 369.09247 -238.252233) (xy 368.40668 -238.252233) (xy 368.40668 -238.976662) (xy 368.437668 -238.98987)
			(xy 368.461392 -239.000518) (xy 368.505732 -239.027681) (xy 368.545653 -239.061001) (xy 368.550165 -239.066049)
			(xy 369.562624 -239.066049) (xy 369.562624 -239.012751) (xy 369.570567 -238.960047) (xy 369.586277 -238.909117)
			(xy 369.609403 -238.861096) (xy 369.639427 -238.817059) (xy 369.675679 -238.777988) (xy 369.71735 -238.744757)
			(xy 369.763508 -238.718108) (xy 369.813122 -238.698636) (xy 369.865084 -238.686776) (xy 369.918234 -238.682793)
			(xy 369.971384 -238.686776) (xy 370.023346 -238.698636) (xy 370.07296 -238.718108) (xy 370.119118 -238.744757)
			(xy 370.160789 -238.777988) (xy 370.197041 -238.817059) (xy 370.227065 -238.861096) (xy 370.250191 -238.909117)
			(xy 370.265901 -238.960047) (xy 370.273844 -239.012751) (xy 370.274342 -239.0394) (xy 370.273844 -239.066049)
			(xy 370.50217 -239.066049) (xy 370.50217 -239.012751) (xy 370.510113 -238.960047) (xy 370.525823 -238.909117)
			(xy 370.548949 -238.861096) (xy 370.578973 -238.817059) (xy 370.615225 -238.777988) (xy 370.656896 -238.744757)
			(xy 370.703054 -238.718108) (xy 370.752668 -238.698636) (xy 370.80463 -238.686776) (xy 370.85778 -238.682793)
			(xy 370.91093 -238.686776) (xy 370.962892 -238.698636) (xy 371.012506 -238.718108) (xy 371.058664 -238.744757)
			(xy 371.100335 -238.777988) (xy 371.136587 -238.817059) (xy 371.166611 -238.861096) (xy 371.189737 -238.909117)
			(xy 371.205447 -238.960047) (xy 371.21339 -239.012751) (xy 371.213888 -239.0394) (xy 371.21339 -239.066049)
			(xy 371.442224 -239.066049) (xy 371.442224 -239.012751) (xy 371.450167 -238.960047) (xy 371.465877 -238.909117)
			(xy 371.489003 -238.861096) (xy 371.519027 -238.817059) (xy 371.555279 -238.777988) (xy 371.59695 -238.744757)
			(xy 371.643108 -238.718108) (xy 371.692722 -238.698636) (xy 371.744684 -238.686776) (xy 371.797834 -238.682793)
			(xy 371.850984 -238.686776) (xy 371.902946 -238.698636) (xy 371.95256 -238.718108) (xy 371.998718 -238.744757)
			(xy 372.040389 -238.777988) (xy 372.076641 -238.817059) (xy 372.106665 -238.861096) (xy 372.129791 -238.909117)
			(xy 372.145501 -238.960047) (xy 372.153444 -239.012751) (xy 372.153942 -239.0394) (xy 372.153444 -239.066049)
			(xy 372.382024 -239.066049) (xy 372.382024 -239.012751) (xy 372.389967 -238.960047) (xy 372.405677 -238.909117)
			(xy 372.428803 -238.861096) (xy 372.458827 -238.817059) (xy 372.495079 -238.777988) (xy 372.53675 -238.744757)
			(xy 372.582908 -238.718108) (xy 372.632522 -238.698636) (xy 372.684484 -238.686776) (xy 372.737634 -238.682793)
			(xy 372.790784 -238.686776) (xy 372.842746 -238.698636) (xy 372.89236 -238.718108) (xy 372.938518 -238.744757)
			(xy 372.980189 -238.777988) (xy 373.016441 -238.817059) (xy 373.046465 -238.861096) (xy 373.069591 -238.909117)
			(xy 373.085301 -238.960047) (xy 373.093244 -239.012751) (xy 373.093742 -239.0394) (xy 373.093244 -239.066049)
			(xy 373.321824 -239.066049) (xy 373.321824 -239.012751) (xy 373.329767 -238.960047) (xy 373.345477 -238.909117)
			(xy 373.368603 -238.861096) (xy 373.398627 -238.817059) (xy 373.434879 -238.777988) (xy 373.47655 -238.744757)
			(xy 373.522708 -238.718108) (xy 373.572322 -238.698636) (xy 373.624284 -238.686776) (xy 373.677434 -238.682793)
			(xy 373.730584 -238.686776) (xy 373.782546 -238.698636) (xy 373.83216 -238.718108) (xy 373.878318 -238.744757)
			(xy 373.919989 -238.777988) (xy 373.956241 -238.817059) (xy 373.986265 -238.861096) (xy 374.009391 -238.909117)
			(xy 374.025101 -238.960047) (xy 374.033044 -239.012751) (xy 374.033542 -239.0394) (xy 374.033044 -239.066049)
			(xy 374.261624 -239.066049) (xy 374.261624 -239.012751) (xy 374.269567 -238.960047) (xy 374.285277 -238.909117)
			(xy 374.308403 -238.861096) (xy 374.338427 -238.817059) (xy 374.374679 -238.777988) (xy 374.41635 -238.744757)
			(xy 374.462508 -238.718108) (xy 374.512122 -238.698636) (xy 374.564084 -238.686776) (xy 374.617234 -238.682793)
			(xy 374.670384 -238.686776) (xy 374.722346 -238.698636) (xy 374.77196 -238.718108) (xy 374.818118 -238.744757)
			(xy 374.859789 -238.777988) (xy 374.896041 -238.817059) (xy 374.926065 -238.861096) (xy 374.949191 -238.909117)
			(xy 374.964901 -238.960047) (xy 374.972844 -239.012751) (xy 374.973342 -239.0394) (xy 374.972844 -239.066049)
			(xy 375.201424 -239.066049) (xy 375.201424 -239.012751) (xy 375.209367 -238.960047) (xy 375.225077 -238.909117)
			(xy 375.248203 -238.861096) (xy 375.278227 -238.817059) (xy 375.314479 -238.777988) (xy 375.35615 -238.744757)
			(xy 375.402308 -238.718108) (xy 375.451922 -238.698636) (xy 375.503884 -238.686776) (xy 375.557034 -238.682793)
			(xy 375.610184 -238.686776) (xy 375.662146 -238.698636) (xy 375.71176 -238.718108) (xy 375.757918 -238.744757)
			(xy 375.799589 -238.777988) (xy 375.835841 -238.817059) (xy 375.865865 -238.861096) (xy 375.888991 -238.909117)
			(xy 375.904701 -238.960047) (xy 375.912644 -239.012751) (xy 375.913142 -239.0394) (xy 375.912644 -239.066049)
			(xy 376.141224 -239.066049) (xy 376.141224 -239.012751) (xy 376.149167 -238.960047) (xy 376.164877 -238.909117)
			(xy 376.188003 -238.861096) (xy 376.218027 -238.817059) (xy 376.254279 -238.777988) (xy 376.29595 -238.744757)
			(xy 376.342108 -238.718108) (xy 376.391722 -238.698636) (xy 376.443684 -238.686776) (xy 376.496834 -238.682793)
			(xy 376.549984 -238.686776) (xy 376.601946 -238.698636) (xy 376.65156 -238.718108) (xy 376.697718 -238.744757)
			(xy 376.739389 -238.777988) (xy 376.775641 -238.817059) (xy 376.805665 -238.861096) (xy 376.828791 -238.909117)
			(xy 376.844501 -238.960047) (xy 376.852444 -239.012751) (xy 376.852942 -239.0394) (xy 376.852444 -239.066049)
			(xy 377.08077 -239.066049) (xy 377.08077 -239.012751) (xy 377.088713 -238.960047) (xy 377.104423 -238.909117)
			(xy 377.127549 -238.861096) (xy 377.157573 -238.817059) (xy 377.193825 -238.777988) (xy 377.235496 -238.744757)
			(xy 377.281654 -238.718108) (xy 377.331268 -238.698636) (xy 377.38323 -238.686776) (xy 377.43638 -238.682793)
			(xy 377.48953 -238.686776) (xy 377.541492 -238.698636) (xy 377.591106 -238.718108) (xy 377.637264 -238.744757)
			(xy 377.678935 -238.777988) (xy 377.715187 -238.817059) (xy 377.745211 -238.861096) (xy 377.768337 -238.909117)
			(xy 377.784047 -238.960047) (xy 377.79199 -239.012751) (xy 377.792488 -239.0394) (xy 377.79199 -239.066049)
			(xy 378.020824 -239.066049) (xy 378.020824 -239.012751) (xy 378.028767 -238.960047) (xy 378.044477 -238.909117)
			(xy 378.067603 -238.861096) (xy 378.097627 -238.817059) (xy 378.133879 -238.777988) (xy 378.17555 -238.744757)
			(xy 378.221708 -238.718108) (xy 378.271322 -238.698636) (xy 378.323284 -238.686776) (xy 378.376434 -238.682793)
			(xy 378.429584 -238.686776) (xy 378.481546 -238.698636) (xy 378.53116 -238.718108) (xy 378.577318 -238.744757)
			(xy 378.618989 -238.777988) (xy 378.655241 -238.817059) (xy 378.685265 -238.861096) (xy 378.708391 -238.909117)
			(xy 378.724101 -238.960047) (xy 378.732044 -239.012751) (xy 378.732542 -239.0394) (xy 378.732044 -239.066049)
			(xy 378.960624 -239.066049) (xy 378.960624 -239.012751) (xy 378.968567 -238.960047) (xy 378.984277 -238.909117)
			(xy 379.007403 -238.861096) (xy 379.037427 -238.817059) (xy 379.073679 -238.777988) (xy 379.11535 -238.744757)
			(xy 379.161508 -238.718108) (xy 379.211122 -238.698636) (xy 379.263084 -238.686776) (xy 379.316234 -238.682793)
			(xy 379.369384 -238.686776) (xy 379.421346 -238.698636) (xy 379.47096 -238.718108) (xy 379.517118 -238.744757)
			(xy 379.558789 -238.777988) (xy 379.595041 -238.817059) (xy 379.625065 -238.861096) (xy 379.648191 -238.909117)
			(xy 379.663901 -238.960047) (xy 379.671844 -239.012751) (xy 379.672342 -239.0394) (xy 379.671844 -239.066049)
			(xy 379.900424 -239.066049) (xy 379.900424 -239.012751) (xy 379.908367 -238.960047) (xy 379.924077 -238.909117)
			(xy 379.947203 -238.861096) (xy 379.977227 -238.817059) (xy 380.013479 -238.777988) (xy 380.05515 -238.744757)
			(xy 380.101308 -238.718108) (xy 380.150922 -238.698636) (xy 380.202884 -238.686776) (xy 380.256034 -238.682793)
			(xy 380.309184 -238.686776) (xy 380.361146 -238.698636) (xy 380.41076 -238.718108) (xy 380.456918 -238.744757)
			(xy 380.498589 -238.777988) (xy 380.534841 -238.817059) (xy 380.564865 -238.861096) (xy 380.587991 -238.909117)
			(xy 380.603701 -238.960047) (xy 380.611644 -239.012751) (xy 380.612142 -239.0394) (xy 380.611644 -239.066049)
			(xy 380.603701 -239.118753) (xy 380.587991 -239.169683) (xy 380.564865 -239.217704) (xy 380.534841 -239.261741)
			(xy 380.498589 -239.300812) (xy 380.456918 -239.334043) (xy 380.41076 -239.360692) (xy 380.361146 -239.380164)
			(xy 380.309184 -239.392024) (xy 380.256034 -239.396008) (xy 380.202884 -239.392024) (xy 380.150922 -239.380164)
			(xy 380.101308 -239.360692) (xy 380.05515 -239.334043) (xy 380.013479 -239.300812) (xy 379.977227 -239.261741)
			(xy 379.947203 -239.217704) (xy 379.924077 -239.169683) (xy 379.908367 -239.118753) (xy 379.900424 -239.066049)
			(xy 379.671844 -239.066049) (xy 379.663901 -239.118753) (xy 379.648191 -239.169683) (xy 379.625065 -239.217704)
			(xy 379.595041 -239.261741) (xy 379.558789 -239.300812) (xy 379.517118 -239.334043) (xy 379.47096 -239.360692)
			(xy 379.421346 -239.380164) (xy 379.369384 -239.392024) (xy 379.316234 -239.396008) (xy 379.263084 -239.392024)
			(xy 379.211122 -239.380164) (xy 379.161508 -239.360692) (xy 379.11535 -239.334043) (xy 379.073679 -239.300812)
			(xy 379.037427 -239.261741) (xy 379.007403 -239.217704) (xy 378.984277 -239.169683) (xy 378.968567 -239.118753)
			(xy 378.960624 -239.066049) (xy 378.732044 -239.066049) (xy 378.724101 -239.118753) (xy 378.708391 -239.169683)
			(xy 378.685265 -239.217704) (xy 378.655241 -239.261741) (xy 378.618989 -239.300812) (xy 378.577318 -239.334043)
			(xy 378.53116 -239.360692) (xy 378.481546 -239.380164) (xy 378.429584 -239.392024) (xy 378.376434 -239.396008)
			(xy 378.323284 -239.392024) (xy 378.271322 -239.380164) (xy 378.221708 -239.360692) (xy 378.17555 -239.334043)
			(xy 378.133879 -239.300812) (xy 378.097627 -239.261741) (xy 378.067603 -239.217704) (xy 378.044477 -239.169683)
			(xy 378.028767 -239.118753) (xy 378.020824 -239.066049) (xy 377.79199 -239.066049) (xy 377.784047 -239.118753)
			(xy 377.768337 -239.169683) (xy 377.745211 -239.217704) (xy 377.715187 -239.261741) (xy 377.678935 -239.300812)
			(xy 377.637264 -239.334043) (xy 377.591106 -239.360692) (xy 377.541492 -239.380164) (xy 377.48953 -239.392024)
			(xy 377.43638 -239.396008) (xy 377.38323 -239.392024) (xy 377.331268 -239.380164) (xy 377.281654 -239.360692)
			(xy 377.235496 -239.334043) (xy 377.193825 -239.300812) (xy 377.157573 -239.261741) (xy 377.127549 -239.217704)
			(xy 377.104423 -239.169683) (xy 377.088713 -239.118753) (xy 377.08077 -239.066049) (xy 376.852444 -239.066049)
			(xy 376.844501 -239.118753) (xy 376.828791 -239.169683) (xy 376.805665 -239.217704) (xy 376.775641 -239.261741)
			(xy 376.739389 -239.300812) (xy 376.697718 -239.334043) (xy 376.65156 -239.360692) (xy 376.601946 -239.380164)
			(xy 376.549984 -239.392024) (xy 376.496834 -239.396008) (xy 376.443684 -239.392024) (xy 376.391722 -239.380164)
			(xy 376.342108 -239.360692) (xy 376.29595 -239.334043) (xy 376.254279 -239.300812) (xy 376.218027 -239.261741)
			(xy 376.188003 -239.217704) (xy 376.164877 -239.169683) (xy 376.149167 -239.118753) (xy 376.141224 -239.066049)
			(xy 375.912644 -239.066049) (xy 375.904701 -239.118753) (xy 375.888991 -239.169683) (xy 375.865865 -239.217704)
			(xy 375.835841 -239.261741) (xy 375.799589 -239.300812) (xy 375.757918 -239.334043) (xy 375.71176 -239.360692)
			(xy 375.662146 -239.380164) (xy 375.610184 -239.392024) (xy 375.557034 -239.396008) (xy 375.503884 -239.392024)
			(xy 375.451922 -239.380164) (xy 375.402308 -239.360692) (xy 375.35615 -239.334043) (xy 375.314479 -239.300812)
			(xy 375.278227 -239.261741) (xy 375.248203 -239.217704) (xy 375.225077 -239.169683) (xy 375.209367 -239.118753)
			(xy 375.201424 -239.066049) (xy 374.972844 -239.066049) (xy 374.964901 -239.118753) (xy 374.949191 -239.169683)
			(xy 374.926065 -239.217704) (xy 374.896041 -239.261741) (xy 374.859789 -239.300812) (xy 374.818118 -239.334043)
			(xy 374.77196 -239.360692) (xy 374.722346 -239.380164) (xy 374.670384 -239.392024) (xy 374.617234 -239.396008)
			(xy 374.564084 -239.392024) (xy 374.512122 -239.380164) (xy 374.462508 -239.360692) (xy 374.41635 -239.334043)
			(xy 374.374679 -239.300812) (xy 374.338427 -239.261741) (xy 374.308403 -239.217704) (xy 374.285277 -239.169683)
			(xy 374.269567 -239.118753) (xy 374.261624 -239.066049) (xy 374.033044 -239.066049) (xy 374.025101 -239.118753)
			(xy 374.009391 -239.169683) (xy 373.986265 -239.217704) (xy 373.956241 -239.261741) (xy 373.919989 -239.300812)
			(xy 373.878318 -239.334043) (xy 373.83216 -239.360692) (xy 373.782546 -239.380164) (xy 373.730584 -239.392024)
			(xy 373.677434 -239.396008) (xy 373.624284 -239.392024) (xy 373.572322 -239.380164) (xy 373.522708 -239.360692)
			(xy 373.47655 -239.334043) (xy 373.434879 -239.300812) (xy 373.398627 -239.261741) (xy 373.368603 -239.217704)
			(xy 373.345477 -239.169683) (xy 373.329767 -239.118753) (xy 373.321824 -239.066049) (xy 373.093244 -239.066049)
			(xy 373.085301 -239.118753) (xy 373.069591 -239.169683) (xy 373.046465 -239.217704) (xy 373.016441 -239.261741)
			(xy 372.980189 -239.300812) (xy 372.938518 -239.334043) (xy 372.89236 -239.360692) (xy 372.842746 -239.380164)
			(xy 372.790784 -239.392024) (xy 372.737634 -239.396008) (xy 372.684484 -239.392024) (xy 372.632522 -239.380164)
			(xy 372.582908 -239.360692) (xy 372.53675 -239.334043) (xy 372.495079 -239.300812) (xy 372.458827 -239.261741)
			(xy 372.428803 -239.217704) (xy 372.405677 -239.169683) (xy 372.389967 -239.118753) (xy 372.382024 -239.066049)
			(xy 372.153444 -239.066049) (xy 372.145501 -239.118753) (xy 372.129791 -239.169683) (xy 372.106665 -239.217704)
			(xy 372.076641 -239.261741) (xy 372.040389 -239.300812) (xy 371.998718 -239.334043) (xy 371.95256 -239.360692)
			(xy 371.902946 -239.380164) (xy 371.850984 -239.392024) (xy 371.797834 -239.396008) (xy 371.744684 -239.392024)
			(xy 371.692722 -239.380164) (xy 371.643108 -239.360692) (xy 371.59695 -239.334043) (xy 371.555279 -239.300812)
			(xy 371.519027 -239.261741) (xy 371.489003 -239.217704) (xy 371.465877 -239.169683) (xy 371.450167 -239.118753)
			(xy 371.442224 -239.066049) (xy 371.21339 -239.066049) (xy 371.205447 -239.118753) (xy 371.189737 -239.169683)
			(xy 371.166611 -239.217704) (xy 371.136587 -239.261741) (xy 371.100335 -239.300812) (xy 371.058664 -239.334043)
			(xy 371.012506 -239.360692) (xy 370.962892 -239.380164) (xy 370.91093 -239.392024) (xy 370.85778 -239.396008)
			(xy 370.80463 -239.392024) (xy 370.752668 -239.380164) (xy 370.703054 -239.360692) (xy 370.656896 -239.334043)
			(xy 370.615225 -239.300812) (xy 370.578973 -239.261741) (xy 370.548949 -239.217704) (xy 370.525823 -239.169683)
			(xy 370.510113 -239.118753) (xy 370.50217 -239.066049) (xy 370.273844 -239.066049) (xy 370.265901 -239.118753)
			(xy 370.250191 -239.169683) (xy 370.227065 -239.217704) (xy 370.197041 -239.261741) (xy 370.160789 -239.300812)
			(xy 370.119118 -239.334043) (xy 370.07296 -239.360692) (xy 370.023346 -239.380164) (xy 369.971384 -239.392024)
			(xy 369.918234 -239.396008) (xy 369.865084 -239.392024) (xy 369.813122 -239.380164) (xy 369.763508 -239.360692)
			(xy 369.71735 -239.334043) (xy 369.675679 -239.300812) (xy 369.639427 -239.261741) (xy 369.609403 -239.217704)
			(xy 369.586277 -239.169683) (xy 369.570567 -239.118753) (xy 369.562624 -239.066049) (xy 368.550165 -239.066049)
			(xy 368.580306 -239.09977) (xy 368.608955 -239.143165) (xy 368.630991 -239.190264) (xy 368.645947 -239.240066)
			(xy 368.653505 -239.291512) (xy 368.653503 -239.343511) (xy 368.645942 -239.394958) (xy 368.630983 -239.444758)
			(xy 368.608943 -239.491855) (xy 368.580291 -239.535248) (xy 368.545636 -239.574015) (xy 368.505713 -239.607333)
			(xy 368.461371 -239.634492) (xy 368.437668 -239.64519) (xy 368.40668 -239.658398) (xy 368.40668 -240.704116)
			(xy 368.533426 -240.704116) (xy 368.533844 -240.679447) (xy 368.540647 -240.63058) (xy 368.55414 -240.583122)
			(xy 368.574062 -240.537984) (xy 368.600032 -240.496034) (xy 368.615468 -240.476786) (xy 368.624077 -240.465644)
			(xy 368.635422 -240.439888) (xy 368.639305 -240.412012) (xy 368.635429 -240.384136) (xy 368.62409 -240.358377)
			(xy 368.615468 -240.347246) (xy 368.600031 -240.328) (xy 368.574072 -240.286044) (xy 368.554155 -240.240905)
			(xy 368.540661 -240.193449) (xy 368.533847 -240.144585) (xy 368.533426 -240.119916) (xy 368.533927 -240.091929)
			(xy 368.542682 -240.036645) (xy 368.559978 -239.983411) (xy 368.585389 -239.933539) (xy 368.618289 -239.888256)
			(xy 368.657869 -239.848678) (xy 368.703154 -239.815779) (xy 368.753028 -239.790371) (xy 368.806263 -239.773078)
			(xy 368.861547 -239.764326) (xy 368.889534 -239.763808) (xy 368.915966 -239.764263) (xy 368.968252 -239.772049)
			(xy 368.993674 -239.779302) (xy 369.008284 -239.783234) (xy 369.038525 -239.783262) (xy 369.067445 -239.774421)
			(xy 369.0925 -239.757486) (xy 369.111487 -239.733949) (xy 369.117626 -239.72012) (xy 369.12801 -239.695784)
			(xy 369.154838 -239.650182) (xy 369.188114 -239.609049) (xy 369.227107 -239.573289) (xy 369.27096 -239.543688)
			(xy 369.318707 -239.520898) (xy 369.3693 -239.505419) (xy 369.421626 -239.497592) (xy 369.44808 -239.497108)
			(xy 369.474733 -239.497548) (xy 369.527445 -239.50549) (xy 369.578384 -239.5212) (xy 369.626412 -239.544327)
			(xy 369.670457 -239.574354) (xy 369.709535 -239.610611) (xy 369.742772 -239.652287) (xy 369.769426 -239.698451)
			(xy 369.788902 -239.748073) (xy 369.800764 -239.800042) (xy 369.804748 -239.8532) (xy 369.80275 -239.879865)
			(xy 370.032524 -239.879865) (xy 370.032524 -239.826567) (xy 370.040467 -239.773863) (xy 370.056177 -239.722933)
			(xy 370.079303 -239.674912) (xy 370.109327 -239.630875) (xy 370.145579 -239.591804) (xy 370.18725 -239.558573)
			(xy 370.233408 -239.531924) (xy 370.283022 -239.512452) (xy 370.334984 -239.500592) (xy 370.388134 -239.496609)
			(xy 370.441284 -239.500592) (xy 370.493246 -239.512452) (xy 370.54286 -239.531924) (xy 370.589018 -239.558573)
			(xy 370.630689 -239.591804) (xy 370.666941 -239.630875) (xy 370.696965 -239.674912) (xy 370.720091 -239.722933)
			(xy 370.735801 -239.773863) (xy 370.743744 -239.826567) (xy 370.744242 -239.853216) (xy 370.743744 -239.879865)
			(xy 370.97207 -239.879865) (xy 370.97207 -239.826567) (xy 370.980013 -239.773863) (xy 370.995723 -239.722933)
			(xy 371.018849 -239.674912) (xy 371.048873 -239.630875) (xy 371.085125 -239.591804) (xy 371.126796 -239.558573)
			(xy 371.172954 -239.531924) (xy 371.222568 -239.512452) (xy 371.27453 -239.500592) (xy 371.32768 -239.496609)
			(xy 371.38083 -239.500592) (xy 371.432792 -239.512452) (xy 371.482406 -239.531924) (xy 371.528564 -239.558573)
			(xy 371.570235 -239.591804) (xy 371.606487 -239.630875) (xy 371.636511 -239.674912) (xy 371.659637 -239.722933)
			(xy 371.675347 -239.773863) (xy 371.68329 -239.826567) (xy 371.683788 -239.853216) (xy 371.68329 -239.879865)
			(xy 371.91187 -239.879865) (xy 371.91187 -239.826567) (xy 371.919813 -239.773863) (xy 371.935523 -239.722933)
			(xy 371.958649 -239.674912) (xy 371.988673 -239.630875) (xy 372.024925 -239.591804) (xy 372.066596 -239.558573)
			(xy 372.112754 -239.531924) (xy 372.162368 -239.512452) (xy 372.21433 -239.500592) (xy 372.26748 -239.496609)
			(xy 372.32063 -239.500592) (xy 372.372592 -239.512452) (xy 372.422206 -239.531924) (xy 372.468364 -239.558573)
			(xy 372.510035 -239.591804) (xy 372.546287 -239.630875) (xy 372.576311 -239.674912) (xy 372.599437 -239.722933)
			(xy 372.615147 -239.773863) (xy 372.62309 -239.826567) (xy 372.623588 -239.853216) (xy 372.62309 -239.879865)
			(xy 372.851924 -239.879865) (xy 372.851924 -239.826567) (xy 372.859867 -239.773863) (xy 372.875577 -239.722933)
			(xy 372.898703 -239.674912) (xy 372.928727 -239.630875) (xy 372.964979 -239.591804) (xy 373.00665 -239.558573)
			(xy 373.052808 -239.531924) (xy 373.102422 -239.512452) (xy 373.154384 -239.500592) (xy 373.207534 -239.496609)
			(xy 373.260684 -239.500592) (xy 373.312646 -239.512452) (xy 373.36226 -239.531924) (xy 373.408418 -239.558573)
			(xy 373.450089 -239.591804) (xy 373.486341 -239.630875) (xy 373.516365 -239.674912) (xy 373.539491 -239.722933)
			(xy 373.555201 -239.773863) (xy 373.563144 -239.826567) (xy 373.563642 -239.853216) (xy 373.563144 -239.879865)
			(xy 373.79147 -239.879865) (xy 373.79147 -239.826567) (xy 373.799413 -239.773863) (xy 373.815123 -239.722933)
			(xy 373.838249 -239.674912) (xy 373.868273 -239.630875) (xy 373.904525 -239.591804) (xy 373.946196 -239.558573)
			(xy 373.992354 -239.531924) (xy 374.041968 -239.512452) (xy 374.09393 -239.500592) (xy 374.14708 -239.496609)
			(xy 374.20023 -239.500592) (xy 374.252192 -239.512452) (xy 374.301806 -239.531924) (xy 374.347964 -239.558573)
			(xy 374.389635 -239.591804) (xy 374.425887 -239.630875) (xy 374.455911 -239.674912) (xy 374.479037 -239.722933)
			(xy 374.494747 -239.773863) (xy 374.50269 -239.826567) (xy 374.503188 -239.853216) (xy 374.50269 -239.879865)
			(xy 374.73127 -239.879865) (xy 374.73127 -239.826567) (xy 374.739213 -239.773863) (xy 374.754923 -239.722933)
			(xy 374.778049 -239.674912) (xy 374.808073 -239.630875) (xy 374.844325 -239.591804) (xy 374.885996 -239.558573)
			(xy 374.932154 -239.531924) (xy 374.981768 -239.512452) (xy 375.03373 -239.500592) (xy 375.08688 -239.496609)
			(xy 375.14003 -239.500592) (xy 375.191992 -239.512452) (xy 375.241606 -239.531924) (xy 375.287764 -239.558573)
			(xy 375.329435 -239.591804) (xy 375.365687 -239.630875) (xy 375.395711 -239.674912) (xy 375.418837 -239.722933)
			(xy 375.434547 -239.773863) (xy 375.44249 -239.826567) (xy 375.442988 -239.853216) (xy 375.44249 -239.879865)
			(xy 375.67107 -239.879865) (xy 375.67107 -239.826567) (xy 375.679013 -239.773863) (xy 375.694723 -239.722933)
			(xy 375.717849 -239.674912) (xy 375.747873 -239.630875) (xy 375.784125 -239.591804) (xy 375.825796 -239.558573)
			(xy 375.871954 -239.531924) (xy 375.921568 -239.512452) (xy 375.97353 -239.500592) (xy 376.02668 -239.496609)
			(xy 376.07983 -239.500592) (xy 376.131792 -239.512452) (xy 376.181406 -239.531924) (xy 376.227564 -239.558573)
			(xy 376.269235 -239.591804) (xy 376.305487 -239.630875) (xy 376.335511 -239.674912) (xy 376.358637 -239.722933)
			(xy 376.374347 -239.773863) (xy 376.38229 -239.826567) (xy 376.382788 -239.853216) (xy 376.38229 -239.879865)
			(xy 376.61087 -239.879865) (xy 376.61087 -239.826567) (xy 376.618813 -239.773863) (xy 376.634523 -239.722933)
			(xy 376.657649 -239.674912) (xy 376.687673 -239.630875) (xy 376.723925 -239.591804) (xy 376.765596 -239.558573)
			(xy 376.811754 -239.531924) (xy 376.861368 -239.512452) (xy 376.91333 -239.500592) (xy 376.96648 -239.496609)
			(xy 377.01963 -239.500592) (xy 377.071592 -239.512452) (xy 377.121206 -239.531924) (xy 377.167364 -239.558573)
			(xy 377.209035 -239.591804) (xy 377.245287 -239.630875) (xy 377.275311 -239.674912) (xy 377.298437 -239.722933)
			(xy 377.314147 -239.773863) (xy 377.32209 -239.826567) (xy 377.322588 -239.853216) (xy 377.32209 -239.879865)
			(xy 377.55067 -239.879865) (xy 377.55067 -239.826567) (xy 377.558613 -239.773863) (xy 377.574323 -239.722933)
			(xy 377.597449 -239.674912) (xy 377.627473 -239.630875) (xy 377.663725 -239.591804) (xy 377.705396 -239.558573)
			(xy 377.751554 -239.531924) (xy 377.801168 -239.512452) (xy 377.85313 -239.500592) (xy 377.90628 -239.496609)
			(xy 377.95943 -239.500592) (xy 378.011392 -239.512452) (xy 378.061006 -239.531924) (xy 378.107164 -239.558573)
			(xy 378.148835 -239.591804) (xy 378.185087 -239.630875) (xy 378.215111 -239.674912) (xy 378.238237 -239.722933)
			(xy 378.253947 -239.773863) (xy 378.26189 -239.826567) (xy 378.262388 -239.853216) (xy 378.26189 -239.879865)
			(xy 378.49047 -239.879865) (xy 378.49047 -239.826567) (xy 378.498413 -239.773863) (xy 378.514123 -239.722933)
			(xy 378.537249 -239.674912) (xy 378.567273 -239.630875) (xy 378.603525 -239.591804) (xy 378.645196 -239.558573)
			(xy 378.691354 -239.531924) (xy 378.740968 -239.512452) (xy 378.79293 -239.500592) (xy 378.84608 -239.496609)
			(xy 378.89923 -239.500592) (xy 378.951192 -239.512452) (xy 379.000806 -239.531924) (xy 379.046964 -239.558573)
			(xy 379.088635 -239.591804) (xy 379.124887 -239.630875) (xy 379.154911 -239.674912) (xy 379.178037 -239.722933)
			(xy 379.193747 -239.773863) (xy 379.20169 -239.826567) (xy 379.202188 -239.853216) (xy 379.20169 -239.879865)
			(xy 379.430524 -239.879865) (xy 379.430524 -239.826567) (xy 379.438467 -239.773863) (xy 379.454177 -239.722933)
			(xy 379.477303 -239.674912) (xy 379.507327 -239.630875) (xy 379.543579 -239.591804) (xy 379.58525 -239.558573)
			(xy 379.631408 -239.531924) (xy 379.681022 -239.512452) (xy 379.732984 -239.500592) (xy 379.786134 -239.496609)
			(xy 379.839284 -239.500592) (xy 379.891246 -239.512452) (xy 379.94086 -239.531924) (xy 379.987018 -239.558573)
			(xy 380.028689 -239.591804) (xy 380.064941 -239.630875) (xy 380.094965 -239.674912) (xy 380.118091 -239.722933)
			(xy 380.133801 -239.773863) (xy 380.141744 -239.826567) (xy 380.142242 -239.853216) (xy 380.141744 -239.879865)
			(xy 380.133801 -239.932569) (xy 380.118091 -239.983499) (xy 380.094965 -240.03152) (xy 380.064941 -240.075557)
			(xy 380.028689 -240.114628) (xy 379.987018 -240.147859) (xy 379.94086 -240.174508) (xy 379.891246 -240.19398)
			(xy 379.839284 -240.20584) (xy 379.786134 -240.209824) (xy 379.732984 -240.20584) (xy 379.681022 -240.19398)
			(xy 379.631408 -240.174508) (xy 379.58525 -240.147859) (xy 379.543579 -240.114628) (xy 379.507327 -240.075557)
			(xy 379.477303 -240.03152) (xy 379.454177 -239.983499) (xy 379.438467 -239.932569) (xy 379.430524 -239.879865)
			(xy 379.20169 -239.879865) (xy 379.193747 -239.932569) (xy 379.178037 -239.983499) (xy 379.154911 -240.03152)
			(xy 379.124887 -240.075557) (xy 379.088635 -240.114628) (xy 379.046964 -240.147859) (xy 379.000806 -240.174508)
			(xy 378.951192 -240.19398) (xy 378.89923 -240.20584) (xy 378.84608 -240.209824) (xy 378.79293 -240.20584)
			(xy 378.740968 -240.19398) (xy 378.691354 -240.174508) (xy 378.645196 -240.147859) (xy 378.603525 -240.114628)
			(xy 378.567273 -240.075557) (xy 378.537249 -240.03152) (xy 378.514123 -239.983499) (xy 378.498413 -239.932569)
			(xy 378.49047 -239.879865) (xy 378.26189 -239.879865) (xy 378.253947 -239.932569) (xy 378.238237 -239.983499)
			(xy 378.215111 -240.03152) (xy 378.185087 -240.075557) (xy 378.148835 -240.114628) (xy 378.107164 -240.147859)
			(xy 378.061006 -240.174508) (xy 378.011392 -240.19398) (xy 377.95943 -240.20584) (xy 377.90628 -240.209824)
			(xy 377.85313 -240.20584) (xy 377.801168 -240.19398) (xy 377.751554 -240.174508) (xy 377.705396 -240.147859)
			(xy 377.663725 -240.114628) (xy 377.627473 -240.075557) (xy 377.597449 -240.03152) (xy 377.574323 -239.983499)
			(xy 377.558613 -239.932569) (xy 377.55067 -239.879865) (xy 377.32209 -239.879865) (xy 377.314147 -239.932569)
			(xy 377.298437 -239.983499) (xy 377.275311 -240.03152) (xy 377.245287 -240.075557) (xy 377.209035 -240.114628)
			(xy 377.167364 -240.147859) (xy 377.121206 -240.174508) (xy 377.071592 -240.19398) (xy 377.01963 -240.20584)
			(xy 376.96648 -240.209824) (xy 376.91333 -240.20584) (xy 376.861368 -240.19398) (xy 376.811754 -240.174508)
			(xy 376.765596 -240.147859) (xy 376.723925 -240.114628) (xy 376.687673 -240.075557) (xy 376.657649 -240.03152)
			(xy 376.634523 -239.983499) (xy 376.618813 -239.932569) (xy 376.61087 -239.879865) (xy 376.38229 -239.879865)
			(xy 376.374347 -239.932569) (xy 376.358637 -239.983499) (xy 376.335511 -240.03152) (xy 376.305487 -240.075557)
			(xy 376.269235 -240.114628) (xy 376.227564 -240.147859) (xy 376.181406 -240.174508) (xy 376.131792 -240.19398)
			(xy 376.07983 -240.20584) (xy 376.02668 -240.209824) (xy 375.97353 -240.20584) (xy 375.921568 -240.19398)
			(xy 375.871954 -240.174508) (xy 375.825796 -240.147859) (xy 375.784125 -240.114628) (xy 375.747873 -240.075557)
			(xy 375.717849 -240.03152) (xy 375.694723 -239.983499) (xy 375.679013 -239.932569) (xy 375.67107 -239.879865)
			(xy 375.44249 -239.879865) (xy 375.434547 -239.932569) (xy 375.418837 -239.983499) (xy 375.395711 -240.03152)
			(xy 375.365687 -240.075557) (xy 375.329435 -240.114628) (xy 375.287764 -240.147859) (xy 375.241606 -240.174508)
			(xy 375.191992 -240.19398) (xy 375.14003 -240.20584) (xy 375.08688 -240.209824) (xy 375.03373 -240.20584)
			(xy 374.981768 -240.19398) (xy 374.932154 -240.174508) (xy 374.885996 -240.147859) (xy 374.844325 -240.114628)
			(xy 374.808073 -240.075557) (xy 374.778049 -240.03152) (xy 374.754923 -239.983499) (xy 374.739213 -239.932569)
			(xy 374.73127 -239.879865) (xy 374.50269 -239.879865) (xy 374.494747 -239.932569) (xy 374.479037 -239.983499)
			(xy 374.455911 -240.03152) (xy 374.425887 -240.075557) (xy 374.389635 -240.114628) (xy 374.347964 -240.147859)
			(xy 374.301806 -240.174508) (xy 374.252192 -240.19398) (xy 374.20023 -240.20584) (xy 374.14708 -240.209824)
			(xy 374.09393 -240.20584) (xy 374.041968 -240.19398) (xy 373.992354 -240.174508) (xy 373.946196 -240.147859)
			(xy 373.904525 -240.114628) (xy 373.868273 -240.075557) (xy 373.838249 -240.03152) (xy 373.815123 -239.983499)
			(xy 373.799413 -239.932569) (xy 373.79147 -239.879865) (xy 373.563144 -239.879865) (xy 373.555201 -239.932569)
			(xy 373.539491 -239.983499) (xy 373.516365 -240.03152) (xy 373.486341 -240.075557) (xy 373.450089 -240.114628)
			(xy 373.408418 -240.147859) (xy 373.36226 -240.174508) (xy 373.312646 -240.19398) (xy 373.260684 -240.20584)
			(xy 373.207534 -240.209824) (xy 373.154384 -240.20584) (xy 373.102422 -240.19398) (xy 373.052808 -240.174508)
			(xy 373.00665 -240.147859) (xy 372.964979 -240.114628) (xy 372.928727 -240.075557) (xy 372.898703 -240.03152)
			(xy 372.875577 -239.983499) (xy 372.859867 -239.932569) (xy 372.851924 -239.879865) (xy 372.62309 -239.879865)
			(xy 372.615147 -239.932569) (xy 372.599437 -239.983499) (xy 372.576311 -240.03152) (xy 372.546287 -240.075557)
			(xy 372.510035 -240.114628) (xy 372.468364 -240.147859) (xy 372.422206 -240.174508) (xy 372.372592 -240.19398)
			(xy 372.32063 -240.20584) (xy 372.26748 -240.209824) (xy 372.21433 -240.20584) (xy 372.162368 -240.19398)
			(xy 372.112754 -240.174508) (xy 372.066596 -240.147859) (xy 372.024925 -240.114628) (xy 371.988673 -240.075557)
			(xy 371.958649 -240.03152) (xy 371.935523 -239.983499) (xy 371.919813 -239.932569) (xy 371.91187 -239.879865)
			(xy 371.68329 -239.879865) (xy 371.675347 -239.932569) (xy 371.659637 -239.983499) (xy 371.636511 -240.03152)
			(xy 371.606487 -240.075557) (xy 371.570235 -240.114628) (xy 371.528564 -240.147859) (xy 371.482406 -240.174508)
			(xy 371.432792 -240.19398) (xy 371.38083 -240.20584) (xy 371.32768 -240.209824) (xy 371.27453 -240.20584)
			(xy 371.222568 -240.19398) (xy 371.172954 -240.174508) (xy 371.126796 -240.147859) (xy 371.085125 -240.114628)
			(xy 371.048873 -240.075557) (xy 371.018849 -240.03152) (xy 370.995723 -239.983499) (xy 370.980013 -239.932569)
			(xy 370.97207 -239.879865) (xy 370.743744 -239.879865) (xy 370.735801 -239.932569) (xy 370.720091 -239.983499)
			(xy 370.696965 -240.03152) (xy 370.666941 -240.075557) (xy 370.630689 -240.114628) (xy 370.589018 -240.147859)
			(xy 370.54286 -240.174508) (xy 370.493246 -240.19398) (xy 370.441284 -240.20584) (xy 370.388134 -240.209824)
			(xy 370.334984 -240.20584) (xy 370.283022 -240.19398) (xy 370.233408 -240.174508) (xy 370.18725 -240.147859)
			(xy 370.145579 -240.114628) (xy 370.109327 -240.075557) (xy 370.079303 -240.03152) (xy 370.056177 -239.983499)
			(xy 370.040467 -239.932569) (xy 370.032524 -239.879865) (xy 369.80275 -239.879865) (xy 369.800764 -239.906358)
			(xy 369.788902 -239.958327) (xy 369.769426 -240.007949) (xy 369.742772 -240.054113) (xy 369.709535 -240.095789)
			(xy 369.670457 -240.132046) (xy 369.626412 -240.162073) (xy 369.578384 -240.1852) (xy 369.527445 -240.20091)
			(xy 369.474733 -240.208852) (xy 369.44808 -240.209324) (xy 369.421648 -240.208865) (xy 369.369362 -240.201082)
			(xy 369.34394 -240.19383) (xy 369.329318 -240.189954) (xy 369.299089 -240.189923) (xy 369.270178 -240.198754)
			(xy 369.245126 -240.215673) (xy 369.226133 -240.239192) (xy 369.219988 -240.253012) (xy 369.209169 -240.278386)
			(xy 369.180844 -240.325716) (xy 369.1636 -240.347246) (xy 369.154956 -240.358364) (xy 369.143607 -240.384128)
			(xy 369.139728 -240.412012) (xy 369.143614 -240.439896) (xy 369.154969 -240.465657) (xy 369.1636 -240.476786)
			(xy 369.179001 -240.49606) (xy 369.204966 -240.538008) (xy 369.224891 -240.583139) (xy 369.238394 -240.630589)
			(xy 369.245216 -240.679449) (xy 369.245466 -240.693935) (xy 370.50217 -240.693935) (xy 370.50217 -240.640637)
			(xy 370.510113 -240.587933) (xy 370.525823 -240.537003) (xy 370.548949 -240.488982) (xy 370.578973 -240.444945)
			(xy 370.615225 -240.405874) (xy 370.656896 -240.372643) (xy 370.703054 -240.345994) (xy 370.752668 -240.326522)
			(xy 370.80463 -240.314662) (xy 370.85778 -240.310679) (xy 370.91093 -240.314662) (xy 370.962892 -240.326522)
			(xy 371.012506 -240.345994) (xy 371.058664 -240.372643) (xy 371.100335 -240.405874) (xy 371.136587 -240.444945)
			(xy 371.166611 -240.488982) (xy 371.189737 -240.537003) (xy 371.205447 -240.587933) (xy 371.21339 -240.640637)
			(xy 371.213888 -240.667286) (xy 371.21339 -240.693935) (xy 371.442224 -240.693935) (xy 371.442224 -240.640637)
			(xy 371.450167 -240.587933) (xy 371.465877 -240.537003) (xy 371.489003 -240.488982) (xy 371.519027 -240.444945)
			(xy 371.555279 -240.405874) (xy 371.59695 -240.372643) (xy 371.643108 -240.345994) (xy 371.692722 -240.326522)
			(xy 371.744684 -240.314662) (xy 371.797834 -240.310679) (xy 371.850984 -240.314662) (xy 371.902946 -240.326522)
			(xy 371.95256 -240.345994) (xy 371.998718 -240.372643) (xy 372.040389 -240.405874) (xy 372.076641 -240.444945)
			(xy 372.106665 -240.488982) (xy 372.129791 -240.537003) (xy 372.145501 -240.587933) (xy 372.153444 -240.640637)
			(xy 372.153942 -240.667286) (xy 372.153444 -240.693935) (xy 372.382024 -240.693935) (xy 372.382024 -240.640637)
			(xy 372.389967 -240.587933) (xy 372.405677 -240.537003) (xy 372.428803 -240.488982) (xy 372.458827 -240.444945)
			(xy 372.495079 -240.405874) (xy 372.53675 -240.372643) (xy 372.582908 -240.345994) (xy 372.632522 -240.326522)
			(xy 372.684484 -240.314662) (xy 372.737634 -240.310679) (xy 372.790784 -240.314662) (xy 372.842746 -240.326522)
			(xy 372.89236 -240.345994) (xy 372.938518 -240.372643) (xy 372.980189 -240.405874) (xy 373.016441 -240.444945)
			(xy 373.046465 -240.488982) (xy 373.069591 -240.537003) (xy 373.085301 -240.587933) (xy 373.093244 -240.640637)
			(xy 373.093742 -240.667286) (xy 373.093244 -240.693935) (xy 373.32157 -240.693935) (xy 373.32157 -240.640637)
			(xy 373.329513 -240.587933) (xy 373.345223 -240.537003) (xy 373.368349 -240.488982) (xy 373.398373 -240.444945)
			(xy 373.434625 -240.405874) (xy 373.476296 -240.372643) (xy 373.522454 -240.345994) (xy 373.572068 -240.326522)
			(xy 373.62403 -240.314662) (xy 373.67718 -240.310679) (xy 373.73033 -240.314662) (xy 373.782292 -240.326522)
			(xy 373.831906 -240.345994) (xy 373.878064 -240.372643) (xy 373.919735 -240.405874) (xy 373.955987 -240.444945)
			(xy 373.986011 -240.488982) (xy 374.009137 -240.537003) (xy 374.024847 -240.587933) (xy 374.03279 -240.640637)
			(xy 374.033288 -240.667286) (xy 374.03279 -240.693935) (xy 374.261624 -240.693935) (xy 374.261624 -240.640637)
			(xy 374.269567 -240.587933) (xy 374.285277 -240.537003) (xy 374.308403 -240.488982) (xy 374.338427 -240.444945)
			(xy 374.374679 -240.405874) (xy 374.41635 -240.372643) (xy 374.462508 -240.345994) (xy 374.512122 -240.326522)
			(xy 374.564084 -240.314662) (xy 374.617234 -240.310679) (xy 374.670384 -240.314662) (xy 374.722346 -240.326522)
			(xy 374.77196 -240.345994) (xy 374.818118 -240.372643) (xy 374.859789 -240.405874) (xy 374.896041 -240.444945)
			(xy 374.926065 -240.488982) (xy 374.949191 -240.537003) (xy 374.964901 -240.587933) (xy 374.972844 -240.640637)
			(xy 374.973342 -240.667286) (xy 374.972844 -240.693935) (xy 375.201424 -240.693935) (xy 375.201424 -240.640637)
			(xy 375.209367 -240.587933) (xy 375.225077 -240.537003) (xy 375.248203 -240.488982) (xy 375.278227 -240.444945)
			(xy 375.314479 -240.405874) (xy 375.35615 -240.372643) (xy 375.402308 -240.345994) (xy 375.451922 -240.326522)
			(xy 375.503884 -240.314662) (xy 375.557034 -240.310679) (xy 375.610184 -240.314662) (xy 375.662146 -240.326522)
			(xy 375.71176 -240.345994) (xy 375.757918 -240.372643) (xy 375.799589 -240.405874) (xy 375.835841 -240.444945)
			(xy 375.865865 -240.488982) (xy 375.888991 -240.537003) (xy 375.904701 -240.587933) (xy 375.912644 -240.640637)
			(xy 375.913142 -240.667286) (xy 375.912644 -240.693935) (xy 376.141224 -240.693935) (xy 376.141224 -240.640637)
			(xy 376.149167 -240.587933) (xy 376.164877 -240.537003) (xy 376.188003 -240.488982) (xy 376.218027 -240.444945)
			(xy 376.254279 -240.405874) (xy 376.29595 -240.372643) (xy 376.342108 -240.345994) (xy 376.391722 -240.326522)
			(xy 376.443684 -240.314662) (xy 376.496834 -240.310679) (xy 376.549984 -240.314662) (xy 376.601946 -240.326522)
			(xy 376.65156 -240.345994) (xy 376.697718 -240.372643) (xy 376.739389 -240.405874) (xy 376.775641 -240.444945)
			(xy 376.805665 -240.488982) (xy 376.828791 -240.537003) (xy 376.844501 -240.587933) (xy 376.852444 -240.640637)
			(xy 376.852942 -240.667286) (xy 376.852444 -240.693935) (xy 377.081024 -240.693935) (xy 377.081024 -240.640637)
			(xy 377.088967 -240.587933) (xy 377.104677 -240.537003) (xy 377.127803 -240.488982) (xy 377.157827 -240.444945)
			(xy 377.194079 -240.405874) (xy 377.23575 -240.372643) (xy 377.281908 -240.345994) (xy 377.331522 -240.326522)
			(xy 377.383484 -240.314662) (xy 377.436634 -240.310679) (xy 377.489784 -240.314662) (xy 377.541746 -240.326522)
			(xy 377.59136 -240.345994) (xy 377.637518 -240.372643) (xy 377.679189 -240.405874) (xy 377.715441 -240.444945)
			(xy 377.745465 -240.488982) (xy 377.768591 -240.537003) (xy 377.784301 -240.587933) (xy 377.792244 -240.640637)
			(xy 377.792742 -240.667286) (xy 377.792244 -240.693935) (xy 378.020824 -240.693935) (xy 378.020824 -240.640637)
			(xy 378.028767 -240.587933) (xy 378.044477 -240.537003) (xy 378.067603 -240.488982) (xy 378.097627 -240.444945)
			(xy 378.133879 -240.405874) (xy 378.17555 -240.372643) (xy 378.221708 -240.345994) (xy 378.271322 -240.326522)
			(xy 378.323284 -240.314662) (xy 378.376434 -240.310679) (xy 378.429584 -240.314662) (xy 378.481546 -240.326522)
			(xy 378.53116 -240.345994) (xy 378.577318 -240.372643) (xy 378.618989 -240.405874) (xy 378.655241 -240.444945)
			(xy 378.685265 -240.488982) (xy 378.708391 -240.537003) (xy 378.724101 -240.587933) (xy 378.732044 -240.640637)
			(xy 378.732542 -240.667286) (xy 378.732044 -240.693935) (xy 378.960624 -240.693935) (xy 378.960624 -240.640637)
			(xy 378.968567 -240.587933) (xy 378.984277 -240.537003) (xy 379.007403 -240.488982) (xy 379.037427 -240.444945)
			(xy 379.073679 -240.405874) (xy 379.11535 -240.372643) (xy 379.161508 -240.345994) (xy 379.211122 -240.326522)
			(xy 379.263084 -240.314662) (xy 379.316234 -240.310679) (xy 379.369384 -240.314662) (xy 379.421346 -240.326522)
			(xy 379.47096 -240.345994) (xy 379.517118 -240.372643) (xy 379.558789 -240.405874) (xy 379.595041 -240.444945)
			(xy 379.625065 -240.488982) (xy 379.648191 -240.537003) (xy 379.663901 -240.587933) (xy 379.671844 -240.640637)
			(xy 379.672342 -240.667286) (xy 379.671844 -240.693935) (xy 379.90017 -240.693935) (xy 379.90017 -240.640637)
			(xy 379.908113 -240.587933) (xy 379.923823 -240.537003) (xy 379.946949 -240.488982) (xy 379.976973 -240.444945)
			(xy 380.013225 -240.405874) (xy 380.054896 -240.372643) (xy 380.101054 -240.345994) (xy 380.150668 -240.326522)
			(xy 380.20263 -240.314662) (xy 380.25578 -240.310679) (xy 380.30893 -240.314662) (xy 380.360892 -240.326522)
			(xy 380.410506 -240.345994) (xy 380.456664 -240.372643) (xy 380.498335 -240.405874) (xy 380.534587 -240.444945)
			(xy 380.564611 -240.488982) (xy 380.587737 -240.537003) (xy 380.603447 -240.587933) (xy 380.61139 -240.640637)
			(xy 380.611888 -240.667286) (xy 380.61139 -240.693935) (xy 380.603447 -240.746639) (xy 380.587737 -240.797569)
			(xy 380.564611 -240.84559) (xy 380.534587 -240.889627) (xy 380.498335 -240.928698) (xy 380.456664 -240.961929)
			(xy 380.410506 -240.988578) (xy 380.360892 -241.00805) (xy 380.30893 -241.01991) (xy 380.25578 -241.023894)
			(xy 380.20263 -241.01991) (xy 380.150668 -241.00805) (xy 380.101054 -240.988578) (xy 380.054896 -240.961929)
			(xy 380.013225 -240.928698) (xy 379.976973 -240.889627) (xy 379.946949 -240.84559) (xy 379.923823 -240.797569)
			(xy 379.908113 -240.746639) (xy 379.90017 -240.693935) (xy 379.671844 -240.693935) (xy 379.663901 -240.746639)
			(xy 379.648191 -240.797569) (xy 379.625065 -240.84559) (xy 379.595041 -240.889627) (xy 379.558789 -240.928698)
			(xy 379.517118 -240.961929) (xy 379.47096 -240.988578) (xy 379.421346 -241.00805) (xy 379.369384 -241.01991)
			(xy 379.316234 -241.023894) (xy 379.263084 -241.01991) (xy 379.211122 -241.00805) (xy 379.161508 -240.988578)
			(xy 379.11535 -240.961929) (xy 379.073679 -240.928698) (xy 379.037427 -240.889627) (xy 379.007403 -240.84559)
			(xy 378.984277 -240.797569) (xy 378.968567 -240.746639) (xy 378.960624 -240.693935) (xy 378.732044 -240.693935)
			(xy 378.724101 -240.746639) (xy 378.708391 -240.797569) (xy 378.685265 -240.84559) (xy 378.655241 -240.889627)
			(xy 378.618989 -240.928698) (xy 378.577318 -240.961929) (xy 378.53116 -240.988578) (xy 378.481546 -241.00805)
			(xy 378.429584 -241.01991) (xy 378.376434 -241.023894) (xy 378.323284 -241.01991) (xy 378.271322 -241.00805)
			(xy 378.221708 -240.988578) (xy 378.17555 -240.961929) (xy 378.133879 -240.928698) (xy 378.097627 -240.889627)
			(xy 378.067603 -240.84559) (xy 378.044477 -240.797569) (xy 378.028767 -240.746639) (xy 378.020824 -240.693935)
			(xy 377.792244 -240.693935) (xy 377.784301 -240.746639) (xy 377.768591 -240.797569) (xy 377.745465 -240.84559)
			(xy 377.715441 -240.889627) (xy 377.679189 -240.928698) (xy 377.637518 -240.961929) (xy 377.59136 -240.988578)
			(xy 377.541746 -241.00805) (xy 377.489784 -241.01991) (xy 377.436634 -241.023894) (xy 377.383484 -241.01991)
			(xy 377.331522 -241.00805) (xy 377.281908 -240.988578) (xy 377.23575 -240.961929) (xy 377.194079 -240.928698)
			(xy 377.157827 -240.889627) (xy 377.127803 -240.84559) (xy 377.104677 -240.797569) (xy 377.088967 -240.746639)
			(xy 377.081024 -240.693935) (xy 376.852444 -240.693935) (xy 376.844501 -240.746639) (xy 376.828791 -240.797569)
			(xy 376.805665 -240.84559) (xy 376.775641 -240.889627) (xy 376.739389 -240.928698) (xy 376.697718 -240.961929)
			(xy 376.65156 -240.988578) (xy 376.601946 -241.00805) (xy 376.549984 -241.01991) (xy 376.496834 -241.023894)
			(xy 376.443684 -241.01991) (xy 376.391722 -241.00805) (xy 376.342108 -240.988578) (xy 376.29595 -240.961929)
			(xy 376.254279 -240.928698) (xy 376.218027 -240.889627) (xy 376.188003 -240.84559) (xy 376.164877 -240.797569)
			(xy 376.149167 -240.746639) (xy 376.141224 -240.693935) (xy 375.912644 -240.693935) (xy 375.904701 -240.746639)
			(xy 375.888991 -240.797569) (xy 375.865865 -240.84559) (xy 375.835841 -240.889627) (xy 375.799589 -240.928698)
			(xy 375.757918 -240.961929) (xy 375.71176 -240.988578) (xy 375.662146 -241.00805) (xy 375.610184 -241.01991)
			(xy 375.557034 -241.023894) (xy 375.503884 -241.01991) (xy 375.451922 -241.00805) (xy 375.402308 -240.988578)
			(xy 375.35615 -240.961929) (xy 375.314479 -240.928698) (xy 375.278227 -240.889627) (xy 375.248203 -240.84559)
			(xy 375.225077 -240.797569) (xy 375.209367 -240.746639) (xy 375.201424 -240.693935) (xy 374.972844 -240.693935)
			(xy 374.964901 -240.746639) (xy 374.949191 -240.797569) (xy 374.926065 -240.84559) (xy 374.896041 -240.889627)
			(xy 374.859789 -240.928698) (xy 374.818118 -240.961929) (xy 374.77196 -240.988578) (xy 374.722346 -241.00805)
			(xy 374.670384 -241.01991) (xy 374.617234 -241.023894) (xy 374.564084 -241.01991) (xy 374.512122 -241.00805)
			(xy 374.462508 -240.988578) (xy 374.41635 -240.961929) (xy 374.374679 -240.928698) (xy 374.338427 -240.889627)
			(xy 374.308403 -240.84559) (xy 374.285277 -240.797569) (xy 374.269567 -240.746639) (xy 374.261624 -240.693935)
			(xy 374.03279 -240.693935) (xy 374.024847 -240.746639) (xy 374.009137 -240.797569) (xy 373.986011 -240.84559)
			(xy 373.955987 -240.889627) (xy 373.919735 -240.928698) (xy 373.878064 -240.961929) (xy 373.831906 -240.988578)
			(xy 373.782292 -241.00805) (xy 373.73033 -241.01991) (xy 373.67718 -241.023894) (xy 373.62403 -241.01991)
			(xy 373.572068 -241.00805) (xy 373.522454 -240.988578) (xy 373.476296 -240.961929) (xy 373.434625 -240.928698)
			(xy 373.398373 -240.889627) (xy 373.368349 -240.84559) (xy 373.345223 -240.797569) (xy 373.329513 -240.746639)
			(xy 373.32157 -240.693935) (xy 373.093244 -240.693935) (xy 373.085301 -240.746639) (xy 373.069591 -240.797569)
			(xy 373.046465 -240.84559) (xy 373.016441 -240.889627) (xy 372.980189 -240.928698) (xy 372.938518 -240.961929)
			(xy 372.89236 -240.988578) (xy 372.842746 -241.00805) (xy 372.790784 -241.01991) (xy 372.737634 -241.023894)
			(xy 372.684484 -241.01991) (xy 372.632522 -241.00805) (xy 372.582908 -240.988578) (xy 372.53675 -240.961929)
			(xy 372.495079 -240.928698) (xy 372.458827 -240.889627) (xy 372.428803 -240.84559) (xy 372.405677 -240.797569)
			(xy 372.389967 -240.746639) (xy 372.382024 -240.693935) (xy 372.153444 -240.693935) (xy 372.145501 -240.746639)
			(xy 372.129791 -240.797569) (xy 372.106665 -240.84559) (xy 372.076641 -240.889627) (xy 372.040389 -240.928698)
			(xy 371.998718 -240.961929) (xy 371.95256 -240.988578) (xy 371.902946 -241.00805) (xy 371.850984 -241.01991)
			(xy 371.797834 -241.023894) (xy 371.744684 -241.01991) (xy 371.692722 -241.00805) (xy 371.643108 -240.988578)
			(xy 371.59695 -240.961929) (xy 371.555279 -240.928698) (xy 371.519027 -240.889627) (xy 371.489003 -240.84559)
			(xy 371.465877 -240.797569) (xy 371.450167 -240.746639) (xy 371.442224 -240.693935) (xy 371.21339 -240.693935)
			(xy 371.205447 -240.746639) (xy 371.189737 -240.797569) (xy 371.166611 -240.84559) (xy 371.136587 -240.889627)
			(xy 371.100335 -240.928698) (xy 371.058664 -240.961929) (xy 371.012506 -240.988578) (xy 370.962892 -241.00805)
			(xy 370.91093 -241.01991) (xy 370.85778 -241.023894) (xy 370.80463 -241.01991) (xy 370.752668 -241.00805)
			(xy 370.703054 -240.988578) (xy 370.656896 -240.961929) (xy 370.615225 -240.928698) (xy 370.578973 -240.889627)
			(xy 370.548949 -240.84559) (xy 370.525823 -240.797569) (xy 370.510113 -240.746639) (xy 370.50217 -240.693935)
			(xy 369.245466 -240.693935) (xy 369.245642 -240.704116) (xy 369.245144 -240.730765) (xy 369.237201 -240.783469)
			(xy 369.221491 -240.834399) (xy 369.198365 -240.88242) (xy 369.168341 -240.926457) (xy 369.132089 -240.965528)
			(xy 369.090418 -240.998759) (xy 369.04426 -241.025408) (xy 368.994646 -241.04488) (xy 368.942684 -241.05674)
			(xy 368.889534 -241.060724) (xy 368.836384 -241.05674) (xy 368.784422 -241.04488) (xy 368.734808 -241.025408)
			(xy 368.68865 -240.998759) (xy 368.646979 -240.965528) (xy 368.610727 -240.926457) (xy 368.580703 -240.88242)
			(xy 368.557577 -240.834399) (xy 368.541867 -240.783469) (xy 368.533924 -240.730765) (xy 368.533426 -240.704116)
			(xy 368.40668 -240.704116) (xy 368.40668 -241.507751) (xy 370.032524 -241.507751) (xy 370.032524 -241.454453)
			(xy 370.040467 -241.401749) (xy 370.056177 -241.350819) (xy 370.079303 -241.302798) (xy 370.109327 -241.258761)
			(xy 370.145579 -241.21969) (xy 370.18725 -241.186459) (xy 370.233408 -241.15981) (xy 370.283022 -241.140338)
			(xy 370.334984 -241.128478) (xy 370.388134 -241.124495) (xy 370.441284 -241.128478) (xy 370.493246 -241.140338)
			(xy 370.54286 -241.15981) (xy 370.589018 -241.186459) (xy 370.630689 -241.21969) (xy 370.666941 -241.258761)
			(xy 370.696965 -241.302798) (xy 370.720091 -241.350819) (xy 370.735801 -241.401749) (xy 370.743744 -241.454453)
			(xy 370.744242 -241.481102) (xy 370.743744 -241.507751) (xy 370.97207 -241.507751) (xy 370.97207 -241.454453)
			(xy 370.980013 -241.401749) (xy 370.995723 -241.350819) (xy 371.018849 -241.302798) (xy 371.048873 -241.258761)
			(xy 371.085125 -241.21969) (xy 371.126796 -241.186459) (xy 371.172954 -241.15981) (xy 371.222568 -241.140338)
			(xy 371.27453 -241.128478) (xy 371.32768 -241.124495) (xy 371.38083 -241.128478) (xy 371.432792 -241.140338)
			(xy 371.482406 -241.15981) (xy 371.528564 -241.186459) (xy 371.570235 -241.21969) (xy 371.606487 -241.258761)
			(xy 371.636511 -241.302798) (xy 371.659637 -241.350819) (xy 371.675347 -241.401749) (xy 371.68329 -241.454453)
			(xy 371.683788 -241.481102) (xy 371.68329 -241.507751) (xy 371.91187 -241.507751) (xy 371.91187 -241.454453)
			(xy 371.919813 -241.401749) (xy 371.935523 -241.350819) (xy 371.958649 -241.302798) (xy 371.988673 -241.258761)
			(xy 372.024925 -241.21969) (xy 372.066596 -241.186459) (xy 372.112754 -241.15981) (xy 372.162368 -241.140338)
			(xy 372.21433 -241.128478) (xy 372.26748 -241.124495) (xy 372.32063 -241.128478) (xy 372.372592 -241.140338)
			(xy 372.422206 -241.15981) (xy 372.468364 -241.186459) (xy 372.510035 -241.21969) (xy 372.546287 -241.258761)
			(xy 372.576311 -241.302798) (xy 372.599437 -241.350819) (xy 372.615147 -241.401749) (xy 372.62309 -241.454453)
			(xy 372.623588 -241.481102) (xy 372.62309 -241.507751) (xy 372.85167 -241.507751) (xy 372.85167 -241.454453)
			(xy 372.859613 -241.401749) (xy 372.875323 -241.350819) (xy 372.898449 -241.302798) (xy 372.928473 -241.258761)
			(xy 372.964725 -241.21969) (xy 373.006396 -241.186459) (xy 373.052554 -241.15981) (xy 373.102168 -241.140338)
			(xy 373.15413 -241.128478) (xy 373.20728 -241.124495) (xy 373.26043 -241.128478) (xy 373.312392 -241.140338)
			(xy 373.362006 -241.15981) (xy 373.408164 -241.186459) (xy 373.449835 -241.21969) (xy 373.486087 -241.258761)
			(xy 373.516111 -241.302798) (xy 373.539237 -241.350819) (xy 373.554947 -241.401749) (xy 373.56289 -241.454453)
			(xy 373.563388 -241.481102) (xy 373.56289 -241.507751) (xy 373.79147 -241.507751) (xy 373.79147 -241.454453)
			(xy 373.799413 -241.401749) (xy 373.815123 -241.350819) (xy 373.838249 -241.302798) (xy 373.868273 -241.258761)
			(xy 373.904525 -241.21969) (xy 373.946196 -241.186459) (xy 373.992354 -241.15981) (xy 374.041968 -241.140338)
			(xy 374.09393 -241.128478) (xy 374.14708 -241.124495) (xy 374.20023 -241.128478) (xy 374.252192 -241.140338)
			(xy 374.301806 -241.15981) (xy 374.347964 -241.186459) (xy 374.389635 -241.21969) (xy 374.425887 -241.258761)
			(xy 374.455911 -241.302798) (xy 374.479037 -241.350819) (xy 374.494747 -241.401749) (xy 374.50269 -241.454453)
			(xy 374.503188 -241.481102) (xy 374.50269 -241.507751) (xy 374.73127 -241.507751) (xy 374.73127 -241.454453)
			(xy 374.739213 -241.401749) (xy 374.754923 -241.350819) (xy 374.778049 -241.302798) (xy 374.808073 -241.258761)
			(xy 374.844325 -241.21969) (xy 374.885996 -241.186459) (xy 374.932154 -241.15981) (xy 374.981768 -241.140338)
			(xy 375.03373 -241.128478) (xy 375.08688 -241.124495) (xy 375.14003 -241.128478) (xy 375.191992 -241.140338)
			(xy 375.241606 -241.15981) (xy 375.287764 -241.186459) (xy 375.329435 -241.21969) (xy 375.365687 -241.258761)
			(xy 375.395711 -241.302798) (xy 375.418837 -241.350819) (xy 375.434547 -241.401749) (xy 375.44249 -241.454453)
			(xy 375.442988 -241.481102) (xy 375.44249 -241.507751) (xy 375.67107 -241.507751) (xy 375.67107 -241.454453)
			(xy 375.679013 -241.401749) (xy 375.694723 -241.350819) (xy 375.717849 -241.302798) (xy 375.747873 -241.258761)
			(xy 375.784125 -241.21969) (xy 375.825796 -241.186459) (xy 375.871954 -241.15981) (xy 375.921568 -241.140338)
			(xy 375.97353 -241.128478) (xy 376.02668 -241.124495) (xy 376.07983 -241.128478) (xy 376.131792 -241.140338)
			(xy 376.181406 -241.15981) (xy 376.227564 -241.186459) (xy 376.269235 -241.21969) (xy 376.305487 -241.258761)
			(xy 376.335511 -241.302798) (xy 376.358637 -241.350819) (xy 376.374347 -241.401749) (xy 376.38229 -241.454453)
			(xy 376.382788 -241.481102) (xy 376.38229 -241.507751) (xy 376.611124 -241.507751) (xy 376.611124 -241.454453)
			(xy 376.619067 -241.401749) (xy 376.634777 -241.350819) (xy 376.657903 -241.302798) (xy 376.687927 -241.258761)
			(xy 376.724179 -241.21969) (xy 376.76585 -241.186459) (xy 376.812008 -241.15981) (xy 376.861622 -241.140338)
			(xy 376.913584 -241.128478) (xy 376.966734 -241.124495) (xy 377.019884 -241.128478) (xy 377.071846 -241.140338)
			(xy 377.12146 -241.15981) (xy 377.167618 -241.186459) (xy 377.209289 -241.21969) (xy 377.245541 -241.258761)
			(xy 377.275565 -241.302798) (xy 377.298691 -241.350819) (xy 377.314401 -241.401749) (xy 377.322344 -241.454453)
			(xy 377.322842 -241.481102) (xy 377.322344 -241.507751) (xy 377.55067 -241.507751) (xy 377.55067 -241.454453)
			(xy 377.558613 -241.401749) (xy 377.574323 -241.350819) (xy 377.597449 -241.302798) (xy 377.627473 -241.258761)
			(xy 377.663725 -241.21969) (xy 377.705396 -241.186459) (xy 377.751554 -241.15981) (xy 377.801168 -241.140338)
			(xy 377.85313 -241.128478) (xy 377.90628 -241.124495) (xy 377.95943 -241.128478) (xy 378.011392 -241.140338)
			(xy 378.061006 -241.15981) (xy 378.107164 -241.186459) (xy 378.148835 -241.21969) (xy 378.185087 -241.258761)
			(xy 378.215111 -241.302798) (xy 378.238237 -241.350819) (xy 378.253947 -241.401749) (xy 378.26189 -241.454453)
			(xy 378.262388 -241.481102) (xy 378.26189 -241.507751) (xy 378.49047 -241.507751) (xy 378.49047 -241.454453)
			(xy 378.498413 -241.401749) (xy 378.514123 -241.350819) (xy 378.537249 -241.302798) (xy 378.567273 -241.258761)
			(xy 378.603525 -241.21969) (xy 378.645196 -241.186459) (xy 378.691354 -241.15981) (xy 378.740968 -241.140338)
			(xy 378.79293 -241.128478) (xy 378.84608 -241.124495) (xy 378.89923 -241.128478) (xy 378.951192 -241.140338)
			(xy 379.000806 -241.15981) (xy 379.046964 -241.186459) (xy 379.088635 -241.21969) (xy 379.124887 -241.258761)
			(xy 379.154911 -241.302798) (xy 379.178037 -241.350819) (xy 379.193747 -241.401749) (xy 379.20169 -241.454453)
			(xy 379.202188 -241.481102) (xy 379.20169 -241.507751) (xy 379.43027 -241.507751) (xy 379.43027 -241.454453)
			(xy 379.438213 -241.401749) (xy 379.453923 -241.350819) (xy 379.477049 -241.302798) (xy 379.507073 -241.258761)
			(xy 379.543325 -241.21969) (xy 379.584996 -241.186459) (xy 379.631154 -241.15981) (xy 379.680768 -241.140338)
			(xy 379.73273 -241.128478) (xy 379.78588 -241.124495) (xy 379.83903 -241.128478) (xy 379.890992 -241.140338)
			(xy 379.940606 -241.15981) (xy 379.986764 -241.186459) (xy 380.028435 -241.21969) (xy 380.064687 -241.258761)
			(xy 380.094711 -241.302798) (xy 380.117837 -241.350819) (xy 380.133547 -241.401749) (xy 380.14149 -241.454453)
			(xy 380.141988 -241.481102) (xy 380.14149 -241.507751) (xy 380.133547 -241.560455) (xy 380.117837 -241.611385)
			(xy 380.094711 -241.659406) (xy 380.064687 -241.703443) (xy 380.028435 -241.742514) (xy 379.986764 -241.775745)
			(xy 379.940606 -241.802394) (xy 379.890992 -241.821866) (xy 379.83903 -241.833726) (xy 379.78588 -241.83771)
			(xy 379.73273 -241.833726) (xy 379.680768 -241.821866) (xy 379.631154 -241.802394) (xy 379.584996 -241.775745)
			(xy 379.543325 -241.742514) (xy 379.507073 -241.703443) (xy 379.477049 -241.659406) (xy 379.453923 -241.611385)
			(xy 379.438213 -241.560455) (xy 379.43027 -241.507751) (xy 379.20169 -241.507751) (xy 379.193747 -241.560455)
			(xy 379.178037 -241.611385) (xy 379.154911 -241.659406) (xy 379.124887 -241.703443) (xy 379.088635 -241.742514)
			(xy 379.046964 -241.775745) (xy 379.000806 -241.802394) (xy 378.951192 -241.821866) (xy 378.89923 -241.833726)
			(xy 378.84608 -241.83771) (xy 378.79293 -241.833726) (xy 378.740968 -241.821866) (xy 378.691354 -241.802394)
			(xy 378.645196 -241.775745) (xy 378.603525 -241.742514) (xy 378.567273 -241.703443) (xy 378.537249 -241.659406)
			(xy 378.514123 -241.611385) (xy 378.498413 -241.560455) (xy 378.49047 -241.507751) (xy 378.26189 -241.507751)
			(xy 378.253947 -241.560455) (xy 378.238237 -241.611385) (xy 378.215111 -241.659406) (xy 378.185087 -241.703443)
			(xy 378.148835 -241.742514) (xy 378.107164 -241.775745) (xy 378.061006 -241.802394) (xy 378.011392 -241.821866)
			(xy 377.95943 -241.833726) (xy 377.90628 -241.83771) (xy 377.85313 -241.833726) (xy 377.801168 -241.821866)
			(xy 377.751554 -241.802394) (xy 377.705396 -241.775745) (xy 377.663725 -241.742514) (xy 377.627473 -241.703443)
			(xy 377.597449 -241.659406) (xy 377.574323 -241.611385) (xy 377.558613 -241.560455) (xy 377.55067 -241.507751)
			(xy 377.322344 -241.507751) (xy 377.314401 -241.560455) (xy 377.298691 -241.611385) (xy 377.275565 -241.659406)
			(xy 377.245541 -241.703443) (xy 377.209289 -241.742514) (xy 377.167618 -241.775745) (xy 377.12146 -241.802394)
			(xy 377.071846 -241.821866) (xy 377.019884 -241.833726) (xy 376.966734 -241.83771) (xy 376.913584 -241.833726)
			(xy 376.861622 -241.821866) (xy 376.812008 -241.802394) (xy 376.76585 -241.775745) (xy 376.724179 -241.742514)
			(xy 376.687927 -241.703443) (xy 376.657903 -241.659406) (xy 376.634777 -241.611385) (xy 376.619067 -241.560455)
			(xy 376.611124 -241.507751) (xy 376.38229 -241.507751) (xy 376.374347 -241.560455) (xy 376.358637 -241.611385)
			(xy 376.335511 -241.659406) (xy 376.305487 -241.703443) (xy 376.269235 -241.742514) (xy 376.227564 -241.775745)
			(xy 376.181406 -241.802394) (xy 376.131792 -241.821866) (xy 376.07983 -241.833726) (xy 376.02668 -241.83771)
			(xy 375.97353 -241.833726) (xy 375.921568 -241.821866) (xy 375.871954 -241.802394) (xy 375.825796 -241.775745)
			(xy 375.784125 -241.742514) (xy 375.747873 -241.703443) (xy 375.717849 -241.659406) (xy 375.694723 -241.611385)
			(xy 375.679013 -241.560455) (xy 375.67107 -241.507751) (xy 375.44249 -241.507751) (xy 375.434547 -241.560455)
			(xy 375.418837 -241.611385) (xy 375.395711 -241.659406) (xy 375.365687 -241.703443) (xy 375.329435 -241.742514)
			(xy 375.287764 -241.775745) (xy 375.241606 -241.802394) (xy 375.191992 -241.821866) (xy 375.14003 -241.833726)
			(xy 375.08688 -241.83771) (xy 375.03373 -241.833726) (xy 374.981768 -241.821866) (xy 374.932154 -241.802394)
			(xy 374.885996 -241.775745) (xy 374.844325 -241.742514) (xy 374.808073 -241.703443) (xy 374.778049 -241.659406)
			(xy 374.754923 -241.611385) (xy 374.739213 -241.560455) (xy 374.73127 -241.507751) (xy 374.50269 -241.507751)
			(xy 374.494747 -241.560455) (xy 374.479037 -241.611385) (xy 374.455911 -241.659406) (xy 374.425887 -241.703443)
			(xy 374.389635 -241.742514) (xy 374.347964 -241.775745) (xy 374.301806 -241.802394) (xy 374.252192 -241.821866)
			(xy 374.20023 -241.833726) (xy 374.14708 -241.83771) (xy 374.09393 -241.833726) (xy 374.041968 -241.821866)
			(xy 373.992354 -241.802394) (xy 373.946196 -241.775745) (xy 373.904525 -241.742514) (xy 373.868273 -241.703443)
			(xy 373.838249 -241.659406) (xy 373.815123 -241.611385) (xy 373.799413 -241.560455) (xy 373.79147 -241.507751)
			(xy 373.56289 -241.507751) (xy 373.554947 -241.560455) (xy 373.539237 -241.611385) (xy 373.516111 -241.659406)
			(xy 373.486087 -241.703443) (xy 373.449835 -241.742514) (xy 373.408164 -241.775745) (xy 373.362006 -241.802394)
			(xy 373.312392 -241.821866) (xy 373.26043 -241.833726) (xy 373.20728 -241.83771) (xy 373.15413 -241.833726)
			(xy 373.102168 -241.821866) (xy 373.052554 -241.802394) (xy 373.006396 -241.775745) (xy 372.964725 -241.742514)
			(xy 372.928473 -241.703443) (xy 372.898449 -241.659406) (xy 372.875323 -241.611385) (xy 372.859613 -241.560455)
			(xy 372.85167 -241.507751) (xy 372.62309 -241.507751) (xy 372.615147 -241.560455) (xy 372.599437 -241.611385)
			(xy 372.576311 -241.659406) (xy 372.546287 -241.703443) (xy 372.510035 -241.742514) (xy 372.468364 -241.775745)
			(xy 372.422206 -241.802394) (xy 372.372592 -241.821866) (xy 372.32063 -241.833726) (xy 372.26748 -241.83771)
			(xy 372.21433 -241.833726) (xy 372.162368 -241.821866) (xy 372.112754 -241.802394) (xy 372.066596 -241.775745)
			(xy 372.024925 -241.742514) (xy 371.988673 -241.703443) (xy 371.958649 -241.659406) (xy 371.935523 -241.611385)
			(xy 371.919813 -241.560455) (xy 371.91187 -241.507751) (xy 371.68329 -241.507751) (xy 371.675347 -241.560455)
			(xy 371.659637 -241.611385) (xy 371.636511 -241.659406) (xy 371.606487 -241.703443) (xy 371.570235 -241.742514)
			(xy 371.528564 -241.775745) (xy 371.482406 -241.802394) (xy 371.432792 -241.821866) (xy 371.38083 -241.833726)
			(xy 371.32768 -241.83771) (xy 371.27453 -241.833726) (xy 371.222568 -241.821866) (xy 371.172954 -241.802394)
			(xy 371.126796 -241.775745) (xy 371.085125 -241.742514) (xy 371.048873 -241.703443) (xy 371.018849 -241.659406)
			(xy 370.995723 -241.611385) (xy 370.980013 -241.560455) (xy 370.97207 -241.507751) (xy 370.743744 -241.507751)
			(xy 370.735801 -241.560455) (xy 370.720091 -241.611385) (xy 370.696965 -241.659406) (xy 370.666941 -241.703443)
			(xy 370.630689 -241.742514) (xy 370.589018 -241.775745) (xy 370.54286 -241.802394) (xy 370.493246 -241.821866)
			(xy 370.441284 -241.833726) (xy 370.388134 -241.83771) (xy 370.334984 -241.833726) (xy 370.283022 -241.821866)
			(xy 370.233408 -241.802394) (xy 370.18725 -241.775745) (xy 370.145579 -241.742514) (xy 370.109327 -241.703443)
			(xy 370.079303 -241.659406) (xy 370.056177 -241.611385) (xy 370.040467 -241.560455) (xy 370.032524 -241.507751)
			(xy 368.40668 -241.507751) (xy 368.40668 -242.321567) (xy 370.502424 -242.321567) (xy 370.502424 -242.268269)
			(xy 370.510367 -242.215565) (xy 370.526077 -242.164635) (xy 370.549203 -242.116614) (xy 370.579227 -242.072577)
			(xy 370.615479 -242.033506) (xy 370.65715 -242.000275) (xy 370.703308 -241.973626) (xy 370.752922 -241.954154)
			(xy 370.804884 -241.942294) (xy 370.858034 -241.938311) (xy 370.911184 -241.942294) (xy 370.963146 -241.954154)
			(xy 371.01276 -241.973626) (xy 371.058918 -242.000275) (xy 371.100589 -242.033506) (xy 371.136841 -242.072577)
			(xy 371.166865 -242.116614) (xy 371.189991 -242.164635) (xy 371.205701 -242.215565) (xy 371.213644 -242.268269)
			(xy 371.214142 -242.294918) (xy 371.213644 -242.321567) (xy 371.442224 -242.321567) (xy 371.442224 -242.268269)
			(xy 371.450167 -242.215565) (xy 371.465877 -242.164635) (xy 371.489003 -242.116614) (xy 371.519027 -242.072577)
			(xy 371.555279 -242.033506) (xy 371.59695 -242.000275) (xy 371.643108 -241.973626) (xy 371.692722 -241.954154)
			(xy 371.744684 -241.942294) (xy 371.797834 -241.938311) (xy 371.850984 -241.942294) (xy 371.902946 -241.954154)
			(xy 371.95256 -241.973626) (xy 371.998718 -242.000275) (xy 372.040389 -242.033506) (xy 372.076641 -242.072577)
			(xy 372.106665 -242.116614) (xy 372.129791 -242.164635) (xy 372.145501 -242.215565) (xy 372.153444 -242.268269)
			(xy 372.153942 -242.294918) (xy 372.153444 -242.321567) (xy 372.382024 -242.321567) (xy 372.382024 -242.268269)
			(xy 372.389967 -242.215565) (xy 372.405677 -242.164635) (xy 372.428803 -242.116614) (xy 372.458827 -242.072577)
			(xy 372.495079 -242.033506) (xy 372.53675 -242.000275) (xy 372.582908 -241.973626) (xy 372.632522 -241.954154)
			(xy 372.684484 -241.942294) (xy 372.737634 -241.938311) (xy 372.790784 -241.942294) (xy 372.842746 -241.954154)
			(xy 372.89236 -241.973626) (xy 372.938518 -242.000275) (xy 372.980189 -242.033506) (xy 373.016441 -242.072577)
			(xy 373.046465 -242.116614) (xy 373.069591 -242.164635) (xy 373.085301 -242.215565) (xy 373.093244 -242.268269)
			(xy 373.093742 -242.294918) (xy 373.093244 -242.321567) (xy 373.321824 -242.321567) (xy 373.321824 -242.268269)
			(xy 373.329767 -242.215565) (xy 373.345477 -242.164635) (xy 373.368603 -242.116614) (xy 373.398627 -242.072577)
			(xy 373.434879 -242.033506) (xy 373.47655 -242.000275) (xy 373.522708 -241.973626) (xy 373.572322 -241.954154)
			(xy 373.624284 -241.942294) (xy 373.677434 -241.938311) (xy 373.730584 -241.942294) (xy 373.782546 -241.954154)
			(xy 373.83216 -241.973626) (xy 373.878318 -242.000275) (xy 373.919989 -242.033506) (xy 373.956241 -242.072577)
			(xy 373.986265 -242.116614) (xy 374.009391 -242.164635) (xy 374.025101 -242.215565) (xy 374.033044 -242.268269)
			(xy 374.033542 -242.294918) (xy 374.033044 -242.321567) (xy 374.261624 -242.321567) (xy 374.261624 -242.268269)
			(xy 374.269567 -242.215565) (xy 374.285277 -242.164635) (xy 374.308403 -242.116614) (xy 374.338427 -242.072577)
			(xy 374.374679 -242.033506) (xy 374.41635 -242.000275) (xy 374.462508 -241.973626) (xy 374.512122 -241.954154)
			(xy 374.564084 -241.942294) (xy 374.617234 -241.938311) (xy 374.670384 -241.942294) (xy 374.722346 -241.954154)
			(xy 374.77196 -241.973626) (xy 374.818118 -242.000275) (xy 374.859789 -242.033506) (xy 374.896041 -242.072577)
			(xy 374.926065 -242.116614) (xy 374.949191 -242.164635) (xy 374.964901 -242.215565) (xy 374.972844 -242.268269)
			(xy 374.973342 -242.294918) (xy 374.972844 -242.321567) (xy 375.201424 -242.321567) (xy 375.201424 -242.268269)
			(xy 375.209367 -242.215565) (xy 375.225077 -242.164635) (xy 375.248203 -242.116614) (xy 375.278227 -242.072577)
			(xy 375.314479 -242.033506) (xy 375.35615 -242.000275) (xy 375.402308 -241.973626) (xy 375.451922 -241.954154)
			(xy 375.503884 -241.942294) (xy 375.557034 -241.938311) (xy 375.610184 -241.942294) (xy 375.662146 -241.954154)
			(xy 375.71176 -241.973626) (xy 375.757918 -242.000275) (xy 375.799589 -242.033506) (xy 375.835841 -242.072577)
			(xy 375.865865 -242.116614) (xy 375.888991 -242.164635) (xy 375.904701 -242.215565) (xy 375.912644 -242.268269)
			(xy 375.913142 -242.294918) (xy 375.912644 -242.321567) (xy 376.141224 -242.321567) (xy 376.141224 -242.268269)
			(xy 376.149167 -242.215565) (xy 376.164877 -242.164635) (xy 376.188003 -242.116614) (xy 376.218027 -242.072577)
			(xy 376.254279 -242.033506) (xy 376.29595 -242.000275) (xy 376.342108 -241.973626) (xy 376.391722 -241.954154)
			(xy 376.443684 -241.942294) (xy 376.496834 -241.938311) (xy 376.549984 -241.942294) (xy 376.601946 -241.954154)
			(xy 376.65156 -241.973626) (xy 376.697718 -242.000275) (xy 376.739389 -242.033506) (xy 376.775641 -242.072577)
			(xy 376.805665 -242.116614) (xy 376.828791 -242.164635) (xy 376.844501 -242.215565) (xy 376.852444 -242.268269)
			(xy 376.852942 -242.294918) (xy 376.852444 -242.321567) (xy 377.081024 -242.321567) (xy 377.081024 -242.268269)
			(xy 377.088967 -242.215565) (xy 377.104677 -242.164635) (xy 377.127803 -242.116614) (xy 377.157827 -242.072577)
			(xy 377.194079 -242.033506) (xy 377.23575 -242.000275) (xy 377.281908 -241.973626) (xy 377.331522 -241.954154)
			(xy 377.383484 -241.942294) (xy 377.436634 -241.938311) (xy 377.489784 -241.942294) (xy 377.541746 -241.954154)
			(xy 377.59136 -241.973626) (xy 377.637518 -242.000275) (xy 377.679189 -242.033506) (xy 377.715441 -242.072577)
			(xy 377.745465 -242.116614) (xy 377.768591 -242.164635) (xy 377.784301 -242.215565) (xy 377.792244 -242.268269)
			(xy 377.792742 -242.294918) (xy 377.792244 -242.321567) (xy 378.020824 -242.321567) (xy 378.020824 -242.268269)
			(xy 378.028767 -242.215565) (xy 378.044477 -242.164635) (xy 378.067603 -242.116614) (xy 378.097627 -242.072577)
			(xy 378.133879 -242.033506) (xy 378.17555 -242.000275) (xy 378.221708 -241.973626) (xy 378.271322 -241.954154)
			(xy 378.323284 -241.942294) (xy 378.376434 -241.938311) (xy 378.429584 -241.942294) (xy 378.481546 -241.954154)
			(xy 378.53116 -241.973626) (xy 378.577318 -242.000275) (xy 378.618989 -242.033506) (xy 378.655241 -242.072577)
			(xy 378.685265 -242.116614) (xy 378.708391 -242.164635) (xy 378.724101 -242.215565) (xy 378.732044 -242.268269)
			(xy 378.732542 -242.294918) (xy 378.732044 -242.321567) (xy 378.960624 -242.321567) (xy 378.960624 -242.268269)
			(xy 378.968567 -242.215565) (xy 378.984277 -242.164635) (xy 379.007403 -242.116614) (xy 379.037427 -242.072577)
			(xy 379.073679 -242.033506) (xy 379.11535 -242.000275) (xy 379.161508 -241.973626) (xy 379.211122 -241.954154)
			(xy 379.263084 -241.942294) (xy 379.316234 -241.938311) (xy 379.369384 -241.942294) (xy 379.421346 -241.954154)
			(xy 379.47096 -241.973626) (xy 379.517118 -242.000275) (xy 379.558789 -242.033506) (xy 379.595041 -242.072577)
			(xy 379.625065 -242.116614) (xy 379.648191 -242.164635) (xy 379.663901 -242.215565) (xy 379.671844 -242.268269)
			(xy 379.672342 -242.294918) (xy 379.671844 -242.321567) (xy 379.900424 -242.321567) (xy 379.900424 -242.268269)
			(xy 379.908367 -242.215565) (xy 379.924077 -242.164635) (xy 379.947203 -242.116614) (xy 379.977227 -242.072577)
			(xy 380.013479 -242.033506) (xy 380.05515 -242.000275) (xy 380.101308 -241.973626) (xy 380.150922 -241.954154)
			(xy 380.202884 -241.942294) (xy 380.256034 -241.938311) (xy 380.309184 -241.942294) (xy 380.361146 -241.954154)
			(xy 380.41076 -241.973626) (xy 380.456918 -242.000275) (xy 380.498589 -242.033506) (xy 380.534841 -242.072577)
			(xy 380.564865 -242.116614) (xy 380.587991 -242.164635) (xy 380.603701 -242.215565) (xy 380.611644 -242.268269)
			(xy 380.612142 -242.294918) (xy 380.611644 -242.321567) (xy 380.603701 -242.374271) (xy 380.587991 -242.425201)
			(xy 380.564865 -242.473222) (xy 380.534841 -242.517259) (xy 380.498589 -242.55633) (xy 380.456918 -242.589561)
			(xy 380.41076 -242.61621) (xy 380.361146 -242.635682) (xy 380.309184 -242.647542) (xy 380.256034 -242.651526)
			(xy 380.202884 -242.647542) (xy 380.150922 -242.635682) (xy 380.101308 -242.61621) (xy 380.05515 -242.589561)
			(xy 380.013479 -242.55633) (xy 379.977227 -242.517259) (xy 379.947203 -242.473222) (xy 379.924077 -242.425201)
			(xy 379.908367 -242.374271) (xy 379.900424 -242.321567) (xy 379.671844 -242.321567) (xy 379.663901 -242.374271)
			(xy 379.648191 -242.425201) (xy 379.625065 -242.473222) (xy 379.595041 -242.517259) (xy 379.558789 -242.55633)
			(xy 379.517118 -242.589561) (xy 379.47096 -242.61621) (xy 379.421346 -242.635682) (xy 379.369384 -242.647542)
			(xy 379.316234 -242.651526) (xy 379.263084 -242.647542) (xy 379.211122 -242.635682) (xy 379.161508 -242.61621)
			(xy 379.11535 -242.589561) (xy 379.073679 -242.55633) (xy 379.037427 -242.517259) (xy 379.007403 -242.473222)
			(xy 378.984277 -242.425201) (xy 378.968567 -242.374271) (xy 378.960624 -242.321567) (xy 378.732044 -242.321567)
			(xy 378.724101 -242.374271) (xy 378.708391 -242.425201) (xy 378.685265 -242.473222) (xy 378.655241 -242.517259)
			(xy 378.618989 -242.55633) (xy 378.577318 -242.589561) (xy 378.53116 -242.61621) (xy 378.481546 -242.635682)
			(xy 378.429584 -242.647542) (xy 378.376434 -242.651526) (xy 378.323284 -242.647542) (xy 378.271322 -242.635682)
			(xy 378.221708 -242.61621) (xy 378.17555 -242.589561) (xy 378.133879 -242.55633) (xy 378.097627 -242.517259)
			(xy 378.067603 -242.473222) (xy 378.044477 -242.425201) (xy 378.028767 -242.374271) (xy 378.020824 -242.321567)
			(xy 377.792244 -242.321567) (xy 377.784301 -242.374271) (xy 377.768591 -242.425201) (xy 377.745465 -242.473222)
			(xy 377.715441 -242.517259) (xy 377.679189 -242.55633) (xy 377.637518 -242.589561) (xy 377.59136 -242.61621)
			(xy 377.541746 -242.635682) (xy 377.489784 -242.647542) (xy 377.436634 -242.651526) (xy 377.383484 -242.647542)
			(xy 377.331522 -242.635682) (xy 377.281908 -242.61621) (xy 377.23575 -242.589561) (xy 377.194079 -242.55633)
			(xy 377.157827 -242.517259) (xy 377.127803 -242.473222) (xy 377.104677 -242.425201) (xy 377.088967 -242.374271)
			(xy 377.081024 -242.321567) (xy 376.852444 -242.321567) (xy 376.844501 -242.374271) (xy 376.828791 -242.425201)
			(xy 376.805665 -242.473222) (xy 376.775641 -242.517259) (xy 376.739389 -242.55633) (xy 376.697718 -242.589561)
			(xy 376.65156 -242.61621) (xy 376.601946 -242.635682) (xy 376.549984 -242.647542) (xy 376.496834 -242.651526)
			(xy 376.443684 -242.647542) (xy 376.391722 -242.635682) (xy 376.342108 -242.61621) (xy 376.29595 -242.589561)
			(xy 376.254279 -242.55633) (xy 376.218027 -242.517259) (xy 376.188003 -242.473222) (xy 376.164877 -242.425201)
			(xy 376.149167 -242.374271) (xy 376.141224 -242.321567) (xy 375.912644 -242.321567) (xy 375.904701 -242.374271)
			(xy 375.888991 -242.425201) (xy 375.865865 -242.473222) (xy 375.835841 -242.517259) (xy 375.799589 -242.55633)
			(xy 375.757918 -242.589561) (xy 375.71176 -242.61621) (xy 375.662146 -242.635682) (xy 375.610184 -242.647542)
			(xy 375.557034 -242.651526) (xy 375.503884 -242.647542) (xy 375.451922 -242.635682) (xy 375.402308 -242.61621)
			(xy 375.35615 -242.589561) (xy 375.314479 -242.55633) (xy 375.278227 -242.517259) (xy 375.248203 -242.473222)
			(xy 375.225077 -242.425201) (xy 375.209367 -242.374271) (xy 375.201424 -242.321567) (xy 374.972844 -242.321567)
			(xy 374.964901 -242.374271) (xy 374.949191 -242.425201) (xy 374.926065 -242.473222) (xy 374.896041 -242.517259)
			(xy 374.859789 -242.55633) (xy 374.818118 -242.589561) (xy 374.77196 -242.61621) (xy 374.722346 -242.635682)
			(xy 374.670384 -242.647542) (xy 374.617234 -242.651526) (xy 374.564084 -242.647542) (xy 374.512122 -242.635682)
			(xy 374.462508 -242.61621) (xy 374.41635 -242.589561) (xy 374.374679 -242.55633) (xy 374.338427 -242.517259)
			(xy 374.308403 -242.473222) (xy 374.285277 -242.425201) (xy 374.269567 -242.374271) (xy 374.261624 -242.321567)
			(xy 374.033044 -242.321567) (xy 374.025101 -242.374271) (xy 374.009391 -242.425201) (xy 373.986265 -242.473222)
			(xy 373.956241 -242.517259) (xy 373.919989 -242.55633) (xy 373.878318 -242.589561) (xy 373.83216 -242.61621)
			(xy 373.782546 -242.635682) (xy 373.730584 -242.647542) (xy 373.677434 -242.651526) (xy 373.624284 -242.647542)
			(xy 373.572322 -242.635682) (xy 373.522708 -242.61621) (xy 373.47655 -242.589561) (xy 373.434879 -242.55633)
			(xy 373.398627 -242.517259) (xy 373.368603 -242.473222) (xy 373.345477 -242.425201) (xy 373.329767 -242.374271)
			(xy 373.321824 -242.321567) (xy 373.093244 -242.321567) (xy 373.085301 -242.374271) (xy 373.069591 -242.425201)
			(xy 373.046465 -242.473222) (xy 373.016441 -242.517259) (xy 372.980189 -242.55633) (xy 372.938518 -242.589561)
			(xy 372.89236 -242.61621) (xy 372.842746 -242.635682) (xy 372.790784 -242.647542) (xy 372.737634 -242.651526)
			(xy 372.684484 -242.647542) (xy 372.632522 -242.635682) (xy 372.582908 -242.61621) (xy 372.53675 -242.589561)
			(xy 372.495079 -242.55633) (xy 372.458827 -242.517259) (xy 372.428803 -242.473222) (xy 372.405677 -242.425201)
			(xy 372.389967 -242.374271) (xy 372.382024 -242.321567) (xy 372.153444 -242.321567) (xy 372.145501 -242.374271)
			(xy 372.129791 -242.425201) (xy 372.106665 -242.473222) (xy 372.076641 -242.517259) (xy 372.040389 -242.55633)
			(xy 371.998718 -242.589561) (xy 371.95256 -242.61621) (xy 371.902946 -242.635682) (xy 371.850984 -242.647542)
			(xy 371.797834 -242.651526) (xy 371.744684 -242.647542) (xy 371.692722 -242.635682) (xy 371.643108 -242.61621)
			(xy 371.59695 -242.589561) (xy 371.555279 -242.55633) (xy 371.519027 -242.517259) (xy 371.489003 -242.473222)
			(xy 371.465877 -242.425201) (xy 371.450167 -242.374271) (xy 371.442224 -242.321567) (xy 371.213644 -242.321567)
			(xy 371.205701 -242.374271) (xy 371.189991 -242.425201) (xy 371.166865 -242.473222) (xy 371.136841 -242.517259)
			(xy 371.100589 -242.55633) (xy 371.058918 -242.589561) (xy 371.01276 -242.61621) (xy 370.963146 -242.635682)
			(xy 370.911184 -242.647542) (xy 370.858034 -242.651526) (xy 370.804884 -242.647542) (xy 370.752922 -242.635682)
			(xy 370.703308 -242.61621) (xy 370.65715 -242.589561) (xy 370.615479 -242.55633) (xy 370.579227 -242.517259)
			(xy 370.549203 -242.473222) (xy 370.526077 -242.425201) (xy 370.510367 -242.374271) (xy 370.502424 -242.321567)
			(xy 368.40668 -242.321567) (xy 368.40668 -243.135637) (xy 370.03227 -243.135637) (xy 370.03227 -243.082339)
			(xy 370.040213 -243.029635) (xy 370.055923 -242.978705) (xy 370.079049 -242.930684) (xy 370.109073 -242.886647)
			(xy 370.145325 -242.847576) (xy 370.186996 -242.814345) (xy 370.233154 -242.787696) (xy 370.282768 -242.768224)
			(xy 370.33473 -242.756364) (xy 370.38788 -242.752381) (xy 370.44103 -242.756364) (xy 370.492992 -242.768224)
			(xy 370.542606 -242.787696) (xy 370.588764 -242.814345) (xy 370.630435 -242.847576) (xy 370.666687 -242.886647)
			(xy 370.696711 -242.930684) (xy 370.719837 -242.978705) (xy 370.735547 -243.029635) (xy 370.74349 -243.082339)
			(xy 370.743988 -243.108988) (xy 370.74349 -243.135637) (xy 370.97207 -243.135637) (xy 370.97207 -243.082339)
			(xy 370.980013 -243.029635) (xy 370.995723 -242.978705) (xy 371.018849 -242.930684) (xy 371.048873 -242.886647)
			(xy 371.085125 -242.847576) (xy 371.126796 -242.814345) (xy 371.172954 -242.787696) (xy 371.222568 -242.768224)
			(xy 371.27453 -242.756364) (xy 371.32768 -242.752381) (xy 371.38083 -242.756364) (xy 371.432792 -242.768224)
			(xy 371.482406 -242.787696) (xy 371.528564 -242.814345) (xy 371.570235 -242.847576) (xy 371.606487 -242.886647)
			(xy 371.636511 -242.930684) (xy 371.659637 -242.978705) (xy 371.675347 -243.029635) (xy 371.68329 -243.082339)
			(xy 371.683788 -243.108988) (xy 371.68329 -243.135637) (xy 371.91187 -243.135637) (xy 371.91187 -243.082339)
			(xy 371.919813 -243.029635) (xy 371.935523 -242.978705) (xy 371.958649 -242.930684) (xy 371.988673 -242.886647)
			(xy 372.024925 -242.847576) (xy 372.066596 -242.814345) (xy 372.112754 -242.787696) (xy 372.162368 -242.768224)
			(xy 372.21433 -242.756364) (xy 372.26748 -242.752381) (xy 372.32063 -242.756364) (xy 372.372592 -242.768224)
			(xy 372.422206 -242.787696) (xy 372.468364 -242.814345) (xy 372.510035 -242.847576) (xy 372.546287 -242.886647)
			(xy 372.576311 -242.930684) (xy 372.599437 -242.978705) (xy 372.615147 -243.029635) (xy 372.62309 -243.082339)
			(xy 372.623588 -243.108988) (xy 372.62309 -243.135637) (xy 372.85167 -243.135637) (xy 372.85167 -243.082339)
			(xy 372.859613 -243.029635) (xy 372.875323 -242.978705) (xy 372.898449 -242.930684) (xy 372.928473 -242.886647)
			(xy 372.964725 -242.847576) (xy 373.006396 -242.814345) (xy 373.052554 -242.787696) (xy 373.102168 -242.768224)
			(xy 373.15413 -242.756364) (xy 373.20728 -242.752381) (xy 373.26043 -242.756364) (xy 373.312392 -242.768224)
			(xy 373.362006 -242.787696) (xy 373.408164 -242.814345) (xy 373.449835 -242.847576) (xy 373.486087 -242.886647)
			(xy 373.516111 -242.930684) (xy 373.539237 -242.978705) (xy 373.554947 -243.029635) (xy 373.56289 -243.082339)
			(xy 373.563388 -243.108988) (xy 373.56289 -243.135637) (xy 373.791724 -243.135637) (xy 373.791724 -243.082339)
			(xy 373.799667 -243.029635) (xy 373.815377 -242.978705) (xy 373.838503 -242.930684) (xy 373.868527 -242.886647)
			(xy 373.904779 -242.847576) (xy 373.94645 -242.814345) (xy 373.992608 -242.787696) (xy 374.042222 -242.768224)
			(xy 374.094184 -242.756364) (xy 374.147334 -242.752381) (xy 374.200484 -242.756364) (xy 374.252446 -242.768224)
			(xy 374.30206 -242.787696) (xy 374.348218 -242.814345) (xy 374.389889 -242.847576) (xy 374.426141 -242.886647)
			(xy 374.456165 -242.930684) (xy 374.479291 -242.978705) (xy 374.495001 -243.029635) (xy 374.502944 -243.082339)
			(xy 374.503442 -243.108988) (xy 374.502944 -243.135637) (xy 374.73127 -243.135637) (xy 374.73127 -243.082339)
			(xy 374.739213 -243.029635) (xy 374.754923 -242.978705) (xy 374.778049 -242.930684) (xy 374.808073 -242.886647)
			(xy 374.844325 -242.847576) (xy 374.885996 -242.814345) (xy 374.932154 -242.787696) (xy 374.981768 -242.768224)
			(xy 375.03373 -242.756364) (xy 375.08688 -242.752381) (xy 375.14003 -242.756364) (xy 375.191992 -242.768224)
			(xy 375.241606 -242.787696) (xy 375.287764 -242.814345) (xy 375.329435 -242.847576) (xy 375.365687 -242.886647)
			(xy 375.395711 -242.930684) (xy 375.418837 -242.978705) (xy 375.434547 -243.029635) (xy 375.44249 -243.082339)
			(xy 375.442988 -243.108988) (xy 375.44249 -243.135637) (xy 375.67107 -243.135637) (xy 375.67107 -243.082339)
			(xy 375.679013 -243.029635) (xy 375.694723 -242.978705) (xy 375.717849 -242.930684) (xy 375.747873 -242.886647)
			(xy 375.784125 -242.847576) (xy 375.825796 -242.814345) (xy 375.871954 -242.787696) (xy 375.921568 -242.768224)
			(xy 375.97353 -242.756364) (xy 376.02668 -242.752381) (xy 376.07983 -242.756364) (xy 376.131792 -242.768224)
			(xy 376.181406 -242.787696) (xy 376.227564 -242.814345) (xy 376.269235 -242.847576) (xy 376.305487 -242.886647)
			(xy 376.335511 -242.930684) (xy 376.358637 -242.978705) (xy 376.374347 -243.029635) (xy 376.38229 -243.082339)
			(xy 376.382788 -243.108988) (xy 376.38229 -243.135637) (xy 376.61087 -243.135637) (xy 376.61087 -243.082339)
			(xy 376.618813 -243.029635) (xy 376.634523 -242.978705) (xy 376.657649 -242.930684) (xy 376.687673 -242.886647)
			(xy 376.723925 -242.847576) (xy 376.765596 -242.814345) (xy 376.811754 -242.787696) (xy 376.861368 -242.768224)
			(xy 376.91333 -242.756364) (xy 376.96648 -242.752381) (xy 377.01963 -242.756364) (xy 377.071592 -242.768224)
			(xy 377.121206 -242.787696) (xy 377.167364 -242.814345) (xy 377.209035 -242.847576) (xy 377.245287 -242.886647)
			(xy 377.275311 -242.930684) (xy 377.298437 -242.978705) (xy 377.314147 -243.029635) (xy 377.32209 -243.082339)
			(xy 377.322588 -243.108988) (xy 377.32209 -243.135637) (xy 377.55067 -243.135637) (xy 377.55067 -243.082339)
			(xy 377.558613 -243.029635) (xy 377.574323 -242.978705) (xy 377.597449 -242.930684) (xy 377.627473 -242.886647)
			(xy 377.663725 -242.847576) (xy 377.705396 -242.814345) (xy 377.751554 -242.787696) (xy 377.801168 -242.768224)
			(xy 377.85313 -242.756364) (xy 377.90628 -242.752381) (xy 377.95943 -242.756364) (xy 378.011392 -242.768224)
			(xy 378.061006 -242.787696) (xy 378.107164 -242.814345) (xy 378.148835 -242.847576) (xy 378.185087 -242.886647)
			(xy 378.215111 -242.930684) (xy 378.238237 -242.978705) (xy 378.253947 -243.029635) (xy 378.26189 -243.082339)
			(xy 378.262388 -243.108988) (xy 378.26189 -243.135637) (xy 378.49047 -243.135637) (xy 378.49047 -243.082339)
			(xy 378.498413 -243.029635) (xy 378.514123 -242.978705) (xy 378.537249 -242.930684) (xy 378.567273 -242.886647)
			(xy 378.603525 -242.847576) (xy 378.645196 -242.814345) (xy 378.691354 -242.787696) (xy 378.740968 -242.768224)
			(xy 378.79293 -242.756364) (xy 378.84608 -242.752381) (xy 378.89923 -242.756364) (xy 378.951192 -242.768224)
			(xy 379.000806 -242.787696) (xy 379.046964 -242.814345) (xy 379.088635 -242.847576) (xy 379.124887 -242.886647)
			(xy 379.154911 -242.930684) (xy 379.178037 -242.978705) (xy 379.193747 -243.029635) (xy 379.20169 -243.082339)
			(xy 379.202188 -243.108988) (xy 379.20169 -243.135637) (xy 379.43027 -243.135637) (xy 379.43027 -243.082339)
			(xy 379.438213 -243.029635) (xy 379.453923 -242.978705) (xy 379.477049 -242.930684) (xy 379.507073 -242.886647)
			(xy 379.543325 -242.847576) (xy 379.584996 -242.814345) (xy 379.631154 -242.787696) (xy 379.680768 -242.768224)
			(xy 379.73273 -242.756364) (xy 379.78588 -242.752381) (xy 379.83903 -242.756364) (xy 379.890992 -242.768224)
			(xy 379.940606 -242.787696) (xy 379.986764 -242.814345) (xy 380.028435 -242.847576) (xy 380.064687 -242.886647)
			(xy 380.094711 -242.930684) (xy 380.117837 -242.978705) (xy 380.133547 -243.029635) (xy 380.14149 -243.082339)
			(xy 380.141988 -243.108988) (xy 380.14149 -243.135637) (xy 380.133547 -243.188341) (xy 380.117837 -243.239271)
			(xy 380.094711 -243.287292) (xy 380.064687 -243.331329) (xy 380.028435 -243.3704) (xy 379.986764 -243.403631)
			(xy 379.940606 -243.43028) (xy 379.890992 -243.449752) (xy 379.83903 -243.461612) (xy 379.78588 -243.465596)
			(xy 379.73273 -243.461612) (xy 379.680768 -243.449752) (xy 379.631154 -243.43028) (xy 379.584996 -243.403631)
			(xy 379.543325 -243.3704) (xy 379.507073 -243.331329) (xy 379.477049 -243.287292) (xy 379.453923 -243.239271)
			(xy 379.438213 -243.188341) (xy 379.43027 -243.135637) (xy 379.20169 -243.135637) (xy 379.193747 -243.188341)
			(xy 379.178037 -243.239271) (xy 379.154911 -243.287292) (xy 379.124887 -243.331329) (xy 379.088635 -243.3704)
			(xy 379.046964 -243.403631) (xy 379.000806 -243.43028) (xy 378.951192 -243.449752) (xy 378.89923 -243.461612)
			(xy 378.84608 -243.465596) (xy 378.79293 -243.461612) (xy 378.740968 -243.449752) (xy 378.691354 -243.43028)
			(xy 378.645196 -243.403631) (xy 378.603525 -243.3704) (xy 378.567273 -243.331329) (xy 378.537249 -243.287292)
			(xy 378.514123 -243.239271) (xy 378.498413 -243.188341) (xy 378.49047 -243.135637) (xy 378.26189 -243.135637)
			(xy 378.253947 -243.188341) (xy 378.238237 -243.239271) (xy 378.215111 -243.287292) (xy 378.185087 -243.331329)
			(xy 378.148835 -243.3704) (xy 378.107164 -243.403631) (xy 378.061006 -243.43028) (xy 378.011392 -243.449752)
			(xy 377.95943 -243.461612) (xy 377.90628 -243.465596) (xy 377.85313 -243.461612) (xy 377.801168 -243.449752)
			(xy 377.751554 -243.43028) (xy 377.705396 -243.403631) (xy 377.663725 -243.3704) (xy 377.627473 -243.331329)
			(xy 377.597449 -243.287292) (xy 377.574323 -243.239271) (xy 377.558613 -243.188341) (xy 377.55067 -243.135637)
			(xy 377.32209 -243.135637) (xy 377.314147 -243.188341) (xy 377.298437 -243.239271) (xy 377.275311 -243.287292)
			(xy 377.245287 -243.331329) (xy 377.209035 -243.3704) (xy 377.167364 -243.403631) (xy 377.121206 -243.43028)
			(xy 377.071592 -243.449752) (xy 377.01963 -243.461612) (xy 376.96648 -243.465596) (xy 376.91333 -243.461612)
			(xy 376.861368 -243.449752) (xy 376.811754 -243.43028) (xy 376.765596 -243.403631) (xy 376.723925 -243.3704)
			(xy 376.687673 -243.331329) (xy 376.657649 -243.287292) (xy 376.634523 -243.239271) (xy 376.618813 -243.188341)
			(xy 376.61087 -243.135637) (xy 376.38229 -243.135637) (xy 376.374347 -243.188341) (xy 376.358637 -243.239271)
			(xy 376.335511 -243.287292) (xy 376.305487 -243.331329) (xy 376.269235 -243.3704) (xy 376.227564 -243.403631)
			(xy 376.181406 -243.43028) (xy 376.131792 -243.449752) (xy 376.07983 -243.461612) (xy 376.02668 -243.465596)
			(xy 375.97353 -243.461612) (xy 375.921568 -243.449752) (xy 375.871954 -243.43028) (xy 375.825796 -243.403631)
			(xy 375.784125 -243.3704) (xy 375.747873 -243.331329) (xy 375.717849 -243.287292) (xy 375.694723 -243.239271)
			(xy 375.679013 -243.188341) (xy 375.67107 -243.135637) (xy 375.44249 -243.135637) (xy 375.434547 -243.188341)
			(xy 375.418837 -243.239271) (xy 375.395711 -243.287292) (xy 375.365687 -243.331329) (xy 375.329435 -243.3704)
			(xy 375.287764 -243.403631) (xy 375.241606 -243.43028) (xy 375.191992 -243.449752) (xy 375.14003 -243.461612)
			(xy 375.08688 -243.465596) (xy 375.03373 -243.461612) (xy 374.981768 -243.449752) (xy 374.932154 -243.43028)
			(xy 374.885996 -243.403631) (xy 374.844325 -243.3704) (xy 374.808073 -243.331329) (xy 374.778049 -243.287292)
			(xy 374.754923 -243.239271) (xy 374.739213 -243.188341) (xy 374.73127 -243.135637) (xy 374.502944 -243.135637)
			(xy 374.495001 -243.188341) (xy 374.479291 -243.239271) (xy 374.456165 -243.287292) (xy 374.426141 -243.331329)
			(xy 374.389889 -243.3704) (xy 374.348218 -243.403631) (xy 374.30206 -243.43028) (xy 374.252446 -243.449752)
			(xy 374.200484 -243.461612) (xy 374.147334 -243.465596) (xy 374.094184 -243.461612) (xy 374.042222 -243.449752)
			(xy 373.992608 -243.43028) (xy 373.94645 -243.403631) (xy 373.904779 -243.3704) (xy 373.868527 -243.331329)
			(xy 373.838503 -243.287292) (xy 373.815377 -243.239271) (xy 373.799667 -243.188341) (xy 373.791724 -243.135637)
			(xy 373.56289 -243.135637) (xy 373.554947 -243.188341) (xy 373.539237 -243.239271) (xy 373.516111 -243.287292)
			(xy 373.486087 -243.331329) (xy 373.449835 -243.3704) (xy 373.408164 -243.403631) (xy 373.362006 -243.43028)
			(xy 373.312392 -243.449752) (xy 373.26043 -243.461612) (xy 373.20728 -243.465596) (xy 373.15413 -243.461612)
			(xy 373.102168 -243.449752) (xy 373.052554 -243.43028) (xy 373.006396 -243.403631) (xy 372.964725 -243.3704)
			(xy 372.928473 -243.331329) (xy 372.898449 -243.287292) (xy 372.875323 -243.239271) (xy 372.859613 -243.188341)
			(xy 372.85167 -243.135637) (xy 372.62309 -243.135637) (xy 372.615147 -243.188341) (xy 372.599437 -243.239271)
			(xy 372.576311 -243.287292) (xy 372.546287 -243.331329) (xy 372.510035 -243.3704) (xy 372.468364 -243.403631)
			(xy 372.422206 -243.43028) (xy 372.372592 -243.449752) (xy 372.32063 -243.461612) (xy 372.26748 -243.465596)
			(xy 372.21433 -243.461612) (xy 372.162368 -243.449752) (xy 372.112754 -243.43028) (xy 372.066596 -243.403631)
			(xy 372.024925 -243.3704) (xy 371.988673 -243.331329) (xy 371.958649 -243.287292) (xy 371.935523 -243.239271)
			(xy 371.919813 -243.188341) (xy 371.91187 -243.135637) (xy 371.68329 -243.135637) (xy 371.675347 -243.188341)
			(xy 371.659637 -243.239271) (xy 371.636511 -243.287292) (xy 371.606487 -243.331329) (xy 371.570235 -243.3704)
			(xy 371.528564 -243.403631) (xy 371.482406 -243.43028) (xy 371.432792 -243.449752) (xy 371.38083 -243.461612)
			(xy 371.32768 -243.465596) (xy 371.27453 -243.461612) (xy 371.222568 -243.449752) (xy 371.172954 -243.43028)
			(xy 371.126796 -243.403631) (xy 371.085125 -243.3704) (xy 371.048873 -243.331329) (xy 371.018849 -243.287292)
			(xy 370.995723 -243.239271) (xy 370.980013 -243.188341) (xy 370.97207 -243.135637) (xy 370.74349 -243.135637)
			(xy 370.735547 -243.188341) (xy 370.719837 -243.239271) (xy 370.696711 -243.287292) (xy 370.666687 -243.331329)
			(xy 370.630435 -243.3704) (xy 370.588764 -243.403631) (xy 370.542606 -243.43028) (xy 370.492992 -243.449752)
			(xy 370.44103 -243.461612) (xy 370.38788 -243.465596) (xy 370.33473 -243.461612) (xy 370.282768 -243.449752)
			(xy 370.233154 -243.43028) (xy 370.186996 -243.403631) (xy 370.145325 -243.3704) (xy 370.109073 -243.331329)
			(xy 370.079049 -243.287292) (xy 370.055923 -243.239271) (xy 370.040213 -243.188341) (xy 370.03227 -243.135637)
			(xy 368.40668 -243.135637) (xy 368.40668 -243.627148) (xy 367.019089 -245.014739) (xy 368.559538 -245.014739)
			(xy 368.56375 -244.960075) (xy 368.576297 -244.906704) (xy 368.596881 -244.85589) (xy 368.625017 -244.808835)
			(xy 368.642138 -244.78742) (xy 368.650717 -244.776256) (xy 368.66207 -244.750508) (xy 368.665959 -244.722639)
			(xy 368.662091 -244.694766) (xy 368.650757 -244.66901) (xy 368.642138 -244.65788) (xy 368.625061 -244.636428)
			(xy 368.596916 -244.589379) (xy 368.57632 -244.538569) (xy 368.563762 -244.485201) (xy 368.559538 -244.430539)
			(xy 368.56375 -244.375875) (xy 368.576297 -244.322504) (xy 368.596881 -244.27169) (xy 368.625017 -244.224635)
			(xy 368.642138 -244.20322) (xy 368.650717 -244.192056) (xy 368.66207 -244.166308) (xy 368.665959 -244.138439)
			(xy 368.662091 -244.110566) (xy 368.650757 -244.08481) (xy 368.642138 -244.07368) (xy 368.626711 -244.054426)
			(xy 368.600752 -244.012471) (xy 368.580834 -243.967335) (xy 368.567336 -243.919881) (xy 368.560519 -243.871018)
			(xy 368.560096 -243.84635) (xy 368.560594 -243.819701) (xy 368.568537 -243.766997) (xy 368.584247 -243.716067)
			(xy 368.607373 -243.668046) (xy 368.637397 -243.624009) (xy 368.673649 -243.584938) (xy 368.71532 -243.551707)
			(xy 368.761478 -243.525058) (xy 368.811092 -243.505586) (xy 368.863054 -243.493726) (xy 368.916204 -243.489743)
			(xy 368.969354 -243.493726) (xy 369.021316 -243.505586) (xy 369.07093 -243.525058) (xy 369.117088 -243.551707)
			(xy 369.158759 -243.584938) (xy 369.195011 -243.624009) (xy 369.225035 -243.668046) (xy 369.248161 -243.716067)
			(xy 369.263871 -243.766997) (xy 369.271814 -243.819701) (xy 369.272312 -243.84635) (xy 369.271889 -243.871019)
			(xy 369.265088 -243.919887) (xy 369.256684 -243.949453) (xy 369.56237 -243.949453) (xy 369.56237 -243.896155)
			(xy 369.570313 -243.843451) (xy 369.586023 -243.792521) (xy 369.609149 -243.7445) (xy 369.639173 -243.700463)
			(xy 369.675425 -243.661392) (xy 369.717096 -243.628161) (xy 369.763254 -243.601512) (xy 369.812868 -243.58204)
			(xy 369.86483 -243.57018) (xy 369.91798 -243.566197) (xy 369.97113 -243.57018) (xy 370.023092 -243.58204)
			(xy 370.072706 -243.601512) (xy 370.118864 -243.628161) (xy 370.160535 -243.661392) (xy 370.196787 -243.700463)
			(xy 370.226811 -243.7445) (xy 370.249937 -243.792521) (xy 370.265647 -243.843451) (xy 370.27359 -243.896155)
			(xy 370.274088 -243.922804) (xy 370.27359 -243.949453) (xy 370.50217 -243.949453) (xy 370.50217 -243.896155)
			(xy 370.510113 -243.843451) (xy 370.525823 -243.792521) (xy 370.548949 -243.7445) (xy 370.578973 -243.700463)
			(xy 370.615225 -243.661392) (xy 370.656896 -243.628161) (xy 370.703054 -243.601512) (xy 370.752668 -243.58204)
			(xy 370.80463 -243.57018) (xy 370.85778 -243.566197) (xy 370.91093 -243.57018) (xy 370.962892 -243.58204)
			(xy 371.012506 -243.601512) (xy 371.058664 -243.628161) (xy 371.100335 -243.661392) (xy 371.136587 -243.700463)
			(xy 371.166611 -243.7445) (xy 371.189737 -243.792521) (xy 371.205447 -243.843451) (xy 371.21339 -243.896155)
			(xy 371.213888 -243.922804) (xy 371.21339 -243.949453) (xy 371.442224 -243.949453) (xy 371.442224 -243.896155)
			(xy 371.450167 -243.843451) (xy 371.465877 -243.792521) (xy 371.489003 -243.7445) (xy 371.519027 -243.700463)
			(xy 371.555279 -243.661392) (xy 371.59695 -243.628161) (xy 371.643108 -243.601512) (xy 371.692722 -243.58204)
			(xy 371.744684 -243.57018) (xy 371.797834 -243.566197) (xy 371.850984 -243.57018) (xy 371.902946 -243.58204)
			(xy 371.95256 -243.601512) (xy 371.998718 -243.628161) (xy 372.040389 -243.661392) (xy 372.076641 -243.700463)
			(xy 372.106665 -243.7445) (xy 372.129791 -243.792521) (xy 372.145501 -243.843451) (xy 372.153444 -243.896155)
			(xy 372.153942 -243.922804) (xy 372.153444 -243.949453) (xy 372.382024 -243.949453) (xy 372.382024 -243.896155)
			(xy 372.389967 -243.843451) (xy 372.405677 -243.792521) (xy 372.428803 -243.7445) (xy 372.458827 -243.700463)
			(xy 372.495079 -243.661392) (xy 372.53675 -243.628161) (xy 372.582908 -243.601512) (xy 372.632522 -243.58204)
			(xy 372.684484 -243.57018) (xy 372.737634 -243.566197) (xy 372.790784 -243.57018) (xy 372.842746 -243.58204)
			(xy 372.89236 -243.601512) (xy 372.938518 -243.628161) (xy 372.980189 -243.661392) (xy 373.016441 -243.700463)
			(xy 373.046465 -243.7445) (xy 373.069591 -243.792521) (xy 373.085301 -243.843451) (xy 373.093244 -243.896155)
			(xy 373.093742 -243.922804) (xy 373.093244 -243.949453) (xy 373.321824 -243.949453) (xy 373.321824 -243.896155)
			(xy 373.329767 -243.843451) (xy 373.345477 -243.792521) (xy 373.368603 -243.7445) (xy 373.398627 -243.700463)
			(xy 373.434879 -243.661392) (xy 373.47655 -243.628161) (xy 373.522708 -243.601512) (xy 373.572322 -243.58204)
			(xy 373.624284 -243.57018) (xy 373.677434 -243.566197) (xy 373.730584 -243.57018) (xy 373.782546 -243.58204)
			(xy 373.83216 -243.601512) (xy 373.878318 -243.628161) (xy 373.919989 -243.661392) (xy 373.956241 -243.700463)
			(xy 373.986265 -243.7445) (xy 374.009391 -243.792521) (xy 374.025101 -243.843451) (xy 374.033044 -243.896155)
			(xy 374.033542 -243.922804) (xy 374.033044 -243.949453) (xy 374.261624 -243.949453) (xy 374.261624 -243.896155)
			(xy 374.269567 -243.843451) (xy 374.285277 -243.792521) (xy 374.308403 -243.7445) (xy 374.338427 -243.700463)
			(xy 374.374679 -243.661392) (xy 374.41635 -243.628161) (xy 374.462508 -243.601512) (xy 374.512122 -243.58204)
			(xy 374.564084 -243.57018) (xy 374.617234 -243.566197) (xy 374.670384 -243.57018) (xy 374.722346 -243.58204)
			(xy 374.77196 -243.601512) (xy 374.818118 -243.628161) (xy 374.859789 -243.661392) (xy 374.896041 -243.700463)
			(xy 374.926065 -243.7445) (xy 374.949191 -243.792521) (xy 374.964901 -243.843451) (xy 374.972844 -243.896155)
			(xy 374.973342 -243.922804) (xy 374.972844 -243.949453) (xy 375.201424 -243.949453) (xy 375.201424 -243.896155)
			(xy 375.209367 -243.843451) (xy 375.225077 -243.792521) (xy 375.248203 -243.7445) (xy 375.278227 -243.700463)
			(xy 375.314479 -243.661392) (xy 375.35615 -243.628161) (xy 375.402308 -243.601512) (xy 375.451922 -243.58204)
			(xy 375.503884 -243.57018) (xy 375.557034 -243.566197) (xy 375.610184 -243.57018) (xy 375.662146 -243.58204)
			(xy 375.71176 -243.601512) (xy 375.757918 -243.628161) (xy 375.799589 -243.661392) (xy 375.835841 -243.700463)
			(xy 375.865865 -243.7445) (xy 375.888991 -243.792521) (xy 375.904701 -243.843451) (xy 375.912644 -243.896155)
			(xy 375.913142 -243.922804) (xy 375.912644 -243.949453) (xy 376.141224 -243.949453) (xy 376.141224 -243.896155)
			(xy 376.149167 -243.843451) (xy 376.164877 -243.792521) (xy 376.188003 -243.7445) (xy 376.218027 -243.700463)
			(xy 376.254279 -243.661392) (xy 376.29595 -243.628161) (xy 376.342108 -243.601512) (xy 376.391722 -243.58204)
			(xy 376.443684 -243.57018) (xy 376.496834 -243.566197) (xy 376.549984 -243.57018) (xy 376.601946 -243.58204)
			(xy 376.65156 -243.601512) (xy 376.697718 -243.628161) (xy 376.739389 -243.661392) (xy 376.775641 -243.700463)
			(xy 376.805665 -243.7445) (xy 376.828791 -243.792521) (xy 376.844501 -243.843451) (xy 376.852444 -243.896155)
			(xy 376.852942 -243.922804) (xy 376.852444 -243.949453) (xy 377.08077 -243.949453) (xy 377.08077 -243.896155)
			(xy 377.088713 -243.843451) (xy 377.104423 -243.792521) (xy 377.127549 -243.7445) (xy 377.157573 -243.700463)
			(xy 377.193825 -243.661392) (xy 377.235496 -243.628161) (xy 377.281654 -243.601512) (xy 377.331268 -243.58204)
			(xy 377.38323 -243.57018) (xy 377.43638 -243.566197) (xy 377.48953 -243.57018) (xy 377.541492 -243.58204)
			(xy 377.591106 -243.601512) (xy 377.637264 -243.628161) (xy 377.678935 -243.661392) (xy 377.715187 -243.700463)
			(xy 377.745211 -243.7445) (xy 377.768337 -243.792521) (xy 377.784047 -243.843451) (xy 377.79199 -243.896155)
			(xy 377.792488 -243.922804) (xy 377.79199 -243.949453) (xy 378.020824 -243.949453) (xy 378.020824 -243.896155)
			(xy 378.028767 -243.843451) (xy 378.044477 -243.792521) (xy 378.067603 -243.7445) (xy 378.097627 -243.700463)
			(xy 378.133879 -243.661392) (xy 378.17555 -243.628161) (xy 378.221708 -243.601512) (xy 378.271322 -243.58204)
			(xy 378.323284 -243.57018) (xy 378.376434 -243.566197) (xy 378.429584 -243.57018) (xy 378.481546 -243.58204)
			(xy 378.53116 -243.601512) (xy 378.577318 -243.628161) (xy 378.618989 -243.661392) (xy 378.655241 -243.700463)
			(xy 378.685265 -243.7445) (xy 378.708391 -243.792521) (xy 378.724101 -243.843451) (xy 378.732044 -243.896155)
			(xy 378.732542 -243.922804) (xy 378.732044 -243.949453) (xy 378.960624 -243.949453) (xy 378.960624 -243.896155)
			(xy 378.968567 -243.843451) (xy 378.984277 -243.792521) (xy 379.007403 -243.7445) (xy 379.037427 -243.700463)
			(xy 379.073679 -243.661392) (xy 379.11535 -243.628161) (xy 379.161508 -243.601512) (xy 379.211122 -243.58204)
			(xy 379.263084 -243.57018) (xy 379.316234 -243.566197) (xy 379.369384 -243.57018) (xy 379.421346 -243.58204)
			(xy 379.47096 -243.601512) (xy 379.517118 -243.628161) (xy 379.558789 -243.661392) (xy 379.595041 -243.700463)
			(xy 379.625065 -243.7445) (xy 379.648191 -243.792521) (xy 379.663901 -243.843451) (xy 379.671844 -243.896155)
			(xy 379.672342 -243.922804) (xy 379.671844 -243.949453) (xy 379.900424 -243.949453) (xy 379.900424 -243.896155)
			(xy 379.908367 -243.843451) (xy 379.924077 -243.792521) (xy 379.947203 -243.7445) (xy 379.977227 -243.700463)
			(xy 380.013479 -243.661392) (xy 380.05515 -243.628161) (xy 380.101308 -243.601512) (xy 380.150922 -243.58204)
			(xy 380.202884 -243.57018) (xy 380.256034 -243.566197) (xy 380.309184 -243.57018) (xy 380.361146 -243.58204)
			(xy 380.41076 -243.601512) (xy 380.456918 -243.628161) (xy 380.498589 -243.661392) (xy 380.534841 -243.700463)
			(xy 380.564865 -243.7445) (xy 380.587991 -243.792521) (xy 380.603701 -243.843451) (xy 380.611644 -243.896155)
			(xy 380.612142 -243.922804) (xy 380.611644 -243.949453) (xy 380.603701 -244.002157) (xy 380.587991 -244.053087)
			(xy 380.564865 -244.101108) (xy 380.534841 -244.145145) (xy 380.498589 -244.184216) (xy 380.456918 -244.217447)
			(xy 380.41076 -244.244096) (xy 380.361146 -244.263568) (xy 380.309184 -244.275428) (xy 380.256034 -244.279412)
			(xy 380.202884 -244.275428) (xy 380.150922 -244.263568) (xy 380.101308 -244.244096) (xy 380.05515 -244.217447)
			(xy 380.013479 -244.184216) (xy 379.977227 -244.145145) (xy 379.947203 -244.101108) (xy 379.924077 -244.053087)
			(xy 379.908367 -244.002157) (xy 379.900424 -243.949453) (xy 379.671844 -243.949453) (xy 379.663901 -244.002157)
			(xy 379.648191 -244.053087) (xy 379.625065 -244.101108) (xy 379.595041 -244.145145) (xy 379.558789 -244.184216)
			(xy 379.517118 -244.217447) (xy 379.47096 -244.244096) (xy 379.421346 -244.263568) (xy 379.369384 -244.275428)
			(xy 379.316234 -244.279412) (xy 379.263084 -244.275428) (xy 379.211122 -244.263568) (xy 379.161508 -244.244096)
			(xy 379.11535 -244.217447) (xy 379.073679 -244.184216) (xy 379.037427 -244.145145) (xy 379.007403 -244.101108)
			(xy 378.984277 -244.053087) (xy 378.968567 -244.002157) (xy 378.960624 -243.949453) (xy 378.732044 -243.949453)
			(xy 378.724101 -244.002157) (xy 378.708391 -244.053087) (xy 378.685265 -244.101108) (xy 378.655241 -244.145145)
			(xy 378.618989 -244.184216) (xy 378.577318 -244.217447) (xy 378.53116 -244.244096) (xy 378.481546 -244.263568)
			(xy 378.429584 -244.275428) (xy 378.376434 -244.279412) (xy 378.323284 -244.275428) (xy 378.271322 -244.263568)
			(xy 378.221708 -244.244096) (xy 378.17555 -244.217447) (xy 378.133879 -244.184216) (xy 378.097627 -244.145145)
			(xy 378.067603 -244.101108) (xy 378.044477 -244.053087) (xy 378.028767 -244.002157) (xy 378.020824 -243.949453)
			(xy 377.79199 -243.949453) (xy 377.784047 -244.002157) (xy 377.768337 -244.053087) (xy 377.745211 -244.101108)
			(xy 377.715187 -244.145145) (xy 377.678935 -244.184216) (xy 377.637264 -244.217447) (xy 377.591106 -244.244096)
			(xy 377.541492 -244.263568) (xy 377.48953 -244.275428) (xy 377.43638 -244.279412) (xy 377.38323 -244.275428)
			(xy 377.331268 -244.263568) (xy 377.281654 -244.244096) (xy 377.235496 -244.217447) (xy 377.193825 -244.184216)
			(xy 377.157573 -244.145145) (xy 377.127549 -244.101108) (xy 377.104423 -244.053087) (xy 377.088713 -244.002157)
			(xy 377.08077 -243.949453) (xy 376.852444 -243.949453) (xy 376.844501 -244.002157) (xy 376.828791 -244.053087)
			(xy 376.805665 -244.101108) (xy 376.775641 -244.145145) (xy 376.739389 -244.184216) (xy 376.697718 -244.217447)
			(xy 376.65156 -244.244096) (xy 376.601946 -244.263568) (xy 376.549984 -244.275428) (xy 376.496834 -244.279412)
			(xy 376.443684 -244.275428) (xy 376.391722 -244.263568) (xy 376.342108 -244.244096) (xy 376.29595 -244.217447)
			(xy 376.254279 -244.184216) (xy 376.218027 -244.145145) (xy 376.188003 -244.101108) (xy 376.164877 -244.053087)
			(xy 376.149167 -244.002157) (xy 376.141224 -243.949453) (xy 375.912644 -243.949453) (xy 375.904701 -244.002157)
			(xy 375.888991 -244.053087) (xy 375.865865 -244.101108) (xy 375.835841 -244.145145) (xy 375.799589 -244.184216)
			(xy 375.757918 -244.217447) (xy 375.71176 -244.244096) (xy 375.662146 -244.263568) (xy 375.610184 -244.275428)
			(xy 375.557034 -244.279412) (xy 375.503884 -244.275428) (xy 375.451922 -244.263568) (xy 375.402308 -244.244096)
			(xy 375.35615 -244.217447) (xy 375.314479 -244.184216) (xy 375.278227 -244.145145) (xy 375.248203 -244.101108)
			(xy 375.225077 -244.053087) (xy 375.209367 -244.002157) (xy 375.201424 -243.949453) (xy 374.972844 -243.949453)
			(xy 374.964901 -244.002157) (xy 374.949191 -244.053087) (xy 374.926065 -244.101108) (xy 374.896041 -244.145145)
			(xy 374.859789 -244.184216) (xy 374.818118 -244.217447) (xy 374.77196 -244.244096) (xy 374.722346 -244.263568)
			(xy 374.670384 -244.275428) (xy 374.617234 -244.279412) (xy 374.564084 -244.275428) (xy 374.512122 -244.263568)
			(xy 374.462508 -244.244096) (xy 374.41635 -244.217447) (xy 374.374679 -244.184216) (xy 374.338427 -244.145145)
			(xy 374.308403 -244.101108) (xy 374.285277 -244.053087) (xy 374.269567 -244.002157) (xy 374.261624 -243.949453)
			(xy 374.033044 -243.949453) (xy 374.025101 -244.002157) (xy 374.009391 -244.053087) (xy 373.986265 -244.101108)
			(xy 373.956241 -244.145145) (xy 373.919989 -244.184216) (xy 373.878318 -244.217447) (xy 373.83216 -244.244096)
			(xy 373.782546 -244.263568) (xy 373.730584 -244.275428) (xy 373.677434 -244.279412) (xy 373.624284 -244.275428)
			(xy 373.572322 -244.263568) (xy 373.522708 -244.244096) (xy 373.47655 -244.217447) (xy 373.434879 -244.184216)
			(xy 373.398627 -244.145145) (xy 373.368603 -244.101108) (xy 373.345477 -244.053087) (xy 373.329767 -244.002157)
			(xy 373.321824 -243.949453) (xy 373.093244 -243.949453) (xy 373.085301 -244.002157) (xy 373.069591 -244.053087)
			(xy 373.046465 -244.101108) (xy 373.016441 -244.145145) (xy 372.980189 -244.184216) (xy 372.938518 -244.217447)
			(xy 372.89236 -244.244096) (xy 372.842746 -244.263568) (xy 372.790784 -244.275428) (xy 372.737634 -244.279412)
			(xy 372.684484 -244.275428) (xy 372.632522 -244.263568) (xy 372.582908 -244.244096) (xy 372.53675 -244.217447)
			(xy 372.495079 -244.184216) (xy 372.458827 -244.145145) (xy 372.428803 -244.101108) (xy 372.405677 -244.053087)
			(xy 372.389967 -244.002157) (xy 372.382024 -243.949453) (xy 372.153444 -243.949453) (xy 372.145501 -244.002157)
			(xy 372.129791 -244.053087) (xy 372.106665 -244.101108) (xy 372.076641 -244.145145) (xy 372.040389 -244.184216)
			(xy 371.998718 -244.217447) (xy 371.95256 -244.244096) (xy 371.902946 -244.263568) (xy 371.850984 -244.275428)
			(xy 371.797834 -244.279412) (xy 371.744684 -244.275428) (xy 371.692722 -244.263568) (xy 371.643108 -244.244096)
			(xy 371.59695 -244.217447) (xy 371.555279 -244.184216) (xy 371.519027 -244.145145) (xy 371.489003 -244.101108)
			(xy 371.465877 -244.053087) (xy 371.450167 -244.002157) (xy 371.442224 -243.949453) (xy 371.21339 -243.949453)
			(xy 371.205447 -244.002157) (xy 371.189737 -244.053087) (xy 371.166611 -244.101108) (xy 371.136587 -244.145145)
			(xy 371.100335 -244.184216) (xy 371.058664 -244.217447) (xy 371.012506 -244.244096) (xy 370.962892 -244.263568)
			(xy 370.91093 -244.275428) (xy 370.85778 -244.279412) (xy 370.80463 -244.275428) (xy 370.752668 -244.263568)
			(xy 370.703054 -244.244096) (xy 370.656896 -244.217447) (xy 370.615225 -244.184216) (xy 370.578973 -244.145145)
			(xy 370.548949 -244.101108) (xy 370.525823 -244.053087) (xy 370.510113 -244.002157) (xy 370.50217 -243.949453)
			(xy 370.27359 -243.949453) (xy 370.265647 -244.002157) (xy 370.249937 -244.053087) (xy 370.226811 -244.101108)
			(xy 370.196787 -244.145145) (xy 370.160535 -244.184216) (xy 370.118864 -244.217447) (xy 370.072706 -244.244096)
			(xy 370.023092 -244.263568) (xy 369.97113 -244.275428) (xy 369.91798 -244.279412) (xy 369.86483 -244.275428)
			(xy 369.812868 -244.263568) (xy 369.763254 -244.244096) (xy 369.717096 -244.217447) (xy 369.675425 -244.184216)
			(xy 369.639173 -244.145145) (xy 369.609149 -244.101108) (xy 369.586023 -244.053087) (xy 369.570313 -244.002157)
			(xy 369.56237 -243.949453) (xy 369.256684 -243.949453) (xy 369.251598 -243.967345) (xy 369.231676 -244.012482)
			(xy 369.205706 -244.054432) (xy 369.19027 -244.07368) (xy 369.181595 -244.084776) (xy 369.170254 -244.110548)
			(xy 369.166382 -244.138439) (xy 369.170275 -244.166326) (xy 369.181636 -244.19209) (xy 369.19027 -244.20322)
			(xy 369.204328 -244.220741) (xy 369.228413 -244.258659) (xy 369.247534 -244.299308) (xy 369.254786 -244.320568)
			(xy 369.259918 -244.334637) (xy 369.27701 -244.359211) (xy 369.30048 -244.37779) (xy 369.32832 -244.388785)
			(xy 369.358151 -244.391258) (xy 369.372896 -244.38864) (xy 369.391462 -244.384858) (xy 369.429135 -244.380789)
			(xy 369.44808 -244.380512) (xy 369.474734 -244.380944) (xy 369.527446 -244.388886) (xy 369.578385 -244.404596)
			(xy 369.626414 -244.427724) (xy 369.67046 -244.457751) (xy 369.709538 -244.494008) (xy 369.742775 -244.535684)
			(xy 369.76943 -244.581849) (xy 369.788906 -244.631471) (xy 369.800768 -244.683442) (xy 369.804752 -244.7366)
			(xy 369.802772 -244.763015) (xy 370.03227 -244.763015) (xy 370.03227 -244.709717) (xy 370.040213 -244.657013)
			(xy 370.055923 -244.606083) (xy 370.079049 -244.558062) (xy 370.109073 -244.514025) (xy 370.145325 -244.474954)
			(xy 370.186996 -244.441723) (xy 370.233154 -244.415074) (xy 370.282768 -244.395602) (xy 370.33473 -244.383742)
			(xy 370.38788 -244.379759) (xy 370.44103 -244.383742) (xy 370.492992 -244.395602) (xy 370.542606 -244.415074)
			(xy 370.588764 -244.441723) (xy 370.630435 -244.474954) (xy 370.666687 -244.514025) (xy 370.696711 -244.558062)
			(xy 370.719837 -244.606083) (xy 370.735547 -244.657013) (xy 370.74349 -244.709717) (xy 370.743988 -244.736366)
			(xy 370.74349 -244.763015) (xy 370.743452 -244.763269) (xy 370.97207 -244.763269) (xy 370.97207 -244.709971)
			(xy 370.980013 -244.657267) (xy 370.995723 -244.606337) (xy 371.018849 -244.558316) (xy 371.048873 -244.514279)
			(xy 371.085125 -244.475208) (xy 371.126796 -244.441977) (xy 371.172954 -244.415328) (xy 371.222568 -244.395856)
			(xy 371.27453 -244.383996) (xy 371.32768 -244.380013) (xy 371.38083 -244.383996) (xy 371.432792 -244.395856)
			(xy 371.482406 -244.415328) (xy 371.528564 -244.441977) (xy 371.570235 -244.475208) (xy 371.606487 -244.514279)
			(xy 371.636511 -244.558316) (xy 371.659637 -244.606337) (xy 371.675347 -244.657267) (xy 371.68329 -244.709971)
			(xy 371.683788 -244.73662) (xy 371.68329 -244.763269) (xy 371.91187 -244.763269) (xy 371.91187 -244.709971)
			(xy 371.919813 -244.657267) (xy 371.935523 -244.606337) (xy 371.958649 -244.558316) (xy 371.988673 -244.514279)
			(xy 372.024925 -244.475208) (xy 372.066596 -244.441977) (xy 372.112754 -244.415328) (xy 372.162368 -244.395856)
			(xy 372.21433 -244.383996) (xy 372.26748 -244.380013) (xy 372.32063 -244.383996) (xy 372.372592 -244.395856)
			(xy 372.422206 -244.415328) (xy 372.468364 -244.441977) (xy 372.510035 -244.475208) (xy 372.546287 -244.514279)
			(xy 372.576311 -244.558316) (xy 372.599437 -244.606337) (xy 372.615147 -244.657267) (xy 372.62309 -244.709971)
			(xy 372.623588 -244.73662) (xy 372.62309 -244.763269) (xy 372.851924 -244.763269) (xy 372.851924 -244.709971)
			(xy 372.859867 -244.657267) (xy 372.875577 -244.606337) (xy 372.898703 -244.558316) (xy 372.928727 -244.514279)
			(xy 372.964979 -244.475208) (xy 373.00665 -244.441977) (xy 373.052808 -244.415328) (xy 373.102422 -244.395856)
			(xy 373.154384 -244.383996) (xy 373.207534 -244.380013) (xy 373.260684 -244.383996) (xy 373.312646 -244.395856)
			(xy 373.36226 -244.415328) (xy 373.408418 -244.441977) (xy 373.450089 -244.475208) (xy 373.486341 -244.514279)
			(xy 373.516365 -244.558316) (xy 373.539491 -244.606337) (xy 373.555201 -244.657267) (xy 373.563144 -244.709971)
			(xy 373.563642 -244.73662) (xy 373.563144 -244.763269) (xy 373.79147 -244.763269) (xy 373.79147 -244.709971)
			(xy 373.799413 -244.657267) (xy 373.815123 -244.606337) (xy 373.838249 -244.558316) (xy 373.868273 -244.514279)
			(xy 373.904525 -244.475208) (xy 373.946196 -244.441977) (xy 373.992354 -244.415328) (xy 374.041968 -244.395856)
			(xy 374.09393 -244.383996) (xy 374.14708 -244.380013) (xy 374.20023 -244.383996) (xy 374.252192 -244.395856)
			(xy 374.301806 -244.415328) (xy 374.347964 -244.441977) (xy 374.389635 -244.475208) (xy 374.425887 -244.514279)
			(xy 374.455911 -244.558316) (xy 374.479037 -244.606337) (xy 374.494747 -244.657267) (xy 374.50269 -244.709971)
			(xy 374.503188 -244.73662) (xy 374.50269 -244.763269) (xy 374.731524 -244.763269) (xy 374.731524 -244.709971)
			(xy 374.739467 -244.657267) (xy 374.755177 -244.606337) (xy 374.778303 -244.558316) (xy 374.808327 -244.514279)
			(xy 374.844579 -244.475208) (xy 374.88625 -244.441977) (xy 374.932408 -244.415328) (xy 374.982022 -244.395856)
			(xy 375.033984 -244.383996) (xy 375.087134 -244.380013) (xy 375.140284 -244.383996) (xy 375.192246 -244.395856)
			(xy 375.24186 -244.415328) (xy 375.288018 -244.441977) (xy 375.329689 -244.475208) (xy 375.365941 -244.514279)
			(xy 375.395965 -244.558316) (xy 375.419091 -244.606337) (xy 375.434801 -244.657267) (xy 375.442744 -244.709971)
			(xy 375.443242 -244.73662) (xy 375.442744 -244.763269) (xy 375.67107 -244.763269) (xy 375.67107 -244.709971)
			(xy 375.679013 -244.657267) (xy 375.694723 -244.606337) (xy 375.717849 -244.558316) (xy 375.747873 -244.514279)
			(xy 375.784125 -244.475208) (xy 375.825796 -244.441977) (xy 375.871954 -244.415328) (xy 375.921568 -244.395856)
			(xy 375.97353 -244.383996) (xy 376.02668 -244.380013) (xy 376.07983 -244.383996) (xy 376.131792 -244.395856)
			(xy 376.181406 -244.415328) (xy 376.227564 -244.441977) (xy 376.269235 -244.475208) (xy 376.305487 -244.514279)
			(xy 376.335511 -244.558316) (xy 376.358637 -244.606337) (xy 376.374347 -244.657267) (xy 376.38229 -244.709971)
			(xy 376.382788 -244.73662) (xy 376.38229 -244.763269) (xy 376.61087 -244.763269) (xy 376.61087 -244.709971)
			(xy 376.618813 -244.657267) (xy 376.634523 -244.606337) (xy 376.657649 -244.558316) (xy 376.687673 -244.514279)
			(xy 376.723925 -244.475208) (xy 376.765596 -244.441977) (xy 376.811754 -244.415328) (xy 376.861368 -244.395856)
			(xy 376.91333 -244.383996) (xy 376.96648 -244.380013) (xy 377.01963 -244.383996) (xy 377.071592 -244.395856)
			(xy 377.121206 -244.415328) (xy 377.167364 -244.441977) (xy 377.209035 -244.475208) (xy 377.245287 -244.514279)
			(xy 377.275311 -244.558316) (xy 377.298437 -244.606337) (xy 377.314147 -244.657267) (xy 377.32209 -244.709971)
			(xy 377.322588 -244.73662) (xy 377.32209 -244.763269) (xy 377.55067 -244.763269) (xy 377.55067 -244.709971)
			(xy 377.558613 -244.657267) (xy 377.574323 -244.606337) (xy 377.597449 -244.558316) (xy 377.627473 -244.514279)
			(xy 377.663725 -244.475208) (xy 377.705396 -244.441977) (xy 377.751554 -244.415328) (xy 377.801168 -244.395856)
			(xy 377.85313 -244.383996) (xy 377.90628 -244.380013) (xy 377.95943 -244.383996) (xy 378.011392 -244.395856)
			(xy 378.061006 -244.415328) (xy 378.107164 -244.441977) (xy 378.148835 -244.475208) (xy 378.185087 -244.514279)
			(xy 378.215111 -244.558316) (xy 378.238237 -244.606337) (xy 378.253947 -244.657267) (xy 378.26189 -244.709971)
			(xy 378.262388 -244.73662) (xy 378.26189 -244.763269) (xy 378.49047 -244.763269) (xy 378.49047 -244.709971)
			(xy 378.498413 -244.657267) (xy 378.514123 -244.606337) (xy 378.537249 -244.558316) (xy 378.567273 -244.514279)
			(xy 378.603525 -244.475208) (xy 378.645196 -244.441977) (xy 378.691354 -244.415328) (xy 378.740968 -244.395856)
			(xy 378.79293 -244.383996) (xy 378.84608 -244.380013) (xy 378.89923 -244.383996) (xy 378.951192 -244.395856)
			(xy 379.000806 -244.415328) (xy 379.046964 -244.441977) (xy 379.088635 -244.475208) (xy 379.124887 -244.514279)
			(xy 379.154911 -244.558316) (xy 379.178037 -244.606337) (xy 379.193747 -244.657267) (xy 379.20169 -244.709971)
			(xy 379.202188 -244.73662) (xy 379.20169 -244.763269) (xy 379.430524 -244.763269) (xy 379.430524 -244.709971)
			(xy 379.438467 -244.657267) (xy 379.454177 -244.606337) (xy 379.477303 -244.558316) (xy 379.507327 -244.514279)
			(xy 379.543579 -244.475208) (xy 379.58525 -244.441977) (xy 379.631408 -244.415328) (xy 379.681022 -244.395856)
			(xy 379.732984 -244.383996) (xy 379.786134 -244.380013) (xy 379.839284 -244.383996) (xy 379.891246 -244.395856)
			(xy 379.94086 -244.415328) (xy 379.987018 -244.441977) (xy 380.028689 -244.475208) (xy 380.064941 -244.514279)
			(xy 380.094965 -244.558316) (xy 380.118091 -244.606337) (xy 380.133801 -244.657267) (xy 380.141744 -244.709971)
			(xy 380.142242 -244.73662) (xy 380.141744 -244.763269) (xy 380.133801 -244.815973) (xy 380.118091 -244.866903)
			(xy 380.094965 -244.914924) (xy 380.064941 -244.958961) (xy 380.028689 -244.998032) (xy 379.987018 -245.031263)
			(xy 379.94086 -245.057912) (xy 379.891246 -245.077384) (xy 379.839284 -245.089244) (xy 379.786134 -245.093228)
			(xy 379.732984 -245.089244) (xy 379.681022 -245.077384) (xy 379.631408 -245.057912) (xy 379.58525 -245.031263)
			(xy 379.543579 -244.998032) (xy 379.507327 -244.958961) (xy 379.477303 -244.914924) (xy 379.454177 -244.866903)
			(xy 379.438467 -244.815973) (xy 379.430524 -244.763269) (xy 379.20169 -244.763269) (xy 379.193747 -244.815973)
			(xy 379.178037 -244.866903) (xy 379.154911 -244.914924) (xy 379.124887 -244.958961) (xy 379.088635 -244.998032)
			(xy 379.046964 -245.031263) (xy 379.000806 -245.057912) (xy 378.951192 -245.077384) (xy 378.89923 -245.089244)
			(xy 378.84608 -245.093228) (xy 378.79293 -245.089244) (xy 378.740968 -245.077384) (xy 378.691354 -245.057912)
			(xy 378.645196 -245.031263) (xy 378.603525 -244.998032) (xy 378.567273 -244.958961) (xy 378.537249 -244.914924)
			(xy 378.514123 -244.866903) (xy 378.498413 -244.815973) (xy 378.49047 -244.763269) (xy 378.26189 -244.763269)
			(xy 378.253947 -244.815973) (xy 378.238237 -244.866903) (xy 378.215111 -244.914924) (xy 378.185087 -244.958961)
			(xy 378.148835 -244.998032) (xy 378.107164 -245.031263) (xy 378.061006 -245.057912) (xy 378.011392 -245.077384)
			(xy 377.95943 -245.089244) (xy 377.90628 -245.093228) (xy 377.85313 -245.089244) (xy 377.801168 -245.077384)
			(xy 377.751554 -245.057912) (xy 377.705396 -245.031263) (xy 377.663725 -244.998032) (xy 377.627473 -244.958961)
			(xy 377.597449 -244.914924) (xy 377.574323 -244.866903) (xy 377.558613 -244.815973) (xy 377.55067 -244.763269)
			(xy 377.32209 -244.763269) (xy 377.314147 -244.815973) (xy 377.298437 -244.866903) (xy 377.275311 -244.914924)
			(xy 377.245287 -244.958961) (xy 377.209035 -244.998032) (xy 377.167364 -245.031263) (xy 377.121206 -245.057912)
			(xy 377.071592 -245.077384) (xy 377.01963 -245.089244) (xy 376.96648 -245.093228) (xy 376.91333 -245.089244)
			(xy 376.861368 -245.077384) (xy 376.811754 -245.057912) (xy 376.765596 -245.031263) (xy 376.723925 -244.998032)
			(xy 376.687673 -244.958961) (xy 376.657649 -244.914924) (xy 376.634523 -244.866903) (xy 376.618813 -244.815973)
			(xy 376.61087 -244.763269) (xy 376.38229 -244.763269) (xy 376.374347 -244.815973) (xy 376.358637 -244.866903)
			(xy 376.335511 -244.914924) (xy 376.305487 -244.958961) (xy 376.269235 -244.998032) (xy 376.227564 -245.031263)
			(xy 376.181406 -245.057912) (xy 376.131792 -245.077384) (xy 376.07983 -245.089244) (xy 376.02668 -245.093228)
			(xy 375.97353 -245.089244) (xy 375.921568 -245.077384) (xy 375.871954 -245.057912) (xy 375.825796 -245.031263)
			(xy 375.784125 -244.998032) (xy 375.747873 -244.958961) (xy 375.717849 -244.914924) (xy 375.694723 -244.866903)
			(xy 375.679013 -244.815973) (xy 375.67107 -244.763269) (xy 375.442744 -244.763269) (xy 375.434801 -244.815973)
			(xy 375.419091 -244.866903) (xy 375.395965 -244.914924) (xy 375.365941 -244.958961) (xy 375.329689 -244.998032)
			(xy 375.288018 -245.031263) (xy 375.24186 -245.057912) (xy 375.192246 -245.077384) (xy 375.140284 -245.089244)
			(xy 375.087134 -245.093228) (xy 375.033984 -245.089244) (xy 374.982022 -245.077384) (xy 374.932408 -245.057912)
			(xy 374.88625 -245.031263) (xy 374.844579 -244.998032) (xy 374.808327 -244.958961) (xy 374.778303 -244.914924)
			(xy 374.755177 -244.866903) (xy 374.739467 -244.815973) (xy 374.731524 -244.763269) (xy 374.50269 -244.763269)
			(xy 374.494747 -244.815973) (xy 374.479037 -244.866903) (xy 374.455911 -244.914924) (xy 374.425887 -244.958961)
			(xy 374.389635 -244.998032) (xy 374.347964 -245.031263) (xy 374.301806 -245.057912) (xy 374.252192 -245.077384)
			(xy 374.20023 -245.089244) (xy 374.14708 -245.093228) (xy 374.09393 -245.089244) (xy 374.041968 -245.077384)
			(xy 373.992354 -245.057912) (xy 373.946196 -245.031263) (xy 373.904525 -244.998032) (xy 373.868273 -244.958961)
			(xy 373.838249 -244.914924) (xy 373.815123 -244.866903) (xy 373.799413 -244.815973) (xy 373.79147 -244.763269)
			(xy 373.563144 -244.763269) (xy 373.555201 -244.815973) (xy 373.539491 -244.866903) (xy 373.516365 -244.914924)
			(xy 373.486341 -244.958961) (xy 373.450089 -244.998032) (xy 373.408418 -245.031263) (xy 373.36226 -245.057912)
			(xy 373.312646 -245.077384) (xy 373.260684 -245.089244) (xy 373.207534 -245.093228) (xy 373.154384 -245.089244)
			(xy 373.102422 -245.077384) (xy 373.052808 -245.057912) (xy 373.00665 -245.031263) (xy 372.964979 -244.998032)
			(xy 372.928727 -244.958961) (xy 372.898703 -244.914924) (xy 372.875577 -244.866903) (xy 372.859867 -244.815973)
			(xy 372.851924 -244.763269) (xy 372.62309 -244.763269) (xy 372.615147 -244.815973) (xy 372.599437 -244.866903)
			(xy 372.576311 -244.914924) (xy 372.546287 -244.958961) (xy 372.510035 -244.998032) (xy 372.468364 -245.031263)
			(xy 372.422206 -245.057912) (xy 372.372592 -245.077384) (xy 372.32063 -245.089244) (xy 372.26748 -245.093228)
			(xy 372.21433 -245.089244) (xy 372.162368 -245.077384) (xy 372.112754 -245.057912) (xy 372.066596 -245.031263)
			(xy 372.024925 -244.998032) (xy 371.988673 -244.958961) (xy 371.958649 -244.914924) (xy 371.935523 -244.866903)
			(xy 371.919813 -244.815973) (xy 371.91187 -244.763269) (xy 371.68329 -244.763269) (xy 371.675347 -244.815973)
			(xy 371.659637 -244.866903) (xy 371.636511 -244.914924) (xy 371.606487 -244.958961) (xy 371.570235 -244.998032)
			(xy 371.528564 -245.031263) (xy 371.482406 -245.057912) (xy 371.432792 -245.077384) (xy 371.38083 -245.089244)
			(xy 371.32768 -245.093228) (xy 371.27453 -245.089244) (xy 371.222568 -245.077384) (xy 371.172954 -245.057912)
			(xy 371.126796 -245.031263) (xy 371.085125 -244.998032) (xy 371.048873 -244.958961) (xy 371.018849 -244.914924)
			(xy 370.995723 -244.866903) (xy 370.980013 -244.815973) (xy 370.97207 -244.763269) (xy 370.743452 -244.763269)
			(xy 370.735547 -244.815719) (xy 370.719837 -244.866649) (xy 370.696711 -244.91467) (xy 370.666687 -244.958707)
			(xy 370.630435 -244.997778) (xy 370.588764 -245.031009) (xy 370.542606 -245.057658) (xy 370.492992 -245.07713)
			(xy 370.44103 -245.08899) (xy 370.38788 -245.092974) (xy 370.33473 -245.08899) (xy 370.282768 -245.07713)
			(xy 370.233154 -245.057658) (xy 370.186996 -245.031009) (xy 370.145325 -244.997778) (xy 370.109073 -244.958707)
			(xy 370.079049 -244.91467) (xy 370.055923 -244.866649) (xy 370.040213 -244.815719) (xy 370.03227 -244.763015)
			(xy 369.802772 -244.763015) (xy 369.800768 -244.789758) (xy 369.788906 -244.841729) (xy 369.76943 -244.891351)
			(xy 369.742775 -244.937516) (xy 369.709538 -244.979192) (xy 369.67046 -245.015449) (xy 369.626414 -245.045476)
			(xy 369.578385 -245.068604) (xy 369.527446 -245.084314) (xy 369.474734 -245.092256) (xy 369.44808 -245.092728)
			(xy 369.427313 -245.092413) (xy 369.38606 -245.087578) (xy 369.365784 -245.083076) (xy 369.351505 -245.080165)
			(xy 369.322416 -245.081702) (xy 369.294941 -245.091379) (xy 369.271309 -245.10841) (xy 369.253439 -245.131415)
			(xy 369.247674 -245.144798) (xy 369.236794 -245.17101) (xy 369.207959 -245.219887) (xy 369.19027 -245.24208)
			(xy 369.181595 -245.253176) (xy 369.170254 -245.278948) (xy 369.166382 -245.306839) (xy 369.170275 -245.334726)
			(xy 369.181636 -245.36049) (xy 369.19027 -245.37162) (xy 369.205698 -245.390873) (xy 369.231656 -245.432828)
			(xy 369.251575 -245.477965) (xy 369.265072 -245.525419) (xy 369.271889 -245.574282) (xy 369.271941 -245.577339)
			(xy 369.562624 -245.577339) (xy 369.562624 -245.524041) (xy 369.570567 -245.471337) (xy 369.586277 -245.420407)
			(xy 369.609403 -245.372386) (xy 369.639427 -245.328349) (xy 369.675679 -245.289278) (xy 369.71735 -245.256047)
			(xy 369.763508 -245.229398) (xy 369.813122 -245.209926) (xy 369.865084 -245.198066) (xy 369.918234 -245.194083)
			(xy 369.971384 -245.198066) (xy 370.023346 -245.209926) (xy 370.07296 -245.229398) (xy 370.119118 -245.256047)
			(xy 370.160789 -245.289278) (xy 370.197041 -245.328349) (xy 370.227065 -245.372386) (xy 370.250191 -245.420407)
			(xy 370.265901 -245.471337) (xy 370.273844 -245.524041) (xy 370.274342 -245.55069) (xy 370.273844 -245.577339)
			(xy 370.502424 -245.577339) (xy 370.502424 -245.524041) (xy 370.510367 -245.471337) (xy 370.526077 -245.420407)
			(xy 370.549203 -245.372386) (xy 370.579227 -245.328349) (xy 370.615479 -245.289278) (xy 370.65715 -245.256047)
			(xy 370.703308 -245.229398) (xy 370.752922 -245.209926) (xy 370.804884 -245.198066) (xy 370.858034 -245.194083)
			(xy 370.911184 -245.198066) (xy 370.963146 -245.209926) (xy 371.01276 -245.229398) (xy 371.058918 -245.256047)
			(xy 371.100589 -245.289278) (xy 371.136841 -245.328349) (xy 371.166865 -245.372386) (xy 371.189991 -245.420407)
			(xy 371.205701 -245.471337) (xy 371.213644 -245.524041) (xy 371.214142 -245.55069) (xy 371.213644 -245.577339)
			(xy 371.442224 -245.577339) (xy 371.442224 -245.524041) (xy 371.450167 -245.471337) (xy 371.465877 -245.420407)
			(xy 371.489003 -245.372386) (xy 371.519027 -245.328349) (xy 371.555279 -245.289278) (xy 371.59695 -245.256047)
			(xy 371.643108 -245.229398) (xy 371.692722 -245.209926) (xy 371.744684 -245.198066) (xy 371.797834 -245.194083)
			(xy 371.850984 -245.198066) (xy 371.902946 -245.209926) (xy 371.95256 -245.229398) (xy 371.998718 -245.256047)
			(xy 372.040389 -245.289278) (xy 372.076641 -245.328349) (xy 372.106665 -245.372386) (xy 372.129791 -245.420407)
			(xy 372.145501 -245.471337) (xy 372.153444 -245.524041) (xy 372.153942 -245.55069) (xy 372.153444 -245.577339)
			(xy 372.382024 -245.577339) (xy 372.382024 -245.524041) (xy 372.389967 -245.471337) (xy 372.405677 -245.420407)
			(xy 372.428803 -245.372386) (xy 372.458827 -245.328349) (xy 372.495079 -245.289278) (xy 372.53675 -245.256047)
			(xy 372.582908 -245.229398) (xy 372.632522 -245.209926) (xy 372.684484 -245.198066) (xy 372.737634 -245.194083)
			(xy 372.790784 -245.198066) (xy 372.842746 -245.209926) (xy 372.89236 -245.229398) (xy 372.938518 -245.256047)
			(xy 372.980189 -245.289278) (xy 373.016441 -245.328349) (xy 373.046465 -245.372386) (xy 373.069591 -245.420407)
			(xy 373.085301 -245.471337) (xy 373.093244 -245.524041) (xy 373.093742 -245.55069) (xy 373.093244 -245.577339)
			(xy 373.32157 -245.577339) (xy 373.32157 -245.524041) (xy 373.329513 -245.471337) (xy 373.345223 -245.420407)
			(xy 373.368349 -245.372386) (xy 373.398373 -245.328349) (xy 373.434625 -245.289278) (xy 373.476296 -245.256047)
			(xy 373.522454 -245.229398) (xy 373.572068 -245.209926) (xy 373.62403 -245.198066) (xy 373.67718 -245.194083)
			(xy 373.73033 -245.198066) (xy 373.782292 -245.209926) (xy 373.831906 -245.229398) (xy 373.878064 -245.256047)
			(xy 373.919735 -245.289278) (xy 373.955987 -245.328349) (xy 373.986011 -245.372386) (xy 374.009137 -245.420407)
			(xy 374.024847 -245.471337) (xy 374.03279 -245.524041) (xy 374.033288 -245.55069) (xy 374.03279 -245.577339)
			(xy 374.261624 -245.577339) (xy 374.261624 -245.524041) (xy 374.269567 -245.471337) (xy 374.285277 -245.420407)
			(xy 374.308403 -245.372386) (xy 374.338427 -245.328349) (xy 374.374679 -245.289278) (xy 374.41635 -245.256047)
			(xy 374.462508 -245.229398) (xy 374.512122 -245.209926) (xy 374.564084 -245.198066) (xy 374.617234 -245.194083)
			(xy 374.670384 -245.198066) (xy 374.722346 -245.209926) (xy 374.77196 -245.229398) (xy 374.818118 -245.256047)
			(xy 374.859789 -245.289278) (xy 374.896041 -245.328349) (xy 374.926065 -245.372386) (xy 374.949191 -245.420407)
			(xy 374.964901 -245.471337) (xy 374.972844 -245.524041) (xy 374.973342 -245.55069) (xy 374.972844 -245.577339)
			(xy 375.20117 -245.577339) (xy 375.20117 -245.524041) (xy 375.209113 -245.471337) (xy 375.224823 -245.420407)
			(xy 375.247949 -245.372386) (xy 375.277973 -245.328349) (xy 375.314225 -245.289278) (xy 375.355896 -245.256047)
			(xy 375.402054 -245.229398) (xy 375.451668 -245.209926) (xy 375.50363 -245.198066) (xy 375.55678 -245.194083)
			(xy 375.60993 -245.198066) (xy 375.661892 -245.209926) (xy 375.711506 -245.229398) (xy 375.757664 -245.256047)
			(xy 375.799335 -245.289278) (xy 375.835587 -245.328349) (xy 375.865611 -245.372386) (xy 375.888737 -245.420407)
			(xy 375.904447 -245.471337) (xy 375.91239 -245.524041) (xy 375.912888 -245.55069) (xy 375.91239 -245.577339)
			(xy 376.141224 -245.577339) (xy 376.141224 -245.524041) (xy 376.149167 -245.471337) (xy 376.164877 -245.420407)
			(xy 376.188003 -245.372386) (xy 376.218027 -245.328349) (xy 376.254279 -245.289278) (xy 376.29595 -245.256047)
			(xy 376.342108 -245.229398) (xy 376.391722 -245.209926) (xy 376.443684 -245.198066) (xy 376.496834 -245.194083)
			(xy 376.549984 -245.198066) (xy 376.601946 -245.209926) (xy 376.65156 -245.229398) (xy 376.697718 -245.256047)
			(xy 376.739389 -245.289278) (xy 376.775641 -245.328349) (xy 376.805665 -245.372386) (xy 376.828791 -245.420407)
			(xy 376.844501 -245.471337) (xy 376.852444 -245.524041) (xy 376.852942 -245.55069) (xy 376.852444 -245.577339)
			(xy 377.081024 -245.577339) (xy 377.081024 -245.524041) (xy 377.088967 -245.471337) (xy 377.104677 -245.420407)
			(xy 377.127803 -245.372386) (xy 377.157827 -245.328349) (xy 377.194079 -245.289278) (xy 377.23575 -245.256047)
			(xy 377.281908 -245.229398) (xy 377.331522 -245.209926) (xy 377.383484 -245.198066) (xy 377.436634 -245.194083)
			(xy 377.489784 -245.198066) (xy 377.541746 -245.209926) (xy 377.59136 -245.229398) (xy 377.637518 -245.256047)
			(xy 377.679189 -245.289278) (xy 377.715441 -245.328349) (xy 377.745465 -245.372386) (xy 377.768591 -245.420407)
			(xy 377.784301 -245.471337) (xy 377.792244 -245.524041) (xy 377.792742 -245.55069) (xy 377.792244 -245.577339)
			(xy 378.020824 -245.577339) (xy 378.020824 -245.524041) (xy 378.028767 -245.471337) (xy 378.044477 -245.420407)
			(xy 378.067603 -245.372386) (xy 378.097627 -245.328349) (xy 378.133879 -245.289278) (xy 378.17555 -245.256047)
			(xy 378.221708 -245.229398) (xy 378.271322 -245.209926) (xy 378.323284 -245.198066) (xy 378.376434 -245.194083)
			(xy 378.429584 -245.198066) (xy 378.481546 -245.209926) (xy 378.53116 -245.229398) (xy 378.577318 -245.256047)
			(xy 378.618989 -245.289278) (xy 378.655241 -245.328349) (xy 378.685265 -245.372386) (xy 378.708391 -245.420407)
			(xy 378.724101 -245.471337) (xy 378.732044 -245.524041) (xy 378.732542 -245.55069) (xy 378.732044 -245.577339)
			(xy 378.960624 -245.577339) (xy 378.960624 -245.524041) (xy 378.968567 -245.471337) (xy 378.984277 -245.420407)
			(xy 379.007403 -245.372386) (xy 379.037427 -245.328349) (xy 379.073679 -245.289278) (xy 379.11535 -245.256047)
			(xy 379.161508 -245.229398) (xy 379.211122 -245.209926) (xy 379.263084 -245.198066) (xy 379.316234 -245.194083)
			(xy 379.369384 -245.198066) (xy 379.421346 -245.209926) (xy 379.47096 -245.229398) (xy 379.517118 -245.256047)
			(xy 379.558789 -245.289278) (xy 379.595041 -245.328349) (xy 379.625065 -245.372386) (xy 379.648191 -245.420407)
			(xy 379.663901 -245.471337) (xy 379.671844 -245.524041) (xy 379.672342 -245.55069) (xy 379.671844 -245.577339)
			(xy 379.90017 -245.577339) (xy 379.90017 -245.524041) (xy 379.908113 -245.471337) (xy 379.923823 -245.420407)
			(xy 379.946949 -245.372386) (xy 379.976973 -245.328349) (xy 380.013225 -245.289278) (xy 380.054896 -245.256047)
			(xy 380.101054 -245.229398) (xy 380.150668 -245.209926) (xy 380.20263 -245.198066) (xy 380.25578 -245.194083)
			(xy 380.30893 -245.198066) (xy 380.360892 -245.209926) (xy 380.410506 -245.229398) (xy 380.456664 -245.256047)
			(xy 380.498335 -245.289278) (xy 380.534587 -245.328349) (xy 380.564611 -245.372386) (xy 380.587737 -245.420407)
			(xy 380.603447 -245.471337) (xy 380.61139 -245.524041) (xy 380.611888 -245.55069) (xy 380.61139 -245.577339)
			(xy 380.603447 -245.630043) (xy 380.587737 -245.680973) (xy 380.564611 -245.728994) (xy 380.534587 -245.773031)
			(xy 380.498335 -245.812102) (xy 380.456664 -245.845333) (xy 380.410506 -245.871982) (xy 380.360892 -245.891454)
			(xy 380.30893 -245.903314) (xy 380.25578 -245.907298) (xy 380.20263 -245.903314) (xy 380.150668 -245.891454)
			(xy 380.101054 -245.871982) (xy 380.054896 -245.845333) (xy 380.013225 -245.812102) (xy 379.976973 -245.773031)
			(xy 379.946949 -245.728994) (xy 379.923823 -245.680973) (xy 379.908113 -245.630043) (xy 379.90017 -245.577339)
			(xy 379.671844 -245.577339) (xy 379.663901 -245.630043) (xy 379.648191 -245.680973) (xy 379.625065 -245.728994)
			(xy 379.595041 -245.773031) (xy 379.558789 -245.812102) (xy 379.517118 -245.845333) (xy 379.47096 -245.871982)
			(xy 379.421346 -245.891454) (xy 379.369384 -245.903314) (xy 379.316234 -245.907298) (xy 379.263084 -245.903314)
			(xy 379.211122 -245.891454) (xy 379.161508 -245.871982) (xy 379.11535 -245.845333) (xy 379.073679 -245.812102)
			(xy 379.037427 -245.773031) (xy 379.007403 -245.728994) (xy 378.984277 -245.680973) (xy 378.968567 -245.630043)
			(xy 378.960624 -245.577339) (xy 378.732044 -245.577339) (xy 378.724101 -245.630043) (xy 378.708391 -245.680973)
			(xy 378.685265 -245.728994) (xy 378.655241 -245.773031) (xy 378.618989 -245.812102) (xy 378.577318 -245.845333)
			(xy 378.53116 -245.871982) (xy 378.481546 -245.891454) (xy 378.429584 -245.903314) (xy 378.376434 -245.907298)
			(xy 378.323284 -245.903314) (xy 378.271322 -245.891454) (xy 378.221708 -245.871982) (xy 378.17555 -245.845333)
			(xy 378.133879 -245.812102) (xy 378.097627 -245.773031) (xy 378.067603 -245.728994) (xy 378.044477 -245.680973)
			(xy 378.028767 -245.630043) (xy 378.020824 -245.577339) (xy 377.792244 -245.577339) (xy 377.784301 -245.630043)
			(xy 377.768591 -245.680973) (xy 377.745465 -245.728994) (xy 377.715441 -245.773031) (xy 377.679189 -245.812102)
			(xy 377.637518 -245.845333) (xy 377.59136 -245.871982) (xy 377.541746 -245.891454) (xy 377.489784 -245.903314)
			(xy 377.436634 -245.907298) (xy 377.383484 -245.903314) (xy 377.331522 -245.891454) (xy 377.281908 -245.871982)
			(xy 377.23575 -245.845333) (xy 377.194079 -245.812102) (xy 377.157827 -245.773031) (xy 377.127803 -245.728994)
			(xy 377.104677 -245.680973) (xy 377.088967 -245.630043) (xy 377.081024 -245.577339) (xy 376.852444 -245.577339)
			(xy 376.844501 -245.630043) (xy 376.828791 -245.680973) (xy 376.805665 -245.728994) (xy 376.775641 -245.773031)
			(xy 376.739389 -245.812102) (xy 376.697718 -245.845333) (xy 376.65156 -245.871982) (xy 376.601946 -245.891454)
			(xy 376.549984 -245.903314) (xy 376.496834 -245.907298) (xy 376.443684 -245.903314) (xy 376.391722 -245.891454)
			(xy 376.342108 -245.871982) (xy 376.29595 -245.845333) (xy 376.254279 -245.812102) (xy 376.218027 -245.773031)
			(xy 376.188003 -245.728994) (xy 376.164877 -245.680973) (xy 376.149167 -245.630043) (xy 376.141224 -245.577339)
			(xy 375.91239 -245.577339) (xy 375.904447 -245.630043) (xy 375.888737 -245.680973) (xy 375.865611 -245.728994)
			(xy 375.835587 -245.773031) (xy 375.799335 -245.812102) (xy 375.757664 -245.845333) (xy 375.711506 -245.871982)
			(xy 375.661892 -245.891454) (xy 375.60993 -245.903314) (xy 375.55678 -245.907298) (xy 375.50363 -245.903314)
			(xy 375.451668 -245.891454) (xy 375.402054 -245.871982) (xy 375.355896 -245.845333) (xy 375.314225 -245.812102)
			(xy 375.277973 -245.773031) (xy 375.247949 -245.728994) (xy 375.224823 -245.680973) (xy 375.209113 -245.630043)
			(xy 375.20117 -245.577339) (xy 374.972844 -245.577339) (xy 374.964901 -245.630043) (xy 374.949191 -245.680973)
			(xy 374.926065 -245.728994) (xy 374.896041 -245.773031) (xy 374.859789 -245.812102) (xy 374.818118 -245.845333)
			(xy 374.77196 -245.871982) (xy 374.722346 -245.891454) (xy 374.670384 -245.903314) (xy 374.617234 -245.907298)
			(xy 374.564084 -245.903314) (xy 374.512122 -245.891454) (xy 374.462508 -245.871982) (xy 374.41635 -245.845333)
			(xy 374.374679 -245.812102) (xy 374.338427 -245.773031) (xy 374.308403 -245.728994) (xy 374.285277 -245.680973)
			(xy 374.269567 -245.630043) (xy 374.261624 -245.577339) (xy 374.03279 -245.577339) (xy 374.024847 -245.630043)
			(xy 374.009137 -245.680973) (xy 373.986011 -245.728994) (xy 373.955987 -245.773031) (xy 373.919735 -245.812102)
			(xy 373.878064 -245.845333) (xy 373.831906 -245.871982) (xy 373.782292 -245.891454) (xy 373.73033 -245.903314)
			(xy 373.67718 -245.907298) (xy 373.62403 -245.903314) (xy 373.572068 -245.891454) (xy 373.522454 -245.871982)
			(xy 373.476296 -245.845333) (xy 373.434625 -245.812102) (xy 373.398373 -245.773031) (xy 373.368349 -245.728994)
			(xy 373.345223 -245.680973) (xy 373.329513 -245.630043) (xy 373.32157 -245.577339) (xy 373.093244 -245.577339)
			(xy 373.085301 -245.630043) (xy 373.069591 -245.680973) (xy 373.046465 -245.728994) (xy 373.016441 -245.773031)
			(xy 372.980189 -245.812102) (xy 372.938518 -245.845333) (xy 372.89236 -245.871982) (xy 372.842746 -245.891454)
			(xy 372.790784 -245.903314) (xy 372.737634 -245.907298) (xy 372.684484 -245.903314) (xy 372.632522 -245.891454)
			(xy 372.582908 -245.871982) (xy 372.53675 -245.845333) (xy 372.495079 -245.812102) (xy 372.458827 -245.773031)
			(xy 372.428803 -245.728994) (xy 372.405677 -245.680973) (xy 372.389967 -245.630043) (xy 372.382024 -245.577339)
			(xy 372.153444 -245.577339) (xy 372.145501 -245.630043) (xy 372.129791 -245.680973) (xy 372.106665 -245.728994)
			(xy 372.076641 -245.773031) (xy 372.040389 -245.812102) (xy 371.998718 -245.845333) (xy 371.95256 -245.871982)
			(xy 371.902946 -245.891454) (xy 371.850984 -245.903314) (xy 371.797834 -245.907298) (xy 371.744684 -245.903314)
			(xy 371.692722 -245.891454) (xy 371.643108 -245.871982) (xy 371.59695 -245.845333) (xy 371.555279 -245.812102)
			(xy 371.519027 -245.773031) (xy 371.489003 -245.728994) (xy 371.465877 -245.680973) (xy 371.450167 -245.630043)
			(xy 371.442224 -245.577339) (xy 371.213644 -245.577339) (xy 371.205701 -245.630043) (xy 371.189991 -245.680973)
			(xy 371.166865 -245.728994) (xy 371.136841 -245.773031) (xy 371.100589 -245.812102) (xy 371.058918 -245.845333)
			(xy 371.01276 -245.871982) (xy 370.963146 -245.891454) (xy 370.911184 -245.903314) (xy 370.858034 -245.907298)
			(xy 370.804884 -245.903314) (xy 370.752922 -245.891454) (xy 370.703308 -245.871982) (xy 370.65715 -245.845333)
			(xy 370.615479 -245.812102) (xy 370.579227 -245.773031) (xy 370.549203 -245.728994) (xy 370.526077 -245.680973)
			(xy 370.510367 -245.630043) (xy 370.502424 -245.577339) (xy 370.273844 -245.577339) (xy 370.265901 -245.630043)
			(xy 370.250191 -245.680973) (xy 370.227065 -245.728994) (xy 370.197041 -245.773031) (xy 370.160789 -245.812102)
			(xy 370.119118 -245.845333) (xy 370.07296 -245.871982) (xy 370.023346 -245.891454) (xy 369.971384 -245.903314)
			(xy 369.918234 -245.907298) (xy 369.865084 -245.903314) (xy 369.813122 -245.891454) (xy 369.763508 -245.871982)
			(xy 369.71735 -245.845333) (xy 369.675679 -245.812102) (xy 369.639427 -245.773031) (xy 369.609403 -245.728994)
			(xy 369.586277 -245.680973) (xy 369.570567 -245.630043) (xy 369.562624 -245.577339) (xy 369.271941 -245.577339)
			(xy 369.272312 -245.59895) (xy 369.271814 -245.625599) (xy 369.263871 -245.678303) (xy 369.248161 -245.729233)
			(xy 369.225035 -245.777254) (xy 369.195011 -245.821291) (xy 369.158759 -245.860362) (xy 369.117088 -245.893593)
			(xy 369.07093 -245.920242) (xy 369.021316 -245.939714) (xy 368.969354 -245.951574) (xy 368.916204 -245.955558)
			(xy 368.863054 -245.951574) (xy 368.811092 -245.939714) (xy 368.761478 -245.920242) (xy 368.71532 -245.893593)
			(xy 368.673649 -245.860362) (xy 368.637397 -245.821291) (xy 368.607373 -245.777254) (xy 368.584247 -245.729233)
			(xy 368.568537 -245.678303) (xy 368.560594 -245.625599) (xy 368.560096 -245.59895) (xy 368.560518 -245.574281)
			(xy 368.567318 -245.525413) (xy 368.580809 -245.477955) (xy 368.600731 -245.432817) (xy 368.626702 -245.390868)
			(xy 368.642138 -245.37162) (xy 368.650717 -245.360456) (xy 368.66207 -245.334708) (xy 368.665959 -245.306839)
			(xy 368.662091 -245.278966) (xy 368.650757 -245.25321) (xy 368.642138 -245.24208) (xy 368.625061 -245.220628)
			(xy 368.596916 -245.173579) (xy 368.57632 -245.122769) (xy 368.563762 -245.069401) (xy 368.559538 -245.014739)
			(xy 367.019089 -245.014739) (xy 366.78108 -245.252748) (xy 366.78108 -246.391155) (xy 369.092724 -246.391155)
			(xy 369.092724 -246.337857) (xy 369.100667 -246.285153) (xy 369.116377 -246.234223) (xy 369.139503 -246.186202)
			(xy 369.169527 -246.142165) (xy 369.205779 -246.103094) (xy 369.24745 -246.069863) (xy 369.293608 -246.043214)
			(xy 369.343222 -246.023742) (xy 369.395184 -246.011882) (xy 369.448334 -246.007899) (xy 369.501484 -246.011882)
			(xy 369.553446 -246.023742) (xy 369.60306 -246.043214) (xy 369.649218 -246.069863) (xy 369.690889 -246.103094)
			(xy 369.727141 -246.142165) (xy 369.757165 -246.186202) (xy 369.780291 -246.234223) (xy 369.796001 -246.285153)
			(xy 369.803944 -246.337857) (xy 369.804442 -246.364506) (xy 369.803944 -246.391155) (xy 370.032524 -246.391155)
			(xy 370.032524 -246.337857) (xy 370.040467 -246.285153) (xy 370.056177 -246.234223) (xy 370.079303 -246.186202)
			(xy 370.109327 -246.142165) (xy 370.145579 -246.103094) (xy 370.18725 -246.069863) (xy 370.233408 -246.043214)
			(xy 370.283022 -246.023742) (xy 370.334984 -246.011882) (xy 370.388134 -246.007899) (xy 370.441284 -246.011882)
			(xy 370.493246 -246.023742) (xy 370.54286 -246.043214) (xy 370.589018 -246.069863) (xy 370.630689 -246.103094)
			(xy 370.666941 -246.142165) (xy 370.696965 -246.186202) (xy 370.720091 -246.234223) (xy 370.735801 -246.285153)
			(xy 370.743744 -246.337857) (xy 370.744242 -246.364506) (xy 370.743744 -246.391155) (xy 370.97207 -246.391155)
			(xy 370.97207 -246.337857) (xy 370.980013 -246.285153) (xy 370.995723 -246.234223) (xy 371.018849 -246.186202)
			(xy 371.048873 -246.142165) (xy 371.085125 -246.103094) (xy 371.126796 -246.069863) (xy 371.172954 -246.043214)
			(xy 371.222568 -246.023742) (xy 371.27453 -246.011882) (xy 371.32768 -246.007899) (xy 371.38083 -246.011882)
			(xy 371.432792 -246.023742) (xy 371.482406 -246.043214) (xy 371.528564 -246.069863) (xy 371.570235 -246.103094)
			(xy 371.606487 -246.142165) (xy 371.636511 -246.186202) (xy 371.659637 -246.234223) (xy 371.675347 -246.285153)
			(xy 371.68329 -246.337857) (xy 371.683788 -246.364506) (xy 371.68329 -246.391155) (xy 371.91187 -246.391155)
			(xy 371.91187 -246.337857) (xy 371.919813 -246.285153) (xy 371.935523 -246.234223) (xy 371.958649 -246.186202)
			(xy 371.988673 -246.142165) (xy 372.024925 -246.103094) (xy 372.066596 -246.069863) (xy 372.112754 -246.043214)
			(xy 372.162368 -246.023742) (xy 372.21433 -246.011882) (xy 372.26748 -246.007899) (xy 372.32063 -246.011882)
			(xy 372.372592 -246.023742) (xy 372.422206 -246.043214) (xy 372.468364 -246.069863) (xy 372.510035 -246.103094)
			(xy 372.546287 -246.142165) (xy 372.576311 -246.186202) (xy 372.599437 -246.234223) (xy 372.615147 -246.285153)
			(xy 372.62309 -246.337857) (xy 372.623588 -246.364506) (xy 372.62309 -246.391155) (xy 372.85167 -246.391155)
			(xy 372.85167 -246.337857) (xy 372.859613 -246.285153) (xy 372.875323 -246.234223) (xy 372.898449 -246.186202)
			(xy 372.928473 -246.142165) (xy 372.964725 -246.103094) (xy 373.006396 -246.069863) (xy 373.052554 -246.043214)
			(xy 373.102168 -246.023742) (xy 373.15413 -246.011882) (xy 373.20728 -246.007899) (xy 373.26043 -246.011882)
			(xy 373.312392 -246.023742) (xy 373.362006 -246.043214) (xy 373.408164 -246.069863) (xy 373.449835 -246.103094)
			(xy 373.486087 -246.142165) (xy 373.516111 -246.186202) (xy 373.539237 -246.234223) (xy 373.554947 -246.285153)
			(xy 373.56289 -246.337857) (xy 373.563388 -246.364506) (xy 373.56289 -246.391155) (xy 373.79147 -246.391155)
			(xy 373.79147 -246.337857) (xy 373.799413 -246.285153) (xy 373.815123 -246.234223) (xy 373.838249 -246.186202)
			(xy 373.868273 -246.142165) (xy 373.904525 -246.103094) (xy 373.946196 -246.069863) (xy 373.992354 -246.043214)
			(xy 374.041968 -246.023742) (xy 374.09393 -246.011882) (xy 374.14708 -246.007899) (xy 374.20023 -246.011882)
			(xy 374.252192 -246.023742) (xy 374.301806 -246.043214) (xy 374.347964 -246.069863) (xy 374.389635 -246.103094)
			(xy 374.425887 -246.142165) (xy 374.455911 -246.186202) (xy 374.479037 -246.234223) (xy 374.494747 -246.285153)
			(xy 374.50269 -246.337857) (xy 374.503188 -246.364506) (xy 374.50269 -246.391155) (xy 374.73127 -246.391155)
			(xy 374.73127 -246.337857) (xy 374.739213 -246.285153) (xy 374.754923 -246.234223) (xy 374.778049 -246.186202)
			(xy 374.808073 -246.142165) (xy 374.844325 -246.103094) (xy 374.885996 -246.069863) (xy 374.932154 -246.043214)
			(xy 374.981768 -246.023742) (xy 375.03373 -246.011882) (xy 375.08688 -246.007899) (xy 375.14003 -246.011882)
			(xy 375.191992 -246.023742) (xy 375.241606 -246.043214) (xy 375.287764 -246.069863) (xy 375.329435 -246.103094)
			(xy 375.365687 -246.142165) (xy 375.395711 -246.186202) (xy 375.418837 -246.234223) (xy 375.434547 -246.285153)
			(xy 375.44249 -246.337857) (xy 375.442988 -246.364506) (xy 375.44249 -246.391155) (xy 375.67107 -246.391155)
			(xy 375.67107 -246.337857) (xy 375.679013 -246.285153) (xy 375.694723 -246.234223) (xy 375.717849 -246.186202)
			(xy 375.747873 -246.142165) (xy 375.784125 -246.103094) (xy 375.825796 -246.069863) (xy 375.871954 -246.043214)
			(xy 375.921568 -246.023742) (xy 375.97353 -246.011882) (xy 376.02668 -246.007899) (xy 376.07983 -246.011882)
			(xy 376.131792 -246.023742) (xy 376.181406 -246.043214) (xy 376.227564 -246.069863) (xy 376.269235 -246.103094)
			(xy 376.305487 -246.142165) (xy 376.335511 -246.186202) (xy 376.358637 -246.234223) (xy 376.374347 -246.285153)
			(xy 376.38229 -246.337857) (xy 376.382788 -246.364506) (xy 376.38229 -246.391155) (xy 376.611124 -246.391155)
			(xy 376.611124 -246.337857) (xy 376.619067 -246.285153) (xy 376.634777 -246.234223) (xy 376.657903 -246.186202)
			(xy 376.687927 -246.142165) (xy 376.724179 -246.103094) (xy 376.76585 -246.069863) (xy 376.812008 -246.043214)
			(xy 376.861622 -246.023742) (xy 376.913584 -246.011882) (xy 376.966734 -246.007899) (xy 377.019884 -246.011882)
			(xy 377.071846 -246.023742) (xy 377.12146 -246.043214) (xy 377.167618 -246.069863) (xy 377.209289 -246.103094)
			(xy 377.245541 -246.142165) (xy 377.275565 -246.186202) (xy 377.298691 -246.234223) (xy 377.314401 -246.285153)
			(xy 377.322344 -246.337857) (xy 377.322842 -246.364506) (xy 377.322344 -246.391155) (xy 377.55067 -246.391155)
			(xy 377.55067 -246.337857) (xy 377.558613 -246.285153) (xy 377.574323 -246.234223) (xy 377.597449 -246.186202)
			(xy 377.627473 -246.142165) (xy 377.663725 -246.103094) (xy 377.705396 -246.069863) (xy 377.751554 -246.043214)
			(xy 377.801168 -246.023742) (xy 377.85313 -246.011882) (xy 377.90628 -246.007899) (xy 377.95943 -246.011882)
			(xy 378.011392 -246.023742) (xy 378.061006 -246.043214) (xy 378.107164 -246.069863) (xy 378.148835 -246.103094)
			(xy 378.185087 -246.142165) (xy 378.215111 -246.186202) (xy 378.238237 -246.234223) (xy 378.253947 -246.285153)
			(xy 378.26189 -246.337857) (xy 378.262388 -246.364506) (xy 378.26189 -246.391155) (xy 378.49047 -246.391155)
			(xy 378.49047 -246.337857) (xy 378.498413 -246.285153) (xy 378.514123 -246.234223) (xy 378.537249 -246.186202)
			(xy 378.567273 -246.142165) (xy 378.603525 -246.103094) (xy 378.645196 -246.069863) (xy 378.691354 -246.043214)
			(xy 378.740968 -246.023742) (xy 378.79293 -246.011882) (xy 378.84608 -246.007899) (xy 378.89923 -246.011882)
			(xy 378.951192 -246.023742) (xy 379.000806 -246.043214) (xy 379.046964 -246.069863) (xy 379.088635 -246.103094)
			(xy 379.124887 -246.142165) (xy 379.154911 -246.186202) (xy 379.178037 -246.234223) (xy 379.193747 -246.285153)
			(xy 379.20169 -246.337857) (xy 379.202188 -246.364506) (xy 379.20169 -246.391155) (xy 379.43027 -246.391155)
			(xy 379.43027 -246.337857) (xy 379.438213 -246.285153) (xy 379.453923 -246.234223) (xy 379.477049 -246.186202)
			(xy 379.507073 -246.142165) (xy 379.543325 -246.103094) (xy 379.584996 -246.069863) (xy 379.631154 -246.043214)
			(xy 379.680768 -246.023742) (xy 379.73273 -246.011882) (xy 379.78588 -246.007899) (xy 379.83903 -246.011882)
			(xy 379.890992 -246.023742) (xy 379.940606 -246.043214) (xy 379.986764 -246.069863) (xy 380.028435 -246.103094)
			(xy 380.064687 -246.142165) (xy 380.094711 -246.186202) (xy 380.117837 -246.234223) (xy 380.133547 -246.285153)
			(xy 380.14149 -246.337857) (xy 380.141988 -246.364506) (xy 380.14149 -246.391155) (xy 380.133547 -246.443859)
			(xy 380.117837 -246.494789) (xy 380.094711 -246.54281) (xy 380.064687 -246.586847) (xy 380.028435 -246.625918)
			(xy 379.986764 -246.659149) (xy 379.940606 -246.685798) (xy 379.890992 -246.70527) (xy 379.83903 -246.71713)
			(xy 379.78588 -246.721114) (xy 379.73273 -246.71713) (xy 379.680768 -246.70527) (xy 379.631154 -246.685798)
			(xy 379.584996 -246.659149) (xy 379.543325 -246.625918) (xy 379.507073 -246.586847) (xy 379.477049 -246.54281)
			(xy 379.453923 -246.494789) (xy 379.438213 -246.443859) (xy 379.43027 -246.391155) (xy 379.20169 -246.391155)
			(xy 379.193747 -246.443859) (xy 379.178037 -246.494789) (xy 379.154911 -246.54281) (xy 379.124887 -246.586847)
			(xy 379.088635 -246.625918) (xy 379.046964 -246.659149) (xy 379.000806 -246.685798) (xy 378.951192 -246.70527)
			(xy 378.89923 -246.71713) (xy 378.84608 -246.721114) (xy 378.79293 -246.71713) (xy 378.740968 -246.70527)
			(xy 378.691354 -246.685798) (xy 378.645196 -246.659149) (xy 378.603525 -246.625918) (xy 378.567273 -246.586847)
			(xy 378.537249 -246.54281) (xy 378.514123 -246.494789) (xy 378.498413 -246.443859) (xy 378.49047 -246.391155)
			(xy 378.26189 -246.391155) (xy 378.253947 -246.443859) (xy 378.238237 -246.494789) (xy 378.215111 -246.54281)
			(xy 378.185087 -246.586847) (xy 378.148835 -246.625918) (xy 378.107164 -246.659149) (xy 378.061006 -246.685798)
			(xy 378.011392 -246.70527) (xy 377.95943 -246.71713) (xy 377.90628 -246.721114) (xy 377.85313 -246.71713)
			(xy 377.801168 -246.70527) (xy 377.751554 -246.685798) (xy 377.705396 -246.659149) (xy 377.663725 -246.625918)
			(xy 377.627473 -246.586847) (xy 377.597449 -246.54281) (xy 377.574323 -246.494789) (xy 377.558613 -246.443859)
			(xy 377.55067 -246.391155) (xy 377.322344 -246.391155) (xy 377.314401 -246.443859) (xy 377.298691 -246.494789)
			(xy 377.275565 -246.54281) (xy 377.245541 -246.586847) (xy 377.209289 -246.625918) (xy 377.167618 -246.659149)
			(xy 377.12146 -246.685798) (xy 377.071846 -246.70527) (xy 377.019884 -246.71713) (xy 376.966734 -246.721114)
			(xy 376.913584 -246.71713) (xy 376.861622 -246.70527) (xy 376.812008 -246.685798) (xy 376.76585 -246.659149)
			(xy 376.724179 -246.625918) (xy 376.687927 -246.586847) (xy 376.657903 -246.54281) (xy 376.634777 -246.494789)
			(xy 376.619067 -246.443859) (xy 376.611124 -246.391155) (xy 376.38229 -246.391155) (xy 376.374347 -246.443859)
			(xy 376.358637 -246.494789) (xy 376.335511 -246.54281) (xy 376.305487 -246.586847) (xy 376.269235 -246.625918)
			(xy 376.227564 -246.659149) (xy 376.181406 -246.685798) (xy 376.131792 -246.70527) (xy 376.07983 -246.71713)
			(xy 376.02668 -246.721114) (xy 375.97353 -246.71713) (xy 375.921568 -246.70527) (xy 375.871954 -246.685798)
			(xy 375.825796 -246.659149) (xy 375.784125 -246.625918) (xy 375.747873 -246.586847) (xy 375.717849 -246.54281)
			(xy 375.694723 -246.494789) (xy 375.679013 -246.443859) (xy 375.67107 -246.391155) (xy 375.44249 -246.391155)
			(xy 375.434547 -246.443859) (xy 375.418837 -246.494789) (xy 375.395711 -246.54281) (xy 375.365687 -246.586847)
			(xy 375.329435 -246.625918) (xy 375.287764 -246.659149) (xy 375.241606 -246.685798) (xy 375.191992 -246.70527)
			(xy 375.14003 -246.71713) (xy 375.08688 -246.721114) (xy 375.03373 -246.71713) (xy 374.981768 -246.70527)
			(xy 374.932154 -246.685798) (xy 374.885996 -246.659149) (xy 374.844325 -246.625918) (xy 374.808073 -246.586847)
			(xy 374.778049 -246.54281) (xy 374.754923 -246.494789) (xy 374.739213 -246.443859) (xy 374.73127 -246.391155)
			(xy 374.50269 -246.391155) (xy 374.494747 -246.443859) (xy 374.479037 -246.494789) (xy 374.455911 -246.54281)
			(xy 374.425887 -246.586847) (xy 374.389635 -246.625918) (xy 374.347964 -246.659149) (xy 374.301806 -246.685798)
			(xy 374.252192 -246.70527) (xy 374.20023 -246.71713) (xy 374.14708 -246.721114) (xy 374.09393 -246.71713)
			(xy 374.041968 -246.70527) (xy 373.992354 -246.685798) (xy 373.946196 -246.659149) (xy 373.904525 -246.625918)
			(xy 373.868273 -246.586847) (xy 373.838249 -246.54281) (xy 373.815123 -246.494789) (xy 373.799413 -246.443859)
			(xy 373.79147 -246.391155) (xy 373.56289 -246.391155) (xy 373.554947 -246.443859) (xy 373.539237 -246.494789)
			(xy 373.516111 -246.54281) (xy 373.486087 -246.586847) (xy 373.449835 -246.625918) (xy 373.408164 -246.659149)
			(xy 373.362006 -246.685798) (xy 373.312392 -246.70527) (xy 373.26043 -246.71713) (xy 373.20728 -246.721114)
			(xy 373.15413 -246.71713) (xy 373.102168 -246.70527) (xy 373.052554 -246.685798) (xy 373.006396 -246.659149)
			(xy 372.964725 -246.625918) (xy 372.928473 -246.586847) (xy 372.898449 -246.54281) (xy 372.875323 -246.494789)
			(xy 372.859613 -246.443859) (xy 372.85167 -246.391155) (xy 372.62309 -246.391155) (xy 372.615147 -246.443859)
			(xy 372.599437 -246.494789) (xy 372.576311 -246.54281) (xy 372.546287 -246.586847) (xy 372.510035 -246.625918)
			(xy 372.468364 -246.659149) (xy 372.422206 -246.685798) (xy 372.372592 -246.70527) (xy 372.32063 -246.71713)
			(xy 372.26748 -246.721114) (xy 372.21433 -246.71713) (xy 372.162368 -246.70527) (xy 372.112754 -246.685798)
			(xy 372.066596 -246.659149) (xy 372.024925 -246.625918) (xy 371.988673 -246.586847) (xy 371.958649 -246.54281)
			(xy 371.935523 -246.494789) (xy 371.919813 -246.443859) (xy 371.91187 -246.391155) (xy 371.68329 -246.391155)
			(xy 371.675347 -246.443859) (xy 371.659637 -246.494789) (xy 371.636511 -246.54281) (xy 371.606487 -246.586847)
			(xy 371.570235 -246.625918) (xy 371.528564 -246.659149) (xy 371.482406 -246.685798) (xy 371.432792 -246.70527)
			(xy 371.38083 -246.71713) (xy 371.32768 -246.721114) (xy 371.27453 -246.71713) (xy 371.222568 -246.70527)
			(xy 371.172954 -246.685798) (xy 371.126796 -246.659149) (xy 371.085125 -246.625918) (xy 371.048873 -246.586847)
			(xy 371.018849 -246.54281) (xy 370.995723 -246.494789) (xy 370.980013 -246.443859) (xy 370.97207 -246.391155)
			(xy 370.743744 -246.391155) (xy 370.735801 -246.443859) (xy 370.720091 -246.494789) (xy 370.696965 -246.54281)
			(xy 370.666941 -246.586847) (xy 370.630689 -246.625918) (xy 370.589018 -246.659149) (xy 370.54286 -246.685798)
			(xy 370.493246 -246.70527) (xy 370.441284 -246.71713) (xy 370.388134 -246.721114) (xy 370.334984 -246.71713)
			(xy 370.283022 -246.70527) (xy 370.233408 -246.685798) (xy 370.18725 -246.659149) (xy 370.145579 -246.625918)
			(xy 370.109327 -246.586847) (xy 370.079303 -246.54281) (xy 370.056177 -246.494789) (xy 370.040467 -246.443859)
			(xy 370.032524 -246.391155) (xy 369.803944 -246.391155) (xy 369.796001 -246.443859) (xy 369.780291 -246.494789)
			(xy 369.757165 -246.54281) (xy 369.727141 -246.586847) (xy 369.690889 -246.625918) (xy 369.649218 -246.659149)
			(xy 369.60306 -246.685798) (xy 369.553446 -246.70527) (xy 369.501484 -246.71713) (xy 369.448334 -246.721114)
			(xy 369.395184 -246.71713) (xy 369.343222 -246.70527) (xy 369.293608 -246.685798) (xy 369.24745 -246.659149)
			(xy 369.205779 -246.625918) (xy 369.169527 -246.586847) (xy 369.139503 -246.54281) (xy 369.116377 -246.494789)
			(xy 369.100667 -246.443859) (xy 369.092724 -246.391155) (xy 366.78108 -246.391155) (xy 366.78108 -247.204971)
			(xy 369.562624 -247.204971) (xy 369.562624 -247.151673) (xy 369.570567 -247.098969) (xy 369.586277 -247.048039)
			(xy 369.609403 -247.000018) (xy 369.639427 -246.955981) (xy 369.675679 -246.91691) (xy 369.71735 -246.883679)
			(xy 369.763508 -246.85703) (xy 369.813122 -246.837558) (xy 369.865084 -246.825698) (xy 369.918234 -246.821715)
			(xy 369.971384 -246.825698) (xy 370.023346 -246.837558) (xy 370.07296 -246.85703) (xy 370.119118 -246.883679)
			(xy 370.160789 -246.91691) (xy 370.197041 -246.955981) (xy 370.227065 -247.000018) (xy 370.250191 -247.048039)
			(xy 370.265901 -247.098969) (xy 370.273844 -247.151673) (xy 370.274342 -247.178322) (xy 370.273844 -247.204971)
			(xy 370.502424 -247.204971) (xy 370.502424 -247.151673) (xy 370.510367 -247.098969) (xy 370.526077 -247.048039)
			(xy 370.549203 -247.000018) (xy 370.579227 -246.955981) (xy 370.615479 -246.91691) (xy 370.65715 -246.883679)
			(xy 370.703308 -246.85703) (xy 370.752922 -246.837558) (xy 370.804884 -246.825698) (xy 370.858034 -246.821715)
			(xy 370.911184 -246.825698) (xy 370.963146 -246.837558) (xy 371.01276 -246.85703) (xy 371.058918 -246.883679)
			(xy 371.100589 -246.91691) (xy 371.136841 -246.955981) (xy 371.166865 -247.000018) (xy 371.189991 -247.048039)
			(xy 371.205701 -247.098969) (xy 371.213644 -247.151673) (xy 371.214142 -247.178322) (xy 371.213644 -247.204971)
			(xy 371.442224 -247.204971) (xy 371.442224 -247.151673) (xy 371.450167 -247.098969) (xy 371.465877 -247.048039)
			(xy 371.489003 -247.000018) (xy 371.519027 -246.955981) (xy 371.555279 -246.91691) (xy 371.59695 -246.883679)
			(xy 371.643108 -246.85703) (xy 371.692722 -246.837558) (xy 371.744684 -246.825698) (xy 371.797834 -246.821715)
			(xy 371.850984 -246.825698) (xy 371.902946 -246.837558) (xy 371.95256 -246.85703) (xy 371.998718 -246.883679)
			(xy 372.040389 -246.91691) (xy 372.076641 -246.955981) (xy 372.106665 -247.000018) (xy 372.129791 -247.048039)
			(xy 372.145501 -247.098969) (xy 372.153444 -247.151673) (xy 372.153942 -247.178322) (xy 372.153444 -247.204971)
			(xy 372.382024 -247.204971) (xy 372.382024 -247.151673) (xy 372.389967 -247.098969) (xy 372.405677 -247.048039)
			(xy 372.428803 -247.000018) (xy 372.458827 -246.955981) (xy 372.495079 -246.91691) (xy 372.53675 -246.883679)
			(xy 372.582908 -246.85703) (xy 372.632522 -246.837558) (xy 372.684484 -246.825698) (xy 372.737634 -246.821715)
			(xy 372.790784 -246.825698) (xy 372.842746 -246.837558) (xy 372.89236 -246.85703) (xy 372.938518 -246.883679)
			(xy 372.980189 -246.91691) (xy 373.016441 -246.955981) (xy 373.046465 -247.000018) (xy 373.069591 -247.048039)
			(xy 373.085301 -247.098969) (xy 373.093244 -247.151673) (xy 373.093742 -247.178322) (xy 373.093244 -247.204971)
			(xy 373.321824 -247.204971) (xy 373.321824 -247.151673) (xy 373.329767 -247.098969) (xy 373.345477 -247.048039)
			(xy 373.368603 -247.000018) (xy 373.398627 -246.955981) (xy 373.434879 -246.91691) (xy 373.47655 -246.883679)
			(xy 373.522708 -246.85703) (xy 373.572322 -246.837558) (xy 373.624284 -246.825698) (xy 373.677434 -246.821715)
			(xy 373.730584 -246.825698) (xy 373.782546 -246.837558) (xy 373.83216 -246.85703) (xy 373.878318 -246.883679)
			(xy 373.919989 -246.91691) (xy 373.956241 -246.955981) (xy 373.986265 -247.000018) (xy 374.009391 -247.048039)
			(xy 374.025101 -247.098969) (xy 374.033044 -247.151673) (xy 374.033542 -247.178322) (xy 374.033044 -247.204971)
			(xy 374.26137 -247.204971) (xy 374.26137 -247.151673) (xy 374.269313 -247.098969) (xy 374.285023 -247.048039)
			(xy 374.308149 -247.000018) (xy 374.338173 -246.955981) (xy 374.374425 -246.91691) (xy 374.416096 -246.883679)
			(xy 374.462254 -246.85703) (xy 374.511868 -246.837558) (xy 374.56383 -246.825698) (xy 374.61698 -246.821715)
			(xy 374.67013 -246.825698) (xy 374.722092 -246.837558) (xy 374.771706 -246.85703) (xy 374.817864 -246.883679)
			(xy 374.859535 -246.91691) (xy 374.895787 -246.955981) (xy 374.925811 -247.000018) (xy 374.948937 -247.048039)
			(xy 374.964647 -247.098969) (xy 374.97259 -247.151673) (xy 374.973088 -247.178322) (xy 374.97259 -247.204971)
			(xy 375.201424 -247.204971) (xy 375.201424 -247.151673) (xy 375.209367 -247.098969) (xy 375.225077 -247.048039)
			(xy 375.248203 -247.000018) (xy 375.278227 -246.955981) (xy 375.314479 -246.91691) (xy 375.35615 -246.883679)
			(xy 375.402308 -246.85703) (xy 375.451922 -246.837558) (xy 375.503884 -246.825698) (xy 375.557034 -246.821715)
			(xy 375.610184 -246.825698) (xy 375.662146 -246.837558) (xy 375.71176 -246.85703) (xy 375.757918 -246.883679)
			(xy 375.799589 -246.91691) (xy 375.835841 -246.955981) (xy 375.865865 -247.000018) (xy 375.888991 -247.048039)
			(xy 375.904701 -247.098969) (xy 375.912644 -247.151673) (xy 375.913142 -247.178322) (xy 375.912644 -247.204971)
			(xy 376.141224 -247.204971) (xy 376.141224 -247.151673) (xy 376.149167 -247.098969) (xy 376.164877 -247.048039)
			(xy 376.188003 -247.000018) (xy 376.218027 -246.955981) (xy 376.254279 -246.91691) (xy 376.29595 -246.883679)
			(xy 376.342108 -246.85703) (xy 376.391722 -246.837558) (xy 376.443684 -246.825698) (xy 376.496834 -246.821715)
			(xy 376.549984 -246.825698) (xy 376.601946 -246.837558) (xy 376.65156 -246.85703) (xy 376.697718 -246.883679)
			(xy 376.739389 -246.91691) (xy 376.775641 -246.955981) (xy 376.805665 -247.000018) (xy 376.828791 -247.048039)
			(xy 376.844501 -247.098969) (xy 376.852444 -247.151673) (xy 376.852942 -247.178322) (xy 376.852444 -247.204971)
			(xy 377.081024 -247.204971) (xy 377.081024 -247.151673) (xy 377.088967 -247.098969) (xy 377.104677 -247.048039)
			(xy 377.127803 -247.000018) (xy 377.157827 -246.955981) (xy 377.194079 -246.91691) (xy 377.23575 -246.883679)
			(xy 377.281908 -246.85703) (xy 377.331522 -246.837558) (xy 377.383484 -246.825698) (xy 377.436634 -246.821715)
			(xy 377.489784 -246.825698) (xy 377.541746 -246.837558) (xy 377.59136 -246.85703) (xy 377.637518 -246.883679)
			(xy 377.679189 -246.91691) (xy 377.715441 -246.955981) (xy 377.745465 -247.000018) (xy 377.768591 -247.048039)
			(xy 377.784301 -247.098969) (xy 377.792244 -247.151673) (xy 377.792742 -247.178322) (xy 377.792244 -247.204971)
			(xy 378.020824 -247.204971) (xy 378.020824 -247.151673) (xy 378.028767 -247.098969) (xy 378.044477 -247.048039)
			(xy 378.067603 -247.000018) (xy 378.097627 -246.955981) (xy 378.133879 -246.91691) (xy 378.17555 -246.883679)
			(xy 378.221708 -246.85703) (xy 378.271322 -246.837558) (xy 378.323284 -246.825698) (xy 378.376434 -246.821715)
			(xy 378.429584 -246.825698) (xy 378.481546 -246.837558) (xy 378.53116 -246.85703) (xy 378.577318 -246.883679)
			(xy 378.618989 -246.91691) (xy 378.655241 -246.955981) (xy 378.685265 -247.000018) (xy 378.708391 -247.048039)
			(xy 378.724101 -247.098969) (xy 378.732044 -247.151673) (xy 378.732542 -247.178322) (xy 378.732044 -247.204971)
			(xy 378.96037 -247.204971) (xy 378.96037 -247.151673) (xy 378.968313 -247.098969) (xy 378.984023 -247.048039)
			(xy 379.007149 -247.000018) (xy 379.037173 -246.955981) (xy 379.073425 -246.91691) (xy 379.115096 -246.883679)
			(xy 379.161254 -246.85703) (xy 379.210868 -246.837558) (xy 379.26283 -246.825698) (xy 379.31598 -246.821715)
			(xy 379.36913 -246.825698) (xy 379.421092 -246.837558) (xy 379.470706 -246.85703) (xy 379.516864 -246.883679)
			(xy 379.558535 -246.91691) (xy 379.594787 -246.955981) (xy 379.624811 -247.000018) (xy 379.647937 -247.048039)
			(xy 379.663647 -247.098969) (xy 379.67159 -247.151673) (xy 379.672088 -247.178322) (xy 379.67159 -247.204971)
			(xy 379.900424 -247.204971) (xy 379.900424 -247.151673) (xy 379.908367 -247.098969) (xy 379.924077 -247.048039)
			(xy 379.947203 -247.000018) (xy 379.977227 -246.955981) (xy 380.013479 -246.91691) (xy 380.05515 -246.883679)
			(xy 380.101308 -246.85703) (xy 380.150922 -246.837558) (xy 380.202884 -246.825698) (xy 380.256034 -246.821715)
			(xy 380.309184 -246.825698) (xy 380.361146 -246.837558) (xy 380.41076 -246.85703) (xy 380.456918 -246.883679)
			(xy 380.498589 -246.91691) (xy 380.534841 -246.955981) (xy 380.564865 -247.000018) (xy 380.587991 -247.048039)
			(xy 380.603701 -247.098969) (xy 380.611644 -247.151673) (xy 380.612142 -247.178322) (xy 380.611644 -247.204971)
			(xy 380.603701 -247.257675) (xy 380.587991 -247.308605) (xy 380.564865 -247.356626) (xy 380.534841 -247.400663)
			(xy 380.498589 -247.439734) (xy 380.456918 -247.472965) (xy 380.41076 -247.499614) (xy 380.361146 -247.519086)
			(xy 380.309184 -247.530946) (xy 380.256034 -247.53493) (xy 380.202884 -247.530946) (xy 380.150922 -247.519086)
			(xy 380.101308 -247.499614) (xy 380.05515 -247.472965) (xy 380.013479 -247.439734) (xy 379.977227 -247.400663)
			(xy 379.947203 -247.356626) (xy 379.924077 -247.308605) (xy 379.908367 -247.257675) (xy 379.900424 -247.204971)
			(xy 379.67159 -247.204971) (xy 379.663647 -247.257675) (xy 379.647937 -247.308605) (xy 379.624811 -247.356626)
			(xy 379.594787 -247.400663) (xy 379.558535 -247.439734) (xy 379.516864 -247.472965) (xy 379.470706 -247.499614)
			(xy 379.421092 -247.519086) (xy 379.36913 -247.530946) (xy 379.31598 -247.53493) (xy 379.26283 -247.530946)
			(xy 379.210868 -247.519086) (xy 379.161254 -247.499614) (xy 379.115096 -247.472965) (xy 379.073425 -247.439734)
			(xy 379.037173 -247.400663) (xy 379.007149 -247.356626) (xy 378.984023 -247.308605) (xy 378.968313 -247.257675)
			(xy 378.96037 -247.204971) (xy 378.732044 -247.204971) (xy 378.724101 -247.257675) (xy 378.708391 -247.308605)
			(xy 378.685265 -247.356626) (xy 378.655241 -247.400663) (xy 378.618989 -247.439734) (xy 378.577318 -247.472965)
			(xy 378.53116 -247.499614) (xy 378.481546 -247.519086) (xy 378.429584 -247.530946) (xy 378.376434 -247.53493)
			(xy 378.323284 -247.530946) (xy 378.271322 -247.519086) (xy 378.221708 -247.499614) (xy 378.17555 -247.472965)
			(xy 378.133879 -247.439734) (xy 378.097627 -247.400663) (xy 378.067603 -247.356626) (xy 378.044477 -247.308605)
			(xy 378.028767 -247.257675) (xy 378.020824 -247.204971) (xy 377.792244 -247.204971) (xy 377.784301 -247.257675)
			(xy 377.768591 -247.308605) (xy 377.745465 -247.356626) (xy 377.715441 -247.400663) (xy 377.679189 -247.439734)
			(xy 377.637518 -247.472965) (xy 377.59136 -247.499614) (xy 377.541746 -247.519086) (xy 377.489784 -247.530946)
			(xy 377.436634 -247.53493) (xy 377.383484 -247.530946) (xy 377.331522 -247.519086) (xy 377.281908 -247.499614)
			(xy 377.23575 -247.472965) (xy 377.194079 -247.439734) (xy 377.157827 -247.400663) (xy 377.127803 -247.356626)
			(xy 377.104677 -247.308605) (xy 377.088967 -247.257675) (xy 377.081024 -247.204971) (xy 376.852444 -247.204971)
			(xy 376.844501 -247.257675) (xy 376.828791 -247.308605) (xy 376.805665 -247.356626) (xy 376.775641 -247.400663)
			(xy 376.739389 -247.439734) (xy 376.697718 -247.472965) (xy 376.65156 -247.499614) (xy 376.601946 -247.519086)
			(xy 376.549984 -247.530946) (xy 376.496834 -247.53493) (xy 376.443684 -247.530946) (xy 376.391722 -247.519086)
			(xy 376.342108 -247.499614) (xy 376.29595 -247.472965) (xy 376.254279 -247.439734) (xy 376.218027 -247.400663)
			(xy 376.188003 -247.356626) (xy 376.164877 -247.308605) (xy 376.149167 -247.257675) (xy 376.141224 -247.204971)
			(xy 375.912644 -247.204971) (xy 375.904701 -247.257675) (xy 375.888991 -247.308605) (xy 375.865865 -247.356626)
			(xy 375.835841 -247.400663) (xy 375.799589 -247.439734) (xy 375.757918 -247.472965) (xy 375.71176 -247.499614)
			(xy 375.662146 -247.519086) (xy 375.610184 -247.530946) (xy 375.557034 -247.53493) (xy 375.503884 -247.530946)
			(xy 375.451922 -247.519086) (xy 375.402308 -247.499614) (xy 375.35615 -247.472965) (xy 375.314479 -247.439734)
			(xy 375.278227 -247.400663) (xy 375.248203 -247.356626) (xy 375.225077 -247.308605) (xy 375.209367 -247.257675)
			(xy 375.201424 -247.204971) (xy 374.97259 -247.204971) (xy 374.964647 -247.257675) (xy 374.948937 -247.308605)
			(xy 374.925811 -247.356626) (xy 374.895787 -247.400663) (xy 374.859535 -247.439734) (xy 374.817864 -247.472965)
			(xy 374.771706 -247.499614) (xy 374.722092 -247.519086) (xy 374.67013 -247.530946) (xy 374.61698 -247.53493)
			(xy 374.56383 -247.530946) (xy 374.511868 -247.519086) (xy 374.462254 -247.499614) (xy 374.416096 -247.472965)
			(xy 374.374425 -247.439734) (xy 374.338173 -247.400663) (xy 374.308149 -247.356626) (xy 374.285023 -247.308605)
			(xy 374.269313 -247.257675) (xy 374.26137 -247.204971) (xy 374.033044 -247.204971) (xy 374.025101 -247.257675)
			(xy 374.009391 -247.308605) (xy 373.986265 -247.356626) (xy 373.956241 -247.400663) (xy 373.919989 -247.439734)
			(xy 373.878318 -247.472965) (xy 373.83216 -247.499614) (xy 373.782546 -247.519086) (xy 373.730584 -247.530946)
			(xy 373.677434 -247.53493) (xy 373.624284 -247.530946) (xy 373.572322 -247.519086) (xy 373.522708 -247.499614)
			(xy 373.47655 -247.472965) (xy 373.434879 -247.439734) (xy 373.398627 -247.400663) (xy 373.368603 -247.356626)
			(xy 373.345477 -247.308605) (xy 373.329767 -247.257675) (xy 373.321824 -247.204971) (xy 373.093244 -247.204971)
			(xy 373.085301 -247.257675) (xy 373.069591 -247.308605) (xy 373.046465 -247.356626) (xy 373.016441 -247.400663)
			(xy 372.980189 -247.439734) (xy 372.938518 -247.472965) (xy 372.89236 -247.499614) (xy 372.842746 -247.519086)
			(xy 372.790784 -247.530946) (xy 372.737634 -247.53493) (xy 372.684484 -247.530946) (xy 372.632522 -247.519086)
			(xy 372.582908 -247.499614) (xy 372.53675 -247.472965) (xy 372.495079 -247.439734) (xy 372.458827 -247.400663)
			(xy 372.428803 -247.356626) (xy 372.405677 -247.308605) (xy 372.389967 -247.257675) (xy 372.382024 -247.204971)
			(xy 372.153444 -247.204971) (xy 372.145501 -247.257675) (xy 372.129791 -247.308605) (xy 372.106665 -247.356626)
			(xy 372.076641 -247.400663) (xy 372.040389 -247.439734) (xy 371.998718 -247.472965) (xy 371.95256 -247.499614)
			(xy 371.902946 -247.519086) (xy 371.850984 -247.530946) (xy 371.797834 -247.53493) (xy 371.744684 -247.530946)
			(xy 371.692722 -247.519086) (xy 371.643108 -247.499614) (xy 371.59695 -247.472965) (xy 371.555279 -247.439734)
			(xy 371.519027 -247.400663) (xy 371.489003 -247.356626) (xy 371.465877 -247.308605) (xy 371.450167 -247.257675)
			(xy 371.442224 -247.204971) (xy 371.213644 -247.204971) (xy 371.205701 -247.257675) (xy 371.189991 -247.308605)
			(xy 371.166865 -247.356626) (xy 371.136841 -247.400663) (xy 371.100589 -247.439734) (xy 371.058918 -247.472965)
			(xy 371.01276 -247.499614) (xy 370.963146 -247.519086) (xy 370.911184 -247.530946) (xy 370.858034 -247.53493)
			(xy 370.804884 -247.530946) (xy 370.752922 -247.519086) (xy 370.703308 -247.499614) (xy 370.65715 -247.472965)
			(xy 370.615479 -247.439734) (xy 370.579227 -247.400663) (xy 370.549203 -247.356626) (xy 370.526077 -247.308605)
			(xy 370.510367 -247.257675) (xy 370.502424 -247.204971) (xy 370.273844 -247.204971) (xy 370.265901 -247.257675)
			(xy 370.250191 -247.308605) (xy 370.227065 -247.356626) (xy 370.197041 -247.400663) (xy 370.160789 -247.439734)
			(xy 370.119118 -247.472965) (xy 370.07296 -247.499614) (xy 370.023346 -247.519086) (xy 369.971384 -247.530946)
			(xy 369.918234 -247.53493) (xy 369.865084 -247.530946) (xy 369.813122 -247.519086) (xy 369.763508 -247.499614)
			(xy 369.71735 -247.472965) (xy 369.675679 -247.439734) (xy 369.639427 -247.400663) (xy 369.609403 -247.356626)
			(xy 369.586277 -247.308605) (xy 369.570567 -247.257675) (xy 369.562624 -247.204971) (xy 366.78108 -247.204971)
			(xy 366.78108 -248.327926) (xy 368.536474 -248.327926) (xy 368.537036 -248.299942) (xy 368.545788 -248.244663)
			(xy 368.563079 -248.191434) (xy 368.588484 -248.141565) (xy 368.621378 -248.096284) (xy 368.660951 -248.056707)
			(xy 368.706227 -248.023807) (xy 368.756093 -247.998396) (xy 368.80932 -247.981098) (xy 368.864598 -247.97234)
			(xy 368.892582 -247.971818) (xy 368.914334 -247.972168) (xy 368.957509 -247.977513) (xy 368.978688 -247.982486)
			(xy 368.991775 -247.985376) (xy 369.018564 -247.984907) (xy 369.044307 -247.977481) (xy 369.06723 -247.963611)
			(xy 369.085752 -247.944251) (xy 369.098597 -247.920738) (xy 369.102132 -247.90781) (xy 369.108852 -247.882319)
			(xy 369.128744 -247.833502) (xy 369.155617 -247.788151) (xy 369.188882 -247.747258) (xy 369.227813 -247.711716)
			(xy 369.271559 -247.682302) (xy 369.319163 -247.65966) (xy 369.369585 -247.644283) (xy 369.421723 -247.636508)
			(xy 369.44808 -247.63603) (xy 369.474735 -247.636426) (xy 369.52745 -247.644369) (xy 369.578392 -247.66008)
			(xy 369.626423 -247.683208) (xy 369.670471 -247.713237) (xy 369.709551 -247.749496) (xy 369.74279 -247.791174)
			(xy 369.769446 -247.837342) (xy 369.788923 -247.886966) (xy 369.800786 -247.938939) (xy 369.80477 -247.9921)
			(xy 369.80277 -248.018787) (xy 370.03227 -248.018787) (xy 370.03227 -247.965489) (xy 370.040213 -247.912785)
			(xy 370.055923 -247.861855) (xy 370.079049 -247.813834) (xy 370.109073 -247.769797) (xy 370.145325 -247.730726)
			(xy 370.186996 -247.697495) (xy 370.233154 -247.670846) (xy 370.282768 -247.651374) (xy 370.33473 -247.639514)
			(xy 370.38788 -247.635531) (xy 370.44103 -247.639514) (xy 370.492992 -247.651374) (xy 370.542606 -247.670846)
			(xy 370.588764 -247.697495) (xy 370.630435 -247.730726) (xy 370.666687 -247.769797) (xy 370.696711 -247.813834)
			(xy 370.719837 -247.861855) (xy 370.735547 -247.912785) (xy 370.74349 -247.965489) (xy 370.743988 -247.992138)
			(xy 370.74349 -248.018787) (xy 370.97207 -248.018787) (xy 370.97207 -247.965489) (xy 370.980013 -247.912785)
			(xy 370.995723 -247.861855) (xy 371.018849 -247.813834) (xy 371.048873 -247.769797) (xy 371.085125 -247.730726)
			(xy 371.126796 -247.697495) (xy 371.172954 -247.670846) (xy 371.222568 -247.651374) (xy 371.27453 -247.639514)
			(xy 371.32768 -247.635531) (xy 371.38083 -247.639514) (xy 371.432792 -247.651374) (xy 371.482406 -247.670846)
			(xy 371.528564 -247.697495) (xy 371.570235 -247.730726) (xy 371.606487 -247.769797) (xy 371.636511 -247.813834)
			(xy 371.659637 -247.861855) (xy 371.675347 -247.912785) (xy 371.68329 -247.965489) (xy 371.683788 -247.992138)
			(xy 371.68329 -248.018787) (xy 371.91187 -248.018787) (xy 371.91187 -247.965489) (xy 371.919813 -247.912785)
			(xy 371.935523 -247.861855) (xy 371.958649 -247.813834) (xy 371.988673 -247.769797) (xy 372.024925 -247.730726)
			(xy 372.066596 -247.697495) (xy 372.112754 -247.670846) (xy 372.162368 -247.651374) (xy 372.21433 -247.639514)
			(xy 372.26748 -247.635531) (xy 372.32063 -247.639514) (xy 372.372592 -247.651374) (xy 372.422206 -247.670846)
			(xy 372.468364 -247.697495) (xy 372.510035 -247.730726) (xy 372.546287 -247.769797) (xy 372.576311 -247.813834)
			(xy 372.599437 -247.861855) (xy 372.615147 -247.912785) (xy 372.62309 -247.965489) (xy 372.623588 -247.992138)
			(xy 372.62309 -248.018787) (xy 372.85167 -248.018787) (xy 372.85167 -247.965489) (xy 372.859613 -247.912785)
			(xy 372.875323 -247.861855) (xy 372.898449 -247.813834) (xy 372.928473 -247.769797) (xy 372.964725 -247.730726)
			(xy 373.006396 -247.697495) (xy 373.052554 -247.670846) (xy 373.102168 -247.651374) (xy 373.15413 -247.639514)
			(xy 373.20728 -247.635531) (xy 373.26043 -247.639514) (xy 373.312392 -247.651374) (xy 373.362006 -247.670846)
			(xy 373.408164 -247.697495) (xy 373.449835 -247.730726) (xy 373.486087 -247.769797) (xy 373.516111 -247.813834)
			(xy 373.539237 -247.861855) (xy 373.554947 -247.912785) (xy 373.56289 -247.965489) (xy 373.563388 -247.992138)
			(xy 373.56289 -248.018787) (xy 373.791724 -248.018787) (xy 373.791724 -247.965489) (xy 373.799667 -247.912785)
			(xy 373.815377 -247.861855) (xy 373.838503 -247.813834) (xy 373.868527 -247.769797) (xy 373.904779 -247.730726)
			(xy 373.94645 -247.697495) (xy 373.992608 -247.670846) (xy 374.042222 -247.651374) (xy 374.094184 -247.639514)
			(xy 374.147334 -247.635531) (xy 374.200484 -247.639514) (xy 374.252446 -247.651374) (xy 374.30206 -247.670846)
			(xy 374.348218 -247.697495) (xy 374.389889 -247.730726) (xy 374.426141 -247.769797) (xy 374.456165 -247.813834)
			(xy 374.479291 -247.861855) (xy 374.495001 -247.912785) (xy 374.502944 -247.965489) (xy 374.503442 -247.992138)
			(xy 374.502944 -248.018787) (xy 374.73127 -248.018787) (xy 374.73127 -247.965489) (xy 374.739213 -247.912785)
			(xy 374.754923 -247.861855) (xy 374.778049 -247.813834) (xy 374.808073 -247.769797) (xy 374.844325 -247.730726)
			(xy 374.885996 -247.697495) (xy 374.932154 -247.670846) (xy 374.981768 -247.651374) (xy 375.03373 -247.639514)
			(xy 375.08688 -247.635531) (xy 375.14003 -247.639514) (xy 375.191992 -247.651374) (xy 375.241606 -247.670846)
			(xy 375.287764 -247.697495) (xy 375.329435 -247.730726) (xy 375.365687 -247.769797) (xy 375.395711 -247.813834)
			(xy 375.418837 -247.861855) (xy 375.434547 -247.912785) (xy 375.44249 -247.965489) (xy 375.442988 -247.992138)
			(xy 375.44249 -248.018787) (xy 375.67107 -248.018787) (xy 375.67107 -247.965489) (xy 375.679013 -247.912785)
			(xy 375.694723 -247.861855) (xy 375.717849 -247.813834) (xy 375.747873 -247.769797) (xy 375.784125 -247.730726)
			(xy 375.825796 -247.697495) (xy 375.871954 -247.670846) (xy 375.921568 -247.651374) (xy 375.97353 -247.639514)
			(xy 376.02668 -247.635531) (xy 376.07983 -247.639514) (xy 376.131792 -247.651374) (xy 376.181406 -247.670846)
			(xy 376.227564 -247.697495) (xy 376.269235 -247.730726) (xy 376.305487 -247.769797) (xy 376.335511 -247.813834)
			(xy 376.358637 -247.861855) (xy 376.374347 -247.912785) (xy 376.38229 -247.965489) (xy 376.382788 -247.992138)
			(xy 376.38229 -248.018787) (xy 376.61087 -248.018787) (xy 376.61087 -247.965489) (xy 376.618813 -247.912785)
			(xy 376.634523 -247.861855) (xy 376.657649 -247.813834) (xy 376.687673 -247.769797) (xy 376.723925 -247.730726)
			(xy 376.765596 -247.697495) (xy 376.811754 -247.670846) (xy 376.861368 -247.651374) (xy 376.91333 -247.639514)
			(xy 376.96648 -247.635531) (xy 377.01963 -247.639514) (xy 377.071592 -247.651374) (xy 377.121206 -247.670846)
			(xy 377.167364 -247.697495) (xy 377.209035 -247.730726) (xy 377.245287 -247.769797) (xy 377.275311 -247.813834)
			(xy 377.298437 -247.861855) (xy 377.314147 -247.912785) (xy 377.32209 -247.965489) (xy 377.322588 -247.992138)
			(xy 377.32209 -248.018787) (xy 377.55067 -248.018787) (xy 377.55067 -247.965489) (xy 377.558613 -247.912785)
			(xy 377.574323 -247.861855) (xy 377.597449 -247.813834) (xy 377.627473 -247.769797) (xy 377.663725 -247.730726)
			(xy 377.705396 -247.697495) (xy 377.751554 -247.670846) (xy 377.801168 -247.651374) (xy 377.85313 -247.639514)
			(xy 377.90628 -247.635531) (xy 377.95943 -247.639514) (xy 378.011392 -247.651374) (xy 378.061006 -247.670846)
			(xy 378.107164 -247.697495) (xy 378.148835 -247.730726) (xy 378.185087 -247.769797) (xy 378.215111 -247.813834)
			(xy 378.238237 -247.861855) (xy 378.253947 -247.912785) (xy 378.26189 -247.965489) (xy 378.262388 -247.992138)
			(xy 378.26189 -248.018787) (xy 378.490724 -248.018787) (xy 378.490724 -247.965489) (xy 378.498667 -247.912785)
			(xy 378.514377 -247.861855) (xy 378.537503 -247.813834) (xy 378.567527 -247.769797) (xy 378.603779 -247.730726)
			(xy 378.64545 -247.697495) (xy 378.691608 -247.670846) (xy 378.741222 -247.651374) (xy 378.793184 -247.639514)
			(xy 378.846334 -247.635531) (xy 378.899484 -247.639514) (xy 378.951446 -247.651374) (xy 379.00106 -247.670846)
			(xy 379.047218 -247.697495) (xy 379.088889 -247.730726) (xy 379.125141 -247.769797) (xy 379.155165 -247.813834)
			(xy 379.178291 -247.861855) (xy 379.194001 -247.912785) (xy 379.201944 -247.965489) (xy 379.202442 -247.992138)
			(xy 379.201944 -248.018787) (xy 379.43027 -248.018787) (xy 379.43027 -247.965489) (xy 379.438213 -247.912785)
			(xy 379.453923 -247.861855) (xy 379.477049 -247.813834) (xy 379.507073 -247.769797) (xy 379.543325 -247.730726)
			(xy 379.584996 -247.697495) (xy 379.631154 -247.670846) (xy 379.680768 -247.651374) (xy 379.73273 -247.639514)
			(xy 379.78588 -247.635531) (xy 379.83903 -247.639514) (xy 379.890992 -247.651374) (xy 379.940606 -247.670846)
			(xy 379.986764 -247.697495) (xy 380.028435 -247.730726) (xy 380.064687 -247.769797) (xy 380.094711 -247.813834)
			(xy 380.117837 -247.861855) (xy 380.133547 -247.912785) (xy 380.14149 -247.965489) (xy 380.141988 -247.992138)
			(xy 380.14149 -248.018787) (xy 380.133547 -248.071491) (xy 380.117837 -248.122421) (xy 380.094711 -248.170442)
			(xy 380.064687 -248.214479) (xy 380.028435 -248.25355) (xy 379.986764 -248.286781) (xy 379.940606 -248.31343)
			(xy 379.890992 -248.332902) (xy 379.83903 -248.344762) (xy 379.78588 -248.348746) (xy 379.73273 -248.344762)
			(xy 379.680768 -248.332902) (xy 379.631154 -248.31343) (xy 379.584996 -248.286781) (xy 379.543325 -248.25355)
			(xy 379.507073 -248.214479) (xy 379.477049 -248.170442) (xy 379.453923 -248.122421) (xy 379.438213 -248.071491)
			(xy 379.43027 -248.018787) (xy 379.201944 -248.018787) (xy 379.194001 -248.071491) (xy 379.178291 -248.122421)
			(xy 379.155165 -248.170442) (xy 379.125141 -248.214479) (xy 379.088889 -248.25355) (xy 379.047218 -248.286781)
			(xy 379.00106 -248.31343) (xy 378.951446 -248.332902) (xy 378.899484 -248.344762) (xy 378.846334 -248.348746)
			(xy 378.793184 -248.344762) (xy 378.741222 -248.332902) (xy 378.691608 -248.31343) (xy 378.64545 -248.286781)
			(xy 378.603779 -248.25355) (xy 378.567527 -248.214479) (xy 378.537503 -248.170442) (xy 378.514377 -248.122421)
			(xy 378.498667 -248.071491) (xy 378.490724 -248.018787) (xy 378.26189 -248.018787) (xy 378.253947 -248.071491)
			(xy 378.238237 -248.122421) (xy 378.215111 -248.170442) (xy 378.185087 -248.214479) (xy 378.148835 -248.25355)
			(xy 378.107164 -248.286781) (xy 378.061006 -248.31343) (xy 378.011392 -248.332902) (xy 377.95943 -248.344762)
			(xy 377.90628 -248.348746) (xy 377.85313 -248.344762) (xy 377.801168 -248.332902) (xy 377.751554 -248.31343)
			(xy 377.705396 -248.286781) (xy 377.663725 -248.25355) (xy 377.627473 -248.214479) (xy 377.597449 -248.170442)
			(xy 377.574323 -248.122421) (xy 377.558613 -248.071491) (xy 377.55067 -248.018787) (xy 377.32209 -248.018787)
			(xy 377.314147 -248.071491) (xy 377.298437 -248.122421) (xy 377.275311 -248.170442) (xy 377.245287 -248.214479)
			(xy 377.209035 -248.25355) (xy 377.167364 -248.286781) (xy 377.121206 -248.31343) (xy 377.071592 -248.332902)
			(xy 377.01963 -248.344762) (xy 376.96648 -248.348746) (xy 376.91333 -248.344762) (xy 376.861368 -248.332902)
			(xy 376.811754 -248.31343) (xy 376.765596 -248.286781) (xy 376.723925 -248.25355) (xy 376.687673 -248.214479)
			(xy 376.657649 -248.170442) (xy 376.634523 -248.122421) (xy 376.618813 -248.071491) (xy 376.61087 -248.018787)
			(xy 376.38229 -248.018787) (xy 376.374347 -248.071491) (xy 376.358637 -248.122421) (xy 376.335511 -248.170442)
			(xy 376.305487 -248.214479) (xy 376.269235 -248.25355) (xy 376.227564 -248.286781) (xy 376.181406 -248.31343)
			(xy 376.131792 -248.332902) (xy 376.07983 -248.344762) (xy 376.02668 -248.348746) (xy 375.97353 -248.344762)
			(xy 375.921568 -248.332902) (xy 375.871954 -248.31343) (xy 375.825796 -248.286781) (xy 375.784125 -248.25355)
			(xy 375.747873 -248.214479) (xy 375.717849 -248.170442) (xy 375.694723 -248.122421) (xy 375.679013 -248.071491)
			(xy 375.67107 -248.018787) (xy 375.44249 -248.018787) (xy 375.434547 -248.071491) (xy 375.418837 -248.122421)
			(xy 375.395711 -248.170442) (xy 375.365687 -248.214479) (xy 375.329435 -248.25355) (xy 375.287764 -248.286781)
			(xy 375.241606 -248.31343) (xy 375.191992 -248.332902) (xy 375.14003 -248.344762) (xy 375.08688 -248.348746)
			(xy 375.03373 -248.344762) (xy 374.981768 -248.332902) (xy 374.932154 -248.31343) (xy 374.885996 -248.286781)
			(xy 374.844325 -248.25355) (xy 374.808073 -248.214479) (xy 374.778049 -248.170442) (xy 374.754923 -248.122421)
			(xy 374.739213 -248.071491) (xy 374.73127 -248.018787) (xy 374.502944 -248.018787) (xy 374.495001 -248.071491)
			(xy 374.479291 -248.122421) (xy 374.456165 -248.170442) (xy 374.426141 -248.214479) (xy 374.389889 -248.25355)
			(xy 374.348218 -248.286781) (xy 374.30206 -248.31343) (xy 374.252446 -248.332902) (xy 374.200484 -248.344762)
			(xy 374.147334 -248.348746) (xy 374.094184 -248.344762) (xy 374.042222 -248.332902) (xy 373.992608 -248.31343)
			(xy 373.94645 -248.286781) (xy 373.904779 -248.25355) (xy 373.868527 -248.214479) (xy 373.838503 -248.170442)
			(xy 373.815377 -248.122421) (xy 373.799667 -248.071491) (xy 373.791724 -248.018787) (xy 373.56289 -248.018787)
			(xy 373.554947 -248.071491) (xy 373.539237 -248.122421) (xy 373.516111 -248.170442) (xy 373.486087 -248.214479)
			(xy 373.449835 -248.25355) (xy 373.408164 -248.286781) (xy 373.362006 -248.31343) (xy 373.312392 -248.332902)
			(xy 373.26043 -248.344762) (xy 373.20728 -248.348746) (xy 373.15413 -248.344762) (xy 373.102168 -248.332902)
			(xy 373.052554 -248.31343) (xy 373.006396 -248.286781) (xy 372.964725 -248.25355) (xy 372.928473 -248.214479)
			(xy 372.898449 -248.170442) (xy 372.875323 -248.122421) (xy 372.859613 -248.071491) (xy 372.85167 -248.018787)
			(xy 372.62309 -248.018787) (xy 372.615147 -248.071491) (xy 372.599437 -248.122421) (xy 372.576311 -248.170442)
			(xy 372.546287 -248.214479) (xy 372.510035 -248.25355) (xy 372.468364 -248.286781) (xy 372.422206 -248.31343)
			(xy 372.372592 -248.332902) (xy 372.32063 -248.344762) (xy 372.26748 -248.348746) (xy 372.21433 -248.344762)
			(xy 372.162368 -248.332902) (xy 372.112754 -248.31343) (xy 372.066596 -248.286781) (xy 372.024925 -248.25355)
			(xy 371.988673 -248.214479) (xy 371.958649 -248.170442) (xy 371.935523 -248.122421) (xy 371.919813 -248.071491)
			(xy 371.91187 -248.018787) (xy 371.68329 -248.018787) (xy 371.675347 -248.071491) (xy 371.659637 -248.122421)
			(xy 371.636511 -248.170442) (xy 371.606487 -248.214479) (xy 371.570235 -248.25355) (xy 371.528564 -248.286781)
			(xy 371.482406 -248.31343) (xy 371.432792 -248.332902) (xy 371.38083 -248.344762) (xy 371.32768 -248.348746)
			(xy 371.27453 -248.344762) (xy 371.222568 -248.332902) (xy 371.172954 -248.31343) (xy 371.126796 -248.286781)
			(xy 371.085125 -248.25355) (xy 371.048873 -248.214479) (xy 371.018849 -248.170442) (xy 370.995723 -248.122421)
			(xy 370.980013 -248.071491) (xy 370.97207 -248.018787) (xy 370.74349 -248.018787) (xy 370.735547 -248.071491)
			(xy 370.719837 -248.122421) (xy 370.696711 -248.170442) (xy 370.666687 -248.214479) (xy 370.630435 -248.25355)
			(xy 370.588764 -248.286781) (xy 370.542606 -248.31343) (xy 370.492992 -248.332902) (xy 370.44103 -248.344762)
			(xy 370.38788 -248.348746) (xy 370.33473 -248.344762) (xy 370.282768 -248.332902) (xy 370.233154 -248.31343)
			(xy 370.186996 -248.286781) (xy 370.145325 -248.25355) (xy 370.109073 -248.214479) (xy 370.079049 -248.170442)
			(xy 370.055923 -248.122421) (xy 370.040213 -248.071491) (xy 370.03227 -248.018787) (xy 369.80277 -248.018787)
			(xy 369.800786 -248.045261) (xy 369.788923 -248.097234) (xy 369.769446 -248.146858) (xy 369.74279 -248.193026)
			(xy 369.709551 -248.234704) (xy 369.670471 -248.270963) (xy 369.626423 -248.300992) (xy 369.578392 -248.32412)
			(xy 369.52745 -248.339831) (xy 369.474735 -248.347774) (xy 369.44808 -248.348246) (xy 369.426328 -248.347904)
			(xy 369.383152 -248.342554) (xy 369.361974 -248.337578) (xy 369.34887 -248.334782) (xy 369.322095 -248.335237)
			(xy 369.296361 -248.342646) (xy 369.273442 -248.356498) (xy 369.25492 -248.375839) (xy 369.24207 -248.399334)
			(xy 369.23853 -248.412254) (xy 369.23188 -248.43755) (xy 369.212216 -248.486016) (xy 369.185669 -248.53108)
			(xy 369.152809 -248.571772) (xy 369.114347 -248.607215) (xy 369.092988 -248.622312) (xy 369.081026 -248.631095)
			(xy 369.062355 -248.654143) (xy 369.051085 -248.68158) (xy 369.048165 -248.711098) (xy 369.053839 -248.740211)
			(xy 369.067632 -248.766471) (xy 369.088381 -248.787668) (xy 369.101116 -248.795286) (xy 369.124628 -248.808827)
			(xy 369.155785 -248.832857) (xy 369.562624 -248.832857) (xy 369.562624 -248.779559) (xy 369.570567 -248.726855)
			(xy 369.586277 -248.675925) (xy 369.609403 -248.627904) (xy 369.639427 -248.583867) (xy 369.675679 -248.544796)
			(xy 369.71735 -248.511565) (xy 369.763508 -248.484916) (xy 369.813122 -248.465444) (xy 369.865084 -248.453584)
			(xy 369.918234 -248.449601) (xy 369.971384 -248.453584) (xy 370.023346 -248.465444) (xy 370.07296 -248.484916)
			(xy 370.119118 -248.511565) (xy 370.160789 -248.544796) (xy 370.197041 -248.583867) (xy 370.227065 -248.627904)
			(xy 370.250191 -248.675925) (xy 370.265901 -248.726855) (xy 370.273844 -248.779559) (xy 370.274342 -248.806208)
			(xy 370.273844 -248.832857) (xy 370.50217 -248.832857) (xy 370.50217 -248.779559) (xy 370.510113 -248.726855)
			(xy 370.525823 -248.675925) (xy 370.548949 -248.627904) (xy 370.578973 -248.583867) (xy 370.615225 -248.544796)
			(xy 370.656896 -248.511565) (xy 370.703054 -248.484916) (xy 370.752668 -248.465444) (xy 370.80463 -248.453584)
			(xy 370.85778 -248.449601) (xy 370.91093 -248.453584) (xy 370.962892 -248.465444) (xy 371.012506 -248.484916)
			(xy 371.058664 -248.511565) (xy 371.100335 -248.544796) (xy 371.136587 -248.583867) (xy 371.166611 -248.627904)
			(xy 371.189737 -248.675925) (xy 371.205447 -248.726855) (xy 371.21339 -248.779559) (xy 371.213888 -248.806208)
			(xy 371.21339 -248.832857) (xy 371.442224 -248.832857) (xy 371.442224 -248.779559) (xy 371.450167 -248.726855)
			(xy 371.465877 -248.675925) (xy 371.489003 -248.627904) (xy 371.519027 -248.583867) (xy 371.555279 -248.544796)
			(xy 371.59695 -248.511565) (xy 371.643108 -248.484916) (xy 371.692722 -248.465444) (xy 371.744684 -248.453584)
			(xy 371.797834 -248.449601) (xy 371.850984 -248.453584) (xy 371.902946 -248.465444) (xy 371.95256 -248.484916)
			(xy 371.998718 -248.511565) (xy 372.040389 -248.544796) (xy 372.076641 -248.583867) (xy 372.106665 -248.627904)
			(xy 372.129791 -248.675925) (xy 372.145501 -248.726855) (xy 372.153444 -248.779559) (xy 372.153942 -248.806208)
			(xy 372.153444 -248.832857) (xy 372.382024 -248.832857) (xy 372.382024 -248.779559) (xy 372.389967 -248.726855)
			(xy 372.405677 -248.675925) (xy 372.428803 -248.627904) (xy 372.458827 -248.583867) (xy 372.495079 -248.544796)
			(xy 372.53675 -248.511565) (xy 372.582908 -248.484916) (xy 372.632522 -248.465444) (xy 372.684484 -248.453584)
			(xy 372.737634 -248.449601) (xy 372.790784 -248.453584) (xy 372.842746 -248.465444) (xy 372.89236 -248.484916)
			(xy 372.938518 -248.511565) (xy 372.980189 -248.544796) (xy 373.016441 -248.583867) (xy 373.046465 -248.627904)
			(xy 373.069591 -248.675925) (xy 373.085301 -248.726855) (xy 373.093244 -248.779559) (xy 373.093742 -248.806208)
			(xy 373.093244 -248.832857) (xy 373.321824 -248.832857) (xy 373.321824 -248.779559) (xy 373.329767 -248.726855)
			(xy 373.345477 -248.675925) (xy 373.368603 -248.627904) (xy 373.398627 -248.583867) (xy 373.434879 -248.544796)
			(xy 373.47655 -248.511565) (xy 373.522708 -248.484916) (xy 373.572322 -248.465444) (xy 373.624284 -248.453584)
			(xy 373.677434 -248.449601) (xy 373.730584 -248.453584) (xy 373.782546 -248.465444) (xy 373.83216 -248.484916)
			(xy 373.878318 -248.511565) (xy 373.919989 -248.544796) (xy 373.956241 -248.583867) (xy 373.986265 -248.627904)
			(xy 374.009391 -248.675925) (xy 374.025101 -248.726855) (xy 374.033044 -248.779559) (xy 374.033542 -248.806208)
			(xy 374.033044 -248.832857) (xy 374.261624 -248.832857) (xy 374.261624 -248.779559) (xy 374.269567 -248.726855)
			(xy 374.285277 -248.675925) (xy 374.308403 -248.627904) (xy 374.338427 -248.583867) (xy 374.374679 -248.544796)
			(xy 374.41635 -248.511565) (xy 374.462508 -248.484916) (xy 374.512122 -248.465444) (xy 374.564084 -248.453584)
			(xy 374.617234 -248.449601) (xy 374.670384 -248.453584) (xy 374.722346 -248.465444) (xy 374.77196 -248.484916)
			(xy 374.818118 -248.511565) (xy 374.859789 -248.544796) (xy 374.896041 -248.583867) (xy 374.926065 -248.627904)
			(xy 374.949191 -248.675925) (xy 374.964901 -248.726855) (xy 374.972844 -248.779559) (xy 374.973342 -248.806208)
			(xy 374.972844 -248.832857) (xy 375.201424 -248.832857) (xy 375.201424 -248.779559) (xy 375.209367 -248.726855)
			(xy 375.225077 -248.675925) (xy 375.248203 -248.627904) (xy 375.278227 -248.583867) (xy 375.314479 -248.544796)
			(xy 375.35615 -248.511565) (xy 375.402308 -248.484916) (xy 375.451922 -248.465444) (xy 375.503884 -248.453584)
			(xy 375.557034 -248.449601) (xy 375.610184 -248.453584) (xy 375.662146 -248.465444) (xy 375.71176 -248.484916)
			(xy 375.757918 -248.511565) (xy 375.799589 -248.544796) (xy 375.835841 -248.583867) (xy 375.865865 -248.627904)
			(xy 375.888991 -248.675925) (xy 375.904701 -248.726855) (xy 375.912644 -248.779559) (xy 375.913142 -248.806208)
			(xy 375.912644 -248.832857) (xy 376.141224 -248.832857) (xy 376.141224 -248.779559) (xy 376.149167 -248.726855)
			(xy 376.164877 -248.675925) (xy 376.188003 -248.627904) (xy 376.218027 -248.583867) (xy 376.254279 -248.544796)
			(xy 376.29595 -248.511565) (xy 376.342108 -248.484916) (xy 376.391722 -248.465444) (xy 376.443684 -248.453584)
			(xy 376.496834 -248.449601) (xy 376.549984 -248.453584) (xy 376.601946 -248.465444) (xy 376.65156 -248.484916)
			(xy 376.697718 -248.511565) (xy 376.739389 -248.544796) (xy 376.775641 -248.583867) (xy 376.805665 -248.627904)
			(xy 376.828791 -248.675925) (xy 376.844501 -248.726855) (xy 376.852444 -248.779559) (xy 376.852942 -248.806208)
			(xy 376.852444 -248.832857) (xy 377.08077 -248.832857) (xy 377.08077 -248.779559) (xy 377.088713 -248.726855)
			(xy 377.104423 -248.675925) (xy 377.127549 -248.627904) (xy 377.157573 -248.583867) (xy 377.193825 -248.544796)
			(xy 377.235496 -248.511565) (xy 377.281654 -248.484916) (xy 377.331268 -248.465444) (xy 377.38323 -248.453584)
			(xy 377.43638 -248.449601) (xy 377.48953 -248.453584) (xy 377.541492 -248.465444) (xy 377.591106 -248.484916)
			(xy 377.637264 -248.511565) (xy 377.678935 -248.544796) (xy 377.715187 -248.583867) (xy 377.745211 -248.627904)
			(xy 377.768337 -248.675925) (xy 377.784047 -248.726855) (xy 377.79199 -248.779559) (xy 377.792488 -248.806208)
			(xy 377.79199 -248.832857) (xy 378.020824 -248.832857) (xy 378.020824 -248.779559) (xy 378.028767 -248.726855)
			(xy 378.044477 -248.675925) (xy 378.067603 -248.627904) (xy 378.097627 -248.583867) (xy 378.133879 -248.544796)
			(xy 378.17555 -248.511565) (xy 378.221708 -248.484916) (xy 378.271322 -248.465444) (xy 378.323284 -248.453584)
			(xy 378.376434 -248.449601) (xy 378.429584 -248.453584) (xy 378.481546 -248.465444) (xy 378.53116 -248.484916)
			(xy 378.577318 -248.511565) (xy 378.618989 -248.544796) (xy 378.655241 -248.583867) (xy 378.685265 -248.627904)
			(xy 378.708391 -248.675925) (xy 378.724101 -248.726855) (xy 378.732044 -248.779559) (xy 378.732542 -248.806208)
			(xy 378.732044 -248.832857) (xy 378.960624 -248.832857) (xy 378.960624 -248.779559) (xy 378.968567 -248.726855)
			(xy 378.984277 -248.675925) (xy 379.007403 -248.627904) (xy 379.037427 -248.583867) (xy 379.073679 -248.544796)
			(xy 379.11535 -248.511565) (xy 379.161508 -248.484916) (xy 379.211122 -248.465444) (xy 379.263084 -248.453584)
			(xy 379.316234 -248.449601) (xy 379.369384 -248.453584) (xy 379.421346 -248.465444) (xy 379.47096 -248.484916)
			(xy 379.517118 -248.511565) (xy 379.558789 -248.544796) (xy 379.595041 -248.583867) (xy 379.625065 -248.627904)
			(xy 379.648191 -248.675925) (xy 379.663901 -248.726855) (xy 379.671844 -248.779559) (xy 379.672342 -248.806208)
			(xy 379.671844 -248.832857) (xy 379.900424 -248.832857) (xy 379.900424 -248.779559) (xy 379.908367 -248.726855)
			(xy 379.924077 -248.675925) (xy 379.947203 -248.627904) (xy 379.977227 -248.583867) (xy 380.013479 -248.544796)
			(xy 380.05515 -248.511565) (xy 380.101308 -248.484916) (xy 380.150922 -248.465444) (xy 380.202884 -248.453584)
			(xy 380.256034 -248.449601) (xy 380.309184 -248.453584) (xy 380.361146 -248.465444) (xy 380.41076 -248.484916)
			(xy 380.456918 -248.511565) (xy 380.498589 -248.544796) (xy 380.534841 -248.583867) (xy 380.564865 -248.627904)
			(xy 380.587991 -248.675925) (xy 380.603701 -248.726855) (xy 380.611644 -248.779559) (xy 380.612142 -248.806208)
			(xy 380.611644 -248.832857) (xy 380.603701 -248.885561) (xy 380.587991 -248.936491) (xy 380.564865 -248.984512)
			(xy 380.534841 -249.028549) (xy 380.498589 -249.06762) (xy 380.456918 -249.100851) (xy 380.41076 -249.1275)
			(xy 380.361146 -249.146972) (xy 380.309184 -249.158832) (xy 380.256034 -249.162816) (xy 380.202884 -249.158832)
			(xy 380.150922 -249.146972) (xy 380.101308 -249.1275) (xy 380.05515 -249.100851) (xy 380.013479 -249.06762)
			(xy 379.977227 -249.028549) (xy 379.947203 -248.984512) (xy 379.924077 -248.936491) (xy 379.908367 -248.885561)
			(xy 379.900424 -248.832857) (xy 379.671844 -248.832857) (xy 379.663901 -248.885561) (xy 379.648191 -248.936491)
			(xy 379.625065 -248.984512) (xy 379.595041 -249.028549) (xy 379.558789 -249.06762) (xy 379.517118 -249.100851)
			(xy 379.47096 -249.1275) (xy 379.421346 -249.146972) (xy 379.369384 -249.158832) (xy 379.316234 -249.162816)
			(xy 379.263084 -249.158832) (xy 379.211122 -249.146972) (xy 379.161508 -249.1275) (xy 379.11535 -249.100851)
			(xy 379.073679 -249.06762) (xy 379.037427 -249.028549) (xy 379.007403 -248.984512) (xy 378.984277 -248.936491)
			(xy 378.968567 -248.885561) (xy 378.960624 -248.832857) (xy 378.732044 -248.832857) (xy 378.724101 -248.885561)
			(xy 378.708391 -248.936491) (xy 378.685265 -248.984512) (xy 378.655241 -249.028549) (xy 378.618989 -249.06762)
			(xy 378.577318 -249.100851) (xy 378.53116 -249.1275) (xy 378.481546 -249.146972) (xy 378.429584 -249.158832)
			(xy 378.376434 -249.162816) (xy 378.323284 -249.158832) (xy 378.271322 -249.146972) (xy 378.221708 -249.1275)
			(xy 378.17555 -249.100851) (xy 378.133879 -249.06762) (xy 378.097627 -249.028549) (xy 378.067603 -248.984512)
			(xy 378.044477 -248.936491) (xy 378.028767 -248.885561) (xy 378.020824 -248.832857) (xy 377.79199 -248.832857)
			(xy 377.784047 -248.885561) (xy 377.768337 -248.936491) (xy 377.745211 -248.984512) (xy 377.715187 -249.028549)
			(xy 377.678935 -249.06762) (xy 377.637264 -249.100851) (xy 377.591106 -249.1275) (xy 377.541492 -249.146972)
			(xy 377.48953 -249.158832) (xy 377.43638 -249.162816) (xy 377.38323 -249.158832) (xy 377.331268 -249.146972)
			(xy 377.281654 -249.1275) (xy 377.235496 -249.100851) (xy 377.193825 -249.06762) (xy 377.157573 -249.028549)
			(xy 377.127549 -248.984512) (xy 377.104423 -248.936491) (xy 377.088713 -248.885561) (xy 377.08077 -248.832857)
			(xy 376.852444 -248.832857) (xy 376.844501 -248.885561) (xy 376.828791 -248.936491) (xy 376.805665 -248.984512)
			(xy 376.775641 -249.028549) (xy 376.739389 -249.06762) (xy 376.697718 -249.100851) (xy 376.65156 -249.1275)
			(xy 376.601946 -249.146972) (xy 376.549984 -249.158832) (xy 376.496834 -249.162816) (xy 376.443684 -249.158832)
			(xy 376.391722 -249.146972) (xy 376.342108 -249.1275) (xy 376.29595 -249.100851) (xy 376.254279 -249.06762)
			(xy 376.218027 -249.028549) (xy 376.188003 -248.984512) (xy 376.164877 -248.936491) (xy 376.149167 -248.885561)
			(xy 376.141224 -248.832857) (xy 375.912644 -248.832857) (xy 375.904701 -248.885561) (xy 375.888991 -248.936491)
			(xy 375.865865 -248.984512) (xy 375.835841 -249.028549) (xy 375.799589 -249.06762) (xy 375.757918 -249.100851)
			(xy 375.71176 -249.1275) (xy 375.662146 -249.146972) (xy 375.610184 -249.158832) (xy 375.557034 -249.162816)
			(xy 375.503884 -249.158832) (xy 375.451922 -249.146972) (xy 375.402308 -249.1275) (xy 375.35615 -249.100851)
			(xy 375.314479 -249.06762) (xy 375.278227 -249.028549) (xy 375.248203 -248.984512) (xy 375.225077 -248.936491)
			(xy 375.209367 -248.885561) (xy 375.201424 -248.832857) (xy 374.972844 -248.832857) (xy 374.964901 -248.885561)
			(xy 374.949191 -248.936491) (xy 374.926065 -248.984512) (xy 374.896041 -249.028549) (xy 374.859789 -249.06762)
			(xy 374.818118 -249.100851) (xy 374.77196 -249.1275) (xy 374.722346 -249.146972) (xy 374.670384 -249.158832)
			(xy 374.617234 -249.162816) (xy 374.564084 -249.158832) (xy 374.512122 -249.146972) (xy 374.462508 -249.1275)
			(xy 374.41635 -249.100851) (xy 374.374679 -249.06762) (xy 374.338427 -249.028549) (xy 374.308403 -248.984512)
			(xy 374.285277 -248.936491) (xy 374.269567 -248.885561) (xy 374.261624 -248.832857) (xy 374.033044 -248.832857)
			(xy 374.025101 -248.885561) (xy 374.009391 -248.936491) (xy 373.986265 -248.984512) (xy 373.956241 -249.028549)
			(xy 373.919989 -249.06762) (xy 373.878318 -249.100851) (xy 373.83216 -249.1275) (xy 373.782546 -249.146972)
			(xy 373.730584 -249.158832) (xy 373.677434 -249.162816) (xy 373.624284 -249.158832) (xy 373.572322 -249.146972)
			(xy 373.522708 -249.1275) (xy 373.47655 -249.100851) (xy 373.434879 -249.06762) (xy 373.398627 -249.028549)
			(xy 373.368603 -248.984512) (xy 373.345477 -248.936491) (xy 373.329767 -248.885561) (xy 373.321824 -248.832857)
			(xy 373.093244 -248.832857) (xy 373.085301 -248.885561) (xy 373.069591 -248.936491) (xy 373.046465 -248.984512)
			(xy 373.016441 -249.028549) (xy 372.980189 -249.06762) (xy 372.938518 -249.100851) (xy 372.89236 -249.1275)
			(xy 372.842746 -249.146972) (xy 372.790784 -249.158832) (xy 372.737634 -249.162816) (xy 372.684484 -249.158832)
			(xy 372.632522 -249.146972) (xy 372.582908 -249.1275) (xy 372.53675 -249.100851) (xy 372.495079 -249.06762)
			(xy 372.458827 -249.028549) (xy 372.428803 -248.984512) (xy 372.405677 -248.936491) (xy 372.389967 -248.885561)
			(xy 372.382024 -248.832857) (xy 372.153444 -248.832857) (xy 372.145501 -248.885561) (xy 372.129791 -248.936491)
			(xy 372.106665 -248.984512) (xy 372.076641 -249.028549) (xy 372.040389 -249.06762) (xy 371.998718 -249.100851)
			(xy 371.95256 -249.1275) (xy 371.902946 -249.146972) (xy 371.850984 -249.158832) (xy 371.797834 -249.162816)
			(xy 371.744684 -249.158832) (xy 371.692722 -249.146972) (xy 371.643108 -249.1275) (xy 371.59695 -249.100851)
			(xy 371.555279 -249.06762) (xy 371.519027 -249.028549) (xy 371.489003 -248.984512) (xy 371.465877 -248.936491)
			(xy 371.450167 -248.885561) (xy 371.442224 -248.832857) (xy 371.21339 -248.832857) (xy 371.205447 -248.885561)
			(xy 371.189737 -248.936491) (xy 371.166611 -248.984512) (xy 371.136587 -249.028549) (xy 371.100335 -249.06762)
			(xy 371.058664 -249.100851) (xy 371.012506 -249.1275) (xy 370.962892 -249.146972) (xy 370.91093 -249.158832)
			(xy 370.85778 -249.162816) (xy 370.80463 -249.158832) (xy 370.752668 -249.146972) (xy 370.703054 -249.1275)
			(xy 370.656896 -249.100851) (xy 370.615225 -249.06762) (xy 370.578973 -249.028549) (xy 370.548949 -248.984512)
			(xy 370.525823 -248.936491) (xy 370.510113 -248.885561) (xy 370.50217 -248.832857) (xy 370.273844 -248.832857)
			(xy 370.265901 -248.885561) (xy 370.250191 -248.936491) (xy 370.227065 -248.984512) (xy 370.197041 -249.028549)
			(xy 370.160789 -249.06762) (xy 370.119118 -249.100851) (xy 370.07296 -249.1275) (xy 370.023346 -249.146972)
			(xy 369.971384 -249.158832) (xy 369.918234 -249.162816) (xy 369.865084 -249.158832) (xy 369.813122 -249.146972)
			(xy 369.763508 -249.1275) (xy 369.71735 -249.100851) (xy 369.675679 -249.06762) (xy 369.639427 -249.028549)
			(xy 369.609403 -248.984512) (xy 369.586277 -248.936491) (xy 369.570567 -248.885561) (xy 369.562624 -248.832857)
			(xy 369.155785 -248.832857) (xy 369.167592 -248.841963) (xy 369.20503 -248.881234) (xy 369.236076 -248.925731)
			(xy 369.260011 -248.974424) (xy 369.276279 -249.026185) (xy 369.284506 -249.079815) (xy 369.285012 -249.106944)
			(xy 369.284919 -249.118662) (xy 369.283397 -249.142049) (xy 369.281964 -249.15368) (xy 369.280668 -249.16705)
			(xy 369.284168 -249.193667) (xy 369.294502 -249.218445) (xy 369.310951 -249.239661) (xy 369.332374 -249.255841)
			(xy 369.357281 -249.26586) (xy 369.38394 -249.269022) (xy 369.39728 -249.267472) (xy 369.409913 -249.265797)
			(xy 369.435337 -249.264014) (xy 369.44808 -249.263916) (xy 369.475162 -249.264376) (xy 369.528701 -249.272575)
			(xy 369.580381 -249.288786) (xy 369.62901 -249.312637) (xy 369.673467 -249.343576) (xy 369.712727 -249.380891)
			(xy 369.745883 -249.42372) (xy 369.772171 -249.471076) (xy 369.790985 -249.521866) (xy 369.801892 -249.57492)
			(xy 369.804638 -249.629014) (xy 369.802843 -249.646673) (xy 370.03227 -249.646673) (xy 370.03227 -249.593375)
			(xy 370.040213 -249.540671) (xy 370.055923 -249.489741) (xy 370.079049 -249.44172) (xy 370.109073 -249.397683)
			(xy 370.145325 -249.358612) (xy 370.186996 -249.325381) (xy 370.233154 -249.298732) (xy 370.282768 -249.27926)
			(xy 370.33473 -249.2674) (xy 370.38788 -249.263417) (xy 370.44103 -249.2674) (xy 370.492992 -249.27926)
			(xy 370.542606 -249.298732) (xy 370.588764 -249.325381) (xy 370.630435 -249.358612) (xy 370.666687 -249.397683)
			(xy 370.696711 -249.44172) (xy 370.719837 -249.489741) (xy 370.735547 -249.540671) (xy 370.74349 -249.593375)
			(xy 370.743988 -249.620024) (xy 370.74349 -249.646673) (xy 370.97207 -249.646673) (xy 370.97207 -249.593375)
			(xy 370.980013 -249.540671) (xy 370.995723 -249.489741) (xy 371.018849 -249.44172) (xy 371.048873 -249.397683)
			(xy 371.085125 -249.358612) (xy 371.126796 -249.325381) (xy 371.172954 -249.298732) (xy 371.222568 -249.27926)
			(xy 371.27453 -249.2674) (xy 371.32768 -249.263417) (xy 371.38083 -249.2674) (xy 371.432792 -249.27926)
			(xy 371.482406 -249.298732) (xy 371.528564 -249.325381) (xy 371.570235 -249.358612) (xy 371.606487 -249.397683)
			(xy 371.636511 -249.44172) (xy 371.659637 -249.489741) (xy 371.675347 -249.540671) (xy 371.68329 -249.593375)
			(xy 371.683788 -249.620024) (xy 371.68329 -249.646673) (xy 371.91187 -249.646673) (xy 371.91187 -249.593375)
			(xy 371.919813 -249.540671) (xy 371.935523 -249.489741) (xy 371.958649 -249.44172) (xy 371.988673 -249.397683)
			(xy 372.024925 -249.358612) (xy 372.066596 -249.325381) (xy 372.112754 -249.298732) (xy 372.162368 -249.27926)
			(xy 372.21433 -249.2674) (xy 372.26748 -249.263417) (xy 372.32063 -249.2674) (xy 372.372592 -249.27926)
			(xy 372.422206 -249.298732) (xy 372.468364 -249.325381) (xy 372.510035 -249.358612) (xy 372.546287 -249.397683)
			(xy 372.576311 -249.44172) (xy 372.599437 -249.489741) (xy 372.615147 -249.540671) (xy 372.62309 -249.593375)
			(xy 372.623588 -249.620024) (xy 372.62309 -249.646673) (xy 372.851924 -249.646673) (xy 372.851924 -249.593375)
			(xy 372.859867 -249.540671) (xy 372.875577 -249.489741) (xy 372.898703 -249.44172) (xy 372.928727 -249.397683)
			(xy 372.964979 -249.358612) (xy 373.00665 -249.325381) (xy 373.052808 -249.298732) (xy 373.102422 -249.27926)
			(xy 373.154384 -249.2674) (xy 373.207534 -249.263417) (xy 373.260684 -249.2674) (xy 373.312646 -249.27926)
			(xy 373.36226 -249.298732) (xy 373.408418 -249.325381) (xy 373.450089 -249.358612) (xy 373.486341 -249.397683)
			(xy 373.516365 -249.44172) (xy 373.539491 -249.489741) (xy 373.555201 -249.540671) (xy 373.563144 -249.593375)
			(xy 373.563642 -249.620024) (xy 373.563144 -249.646673) (xy 373.79147 -249.646673) (xy 373.79147 -249.593375)
			(xy 373.799413 -249.540671) (xy 373.815123 -249.489741) (xy 373.838249 -249.44172) (xy 373.868273 -249.397683)
			(xy 373.904525 -249.358612) (xy 373.946196 -249.325381) (xy 373.992354 -249.298732) (xy 374.041968 -249.27926)
			(xy 374.09393 -249.2674) (xy 374.14708 -249.263417) (xy 374.20023 -249.2674) (xy 374.252192 -249.27926)
			(xy 374.301806 -249.298732) (xy 374.347964 -249.325381) (xy 374.389635 -249.358612) (xy 374.425887 -249.397683)
			(xy 374.455911 -249.44172) (xy 374.479037 -249.489741) (xy 374.494747 -249.540671) (xy 374.50269 -249.593375)
			(xy 374.503188 -249.620024) (xy 374.50269 -249.646673) (xy 374.73127 -249.646673) (xy 374.73127 -249.593375)
			(xy 374.739213 -249.540671) (xy 374.754923 -249.489741) (xy 374.778049 -249.44172) (xy 374.808073 -249.397683)
			(xy 374.844325 -249.358612) (xy 374.885996 -249.325381) (xy 374.932154 -249.298732) (xy 374.981768 -249.27926)
			(xy 375.03373 -249.2674) (xy 375.08688 -249.263417) (xy 375.14003 -249.2674) (xy 375.191992 -249.27926)
			(xy 375.241606 -249.298732) (xy 375.287764 -249.325381) (xy 375.329435 -249.358612) (xy 375.365687 -249.397683)
			(xy 375.395711 -249.44172) (xy 375.418837 -249.489741) (xy 375.434547 -249.540671) (xy 375.44249 -249.593375)
			(xy 375.442988 -249.620024) (xy 375.44249 -249.646673) (xy 375.67107 -249.646673) (xy 375.67107 -249.593375)
			(xy 375.679013 -249.540671) (xy 375.694723 -249.489741) (xy 375.717849 -249.44172) (xy 375.747873 -249.397683)
			(xy 375.784125 -249.358612) (xy 375.825796 -249.325381) (xy 375.871954 -249.298732) (xy 375.921568 -249.27926)
			(xy 375.97353 -249.2674) (xy 376.02668 -249.263417) (xy 376.07983 -249.2674) (xy 376.131792 -249.27926)
			(xy 376.181406 -249.298732) (xy 376.227564 -249.325381) (xy 376.269235 -249.358612) (xy 376.305487 -249.397683)
			(xy 376.335511 -249.44172) (xy 376.358637 -249.489741) (xy 376.374347 -249.540671) (xy 376.38229 -249.593375)
			(xy 376.382788 -249.620024) (xy 376.38229 -249.646673) (xy 376.61087 -249.646673) (xy 376.61087 -249.593375)
			(xy 376.618813 -249.540671) (xy 376.634523 -249.489741) (xy 376.657649 -249.44172) (xy 376.687673 -249.397683)
			(xy 376.723925 -249.358612) (xy 376.765596 -249.325381) (xy 376.811754 -249.298732) (xy 376.861368 -249.27926)
			(xy 376.91333 -249.2674) (xy 376.96648 -249.263417) (xy 377.01963 -249.2674) (xy 377.071592 -249.27926)
			(xy 377.121206 -249.298732) (xy 377.167364 -249.325381) (xy 377.209035 -249.358612) (xy 377.245287 -249.397683)
			(xy 377.275311 -249.44172) (xy 377.298437 -249.489741) (xy 377.314147 -249.540671) (xy 377.32209 -249.593375)
			(xy 377.322588 -249.620024) (xy 377.32209 -249.646673) (xy 377.55067 -249.646673) (xy 377.55067 -249.593375)
			(xy 377.558613 -249.540671) (xy 377.574323 -249.489741) (xy 377.597449 -249.44172) (xy 377.627473 -249.397683)
			(xy 377.663725 -249.358612) (xy 377.705396 -249.325381) (xy 377.751554 -249.298732) (xy 377.801168 -249.27926)
			(xy 377.85313 -249.2674) (xy 377.90628 -249.263417) (xy 377.95943 -249.2674) (xy 378.011392 -249.27926)
			(xy 378.061006 -249.298732) (xy 378.107164 -249.325381) (xy 378.148835 -249.358612) (xy 378.185087 -249.397683)
			(xy 378.215111 -249.44172) (xy 378.238237 -249.489741) (xy 378.253947 -249.540671) (xy 378.26189 -249.593375)
			(xy 378.262388 -249.620024) (xy 378.26189 -249.646673) (xy 378.49047 -249.646673) (xy 378.49047 -249.593375)
			(xy 378.498413 -249.540671) (xy 378.514123 -249.489741) (xy 378.537249 -249.44172) (xy 378.567273 -249.397683)
			(xy 378.603525 -249.358612) (xy 378.645196 -249.325381) (xy 378.691354 -249.298732) (xy 378.740968 -249.27926)
			(xy 378.79293 -249.2674) (xy 378.84608 -249.263417) (xy 378.89923 -249.2674) (xy 378.951192 -249.27926)
			(xy 379.000806 -249.298732) (xy 379.046964 -249.325381) (xy 379.088635 -249.358612) (xy 379.124887 -249.397683)
			(xy 379.154911 -249.44172) (xy 379.178037 -249.489741) (xy 379.193747 -249.540671) (xy 379.20169 -249.593375)
			(xy 379.202188 -249.620024) (xy 379.20169 -249.646673) (xy 379.430524 -249.646673) (xy 379.430524 -249.593375)
			(xy 379.438467 -249.540671) (xy 379.454177 -249.489741) (xy 379.477303 -249.44172) (xy 379.507327 -249.397683)
			(xy 379.543579 -249.358612) (xy 379.58525 -249.325381) (xy 379.631408 -249.298732) (xy 379.681022 -249.27926)
			(xy 379.732984 -249.2674) (xy 379.786134 -249.263417) (xy 379.839284 -249.2674) (xy 379.891246 -249.27926)
			(xy 379.94086 -249.298732) (xy 379.987018 -249.325381) (xy 380.028689 -249.358612) (xy 380.064941 -249.397683)
			(xy 380.094965 -249.44172) (xy 380.118091 -249.489741) (xy 380.133801 -249.540671) (xy 380.141744 -249.593375)
			(xy 380.142242 -249.620024) (xy 380.141744 -249.646673) (xy 380.133801 -249.699377) (xy 380.118091 -249.750307)
			(xy 380.094965 -249.798328) (xy 380.064941 -249.842365) (xy 380.028689 -249.881436) (xy 379.987018 -249.914667)
			(xy 379.94086 -249.941316) (xy 379.891246 -249.960788) (xy 379.839284 -249.972648) (xy 379.786134 -249.976632)
			(xy 379.732984 -249.972648) (xy 379.681022 -249.960788) (xy 379.631408 -249.941316) (xy 379.58525 -249.914667)
			(xy 379.543579 -249.881436) (xy 379.507327 -249.842365) (xy 379.477303 -249.798328) (xy 379.454177 -249.750307)
			(xy 379.438467 -249.699377) (xy 379.430524 -249.646673) (xy 379.20169 -249.646673) (xy 379.193747 -249.699377)
			(xy 379.178037 -249.750307) (xy 379.154911 -249.798328) (xy 379.124887 -249.842365) (xy 379.088635 -249.881436)
			(xy 379.046964 -249.914667) (xy 379.000806 -249.941316) (xy 378.951192 -249.960788) (xy 378.89923 -249.972648)
			(xy 378.84608 -249.976632) (xy 378.79293 -249.972648) (xy 378.740968 -249.960788) (xy 378.691354 -249.941316)
			(xy 378.645196 -249.914667) (xy 378.603525 -249.881436) (xy 378.567273 -249.842365) (xy 378.537249 -249.798328)
			(xy 378.514123 -249.750307) (xy 378.498413 -249.699377) (xy 378.49047 -249.646673) (xy 378.26189 -249.646673)
			(xy 378.253947 -249.699377) (xy 378.238237 -249.750307) (xy 378.215111 -249.798328) (xy 378.185087 -249.842365)
			(xy 378.148835 -249.881436) (xy 378.107164 -249.914667) (xy 378.061006 -249.941316) (xy 378.011392 -249.960788)
			(xy 377.95943 -249.972648) (xy 377.90628 -249.976632) (xy 377.85313 -249.972648) (xy 377.801168 -249.960788)
			(xy 377.751554 -249.941316) (xy 377.705396 -249.914667) (xy 377.663725 -249.881436) (xy 377.627473 -249.842365)
			(xy 377.597449 -249.798328) (xy 377.574323 -249.750307) (xy 377.558613 -249.699377) (xy 377.55067 -249.646673)
			(xy 377.32209 -249.646673) (xy 377.314147 -249.699377) (xy 377.298437 -249.750307) (xy 377.275311 -249.798328)
			(xy 377.245287 -249.842365) (xy 377.209035 -249.881436) (xy 377.167364 -249.914667) (xy 377.121206 -249.941316)
			(xy 377.071592 -249.960788) (xy 377.01963 -249.972648) (xy 376.96648 -249.976632) (xy 376.91333 -249.972648)
			(xy 376.861368 -249.960788) (xy 376.811754 -249.941316) (xy 376.765596 -249.914667) (xy 376.723925 -249.881436)
			(xy 376.687673 -249.842365) (xy 376.657649 -249.798328) (xy 376.634523 -249.750307) (xy 376.618813 -249.699377)
			(xy 376.61087 -249.646673) (xy 376.38229 -249.646673) (xy 376.374347 -249.699377) (xy 376.358637 -249.750307)
			(xy 376.335511 -249.798328) (xy 376.305487 -249.842365) (xy 376.269235 -249.881436) (xy 376.227564 -249.914667)
			(xy 376.181406 -249.941316) (xy 376.131792 -249.960788) (xy 376.07983 -249.972648) (xy 376.02668 -249.976632)
			(xy 375.97353 -249.972648) (xy 375.921568 -249.960788) (xy 375.871954 -249.941316) (xy 375.825796 -249.914667)
			(xy 375.784125 -249.881436) (xy 375.747873 -249.842365) (xy 375.717849 -249.798328) (xy 375.694723 -249.750307)
			(xy 375.679013 -249.699377) (xy 375.67107 -249.646673) (xy 375.44249 -249.646673) (xy 375.434547 -249.699377)
			(xy 375.418837 -249.750307) (xy 375.395711 -249.798328) (xy 375.365687 -249.842365) (xy 375.329435 -249.881436)
			(xy 375.287764 -249.914667) (xy 375.241606 -249.941316) (xy 375.191992 -249.960788) (xy 375.14003 -249.972648)
			(xy 375.08688 -249.976632) (xy 375.03373 -249.972648) (xy 374.981768 -249.960788) (xy 374.932154 -249.941316)
			(xy 374.885996 -249.914667) (xy 374.844325 -249.881436) (xy 374.808073 -249.842365) (xy 374.778049 -249.798328)
			(xy 374.754923 -249.750307) (xy 374.739213 -249.699377) (xy 374.73127 -249.646673) (xy 374.50269 -249.646673)
			(xy 374.494747 -249.699377) (xy 374.479037 -249.750307) (xy 374.455911 -249.798328) (xy 374.425887 -249.842365)
			(xy 374.389635 -249.881436) (xy 374.347964 -249.914667) (xy 374.301806 -249.941316) (xy 374.252192 -249.960788)
			(xy 374.20023 -249.972648) (xy 374.14708 -249.976632) (xy 374.09393 -249.972648) (xy 374.041968 -249.960788)
			(xy 373.992354 -249.941316) (xy 373.946196 -249.914667) (xy 373.904525 -249.881436) (xy 373.868273 -249.842365)
			(xy 373.838249 -249.798328) (xy 373.815123 -249.750307) (xy 373.799413 -249.699377) (xy 373.79147 -249.646673)
			(xy 373.563144 -249.646673) (xy 373.555201 -249.699377) (xy 373.539491 -249.750307) (xy 373.516365 -249.798328)
			(xy 373.486341 -249.842365) (xy 373.450089 -249.881436) (xy 373.408418 -249.914667) (xy 373.36226 -249.941316)
			(xy 373.312646 -249.960788) (xy 373.260684 -249.972648) (xy 373.207534 -249.976632) (xy 373.154384 -249.972648)
			(xy 373.102422 -249.960788) (xy 373.052808 -249.941316) (xy 373.00665 -249.914667) (xy 372.964979 -249.881436)
			(xy 372.928727 -249.842365) (xy 372.898703 -249.798328) (xy 372.875577 -249.750307) (xy 372.859867 -249.699377)
			(xy 372.851924 -249.646673) (xy 372.62309 -249.646673) (xy 372.615147 -249.699377) (xy 372.599437 -249.750307)
			(xy 372.576311 -249.798328) (xy 372.546287 -249.842365) (xy 372.510035 -249.881436) (xy 372.468364 -249.914667)
			(xy 372.422206 -249.941316) (xy 372.372592 -249.960788) (xy 372.32063 -249.972648) (xy 372.26748 -249.976632)
			(xy 372.21433 -249.972648) (xy 372.162368 -249.960788) (xy 372.112754 -249.941316) (xy 372.066596 -249.914667)
			(xy 372.024925 -249.881436) (xy 371.988673 -249.842365) (xy 371.958649 -249.798328) (xy 371.935523 -249.750307)
			(xy 371.919813 -249.699377) (xy 371.91187 -249.646673) (xy 371.68329 -249.646673) (xy 371.675347 -249.699377)
			(xy 371.659637 -249.750307) (xy 371.636511 -249.798328) (xy 371.606487 -249.842365) (xy 371.570235 -249.881436)
			(xy 371.528564 -249.914667) (xy 371.482406 -249.941316) (xy 371.432792 -249.960788) (xy 371.38083 -249.972648)
			(xy 371.32768 -249.976632) (xy 371.27453 -249.972648) (xy 371.222568 -249.960788) (xy 371.172954 -249.941316)
			(xy 371.126796 -249.914667) (xy 371.085125 -249.881436) (xy 371.048873 -249.842365) (xy 371.018849 -249.798328)
			(xy 370.995723 -249.750307) (xy 370.980013 -249.699377) (xy 370.97207 -249.646673) (xy 370.74349 -249.646673)
			(xy 370.735547 -249.699377) (xy 370.719837 -249.750307) (xy 370.696711 -249.798328) (xy 370.666687 -249.842365)
			(xy 370.630435 -249.881436) (xy 370.588764 -249.914667) (xy 370.542606 -249.941316) (xy 370.492992 -249.960788)
			(xy 370.44103 -249.972648) (xy 370.38788 -249.976632) (xy 370.33473 -249.972648) (xy 370.282768 -249.960788)
			(xy 370.233154 -249.941316) (xy 370.186996 -249.914667) (xy 370.145325 -249.881436) (xy 370.109073 -249.842365)
			(xy 370.079049 -249.798328) (xy 370.055923 -249.750307) (xy 370.040213 -249.699377) (xy 370.03227 -249.646673)
			(xy 369.802843 -249.646673) (xy 369.799162 -249.682899) (xy 369.785589 -249.735334) (xy 369.764232 -249.785109)
			(xy 369.735585 -249.831076) (xy 369.700307 -249.872175) (xy 369.659212 -249.907458) (xy 369.613248 -249.936112)
			(xy 369.563476 -249.957474) (xy 369.511043 -249.971054) (xy 369.457158 -249.976537) (xy 369.403064 -249.973797)
			(xy 369.350008 -249.962898) (xy 369.299216 -249.94409) (xy 369.251856 -249.917807) (xy 369.209023 -249.884656)
			(xy 369.171704 -249.845402) (xy 369.140759 -249.800948) (xy 369.116903 -249.752322) (xy 369.100685 -249.700644)
			(xy 369.09248 -249.647106) (xy 369.091972 -249.620024) (xy 369.092062 -249.608306) (xy 369.093586 -249.584919)
			(xy 369.09502 -249.573288) (xy 369.096366 -249.559922) (xy 369.092858 -249.533299) (xy 369.082516 -249.508518)
			(xy 369.066058 -249.487301) (xy 369.044627 -249.471121) (xy 369.019713 -249.461104) (xy 368.993047 -249.457944)
			(xy 368.979704 -249.459496) (xy 368.967071 -249.461172) (xy 368.941647 -249.462954) (xy 368.928904 -249.463052)
			(xy 368.900923 -249.462456) (xy 368.84565 -249.453702) (xy 368.792427 -249.436411) (xy 368.742564 -249.411007)
			(xy 368.697288 -249.378117) (xy 368.657715 -249.338548) (xy 368.624818 -249.293277) (xy 368.599407 -249.243417)
			(xy 368.582109 -249.190196) (xy 368.573348 -249.134925) (xy 368.572796 -249.106944) (xy 368.573328 -249.078046)
			(xy 368.582656 -249.021009) (xy 368.601075 -248.966227) (xy 368.6281 -248.915139) (xy 368.663022 -248.869087)
			(xy 368.704924 -248.829281) (xy 368.728498 -248.812558) (xy 368.740492 -248.803815) (xy 368.759167 -248.780759)
			(xy 368.770437 -248.753312) (xy 368.773354 -248.723785) (xy 368.767673 -248.694664) (xy 368.753871 -248.668399)
			(xy 368.733111 -248.647201) (xy 368.72037 -248.639584) (xy 368.696841 -248.62607) (xy 368.653878 -248.592929)
			(xy 368.616441 -248.553653) (xy 368.585397 -248.509151) (xy 368.561466 -248.460454) (xy 368.5452 -248.408689)
			(xy 368.536978 -248.355056) (xy 368.536474 -248.327926) (xy 366.78108 -248.327926) (xy 366.78108 -248.478548)
			(xy 368.58448 -250.281948) (xy 368.58448 -250.461018) (xy 368.584994 -250.476274) (xy 368.594002 -250.505427)
			(xy 368.611211 -250.530623) (xy 368.635088 -250.54962) (xy 368.663508 -250.560726) (xy 368.693939 -250.562953)
			(xy 368.723672 -250.556101) (xy 368.737134 -250.548902) (xy 368.757606 -250.537435) (xy 368.800918 -250.519385)
			(xy 368.846225 -250.507176) (xy 368.892742 -250.501018) (xy 368.916204 -250.500642) (xy 368.944188 -250.501191)
			(xy 368.999468 -250.509946) (xy 369.052698 -250.527241) (xy 369.102567 -250.552648) (xy 369.147848 -250.585544)
			(xy 369.187427 -250.625117) (xy 369.220328 -250.670394) (xy 369.245742 -250.72026) (xy 369.263043 -250.773487)
			(xy 369.271805 -250.828766) (xy 369.272312 -250.85675) (xy 369.271889 -250.881418) (xy 369.265072 -250.930281)
			(xy 369.251575 -250.977735) (xy 369.231656 -251.022872) (xy 369.205698 -251.064827) (xy 369.19027 -251.08408)
			(xy 369.18165 -251.095209) (xy 369.170316 -251.120966) (xy 369.166447 -251.148839) (xy 369.170337 -251.176709)
			(xy 369.181691 -251.202456) (xy 369.19027 -251.21362) (xy 369.205706 -251.232868) (xy 369.231676 -251.274818)
			(xy 369.251598 -251.319955) (xy 369.265088 -251.367413) (xy 369.271889 -251.416281) (xy 369.272312 -251.44095)
			(xy 369.271759 -251.468931) (xy 369.262998 -251.524202) (xy 369.245699 -251.577423) (xy 369.220288 -251.627282)
			(xy 369.187392 -251.672553) (xy 369.147818 -251.712121) (xy 369.102543 -251.745013) (xy 369.05268 -251.770417)
			(xy 368.999457 -251.787709) (xy 368.944185 -251.796463) (xy 368.916204 -251.797058) (xy 368.892742 -251.796685)
			(xy 368.846225 -251.790527) (xy 368.800918 -251.778317) (xy 368.757605 -251.760267) (xy 368.737134 -251.748798)
			(xy 368.723686 -251.741574) (xy 368.693952 -251.734713) (xy 368.663519 -251.736937) (xy 368.635099 -251.748048)
			(xy 368.611226 -251.767055) (xy 368.59403 -251.792263) (xy 368.585044 -251.821424) (xy 368.58448 -251.836682)
			(xy 368.58448 -252.213618) (xy 368.584994 -252.228874) (xy 368.594002 -252.258027) (xy 368.611211 -252.283223)
			(xy 368.635088 -252.30222) (xy 368.663508 -252.313326) (xy 368.693939 -252.315553) (xy 368.723672 -252.308701)
			(xy 368.737134 -252.301502) (xy 368.757606 -252.290035) (xy 368.800918 -252.271985) (xy 368.846225 -252.259776)
			(xy 368.892742 -252.253618) (xy 368.916204 -252.253242) (xy 368.944188 -252.253791) (xy 368.999468 -252.262546)
			(xy 369.052698 -252.279841) (xy 369.102567 -252.305248) (xy 369.147848 -252.338144) (xy 369.187427 -252.377717)
			(xy 369.220328 -252.422994) (xy 369.245742 -252.47286) (xy 369.263043 -252.526087) (xy 369.271805 -252.581366)
			(xy 369.272312 -252.60935) (xy 369.271889 -252.634018) (xy 369.265072 -252.682881) (xy 369.251575 -252.730335)
			(xy 369.231656 -252.775472) (xy 369.205698 -252.817427) (xy 369.19027 -252.83668) (xy 369.18165 -252.847809)
			(xy 369.170316 -252.873566) (xy 369.166447 -252.901439) (xy 369.170337 -252.929309) (xy 369.181691 -252.955056)
			(xy 369.19027 -252.96622) (xy 369.205706 -252.985468) (xy 369.231676 -253.027418) (xy 369.251598 -253.072555)
			(xy 369.265088 -253.120013) (xy 369.271889 -253.168881) (xy 369.272312 -253.19355) (xy 369.271759 -253.221531)
			(xy 369.262998 -253.276802) (xy 369.245699 -253.330023) (xy 369.220288 -253.379882) (xy 369.187392 -253.425153)
			(xy 369.147818 -253.464721) (xy 369.102543 -253.497613) (xy 369.05268 -253.523017) (xy 368.999457 -253.540309)
			(xy 368.944185 -253.549063) (xy 368.916204 -253.549658) (xy 368.892742 -253.549285) (xy 368.846225 -253.543127)
			(xy 368.800918 -253.530917) (xy 368.757605 -253.512867) (xy 368.737134 -253.501398) (xy 368.723686 -253.494174)
			(xy 368.693952 -253.487313) (xy 368.663519 -253.489537) (xy 368.635099 -253.500648) (xy 368.611226 -253.519655)
			(xy 368.59403 -253.544863) (xy 368.585044 -253.574024) (xy 368.58448 -253.589282) (xy 368.58448 -253.946385)
			(xy 369.672606 -253.946385) (xy 369.672606 -253.893087) (xy 369.680549 -253.840383) (xy 369.696259 -253.789453)
			(xy 369.719385 -253.741432) (xy 369.749409 -253.697395) (xy 369.785661 -253.658324) (xy 369.827332 -253.625093)
			(xy 369.87349 -253.598444) (xy 369.923104 -253.578972) (xy 369.975066 -253.567112) (xy 370.028216 -253.563129)
			(xy 370.081366 -253.567112) (xy 370.133328 -253.578972) (xy 370.182942 -253.598444) (xy 370.2291 -253.625093)
			(xy 370.270771 -253.658324) (xy 370.307023 -253.697395) (xy 370.337047 -253.741432) (xy 370.360173 -253.789453)
			(xy 370.375883 -253.840383) (xy 370.383826 -253.893087) (xy 370.384324 -253.919736) (xy 370.383826 -253.946385)
			(xy 370.612152 -253.946385) (xy 370.612152 -253.893087) (xy 370.620095 -253.840383) (xy 370.635805 -253.789453)
			(xy 370.658931 -253.741432) (xy 370.688955 -253.697395) (xy 370.725207 -253.658324) (xy 370.766878 -253.625093)
			(xy 370.813036 -253.598444) (xy 370.86265 -253.578972) (xy 370.914612 -253.567112) (xy 370.967762 -253.563129)
			(xy 371.020912 -253.567112) (xy 371.072874 -253.578972) (xy 371.122488 -253.598444) (xy 371.168646 -253.625093)
			(xy 371.210317 -253.658324) (xy 371.246569 -253.697395) (xy 371.276593 -253.741432) (xy 371.299719 -253.789453)
			(xy 371.315429 -253.840383) (xy 371.323372 -253.893087) (xy 371.32387 -253.919736) (xy 371.323372 -253.946385)
			(xy 371.552206 -253.946385) (xy 371.552206 -253.893087) (xy 371.560149 -253.840383) (xy 371.575859 -253.789453)
			(xy 371.598985 -253.741432) (xy 371.629009 -253.697395) (xy 371.665261 -253.658324) (xy 371.706932 -253.625093)
			(xy 371.75309 -253.598444) (xy 371.802704 -253.578972) (xy 371.854666 -253.567112) (xy 371.907816 -253.563129)
			(xy 371.960966 -253.567112) (xy 372.012928 -253.578972) (xy 372.062542 -253.598444) (xy 372.1087 -253.625093)
			(xy 372.150371 -253.658324) (xy 372.186623 -253.697395) (xy 372.216647 -253.741432) (xy 372.239773 -253.789453)
			(xy 372.255483 -253.840383) (xy 372.263426 -253.893087) (xy 372.263924 -253.919736) (xy 372.263426 -253.946385)
			(xy 372.492006 -253.946385) (xy 372.492006 -253.893087) (xy 372.499949 -253.840383) (xy 372.515659 -253.789453)
			(xy 372.538785 -253.741432) (xy 372.568809 -253.697395) (xy 372.605061 -253.658324) (xy 372.646732 -253.625093)
			(xy 372.69289 -253.598444) (xy 372.742504 -253.578972) (xy 372.794466 -253.567112) (xy 372.847616 -253.563129)
			(xy 372.900766 -253.567112) (xy 372.952728 -253.578972) (xy 373.002342 -253.598444) (xy 373.0485 -253.625093)
			(xy 373.090171 -253.658324) (xy 373.126423 -253.697395) (xy 373.156447 -253.741432) (xy 373.179573 -253.789453)
			(xy 373.195283 -253.840383) (xy 373.203226 -253.893087) (xy 373.203724 -253.919736) (xy 373.203226 -253.946385)
			(xy 373.431806 -253.946385) (xy 373.431806 -253.893087) (xy 373.439749 -253.840383) (xy 373.455459 -253.789453)
			(xy 373.478585 -253.741432) (xy 373.508609 -253.697395) (xy 373.544861 -253.658324) (xy 373.586532 -253.625093)
			(xy 373.63269 -253.598444) (xy 373.682304 -253.578972) (xy 373.734266 -253.567112) (xy 373.787416 -253.563129)
			(xy 373.840566 -253.567112) (xy 373.892528 -253.578972) (xy 373.942142 -253.598444) (xy 373.9883 -253.625093)
			(xy 374.029971 -253.658324) (xy 374.066223 -253.697395) (xy 374.096247 -253.741432) (xy 374.119373 -253.789453)
			(xy 374.135083 -253.840383) (xy 374.143026 -253.893087) (xy 374.143524 -253.919736) (xy 374.143026 -253.946385)
			(xy 374.371606 -253.946385) (xy 374.371606 -253.893087) (xy 374.379549 -253.840383) (xy 374.395259 -253.789453)
			(xy 374.418385 -253.741432) (xy 374.448409 -253.697395) (xy 374.484661 -253.658324) (xy 374.526332 -253.625093)
			(xy 374.57249 -253.598444) (xy 374.622104 -253.578972) (xy 374.674066 -253.567112) (xy 374.727216 -253.563129)
			(xy 374.780366 -253.567112) (xy 374.832328 -253.578972) (xy 374.881942 -253.598444) (xy 374.9281 -253.625093)
			(xy 374.969771 -253.658324) (xy 375.006023 -253.697395) (xy 375.036047 -253.741432) (xy 375.059173 -253.789453)
			(xy 375.074883 -253.840383) (xy 375.082826 -253.893087) (xy 375.083324 -253.919736) (xy 375.082826 -253.946385)
			(xy 375.311406 -253.946385) (xy 375.311406 -253.893087) (xy 375.319349 -253.840383) (xy 375.335059 -253.789453)
			(xy 375.358185 -253.741432) (xy 375.388209 -253.697395) (xy 375.424461 -253.658324) (xy 375.466132 -253.625093)
			(xy 375.51229 -253.598444) (xy 375.561904 -253.578972) (xy 375.613866 -253.567112) (xy 375.667016 -253.563129)
			(xy 375.720166 -253.567112) (xy 375.772128 -253.578972) (xy 375.821742 -253.598444) (xy 375.8679 -253.625093)
			(xy 375.909571 -253.658324) (xy 375.945823 -253.697395) (xy 375.975847 -253.741432) (xy 375.998973 -253.789453)
			(xy 376.014683 -253.840383) (xy 376.022626 -253.893087) (xy 376.023124 -253.919736) (xy 376.022626 -253.946385)
			(xy 376.250952 -253.946385) (xy 376.250952 -253.893087) (xy 376.258895 -253.840383) (xy 376.274605 -253.789453)
			(xy 376.297731 -253.741432) (xy 376.327755 -253.697395) (xy 376.364007 -253.658324) (xy 376.405678 -253.625093)
			(xy 376.451836 -253.598444) (xy 376.50145 -253.578972) (xy 376.553412 -253.567112) (xy 376.606562 -253.563129)
			(xy 376.659712 -253.567112) (xy 376.711674 -253.578972) (xy 376.761288 -253.598444) (xy 376.807446 -253.625093)
			(xy 376.849117 -253.658324) (xy 376.885369 -253.697395) (xy 376.915393 -253.741432) (xy 376.938519 -253.789453)
			(xy 376.954229 -253.840383) (xy 376.962172 -253.893087) (xy 376.96267 -253.919736) (xy 376.962172 -253.946385)
			(xy 377.190752 -253.946385) (xy 377.190752 -253.893087) (xy 377.198695 -253.840383) (xy 377.214405 -253.789453)
			(xy 377.237531 -253.741432) (xy 377.267555 -253.697395) (xy 377.303807 -253.658324) (xy 377.345478 -253.625093)
			(xy 377.391636 -253.598444) (xy 377.44125 -253.578972) (xy 377.493212 -253.567112) (xy 377.546362 -253.563129)
			(xy 377.599512 -253.567112) (xy 377.651474 -253.578972) (xy 377.701088 -253.598444) (xy 377.747246 -253.625093)
			(xy 377.788917 -253.658324) (xy 377.825169 -253.697395) (xy 377.855193 -253.741432) (xy 377.878319 -253.789453)
			(xy 377.894029 -253.840383) (xy 377.901972 -253.893087) (xy 377.90247 -253.919736) (xy 377.901972 -253.946385)
			(xy 378.130806 -253.946385) (xy 378.130806 -253.893087) (xy 378.138749 -253.840383) (xy 378.154459 -253.789453)
			(xy 378.177585 -253.741432) (xy 378.207609 -253.697395) (xy 378.243861 -253.658324) (xy 378.285532 -253.625093)
			(xy 378.33169 -253.598444) (xy 378.381304 -253.578972) (xy 378.433266 -253.567112) (xy 378.486416 -253.563129)
			(xy 378.539566 -253.567112) (xy 378.591528 -253.578972) (xy 378.641142 -253.598444) (xy 378.6873 -253.625093)
			(xy 378.728971 -253.658324) (xy 378.765223 -253.697395) (xy 378.795247 -253.741432) (xy 378.818373 -253.789453)
			(xy 378.834083 -253.840383) (xy 378.842026 -253.893087) (xy 378.842524 -253.919736) (xy 378.842026 -253.946385)
			(xy 379.070352 -253.946385) (xy 379.070352 -253.893087) (xy 379.078295 -253.840383) (xy 379.094005 -253.789453)
			(xy 379.117131 -253.741432) (xy 379.147155 -253.697395) (xy 379.183407 -253.658324) (xy 379.225078 -253.625093)
			(xy 379.271236 -253.598444) (xy 379.32085 -253.578972) (xy 379.372812 -253.567112) (xy 379.425962 -253.563129)
			(xy 379.479112 -253.567112) (xy 379.531074 -253.578972) (xy 379.580688 -253.598444) (xy 379.626846 -253.625093)
			(xy 379.668517 -253.658324) (xy 379.704769 -253.697395) (xy 379.734793 -253.741432) (xy 379.757919 -253.789453)
			(xy 379.773629 -253.840383) (xy 379.781572 -253.893087) (xy 379.78207 -253.919736) (xy 379.781572 -253.946385)
			(xy 380.010152 -253.946385) (xy 380.010152 -253.893087) (xy 380.018095 -253.840383) (xy 380.033805 -253.789453)
			(xy 380.056931 -253.741432) (xy 380.086955 -253.697395) (xy 380.123207 -253.658324) (xy 380.164878 -253.625093)
			(xy 380.211036 -253.598444) (xy 380.26065 -253.578972) (xy 380.312612 -253.567112) (xy 380.365762 -253.563129)
			(xy 380.418912 -253.567112) (xy 380.470874 -253.578972) (xy 380.520488 -253.598444) (xy 380.566646 -253.625093)
			(xy 380.608317 -253.658324) (xy 380.644569 -253.697395) (xy 380.674593 -253.741432) (xy 380.697719 -253.789453)
			(xy 380.713429 -253.840383) (xy 380.721372 -253.893087) (xy 380.72187 -253.919736) (xy 380.721372 -253.946385)
			(xy 380.713429 -253.999089) (xy 380.697719 -254.050019) (xy 380.674593 -254.09804) (xy 380.644569 -254.142077)
			(xy 380.608317 -254.181148) (xy 380.566646 -254.214379) (xy 380.520488 -254.241028) (xy 380.470874 -254.2605)
			(xy 380.418912 -254.27236) (xy 380.365762 -254.276344) (xy 380.312612 -254.27236) (xy 380.26065 -254.2605)
			(xy 380.211036 -254.241028) (xy 380.164878 -254.214379) (xy 380.123207 -254.181148) (xy 380.086955 -254.142077)
			(xy 380.056931 -254.09804) (xy 380.033805 -254.050019) (xy 380.018095 -253.999089) (xy 380.010152 -253.946385)
			(xy 379.781572 -253.946385) (xy 379.773629 -253.999089) (xy 379.757919 -254.050019) (xy 379.734793 -254.09804)
			(xy 379.704769 -254.142077) (xy 379.668517 -254.181148) (xy 379.626846 -254.214379) (xy 379.580688 -254.241028)
			(xy 379.531074 -254.2605) (xy 379.479112 -254.27236) (xy 379.425962 -254.276344) (xy 379.372812 -254.27236)
			(xy 379.32085 -254.2605) (xy 379.271236 -254.241028) (xy 379.225078 -254.214379) (xy 379.183407 -254.181148)
			(xy 379.147155 -254.142077) (xy 379.117131 -254.09804) (xy 379.094005 -254.050019) (xy 379.078295 -253.999089)
			(xy 379.070352 -253.946385) (xy 378.842026 -253.946385) (xy 378.834083 -253.999089) (xy 378.818373 -254.050019)
			(xy 378.795247 -254.09804) (xy 378.765223 -254.142077) (xy 378.728971 -254.181148) (xy 378.6873 -254.214379)
			(xy 378.641142 -254.241028) (xy 378.591528 -254.2605) (xy 378.539566 -254.27236) (xy 378.486416 -254.276344)
			(xy 378.433266 -254.27236) (xy 378.381304 -254.2605) (xy 378.33169 -254.241028) (xy 378.285532 -254.214379)
			(xy 378.243861 -254.181148) (xy 378.207609 -254.142077) (xy 378.177585 -254.09804) (xy 378.154459 -254.050019)
			(xy 378.138749 -253.999089) (xy 378.130806 -253.946385) (xy 377.901972 -253.946385) (xy 377.894029 -253.999089)
			(xy 377.878319 -254.050019) (xy 377.855193 -254.09804) (xy 377.825169 -254.142077) (xy 377.788917 -254.181148)
			(xy 377.747246 -254.214379) (xy 377.701088 -254.241028) (xy 377.651474 -254.2605) (xy 377.599512 -254.27236)
			(xy 377.546362 -254.276344) (xy 377.493212 -254.27236) (xy 377.44125 -254.2605) (xy 377.391636 -254.241028)
			(xy 377.345478 -254.214379) (xy 377.303807 -254.181148) (xy 377.267555 -254.142077) (xy 377.237531 -254.09804)
			(xy 377.214405 -254.050019) (xy 377.198695 -253.999089) (xy 377.190752 -253.946385) (xy 376.962172 -253.946385)
			(xy 376.954229 -253.999089) (xy 376.938519 -254.050019) (xy 376.915393 -254.09804) (xy 376.885369 -254.142077)
			(xy 376.849117 -254.181148) (xy 376.807446 -254.214379) (xy 376.761288 -254.241028) (xy 376.711674 -254.2605)
			(xy 376.659712 -254.27236) (xy 376.606562 -254.276344) (xy 376.553412 -254.27236) (xy 376.50145 -254.2605)
			(xy 376.451836 -254.241028) (xy 376.405678 -254.214379) (xy 376.364007 -254.181148) (xy 376.327755 -254.142077)
			(xy 376.297731 -254.09804) (xy 376.274605 -254.050019) (xy 376.258895 -253.999089) (xy 376.250952 -253.946385)
			(xy 376.022626 -253.946385) (xy 376.014683 -253.999089) (xy 375.998973 -254.050019) (xy 375.975847 -254.09804)
			(xy 375.945823 -254.142077) (xy 375.909571 -254.181148) (xy 375.8679 -254.214379) (xy 375.821742 -254.241028)
			(xy 375.772128 -254.2605) (xy 375.720166 -254.27236) (xy 375.667016 -254.276344) (xy 375.613866 -254.27236)
			(xy 375.561904 -254.2605) (xy 375.51229 -254.241028) (xy 375.466132 -254.214379) (xy 375.424461 -254.181148)
			(xy 375.388209 -254.142077) (xy 375.358185 -254.09804) (xy 375.335059 -254.050019) (xy 375.319349 -253.999089)
			(xy 375.311406 -253.946385) (xy 375.082826 -253.946385) (xy 375.074883 -253.999089) (xy 375.059173 -254.050019)
			(xy 375.036047 -254.09804) (xy 375.006023 -254.142077) (xy 374.969771 -254.181148) (xy 374.9281 -254.214379)
			(xy 374.881942 -254.241028) (xy 374.832328 -254.2605) (xy 374.780366 -254.27236) (xy 374.727216 -254.276344)
			(xy 374.674066 -254.27236) (xy 374.622104 -254.2605) (xy 374.57249 -254.241028) (xy 374.526332 -254.214379)
			(xy 374.484661 -254.181148) (xy 374.448409 -254.142077) (xy 374.418385 -254.09804) (xy 374.395259 -254.050019)
			(xy 374.379549 -253.999089) (xy 374.371606 -253.946385) (xy 374.143026 -253.946385) (xy 374.135083 -253.999089)
			(xy 374.119373 -254.050019) (xy 374.096247 -254.09804) (xy 374.066223 -254.142077) (xy 374.029971 -254.181148)
			(xy 373.9883 -254.214379) (xy 373.942142 -254.241028) (xy 373.892528 -254.2605) (xy 373.840566 -254.27236)
			(xy 373.787416 -254.276344) (xy 373.734266 -254.27236) (xy 373.682304 -254.2605) (xy 373.63269 -254.241028)
			(xy 373.586532 -254.214379) (xy 373.544861 -254.181148) (xy 373.508609 -254.142077) (xy 373.478585 -254.09804)
			(xy 373.455459 -254.050019) (xy 373.439749 -253.999089) (xy 373.431806 -253.946385) (xy 373.203226 -253.946385)
			(xy 373.195283 -253.999089) (xy 373.179573 -254.050019) (xy 373.156447 -254.09804) (xy 373.126423 -254.142077)
			(xy 373.090171 -254.181148) (xy 373.0485 -254.214379) (xy 373.002342 -254.241028) (xy 372.952728 -254.2605)
			(xy 372.900766 -254.27236) (xy 372.847616 -254.276344) (xy 372.794466 -254.27236) (xy 372.742504 -254.2605)
			(xy 372.69289 -254.241028) (xy 372.646732 -254.214379) (xy 372.605061 -254.181148) (xy 372.568809 -254.142077)
			(xy 372.538785 -254.09804) (xy 372.515659 -254.050019) (xy 372.499949 -253.999089) (xy 372.492006 -253.946385)
			(xy 372.263426 -253.946385) (xy 372.255483 -253.999089) (xy 372.239773 -254.050019) (xy 372.216647 -254.09804)
			(xy 372.186623 -254.142077) (xy 372.150371 -254.181148) (xy 372.1087 -254.214379) (xy 372.062542 -254.241028)
			(xy 372.012928 -254.2605) (xy 371.960966 -254.27236) (xy 371.907816 -254.276344) (xy 371.854666 -254.27236)
			(xy 371.802704 -254.2605) (xy 371.75309 -254.241028) (xy 371.706932 -254.214379) (xy 371.665261 -254.181148)
			(xy 371.629009 -254.142077) (xy 371.598985 -254.09804) (xy 371.575859 -254.050019) (xy 371.560149 -253.999089)
			(xy 371.552206 -253.946385) (xy 371.323372 -253.946385) (xy 371.315429 -253.999089) (xy 371.299719 -254.050019)
			(xy 371.276593 -254.09804) (xy 371.246569 -254.142077) (xy 371.210317 -254.181148) (xy 371.168646 -254.214379)
			(xy 371.122488 -254.241028) (xy 371.072874 -254.2605) (xy 371.020912 -254.27236) (xy 370.967762 -254.276344)
			(xy 370.914612 -254.27236) (xy 370.86265 -254.2605) (xy 370.813036 -254.241028) (xy 370.766878 -254.214379)
			(xy 370.725207 -254.181148) (xy 370.688955 -254.142077) (xy 370.658931 -254.09804) (xy 370.635805 -254.050019)
			(xy 370.620095 -253.999089) (xy 370.612152 -253.946385) (xy 370.383826 -253.946385) (xy 370.375883 -253.999089)
			(xy 370.360173 -254.050019) (xy 370.337047 -254.09804) (xy 370.307023 -254.142077) (xy 370.270771 -254.181148)
			(xy 370.2291 -254.214379) (xy 370.182942 -254.241028) (xy 370.133328 -254.2605) (xy 370.081366 -254.27236)
			(xy 370.028216 -254.276344) (xy 369.975066 -254.27236) (xy 369.923104 -254.2605) (xy 369.87349 -254.241028)
			(xy 369.827332 -254.214379) (xy 369.785661 -254.181148) (xy 369.749409 -254.142077) (xy 369.719385 -254.09804)
			(xy 369.696259 -254.050019) (xy 369.680549 -253.999089) (xy 369.672606 -253.946385) (xy 368.58448 -253.946385)
			(xy 368.58448 -254.550418) (xy 368.584994 -254.565674) (xy 368.594002 -254.594827) (xy 368.611211 -254.620023)
			(xy 368.635088 -254.63902) (xy 368.663508 -254.650126) (xy 368.693939 -254.652353) (xy 368.723672 -254.645501)
			(xy 368.737134 -254.638302) (xy 368.757606 -254.626835) (xy 368.800918 -254.608785) (xy 368.846225 -254.596576)
			(xy 368.892742 -254.590418) (xy 368.916204 -254.590042) (xy 368.946566 -254.590659) (xy 369.006414 -254.600945)
			(xy 369.063661 -254.621201) (xy 369.090448 -254.635508) (xy 369.102968 -254.642027) (xy 369.130409 -254.648596)
			(xy 369.158599 -254.647393) (xy 369.185381 -254.638511) (xy 369.208703 -254.622629) (xy 369.226779 -254.600964)
			(xy 369.232942 -254.588264) (xy 369.243802 -254.565056) (xy 369.271198 -254.521757) (xy 369.304516 -254.482831)
			(xy 369.343069 -254.44908) (xy 369.38606 -254.421203) (xy 369.432602 -254.399774) (xy 369.481734 -254.385235)
			(xy 369.532443 -254.377887) (xy 369.558062 -254.377444) (xy 369.584719 -254.377915) (xy 369.637437 -254.385855)
			(xy 369.688383 -254.401565) (xy 369.736418 -254.424693) (xy 369.780469 -254.454723) (xy 369.819553 -254.490983)
			(xy 369.852795 -254.532663) (xy 369.879453 -254.578833) (xy 369.898932 -254.62846) (xy 369.910796 -254.680436)
			(xy 369.91478 -254.7336) (xy 369.912787 -254.760201) (xy 370.142252 -254.760201) (xy 370.142252 -254.706903)
			(xy 370.150195 -254.654199) (xy 370.165905 -254.603269) (xy 370.189031 -254.555248) (xy 370.219055 -254.511211)
			(xy 370.255307 -254.47214) (xy 370.296978 -254.438909) (xy 370.343136 -254.41226) (xy 370.39275 -254.392788)
			(xy 370.444712 -254.380928) (xy 370.497862 -254.376945) (xy 370.551012 -254.380928) (xy 370.602974 -254.392788)
			(xy 370.652588 -254.41226) (xy 370.698746 -254.438909) (xy 370.740417 -254.47214) (xy 370.776669 -254.511211)
			(xy 370.806693 -254.555248) (xy 370.829819 -254.603269) (xy 370.845529 -254.654199) (xy 370.853472 -254.706903)
			(xy 370.85397 -254.733552) (xy 370.853472 -254.760201) (xy 371.082052 -254.760201) (xy 371.082052 -254.706903)
			(xy 371.089995 -254.654199) (xy 371.105705 -254.603269) (xy 371.128831 -254.555248) (xy 371.158855 -254.511211)
			(xy 371.195107 -254.47214) (xy 371.236778 -254.438909) (xy 371.282936 -254.41226) (xy 371.33255 -254.392788)
			(xy 371.384512 -254.380928) (xy 371.437662 -254.376945) (xy 371.490812 -254.380928) (xy 371.542774 -254.392788)
			(xy 371.592388 -254.41226) (xy 371.638546 -254.438909) (xy 371.680217 -254.47214) (xy 371.716469 -254.511211)
			(xy 371.746493 -254.555248) (xy 371.769619 -254.603269) (xy 371.785329 -254.654199) (xy 371.793272 -254.706903)
			(xy 371.79377 -254.733552) (xy 371.793272 -254.760201) (xy 372.022106 -254.760201) (xy 372.022106 -254.706903)
			(xy 372.030049 -254.654199) (xy 372.045759 -254.603269) (xy 372.068885 -254.555248) (xy 372.098909 -254.511211)
			(xy 372.135161 -254.47214) (xy 372.176832 -254.438909) (xy 372.22299 -254.41226) (xy 372.272604 -254.392788)
			(xy 372.324566 -254.380928) (xy 372.377716 -254.376945) (xy 372.430866 -254.380928) (xy 372.482828 -254.392788)
			(xy 372.532442 -254.41226) (xy 372.5786 -254.438909) (xy 372.620271 -254.47214) (xy 372.656523 -254.511211)
			(xy 372.686547 -254.555248) (xy 372.709673 -254.603269) (xy 372.725383 -254.654199) (xy 372.733326 -254.706903)
			(xy 372.733824 -254.733552) (xy 372.733326 -254.760201) (xy 372.961652 -254.760201) (xy 372.961652 -254.706903)
			(xy 372.969595 -254.654199) (xy 372.985305 -254.603269) (xy 373.008431 -254.555248) (xy 373.038455 -254.511211)
			(xy 373.074707 -254.47214) (xy 373.116378 -254.438909) (xy 373.162536 -254.41226) (xy 373.21215 -254.392788)
			(xy 373.264112 -254.380928) (xy 373.317262 -254.376945) (xy 373.370412 -254.380928) (xy 373.422374 -254.392788)
			(xy 373.471988 -254.41226) (xy 373.518146 -254.438909) (xy 373.559817 -254.47214) (xy 373.596069 -254.511211)
			(xy 373.626093 -254.555248) (xy 373.649219 -254.603269) (xy 373.664929 -254.654199) (xy 373.672872 -254.706903)
			(xy 373.67337 -254.733552) (xy 373.672872 -254.760201) (xy 373.901706 -254.760201) (xy 373.901706 -254.706903)
			(xy 373.909649 -254.654199) (xy 373.925359 -254.603269) (xy 373.948485 -254.555248) (xy 373.978509 -254.511211)
			(xy 374.014761 -254.47214) (xy 374.056432 -254.438909) (xy 374.10259 -254.41226) (xy 374.152204 -254.392788)
			(xy 374.204166 -254.380928) (xy 374.257316 -254.376945) (xy 374.310466 -254.380928) (xy 374.362428 -254.392788)
			(xy 374.412042 -254.41226) (xy 374.4582 -254.438909) (xy 374.499871 -254.47214) (xy 374.536123 -254.511211)
			(xy 374.566147 -254.555248) (xy 374.589273 -254.603269) (xy 374.604983 -254.654199) (xy 374.612926 -254.706903)
			(xy 374.613424 -254.733552) (xy 374.612926 -254.760201) (xy 374.841252 -254.760201) (xy 374.841252 -254.706903)
			(xy 374.849195 -254.654199) (xy 374.864905 -254.603269) (xy 374.888031 -254.555248) (xy 374.918055 -254.511211)
			(xy 374.954307 -254.47214) (xy 374.995978 -254.438909) (xy 375.042136 -254.41226) (xy 375.09175 -254.392788)
			(xy 375.143712 -254.380928) (xy 375.196862 -254.376945) (xy 375.250012 -254.380928) (xy 375.301974 -254.392788)
			(xy 375.351588 -254.41226) (xy 375.397746 -254.438909) (xy 375.439417 -254.47214) (xy 375.475669 -254.511211)
			(xy 375.505693 -254.555248) (xy 375.528819 -254.603269) (xy 375.544529 -254.654199) (xy 375.552472 -254.706903)
			(xy 375.55297 -254.733552) (xy 375.552472 -254.760201) (xy 375.781052 -254.760201) (xy 375.781052 -254.706903)
			(xy 375.788995 -254.654199) (xy 375.804705 -254.603269) (xy 375.827831 -254.555248) (xy 375.857855 -254.511211)
			(xy 375.894107 -254.47214) (xy 375.935778 -254.438909) (xy 375.981936 -254.41226) (xy 376.03155 -254.392788)
			(xy 376.083512 -254.380928) (xy 376.136662 -254.376945) (xy 376.189812 -254.380928) (xy 376.241774 -254.392788)
			(xy 376.291388 -254.41226) (xy 376.337546 -254.438909) (xy 376.379217 -254.47214) (xy 376.415469 -254.511211)
			(xy 376.445493 -254.555248) (xy 376.468619 -254.603269) (xy 376.484329 -254.654199) (xy 376.492272 -254.706903)
			(xy 376.49277 -254.733552) (xy 376.492272 -254.760201) (xy 376.720852 -254.760201) (xy 376.720852 -254.706903)
			(xy 376.728795 -254.654199) (xy 376.744505 -254.603269) (xy 376.767631 -254.555248) (xy 376.797655 -254.511211)
			(xy 376.833907 -254.47214) (xy 376.875578 -254.438909) (xy 376.921736 -254.41226) (xy 376.97135 -254.392788)
			(xy 377.023312 -254.380928) (xy 377.076462 -254.376945) (xy 377.129612 -254.380928) (xy 377.181574 -254.392788)
			(xy 377.231188 -254.41226) (xy 377.277346 -254.438909) (xy 377.319017 -254.47214) (xy 377.355269 -254.511211)
			(xy 377.385293 -254.555248) (xy 377.408419 -254.603269) (xy 377.424129 -254.654199) (xy 377.432072 -254.706903)
			(xy 377.43257 -254.733552) (xy 377.432072 -254.760201) (xy 377.660652 -254.760201) (xy 377.660652 -254.706903)
			(xy 377.668595 -254.654199) (xy 377.684305 -254.603269) (xy 377.707431 -254.555248) (xy 377.737455 -254.511211)
			(xy 377.773707 -254.47214) (xy 377.815378 -254.438909) (xy 377.861536 -254.41226) (xy 377.91115 -254.392788)
			(xy 377.963112 -254.380928) (xy 378.016262 -254.376945) (xy 378.069412 -254.380928) (xy 378.121374 -254.392788)
			(xy 378.170988 -254.41226) (xy 378.217146 -254.438909) (xy 378.258817 -254.47214) (xy 378.295069 -254.511211)
			(xy 378.325093 -254.555248) (xy 378.348219 -254.603269) (xy 378.363929 -254.654199) (xy 378.371872 -254.706903)
			(xy 378.37237 -254.733552) (xy 378.371872 -254.760201) (xy 378.600452 -254.760201) (xy 378.600452 -254.706903)
			(xy 378.608395 -254.654199) (xy 378.624105 -254.603269) (xy 378.647231 -254.555248) (xy 378.677255 -254.511211)
			(xy 378.713507 -254.47214) (xy 378.755178 -254.438909) (xy 378.801336 -254.41226) (xy 378.85095 -254.392788)
			(xy 378.902912 -254.380928) (xy 378.956062 -254.376945) (xy 379.009212 -254.380928) (xy 379.061174 -254.392788)
			(xy 379.110788 -254.41226) (xy 379.156946 -254.438909) (xy 379.198617 -254.47214) (xy 379.234869 -254.511211)
			(xy 379.264893 -254.555248) (xy 379.288019 -254.603269) (xy 379.303729 -254.654199) (xy 379.311672 -254.706903)
			(xy 379.31217 -254.733552) (xy 379.311672 -254.760201) (xy 379.54076 -254.760201) (xy 379.54076 -254.706903)
			(xy 379.548703 -254.654199) (xy 379.564413 -254.603269) (xy 379.587539 -254.555248) (xy 379.617563 -254.511211)
			(xy 379.653815 -254.47214) (xy 379.695486 -254.438909) (xy 379.741644 -254.41226) (xy 379.791258 -254.392788)
			(xy 379.84322 -254.380928) (xy 379.89637 -254.376945) (xy 379.94952 -254.380928) (xy 380.001482 -254.392788)
			(xy 380.051096 -254.41226) (xy 380.097254 -254.438909) (xy 380.138925 -254.47214) (xy 380.175177 -254.511211)
			(xy 380.205201 -254.555248) (xy 380.228327 -254.603269) (xy 380.244037 -254.654199) (xy 380.25198 -254.706903)
			(xy 380.252478 -254.733552) (xy 380.25198 -254.760201) (xy 380.244037 -254.812905) (xy 380.228327 -254.863835)
			(xy 380.205201 -254.911856) (xy 380.175177 -254.955893) (xy 380.138925 -254.994964) (xy 380.097254 -255.028195)
			(xy 380.051096 -255.054844) (xy 380.001482 -255.074316) (xy 379.94952 -255.086176) (xy 379.89637 -255.09016)
			(xy 379.84322 -255.086176) (xy 379.791258 -255.074316) (xy 379.741644 -255.054844) (xy 379.695486 -255.028195)
			(xy 379.653815 -254.994964) (xy 379.617563 -254.955893) (xy 379.587539 -254.911856) (xy 379.564413 -254.863835)
			(xy 379.548703 -254.812905) (xy 379.54076 -254.760201) (xy 379.311672 -254.760201) (xy 379.303729 -254.812905)
			(xy 379.288019 -254.863835) (xy 379.264893 -254.911856) (xy 379.234869 -254.955893) (xy 379.198617 -254.994964)
			(xy 379.156946 -255.028195) (xy 379.110788 -255.054844) (xy 379.061174 -255.074316) (xy 379.009212 -255.086176)
			(xy 378.956062 -255.09016) (xy 378.902912 -255.086176) (xy 378.85095 -255.074316) (xy 378.801336 -255.054844)
			(xy 378.755178 -255.028195) (xy 378.713507 -254.994964) (xy 378.677255 -254.955893) (xy 378.647231 -254.911856)
			(xy 378.624105 -254.863835) (xy 378.608395 -254.812905) (xy 378.600452 -254.760201) (xy 378.371872 -254.760201)
			(xy 378.363929 -254.812905) (xy 378.348219 -254.863835) (xy 378.325093 -254.911856) (xy 378.295069 -254.955893)
			(xy 378.258817 -254.994964) (xy 378.217146 -255.028195) (xy 378.170988 -255.054844) (xy 378.121374 -255.074316)
			(xy 378.069412 -255.086176) (xy 378.016262 -255.09016) (xy 377.963112 -255.086176) (xy 377.91115 -255.074316)
			(xy 377.861536 -255.054844) (xy 377.815378 -255.028195) (xy 377.773707 -254.994964) (xy 377.737455 -254.955893)
			(xy 377.707431 -254.911856) (xy 377.684305 -254.863835) (xy 377.668595 -254.812905) (xy 377.660652 -254.760201)
			(xy 377.432072 -254.760201) (xy 377.424129 -254.812905) (xy 377.408419 -254.863835) (xy 377.385293 -254.911856)
			(xy 377.355269 -254.955893) (xy 377.319017 -254.994964) (xy 377.277346 -255.028195) (xy 377.231188 -255.054844)
			(xy 377.181574 -255.074316) (xy 377.129612 -255.086176) (xy 377.076462 -255.09016) (xy 377.023312 -255.086176)
			(xy 376.97135 -255.074316) (xy 376.921736 -255.054844) (xy 376.875578 -255.028195) (xy 376.833907 -254.994964)
			(xy 376.797655 -254.955893) (xy 376.767631 -254.911856) (xy 376.744505 -254.863835) (xy 376.728795 -254.812905)
			(xy 376.720852 -254.760201) (xy 376.492272 -254.760201) (xy 376.484329 -254.812905) (xy 376.468619 -254.863835)
			(xy 376.445493 -254.911856) (xy 376.415469 -254.955893) (xy 376.379217 -254.994964) (xy 376.337546 -255.028195)
			(xy 376.291388 -255.054844) (xy 376.241774 -255.074316) (xy 376.189812 -255.086176) (xy 376.136662 -255.09016)
			(xy 376.083512 -255.086176) (xy 376.03155 -255.074316) (xy 375.981936 -255.054844) (xy 375.935778 -255.028195)
			(xy 375.894107 -254.994964) (xy 375.857855 -254.955893) (xy 375.827831 -254.911856) (xy 375.804705 -254.863835)
			(xy 375.788995 -254.812905) (xy 375.781052 -254.760201) (xy 375.552472 -254.760201) (xy 375.544529 -254.812905)
			(xy 375.528819 -254.863835) (xy 375.505693 -254.911856) (xy 375.475669 -254.955893) (xy 375.439417 -254.994964)
			(xy 375.397746 -255.028195) (xy 375.351588 -255.054844) (xy 375.301974 -255.074316) (xy 375.250012 -255.086176)
			(xy 375.196862 -255.09016) (xy 375.143712 -255.086176) (xy 375.09175 -255.074316) (xy 375.042136 -255.054844)
			(xy 374.995978 -255.028195) (xy 374.954307 -254.994964) (xy 374.918055 -254.955893) (xy 374.888031 -254.911856)
			(xy 374.864905 -254.863835) (xy 374.849195 -254.812905) (xy 374.841252 -254.760201) (xy 374.612926 -254.760201)
			(xy 374.604983 -254.812905) (xy 374.589273 -254.863835) (xy 374.566147 -254.911856) (xy 374.536123 -254.955893)
			(xy 374.499871 -254.994964) (xy 374.4582 -255.028195) (xy 374.412042 -255.054844) (xy 374.362428 -255.074316)
			(xy 374.310466 -255.086176) (xy 374.257316 -255.09016) (xy 374.204166 -255.086176) (xy 374.152204 -255.074316)
			(xy 374.10259 -255.054844) (xy 374.056432 -255.028195) (xy 374.014761 -254.994964) (xy 373.978509 -254.955893)
			(xy 373.948485 -254.911856) (xy 373.925359 -254.863835) (xy 373.909649 -254.812905) (xy 373.901706 -254.760201)
			(xy 373.672872 -254.760201) (xy 373.664929 -254.812905) (xy 373.649219 -254.863835) (xy 373.626093 -254.911856)
			(xy 373.596069 -254.955893) (xy 373.559817 -254.994964) (xy 373.518146 -255.028195) (xy 373.471988 -255.054844)
			(xy 373.422374 -255.074316) (xy 373.370412 -255.086176) (xy 373.317262 -255.09016) (xy 373.264112 -255.086176)
			(xy 373.21215 -255.074316) (xy 373.162536 -255.054844) (xy 373.116378 -255.028195) (xy 373.074707 -254.994964)
			(xy 373.038455 -254.955893) (xy 373.008431 -254.911856) (xy 372.985305 -254.863835) (xy 372.969595 -254.812905)
			(xy 372.961652 -254.760201) (xy 372.733326 -254.760201) (xy 372.725383 -254.812905) (xy 372.709673 -254.863835)
			(xy 372.686547 -254.911856) (xy 372.656523 -254.955893) (xy 372.620271 -254.994964) (xy 372.5786 -255.028195)
			(xy 372.532442 -255.054844) (xy 372.482828 -255.074316) (xy 372.430866 -255.086176) (xy 372.377716 -255.09016)
			(xy 372.324566 -255.086176) (xy 372.272604 -255.074316) (xy 372.22299 -255.054844) (xy 372.176832 -255.028195)
			(xy 372.135161 -254.994964) (xy 372.098909 -254.955893) (xy 372.068885 -254.911856) (xy 372.045759 -254.863835)
			(xy 372.030049 -254.812905) (xy 372.022106 -254.760201) (xy 371.793272 -254.760201) (xy 371.785329 -254.812905)
			(xy 371.769619 -254.863835) (xy 371.746493 -254.911856) (xy 371.716469 -254.955893) (xy 371.680217 -254.994964)
			(xy 371.638546 -255.028195) (xy 371.592388 -255.054844) (xy 371.542774 -255.074316) (xy 371.490812 -255.086176)
			(xy 371.437662 -255.09016) (xy 371.384512 -255.086176) (xy 371.33255 -255.074316) (xy 371.282936 -255.054844)
			(xy 371.236778 -255.028195) (xy 371.195107 -254.994964) (xy 371.158855 -254.955893) (xy 371.128831 -254.911856)
			(xy 371.105705 -254.863835) (xy 371.089995 -254.812905) (xy 371.082052 -254.760201) (xy 370.853472 -254.760201)
			(xy 370.845529 -254.812905) (xy 370.829819 -254.863835) (xy 370.806693 -254.911856) (xy 370.776669 -254.955893)
			(xy 370.740417 -254.994964) (xy 370.698746 -255.028195) (xy 370.652588 -255.054844) (xy 370.602974 -255.074316)
			(xy 370.551012 -255.086176) (xy 370.497862 -255.09016) (xy 370.444712 -255.086176) (xy 370.39275 -255.074316)
			(xy 370.343136 -255.054844) (xy 370.296978 -255.028195) (xy 370.255307 -254.994964) (xy 370.219055 -254.955893)
			(xy 370.189031 -254.911856) (xy 370.165905 -254.863835) (xy 370.150195 -254.812905) (xy 370.142252 -254.760201)
			(xy 369.912787 -254.760201) (xy 369.910796 -254.786764) (xy 369.898932 -254.83874) (xy 369.879453 -254.888367)
			(xy 369.852795 -254.934537) (xy 369.819553 -254.976217) (xy 369.780469 -255.012477) (xy 369.736418 -255.042507)
			(xy 369.688383 -255.065635) (xy 369.637437 -255.081345) (xy 369.584719 -255.089285) (xy 369.558062 -255.08966)
			(xy 369.5277 -255.08904) (xy 369.467855 -255.078749) (xy 369.410611 -255.058488) (xy 369.383818 -255.044194)
			(xy 369.371299 -255.03768) (xy 369.343864 -255.03112) (xy 369.315681 -255.032329) (xy 369.288908 -255.041215)
			(xy 369.265595 -255.057097) (xy 369.247527 -255.07876) (xy 369.241324 -255.091438) (xy 369.231078 -255.113414)
			(xy 369.205461 -255.154582) (xy 369.19027 -255.17348) (xy 369.18165 -255.184609) (xy 369.170316 -255.210366)
			(xy 369.166447 -255.238239) (xy 369.170337 -255.266109) (xy 369.181691 -255.291856) (xy 369.19027 -255.30302)
			(xy 369.205706 -255.322268) (xy 369.231676 -255.364218) (xy 369.251598 -255.409355) (xy 369.265088 -255.456813)
			(xy 369.271889 -255.505681) (xy 369.272312 -255.53035) (xy 369.271759 -255.558331) (xy 369.269232 -255.574271)
			(xy 370.612406 -255.574271) (xy 370.612406 -255.520973) (xy 370.620349 -255.468269) (xy 370.636059 -255.417339)
			(xy 370.659185 -255.369318) (xy 370.689209 -255.325281) (xy 370.725461 -255.28621) (xy 370.767132 -255.252979)
			(xy 370.81329 -255.22633) (xy 370.862904 -255.206858) (xy 370.914866 -255.194998) (xy 370.968016 -255.191015)
			(xy 371.021166 -255.194998) (xy 371.073128 -255.206858) (xy 371.122742 -255.22633) (xy 371.1689 -255.252979)
			(xy 371.210571 -255.28621) (xy 371.246823 -255.325281) (xy 371.276847 -255.369318) (xy 371.299973 -255.417339)
			(xy 371.315683 -255.468269) (xy 371.323626 -255.520973) (xy 371.324124 -255.547622) (xy 371.323626 -255.574271)
			(xy 371.552206 -255.574271) (xy 371.552206 -255.520973) (xy 371.560149 -255.468269) (xy 371.575859 -255.417339)
			(xy 371.598985 -255.369318) (xy 371.629009 -255.325281) (xy 371.665261 -255.28621) (xy 371.706932 -255.252979)
			(xy 371.75309 -255.22633) (xy 371.802704 -255.206858) (xy 371.854666 -255.194998) (xy 371.907816 -255.191015)
			(xy 371.960966 -255.194998) (xy 372.012928 -255.206858) (xy 372.062542 -255.22633) (xy 372.1087 -255.252979)
			(xy 372.150371 -255.28621) (xy 372.186623 -255.325281) (xy 372.216647 -255.369318) (xy 372.239773 -255.417339)
			(xy 372.255483 -255.468269) (xy 372.263426 -255.520973) (xy 372.263924 -255.547622) (xy 372.263426 -255.574271)
			(xy 372.491752 -255.574271) (xy 372.491752 -255.520973) (xy 372.499695 -255.468269) (xy 372.515405 -255.417339)
			(xy 372.538531 -255.369318) (xy 372.568555 -255.325281) (xy 372.604807 -255.28621) (xy 372.646478 -255.252979)
			(xy 372.692636 -255.22633) (xy 372.74225 -255.206858) (xy 372.794212 -255.194998) (xy 372.847362 -255.191015)
			(xy 372.900512 -255.194998) (xy 372.952474 -255.206858) (xy 373.002088 -255.22633) (xy 373.048246 -255.252979)
			(xy 373.089917 -255.28621) (xy 373.126169 -255.325281) (xy 373.156193 -255.369318) (xy 373.179319 -255.417339)
			(xy 373.195029 -255.468269) (xy 373.202972 -255.520973) (xy 373.20347 -255.547622) (xy 373.202972 -255.574271)
			(xy 373.431806 -255.574271) (xy 373.431806 -255.520973) (xy 373.439749 -255.468269) (xy 373.455459 -255.417339)
			(xy 373.478585 -255.369318) (xy 373.508609 -255.325281) (xy 373.544861 -255.28621) (xy 373.586532 -255.252979)
			(xy 373.63269 -255.22633) (xy 373.682304 -255.206858) (xy 373.734266 -255.194998) (xy 373.787416 -255.191015)
			(xy 373.840566 -255.194998) (xy 373.892528 -255.206858) (xy 373.942142 -255.22633) (xy 373.9883 -255.252979)
			(xy 374.029971 -255.28621) (xy 374.066223 -255.325281) (xy 374.096247 -255.369318) (xy 374.119373 -255.417339)
			(xy 374.135083 -255.468269) (xy 374.143026 -255.520973) (xy 374.143524 -255.547622) (xy 374.143026 -255.574271)
			(xy 374.371352 -255.574271) (xy 374.371352 -255.520973) (xy 374.379295 -255.468269) (xy 374.395005 -255.417339)
			(xy 374.418131 -255.369318) (xy 374.448155 -255.325281) (xy 374.484407 -255.28621) (xy 374.526078 -255.252979)
			(xy 374.572236 -255.22633) (xy 374.62185 -255.206858) (xy 374.673812 -255.194998) (xy 374.726962 -255.191015)
			(xy 374.780112 -255.194998) (xy 374.832074 -255.206858) (xy 374.881688 -255.22633) (xy 374.927846 -255.252979)
			(xy 374.969517 -255.28621) (xy 375.005769 -255.325281) (xy 375.035793 -255.369318) (xy 375.058919 -255.417339)
			(xy 375.074629 -255.468269) (xy 375.082572 -255.520973) (xy 375.08307 -255.547622) (xy 375.323103 -255.547622)
			(xy 375.327133 -255.495124) (xy 375.33913 -255.443856) (xy 375.358813 -255.395021) (xy 375.385719 -255.349762)
			(xy 375.419219 -255.309141) (xy 375.458527 -255.27411) (xy 375.502722 -255.24549) (xy 375.550767 -255.223951)
			(xy 375.601538 -255.209999) (xy 375.653843 -255.203961) (xy 375.706457 -255.205978) (xy 375.758147 -255.216002)
			(xy 375.8077 -255.2338) (xy 375.853956 -255.258953) (xy 375.89583 -255.290872) (xy 375.932342 -255.32881)
			(xy 375.962634 -255.371876) (xy 375.985997 -255.419061) (xy 376.001883 -255.46926) (xy 376.00992 -255.521296)
			(xy 376.010424 -255.547622) (xy 376.00992 -255.573948) (xy 376.00987 -255.574271) (xy 376.251206 -255.574271)
			(xy 376.251206 -255.520973) (xy 376.259149 -255.468269) (xy 376.274859 -255.417339) (xy 376.297985 -255.369318)
			(xy 376.328009 -255.325281) (xy 376.364261 -255.28621) (xy 376.405932 -255.252979) (xy 376.45209 -255.22633)
			(xy 376.501704 -255.206858) (xy 376.553666 -255.194998) (xy 376.606816 -255.191015) (xy 376.659966 -255.194998)
			(xy 376.711928 -255.206858) (xy 376.761542 -255.22633) (xy 376.8077 -255.252979) (xy 376.849371 -255.28621)
			(xy 376.885623 -255.325281) (xy 376.915647 -255.369318) (xy 376.938773 -255.417339) (xy 376.954483 -255.468269)
			(xy 376.962426 -255.520973) (xy 376.962924 -255.547622) (xy 376.962426 -255.574271) (xy 377.191006 -255.574271)
			(xy 377.191006 -255.520973) (xy 377.198949 -255.468269) (xy 377.214659 -255.417339) (xy 377.237785 -255.369318)
			(xy 377.267809 -255.325281) (xy 377.304061 -255.28621) (xy 377.345732 -255.252979) (xy 377.39189 -255.22633)
			(xy 377.441504 -255.206858) (xy 377.493466 -255.194998) (xy 377.546616 -255.191015) (xy 377.599766 -255.194998)
			(xy 377.651728 -255.206858) (xy 377.701342 -255.22633) (xy 377.7475 -255.252979) (xy 377.789171 -255.28621)
			(xy 377.825423 -255.325281) (xy 377.855447 -255.369318) (xy 377.878573 -255.417339) (xy 377.894283 -255.468269)
			(xy 377.902226 -255.520973) (xy 377.902724 -255.547622) (xy 377.902226 -255.574271) (xy 378.130806 -255.574271)
			(xy 378.130806 -255.520973) (xy 378.138749 -255.468269) (xy 378.154459 -255.417339) (xy 378.177585 -255.369318)
			(xy 378.207609 -255.325281) (xy 378.243861 -255.28621) (xy 378.285532 -255.252979) (xy 378.33169 -255.22633)
			(xy 378.381304 -255.206858) (xy 378.433266 -255.194998) (xy 378.486416 -255.191015) (xy 378.539566 -255.194998)
			(xy 378.591528 -255.206858) (xy 378.641142 -255.22633) (xy 378.6873 -255.252979) (xy 378.728971 -255.28621)
			(xy 378.765223 -255.325281) (xy 378.795247 -255.369318) (xy 378.818373 -255.417339) (xy 378.834083 -255.468269)
			(xy 378.842026 -255.520973) (xy 378.842524 -255.547622) (xy 378.842026 -255.574271) (xy 379.070606 -255.574271)
			(xy 379.070606 -255.520973) (xy 379.078549 -255.468269) (xy 379.094259 -255.417339) (xy 379.117385 -255.369318)
			(xy 379.147409 -255.325281) (xy 379.183661 -255.28621) (xy 379.225332 -255.252979) (xy 379.27149 -255.22633)
			(xy 379.321104 -255.206858) (xy 379.373066 -255.194998) (xy 379.426216 -255.191015) (xy 379.479366 -255.194998)
			(xy 379.531328 -255.206858) (xy 379.580942 -255.22633) (xy 379.6271 -255.252979) (xy 379.668771 -255.28621)
			(xy 379.705023 -255.325281) (xy 379.735047 -255.369318) (xy 379.758173 -255.417339) (xy 379.773883 -255.468269)
			(xy 379.781826 -255.520973) (xy 379.782324 -255.547622) (xy 379.781826 -255.574271) (xy 380.010406 -255.574271)
			(xy 380.010406 -255.520973) (xy 380.018349 -255.468269) (xy 380.034059 -255.417339) (xy 380.057185 -255.369318)
			(xy 380.087209 -255.325281) (xy 380.123461 -255.28621) (xy 380.165132 -255.252979) (xy 380.21129 -255.22633)
			(xy 380.260904 -255.206858) (xy 380.312866 -255.194998) (xy 380.366016 -255.191015) (xy 380.419166 -255.194998)
			(xy 380.471128 -255.206858) (xy 380.520742 -255.22633) (xy 380.5669 -255.252979) (xy 380.608571 -255.28621)
			(xy 380.644823 -255.325281) (xy 380.674847 -255.369318) (xy 380.697973 -255.417339) (xy 380.713683 -255.468269)
			(xy 380.721626 -255.520973) (xy 380.722124 -255.547622) (xy 380.721626 -255.574271) (xy 380.713683 -255.626975)
			(xy 380.697973 -255.677905) (xy 380.674847 -255.725926) (xy 380.644823 -255.769963) (xy 380.608571 -255.809034)
			(xy 380.5669 -255.842265) (xy 380.520742 -255.868914) (xy 380.471128 -255.888386) (xy 380.419166 -255.900246)
			(xy 380.366016 -255.90423) (xy 380.312866 -255.900246) (xy 380.260904 -255.888386) (xy 380.21129 -255.868914)
			(xy 380.165132 -255.842265) (xy 380.123461 -255.809034) (xy 380.087209 -255.769963) (xy 380.057185 -255.725926)
			(xy 380.034059 -255.677905) (xy 380.018349 -255.626975) (xy 380.010406 -255.574271) (xy 379.781826 -255.574271)
			(xy 379.773883 -255.626975) (xy 379.758173 -255.677905) (xy 379.735047 -255.725926) (xy 379.705023 -255.769963)
			(xy 379.668771 -255.809034) (xy 379.6271 -255.842265) (xy 379.580942 -255.868914) (xy 379.531328 -255.888386)
			(xy 379.479366 -255.900246) (xy 379.426216 -255.90423) (xy 379.373066 -255.900246) (xy 379.321104 -255.888386)
			(xy 379.27149 -255.868914) (xy 379.225332 -255.842265) (xy 379.183661 -255.809034) (xy 379.147409 -255.769963)
			(xy 379.117385 -255.725926) (xy 379.094259 -255.677905) (xy 379.078549 -255.626975) (xy 379.070606 -255.574271)
			(xy 378.842026 -255.574271) (xy 378.834083 -255.626975) (xy 378.818373 -255.677905) (xy 378.795247 -255.725926)
			(xy 378.765223 -255.769963) (xy 378.728971 -255.809034) (xy 378.6873 -255.842265) (xy 378.641142 -255.868914)
			(xy 378.591528 -255.888386) (xy 378.539566 -255.900246) (xy 378.486416 -255.90423) (xy 378.433266 -255.900246)
			(xy 378.381304 -255.888386) (xy 378.33169 -255.868914) (xy 378.285532 -255.842265) (xy 378.243861 -255.809034)
			(xy 378.207609 -255.769963) (xy 378.177585 -255.725926) (xy 378.154459 -255.677905) (xy 378.138749 -255.626975)
			(xy 378.130806 -255.574271) (xy 377.902226 -255.574271) (xy 377.894283 -255.626975) (xy 377.878573 -255.677905)
			(xy 377.855447 -255.725926) (xy 377.825423 -255.769963) (xy 377.789171 -255.809034) (xy 377.7475 -255.842265)
			(xy 377.701342 -255.868914) (xy 377.651728 -255.888386) (xy 377.599766 -255.900246) (xy 377.546616 -255.90423)
			(xy 377.493466 -255.900246) (xy 377.441504 -255.888386) (xy 377.39189 -255.868914) (xy 377.345732 -255.842265)
			(xy 377.304061 -255.809034) (xy 377.267809 -255.769963) (xy 377.237785 -255.725926) (xy 377.214659 -255.677905)
			(xy 377.198949 -255.626975) (xy 377.191006 -255.574271) (xy 376.962426 -255.574271) (xy 376.954483 -255.626975)
			(xy 376.938773 -255.677905) (xy 376.915647 -255.725926) (xy 376.885623 -255.769963) (xy 376.849371 -255.809034)
			(xy 376.8077 -255.842265) (xy 376.761542 -255.868914) (xy 376.711928 -255.888386) (xy 376.659966 -255.900246)
			(xy 376.606816 -255.90423) (xy 376.553666 -255.900246) (xy 376.501704 -255.888386) (xy 376.45209 -255.868914)
			(xy 376.405932 -255.842265) (xy 376.364261 -255.809034) (xy 376.328009 -255.769963) (xy 376.297985 -255.725926)
			(xy 376.274859 -255.677905) (xy 376.259149 -255.626975) (xy 376.251206 -255.574271) (xy 376.00987 -255.574271)
			(xy 376.001883 -255.625984) (xy 375.985997 -255.676183) (xy 375.962634 -255.723368) (xy 375.932342 -255.766434)
			(xy 375.89583 -255.804372) (xy 375.853956 -255.836291) (xy 375.8077 -255.861444) (xy 375.758147 -255.879242)
			(xy 375.706457 -255.889266) (xy 375.653843 -255.891283) (xy 375.601538 -255.885245) (xy 375.550767 -255.871293)
			(xy 375.502722 -255.849754) (xy 375.458527 -255.821134) (xy 375.419219 -255.786103) (xy 375.385719 -255.745482)
			(xy 375.358813 -255.700223) (xy 375.33913 -255.651388) (xy 375.327133 -255.60012) (xy 375.323103 -255.547622)
			(xy 375.08307 -255.547622) (xy 375.082572 -255.574271) (xy 375.074629 -255.626975) (xy 375.058919 -255.677905)
			(xy 375.035793 -255.725926) (xy 375.005769 -255.769963) (xy 374.969517 -255.809034) (xy 374.927846 -255.842265)
			(xy 374.881688 -255.868914) (xy 374.832074 -255.888386) (xy 374.780112 -255.900246) (xy 374.726962 -255.90423)
			(xy 374.673812 -255.900246) (xy 374.62185 -255.888386) (xy 374.572236 -255.868914) (xy 374.526078 -255.842265)
			(xy 374.484407 -255.809034) (xy 374.448155 -255.769963) (xy 374.418131 -255.725926) (xy 374.395005 -255.677905)
			(xy 374.379295 -255.626975) (xy 374.371352 -255.574271) (xy 374.143026 -255.574271) (xy 374.135083 -255.626975)
			(xy 374.119373 -255.677905) (xy 374.096247 -255.725926) (xy 374.066223 -255.769963) (xy 374.029971 -255.809034)
			(xy 373.9883 -255.842265) (xy 373.942142 -255.868914) (xy 373.892528 -255.888386) (xy 373.840566 -255.900246)
			(xy 373.787416 -255.90423) (xy 373.734266 -255.900246) (xy 373.682304 -255.888386) (xy 373.63269 -255.868914)
			(xy 373.586532 -255.842265) (xy 373.544861 -255.809034) (xy 373.508609 -255.769963) (xy 373.478585 -255.725926)
			(xy 373.455459 -255.677905) (xy 373.439749 -255.626975) (xy 373.431806 -255.574271) (xy 373.202972 -255.574271)
			(xy 373.195029 -255.626975) (xy 373.179319 -255.677905) (xy 373.156193 -255.725926) (xy 373.126169 -255.769963)
			(xy 373.089917 -255.809034) (xy 373.048246 -255.842265) (xy 373.002088 -255.868914) (xy 372.952474 -255.888386)
			(xy 372.900512 -255.900246) (xy 372.847362 -255.90423) (xy 372.794212 -255.900246) (xy 372.74225 -255.888386)
			(xy 372.692636 -255.868914) (xy 372.646478 -255.842265) (xy 372.604807 -255.809034) (xy 372.568555 -255.769963)
			(xy 372.538531 -255.725926) (xy 372.515405 -255.677905) (xy 372.499695 -255.626975) (xy 372.491752 -255.574271)
			(xy 372.263426 -255.574271) (xy 372.255483 -255.626975) (xy 372.239773 -255.677905) (xy 372.216647 -255.725926)
			(xy 372.186623 -255.769963) (xy 372.150371 -255.809034) (xy 372.1087 -255.842265) (xy 372.062542 -255.868914)
			(xy 372.012928 -255.888386) (xy 371.960966 -255.900246) (xy 371.907816 -255.90423) (xy 371.854666 -255.900246)
			(xy 371.802704 -255.888386) (xy 371.75309 -255.868914) (xy 371.706932 -255.842265) (xy 371.665261 -255.809034)
			(xy 371.629009 -255.769963) (xy 371.598985 -255.725926) (xy 371.575859 -255.677905) (xy 371.560149 -255.626975)
			(xy 371.552206 -255.574271) (xy 371.323626 -255.574271) (xy 371.315683 -255.626975) (xy 371.299973 -255.677905)
			(xy 371.276847 -255.725926) (xy 371.246823 -255.769963) (xy 371.210571 -255.809034) (xy 371.1689 -255.842265)
			(xy 371.122742 -255.868914) (xy 371.073128 -255.888386) (xy 371.021166 -255.900246) (xy 370.968016 -255.90423)
			(xy 370.914866 -255.900246) (xy 370.862904 -255.888386) (xy 370.81329 -255.868914) (xy 370.767132 -255.842265)
			(xy 370.725461 -255.809034) (xy 370.689209 -255.769963) (xy 370.659185 -255.725926) (xy 370.636059 -255.677905)
			(xy 370.620349 -255.626975) (xy 370.612406 -255.574271) (xy 369.269232 -255.574271) (xy 369.262998 -255.613602)
			(xy 369.245699 -255.666823) (xy 369.220288 -255.716682) (xy 369.187392 -255.761953) (xy 369.147818 -255.801521)
			(xy 369.102543 -255.834413) (xy 369.05268 -255.859817) (xy 368.999457 -255.877109) (xy 368.944185 -255.885863)
			(xy 368.916204 -255.886458) (xy 368.892742 -255.886085) (xy 368.846225 -255.879927) (xy 368.800918 -255.867717)
			(xy 368.757605 -255.849667) (xy 368.737134 -255.838198) (xy 368.723686 -255.830974) (xy 368.693952 -255.824113)
			(xy 368.663519 -255.826337) (xy 368.635099 -255.837448) (xy 368.611226 -255.856455) (xy 368.59403 -255.881663)
			(xy 368.585044 -255.910824) (xy 368.58448 -255.926082) (xy 368.58448 -256.272538) (xy 368.585002 -256.287841)
			(xy 368.594062 -256.317076) (xy 368.611361 -256.342325) (xy 368.635352 -256.36133) (xy 368.66389 -256.372393)
			(xy 368.694422 -256.374523) (xy 368.724219 -256.367531) (xy 368.737642 -256.360168) (xy 368.758296 -256.348419)
			(xy 368.802056 -256.329901) (xy 368.847891 -256.317371) (xy 368.894986 -256.311053) (xy 368.918744 -256.310638)
			(xy 368.94486 -256.311078) (xy 368.996536 -256.318671) (xy 369.046549 -256.333733) (xy 369.070382 -256.34442)
			(xy 369.084191 -256.350331) (xy 369.1139 -256.354664) (xy 369.143582 -256.350157) (xy 369.170665 -256.3372)
			(xy 369.192801 -256.316918) (xy 369.208071 -256.291068) (xy 369.212114 -256.276602) (xy 369.218842 -256.251133)
			(xy 369.238777 -256.202374) (xy 369.265679 -256.157084) (xy 369.298961 -256.116254) (xy 369.337896 -256.080773)
			(xy 369.381635 -256.051416) (xy 369.429222 -256.028826) (xy 369.479618 -256.013494) (xy 369.531723 -256.005755)
			(xy 369.558062 -256.00533) (xy 369.584712 -256.0058) (xy 369.637418 -256.013739) (xy 369.688351 -256.029445)
			(xy 369.736375 -256.052568) (xy 369.780416 -256.08259) (xy 369.81949 -256.118841) (xy 369.852724 -256.160511)
			(xy 369.879375 -256.20667) (xy 369.898849 -256.256285) (xy 369.910711 -256.308249) (xy 369.914694 -256.3614)
			(xy 369.912694 -256.388087) (xy 370.142506 -256.388087) (xy 370.142506 -256.334789) (xy 370.150449 -256.282085)
			(xy 370.166159 -256.231155) (xy 370.189285 -256.183134) (xy 370.219309 -256.139097) (xy 370.255561 -256.100026)
			(xy 370.297232 -256.066795) (xy 370.34339 -256.040146) (xy 370.393004 -256.020674) (xy 370.444966 -256.008814)
			(xy 370.498116 -256.004831) (xy 370.551266 -256.008814) (xy 370.603228 -256.020674) (xy 370.652842 -256.040146)
			(xy 370.699 -256.066795) (xy 370.740671 -256.100026) (xy 370.776923 -256.139097) (xy 370.806947 -256.183134)
			(xy 370.830073 -256.231155) (xy 370.845783 -256.282085) (xy 370.853726 -256.334789) (xy 370.854224 -256.361438)
			(xy 370.853726 -256.388087) (xy 371.082052 -256.388087) (xy 371.082052 -256.334789) (xy 371.089995 -256.282085)
			(xy 371.105705 -256.231155) (xy 371.128831 -256.183134) (xy 371.158855 -256.139097) (xy 371.195107 -256.100026)
			(xy 371.236778 -256.066795) (xy 371.282936 -256.040146) (xy 371.33255 -256.020674) (xy 371.384512 -256.008814)
			(xy 371.437662 -256.004831) (xy 371.490812 -256.008814) (xy 371.542774 -256.020674) (xy 371.592388 -256.040146)
			(xy 371.638546 -256.066795) (xy 371.680217 -256.100026) (xy 371.716469 -256.139097) (xy 371.746493 -256.183134)
			(xy 371.769619 -256.231155) (xy 371.785329 -256.282085) (xy 371.793272 -256.334789) (xy 371.79377 -256.361438)
			(xy 371.793272 -256.388087) (xy 372.021852 -256.388087) (xy 372.021852 -256.334789) (xy 372.029795 -256.282085)
			(xy 372.045505 -256.231155) (xy 372.068631 -256.183134) (xy 372.098655 -256.139097) (xy 372.134907 -256.100026)
			(xy 372.176578 -256.066795) (xy 372.222736 -256.040146) (xy 372.27235 -256.020674) (xy 372.324312 -256.008814)
			(xy 372.377462 -256.004831) (xy 372.430612 -256.008814) (xy 372.482574 -256.020674) (xy 372.532188 -256.040146)
			(xy 372.578346 -256.066795) (xy 372.620017 -256.100026) (xy 372.656269 -256.139097) (xy 372.686293 -256.183134)
			(xy 372.709419 -256.231155) (xy 372.725129 -256.282085) (xy 372.733072 -256.334789) (xy 372.73357 -256.361438)
			(xy 372.733072 -256.388087) (xy 372.961652 -256.388087) (xy 372.961652 -256.334789) (xy 372.969595 -256.282085)
			(xy 372.985305 -256.231155) (xy 373.008431 -256.183134) (xy 373.038455 -256.139097) (xy 373.074707 -256.100026)
			(xy 373.116378 -256.066795) (xy 373.162536 -256.040146) (xy 373.21215 -256.020674) (xy 373.264112 -256.008814)
			(xy 373.317262 -256.004831) (xy 373.370412 -256.008814) (xy 373.422374 -256.020674) (xy 373.471988 -256.040146)
			(xy 373.518146 -256.066795) (xy 373.559817 -256.100026) (xy 373.596069 -256.139097) (xy 373.626093 -256.183134)
			(xy 373.649219 -256.231155) (xy 373.664929 -256.282085) (xy 373.672872 -256.334789) (xy 373.67337 -256.361438)
			(xy 373.672872 -256.388087) (xy 373.901452 -256.388087) (xy 373.901452 -256.334789) (xy 373.909395 -256.282085)
			(xy 373.925105 -256.231155) (xy 373.948231 -256.183134) (xy 373.978255 -256.139097) (xy 374.014507 -256.100026)
			(xy 374.056178 -256.066795) (xy 374.102336 -256.040146) (xy 374.15195 -256.020674) (xy 374.203912 -256.008814)
			(xy 374.257062 -256.004831) (xy 374.310212 -256.008814) (xy 374.362174 -256.020674) (xy 374.411788 -256.040146)
			(xy 374.457946 -256.066795) (xy 374.499617 -256.100026) (xy 374.535869 -256.139097) (xy 374.565893 -256.183134)
			(xy 374.589019 -256.231155) (xy 374.604729 -256.282085) (xy 374.612672 -256.334789) (xy 374.61317 -256.361438)
			(xy 374.612672 -256.388087) (xy 374.841252 -256.388087) (xy 374.841252 -256.334789) (xy 374.849195 -256.282085)
			(xy 374.864905 -256.231155) (xy 374.888031 -256.183134) (xy 374.918055 -256.139097) (xy 374.954307 -256.100026)
			(xy 374.995978 -256.066795) (xy 375.042136 -256.040146) (xy 375.09175 -256.020674) (xy 375.143712 -256.008814)
			(xy 375.196862 -256.004831) (xy 375.250012 -256.008814) (xy 375.301974 -256.020674) (xy 375.351588 -256.040146)
			(xy 375.397746 -256.066795) (xy 375.439417 -256.100026) (xy 375.475669 -256.139097) (xy 375.505693 -256.183134)
			(xy 375.528819 -256.231155) (xy 375.544529 -256.282085) (xy 375.552472 -256.334789) (xy 375.55297 -256.361438)
			(xy 375.552472 -256.388087) (xy 375.781052 -256.388087) (xy 375.781052 -256.334789) (xy 375.788995 -256.282085)
			(xy 375.804705 -256.231155) (xy 375.827831 -256.183134) (xy 375.857855 -256.139097) (xy 375.894107 -256.100026)
			(xy 375.935778 -256.066795) (xy 375.981936 -256.040146) (xy 376.03155 -256.020674) (xy 376.083512 -256.008814)
			(xy 376.136662 -256.004831) (xy 376.189812 -256.008814) (xy 376.241774 -256.020674) (xy 376.291388 -256.040146)
			(xy 376.337546 -256.066795) (xy 376.379217 -256.100026) (xy 376.415469 -256.139097) (xy 376.445493 -256.183134)
			(xy 376.468619 -256.231155) (xy 376.484329 -256.282085) (xy 376.492272 -256.334789) (xy 376.49277 -256.361438)
			(xy 376.492272 -256.388087) (xy 376.721106 -256.388087) (xy 376.721106 -256.334789) (xy 376.729049 -256.282085)
			(xy 376.744759 -256.231155) (xy 376.767885 -256.183134) (xy 376.797909 -256.139097) (xy 376.834161 -256.100026)
			(xy 376.875832 -256.066795) (xy 376.92199 -256.040146) (xy 376.971604 -256.020674) (xy 377.023566 -256.008814)
			(xy 377.076716 -256.004831) (xy 377.129866 -256.008814) (xy 377.181828 -256.020674) (xy 377.231442 -256.040146)
			(xy 377.2776 -256.066795) (xy 377.319271 -256.100026) (xy 377.355523 -256.139097) (xy 377.385547 -256.183134)
			(xy 377.408673 -256.231155) (xy 377.424383 -256.282085) (xy 377.432326 -256.334789) (xy 377.432824 -256.361438)
			(xy 377.432326 -256.388087) (xy 377.660652 -256.388087) (xy 377.660652 -256.334789) (xy 377.668595 -256.282085)
			(xy 377.684305 -256.231155) (xy 377.707431 -256.183134) (xy 377.737455 -256.139097) (xy 377.773707 -256.100026)
			(xy 377.815378 -256.066795) (xy 377.861536 -256.040146) (xy 377.91115 -256.020674) (xy 377.963112 -256.008814)
			(xy 378.016262 -256.004831) (xy 378.069412 -256.008814) (xy 378.121374 -256.020674) (xy 378.170988 -256.040146)
			(xy 378.217146 -256.066795) (xy 378.258817 -256.100026) (xy 378.295069 -256.139097) (xy 378.325093 -256.183134)
			(xy 378.348219 -256.231155) (xy 378.363929 -256.282085) (xy 378.371872 -256.334789) (xy 378.37237 -256.361438)
			(xy 378.371872 -256.388087) (xy 378.600452 -256.388087) (xy 378.600452 -256.334789) (xy 378.608395 -256.282085)
			(xy 378.624105 -256.231155) (xy 378.647231 -256.183134) (xy 378.677255 -256.139097) (xy 378.713507 -256.100026)
			(xy 378.755178 -256.066795) (xy 378.801336 -256.040146) (xy 378.85095 -256.020674) (xy 378.902912 -256.008814)
			(xy 378.956062 -256.004831) (xy 379.009212 -256.008814) (xy 379.061174 -256.020674) (xy 379.110788 -256.040146)
			(xy 379.156946 -256.066795) (xy 379.198617 -256.100026) (xy 379.234869 -256.139097) (xy 379.264893 -256.183134)
			(xy 379.288019 -256.231155) (xy 379.303729 -256.282085) (xy 379.311672 -256.334789) (xy 379.31217 -256.361438)
			(xy 379.311672 -256.388087) (xy 379.540252 -256.388087) (xy 379.540252 -256.334789) (xy 379.548195 -256.282085)
			(xy 379.563905 -256.231155) (xy 379.587031 -256.183134) (xy 379.617055 -256.139097) (xy 379.653307 -256.100026)
			(xy 379.694978 -256.066795) (xy 379.741136 -256.040146) (xy 379.79075 -256.020674) (xy 379.842712 -256.008814)
			(xy 379.895862 -256.004831) (xy 379.949012 -256.008814) (xy 380.000974 -256.020674) (xy 380.050588 -256.040146)
			(xy 380.096746 -256.066795) (xy 380.138417 -256.100026) (xy 380.174669 -256.139097) (xy 380.204693 -256.183134)
			(xy 380.227819 -256.231155) (xy 380.243529 -256.282085) (xy 380.251472 -256.334789) (xy 380.25197 -256.361438)
			(xy 380.251472 -256.388087) (xy 380.243529 -256.440791) (xy 380.227819 -256.491721) (xy 380.204693 -256.539742)
			(xy 380.174669 -256.583779) (xy 380.138417 -256.62285) (xy 380.096746 -256.656081) (xy 380.050588 -256.68273)
			(xy 380.000974 -256.702202) (xy 379.949012 -256.714062) (xy 379.895862 -256.718046) (xy 379.842712 -256.714062)
			(xy 379.79075 -256.702202) (xy 379.741136 -256.68273) (xy 379.694978 -256.656081) (xy 379.653307 -256.62285)
			(xy 379.617055 -256.583779) (xy 379.587031 -256.539742) (xy 379.563905 -256.491721) (xy 379.548195 -256.440791)
			(xy 379.540252 -256.388087) (xy 379.311672 -256.388087) (xy 379.303729 -256.440791) (xy 379.288019 -256.491721)
			(xy 379.264893 -256.539742) (xy 379.234869 -256.583779) (xy 379.198617 -256.62285) (xy 379.156946 -256.656081)
			(xy 379.110788 -256.68273) (xy 379.061174 -256.702202) (xy 379.009212 -256.714062) (xy 378.956062 -256.718046)
			(xy 378.902912 -256.714062) (xy 378.85095 -256.702202) (xy 378.801336 -256.68273) (xy 378.755178 -256.656081)
			(xy 378.713507 -256.62285) (xy 378.677255 -256.583779) (xy 378.647231 -256.539742) (xy 378.624105 -256.491721)
			(xy 378.608395 -256.440791) (xy 378.600452 -256.388087) (xy 378.371872 -256.388087) (xy 378.363929 -256.440791)
			(xy 378.348219 -256.491721) (xy 378.325093 -256.539742) (xy 378.295069 -256.583779) (xy 378.258817 -256.62285)
			(xy 378.217146 -256.656081) (xy 378.170988 -256.68273) (xy 378.121374 -256.702202) (xy 378.069412 -256.714062)
			(xy 378.016262 -256.718046) (xy 377.963112 -256.714062) (xy 377.91115 -256.702202) (xy 377.861536 -256.68273)
			(xy 377.815378 -256.656081) (xy 377.773707 -256.62285) (xy 377.737455 -256.583779) (xy 377.707431 -256.539742)
			(xy 377.684305 -256.491721) (xy 377.668595 -256.440791) (xy 377.660652 -256.388087) (xy 377.432326 -256.388087)
			(xy 377.424383 -256.440791) (xy 377.408673 -256.491721) (xy 377.385547 -256.539742) (xy 377.355523 -256.583779)
			(xy 377.319271 -256.62285) (xy 377.2776 -256.656081) (xy 377.231442 -256.68273) (xy 377.181828 -256.702202)
			(xy 377.129866 -256.714062) (xy 377.076716 -256.718046) (xy 377.023566 -256.714062) (xy 376.971604 -256.702202)
			(xy 376.92199 -256.68273) (xy 376.875832 -256.656081) (xy 376.834161 -256.62285) (xy 376.797909 -256.583779)
			(xy 376.767885 -256.539742) (xy 376.744759 -256.491721) (xy 376.729049 -256.440791) (xy 376.721106 -256.388087)
			(xy 376.492272 -256.388087) (xy 376.484329 -256.440791) (xy 376.468619 -256.491721) (xy 376.445493 -256.539742)
			(xy 376.415469 -256.583779) (xy 376.379217 -256.62285) (xy 376.337546 -256.656081) (xy 376.291388 -256.68273)
			(xy 376.241774 -256.702202) (xy 376.189812 -256.714062) (xy 376.136662 -256.718046) (xy 376.083512 -256.714062)
			(xy 376.03155 -256.702202) (xy 375.981936 -256.68273) (xy 375.935778 -256.656081) (xy 375.894107 -256.62285)
			(xy 375.857855 -256.583779) (xy 375.827831 -256.539742) (xy 375.804705 -256.491721) (xy 375.788995 -256.440791)
			(xy 375.781052 -256.388087) (xy 375.552472 -256.388087) (xy 375.544529 -256.440791) (xy 375.528819 -256.491721)
			(xy 375.505693 -256.539742) (xy 375.475669 -256.583779) (xy 375.439417 -256.62285) (xy 375.397746 -256.656081)
			(xy 375.351588 -256.68273) (xy 375.301974 -256.702202) (xy 375.250012 -256.714062) (xy 375.196862 -256.718046)
			(xy 375.143712 -256.714062) (xy 375.09175 -256.702202) (xy 375.042136 -256.68273) (xy 374.995978 -256.656081)
			(xy 374.954307 -256.62285) (xy 374.918055 -256.583779) (xy 374.888031 -256.539742) (xy 374.864905 -256.491721)
			(xy 374.849195 -256.440791) (xy 374.841252 -256.388087) (xy 374.612672 -256.388087) (xy 374.604729 -256.440791)
			(xy 374.589019 -256.491721) (xy 374.565893 -256.539742) (xy 374.535869 -256.583779) (xy 374.499617 -256.62285)
			(xy 374.457946 -256.656081) (xy 374.411788 -256.68273) (xy 374.362174 -256.702202) (xy 374.310212 -256.714062)
			(xy 374.257062 -256.718046) (xy 374.203912 -256.714062) (xy 374.15195 -256.702202) (xy 374.102336 -256.68273)
			(xy 374.056178 -256.656081) (xy 374.014507 -256.62285) (xy 373.978255 -256.583779) (xy 373.948231 -256.539742)
			(xy 373.925105 -256.491721) (xy 373.909395 -256.440791) (xy 373.901452 -256.388087) (xy 373.672872 -256.388087)
			(xy 373.664929 -256.440791) (xy 373.649219 -256.491721) (xy 373.626093 -256.539742) (xy 373.596069 -256.583779)
			(xy 373.559817 -256.62285) (xy 373.518146 -256.656081) (xy 373.471988 -256.68273) (xy 373.422374 -256.702202)
			(xy 373.370412 -256.714062) (xy 373.317262 -256.718046) (xy 373.264112 -256.714062) (xy 373.21215 -256.702202)
			(xy 373.162536 -256.68273) (xy 373.116378 -256.656081) (xy 373.074707 -256.62285) (xy 373.038455 -256.583779)
			(xy 373.008431 -256.539742) (xy 372.985305 -256.491721) (xy 372.969595 -256.440791) (xy 372.961652 -256.388087)
			(xy 372.733072 -256.388087) (xy 372.725129 -256.440791) (xy 372.709419 -256.491721) (xy 372.686293 -256.539742)
			(xy 372.656269 -256.583779) (xy 372.620017 -256.62285) (xy 372.578346 -256.656081) (xy 372.532188 -256.68273)
			(xy 372.482574 -256.702202) (xy 372.430612 -256.714062) (xy 372.377462 -256.718046) (xy 372.324312 -256.714062)
			(xy 372.27235 -256.702202) (xy 372.222736 -256.68273) (xy 372.176578 -256.656081) (xy 372.134907 -256.62285)
			(xy 372.098655 -256.583779) (xy 372.068631 -256.539742) (xy 372.045505 -256.491721) (xy 372.029795 -256.440791)
			(xy 372.021852 -256.388087) (xy 371.793272 -256.388087) (xy 371.785329 -256.440791) (xy 371.769619 -256.491721)
			(xy 371.746493 -256.539742) (xy 371.716469 -256.583779) (xy 371.680217 -256.62285) (xy 371.638546 -256.656081)
			(xy 371.592388 -256.68273) (xy 371.542774 -256.702202) (xy 371.490812 -256.714062) (xy 371.437662 -256.718046)
			(xy 371.384512 -256.714062) (xy 371.33255 -256.702202) (xy 371.282936 -256.68273) (xy 371.236778 -256.656081)
			(xy 371.195107 -256.62285) (xy 371.158855 -256.583779) (xy 371.128831 -256.539742) (xy 371.105705 -256.491721)
			(xy 371.089995 -256.440791) (xy 371.082052 -256.388087) (xy 370.853726 -256.388087) (xy 370.845783 -256.440791)
			(xy 370.830073 -256.491721) (xy 370.806947 -256.539742) (xy 370.776923 -256.583779) (xy 370.740671 -256.62285)
			(xy 370.699 -256.656081) (xy 370.652842 -256.68273) (xy 370.603228 -256.702202) (xy 370.551266 -256.714062)
			(xy 370.498116 -256.718046) (xy 370.444966 -256.714062) (xy 370.393004 -256.702202) (xy 370.34339 -256.68273)
			(xy 370.297232 -256.656081) (xy 370.255561 -256.62285) (xy 370.219309 -256.583779) (xy 370.189285 -256.539742)
			(xy 370.166159 -256.491721) (xy 370.150449 -256.440791) (xy 370.142506 -256.388087) (xy 369.912694 -256.388087)
			(xy 369.910711 -256.414551) (xy 369.898849 -256.466515) (xy 369.879375 -256.51613) (xy 369.852724 -256.562289)
			(xy 369.81949 -256.603959) (xy 369.780416 -256.64021) (xy 369.736375 -256.670232) (xy 369.688351 -256.693355)
			(xy 369.637418 -256.709061) (xy 369.584712 -256.717) (xy 369.558062 -256.717546) (xy 369.531946 -256.717106)
			(xy 369.480269 -256.709514) (xy 369.430257 -256.694452) (xy 369.406424 -256.683764) (xy 369.392614 -256.677852)
			(xy 369.362904 -256.673519) (xy 369.333219 -256.678025) (xy 369.306133 -256.69098) (xy 369.283993 -256.711262)
			(xy 369.26872 -256.737111) (xy 369.264692 -256.751582) (xy 369.257012 -256.780405) (xy 369.233355 -256.835159)
			(xy 369.200883 -256.88519) (xy 369.181126 -256.907538) (xy 369.171325 -256.918984) (xy 369.158277 -256.946128)
			(xy 369.153717 -256.975898) (xy 369.158042 -257.005704) (xy 369.170876 -257.03295) (xy 369.180618 -257.044444)
			(xy 369.197788 -257.06417) (xy 369.226757 -257.107708) (xy 369.249048 -257.155014) (xy 369.263225 -257.201903)
			(xy 369.672606 -257.201903) (xy 369.672606 -257.148605) (xy 369.680549 -257.095901) (xy 369.696259 -257.044971)
			(xy 369.719385 -256.99695) (xy 369.749409 -256.952913) (xy 369.785661 -256.913842) (xy 369.827332 -256.880611)
			(xy 369.87349 -256.853962) (xy 369.923104 -256.83449) (xy 369.975066 -256.82263) (xy 370.028216 -256.818647)
			(xy 370.081366 -256.82263) (xy 370.133328 -256.83449) (xy 370.182942 -256.853962) (xy 370.2291 -256.880611)
			(xy 370.270771 -256.913842) (xy 370.307023 -256.952913) (xy 370.337047 -256.99695) (xy 370.360173 -257.044971)
			(xy 370.375883 -257.095901) (xy 370.383826 -257.148605) (xy 370.384324 -257.175254) (xy 370.383826 -257.201903)
			(xy 370.612406 -257.201903) (xy 370.612406 -257.148605) (xy 370.620349 -257.095901) (xy 370.636059 -257.044971)
			(xy 370.659185 -256.99695) (xy 370.689209 -256.952913) (xy 370.725461 -256.913842) (xy 370.767132 -256.880611)
			(xy 370.81329 -256.853962) (xy 370.862904 -256.83449) (xy 370.914866 -256.82263) (xy 370.968016 -256.818647)
			(xy 371.021166 -256.82263) (xy 371.073128 -256.83449) (xy 371.122742 -256.853962) (xy 371.1689 -256.880611)
			(xy 371.210571 -256.913842) (xy 371.246823 -256.952913) (xy 371.276847 -256.99695) (xy 371.299973 -257.044971)
			(xy 371.315683 -257.095901) (xy 371.323626 -257.148605) (xy 371.324124 -257.175254) (xy 371.323626 -257.201903)
			(xy 371.552206 -257.201903) (xy 371.552206 -257.148605) (xy 371.560149 -257.095901) (xy 371.575859 -257.044971)
			(xy 371.598985 -256.99695) (xy 371.629009 -256.952913) (xy 371.665261 -256.913842) (xy 371.706932 -256.880611)
			(xy 371.75309 -256.853962) (xy 371.802704 -256.83449) (xy 371.854666 -256.82263) (xy 371.907816 -256.818647)
			(xy 371.960966 -256.82263) (xy 372.012928 -256.83449) (xy 372.062542 -256.853962) (xy 372.1087 -256.880611)
			(xy 372.150371 -256.913842) (xy 372.186623 -256.952913) (xy 372.216647 -256.99695) (xy 372.239773 -257.044971)
			(xy 372.255483 -257.095901) (xy 372.263426 -257.148605) (xy 372.263924 -257.175254) (xy 372.263426 -257.201903)
			(xy 372.491752 -257.201903) (xy 372.491752 -257.148605) (xy 372.499695 -257.095901) (xy 372.515405 -257.044971)
			(xy 372.538531 -256.99695) (xy 372.568555 -256.952913) (xy 372.604807 -256.913842) (xy 372.646478 -256.880611)
			(xy 372.692636 -256.853962) (xy 372.74225 -256.83449) (xy 372.794212 -256.82263) (xy 372.847362 -256.818647)
			(xy 372.900512 -256.82263) (xy 372.952474 -256.83449) (xy 373.002088 -256.853962) (xy 373.048246 -256.880611)
			(xy 373.089917 -256.913842) (xy 373.126169 -256.952913) (xy 373.156193 -256.99695) (xy 373.179319 -257.044971)
			(xy 373.195029 -257.095901) (xy 373.202972 -257.148605) (xy 373.20347 -257.175254) (xy 373.202972 -257.201903)
			(xy 373.431552 -257.201903) (xy 373.431552 -257.148605) (xy 373.439495 -257.095901) (xy 373.455205 -257.044971)
			(xy 373.478331 -256.99695) (xy 373.508355 -256.952913) (xy 373.544607 -256.913842) (xy 373.586278 -256.880611)
			(xy 373.632436 -256.853962) (xy 373.68205 -256.83449) (xy 373.734012 -256.82263) (xy 373.787162 -256.818647)
			(xy 373.840312 -256.82263) (xy 373.892274 -256.83449) (xy 373.941888 -256.853962) (xy 373.988046 -256.880611)
			(xy 374.029717 -256.913842) (xy 374.065969 -256.952913) (xy 374.095993 -256.99695) (xy 374.119119 -257.044971)
			(xy 374.134829 -257.095901) (xy 374.142772 -257.148605) (xy 374.14327 -257.175254) (xy 374.142772 -257.201903)
			(xy 374.371606 -257.201903) (xy 374.371606 -257.148605) (xy 374.379549 -257.095901) (xy 374.395259 -257.044971)
			(xy 374.418385 -256.99695) (xy 374.448409 -256.952913) (xy 374.484661 -256.913842) (xy 374.526332 -256.880611)
			(xy 374.57249 -256.853962) (xy 374.622104 -256.83449) (xy 374.674066 -256.82263) (xy 374.727216 -256.818647)
			(xy 374.780366 -256.82263) (xy 374.832328 -256.83449) (xy 374.881942 -256.853962) (xy 374.9281 -256.880611)
			(xy 374.969771 -256.913842) (xy 375.006023 -256.952913) (xy 375.036047 -256.99695) (xy 375.059173 -257.044971)
			(xy 375.074883 -257.095901) (xy 375.082826 -257.148605) (xy 375.083324 -257.175254) (xy 375.082826 -257.201903)
			(xy 375.311152 -257.201903) (xy 375.311152 -257.148605) (xy 375.319095 -257.095901) (xy 375.334805 -257.044971)
			(xy 375.357931 -256.99695) (xy 375.387955 -256.952913) (xy 375.424207 -256.913842) (xy 375.465878 -256.880611)
			(xy 375.512036 -256.853962) (xy 375.56165 -256.83449) (xy 375.613612 -256.82263) (xy 375.666762 -256.818647)
			(xy 375.719912 -256.82263) (xy 375.771874 -256.83449) (xy 375.821488 -256.853962) (xy 375.867646 -256.880611)
			(xy 375.909317 -256.913842) (xy 375.945569 -256.952913) (xy 375.975593 -256.99695) (xy 375.998719 -257.044971)
			(xy 376.014429 -257.095901) (xy 376.022372 -257.148605) (xy 376.02287 -257.175254) (xy 376.022372 -257.201903)
			(xy 376.251206 -257.201903) (xy 376.251206 -257.148605) (xy 376.259149 -257.095901) (xy 376.274859 -257.044971)
			(xy 376.297985 -256.99695) (xy 376.328009 -256.952913) (xy 376.364261 -256.913842) (xy 376.405932 -256.880611)
			(xy 376.45209 -256.853962) (xy 376.501704 -256.83449) (xy 376.553666 -256.82263) (xy 376.606816 -256.818647)
			(xy 376.659966 -256.82263) (xy 376.711928 -256.83449) (xy 376.761542 -256.853962) (xy 376.8077 -256.880611)
			(xy 376.849371 -256.913842) (xy 376.885623 -256.952913) (xy 376.915647 -256.99695) (xy 376.938773 -257.044971)
			(xy 376.954483 -257.095901) (xy 376.962426 -257.148605) (xy 376.962924 -257.175254) (xy 376.962426 -257.201903)
			(xy 377.191006 -257.201903) (xy 377.191006 -257.148605) (xy 377.198949 -257.095901) (xy 377.214659 -257.044971)
			(xy 377.237785 -256.99695) (xy 377.267809 -256.952913) (xy 377.304061 -256.913842) (xy 377.345732 -256.880611)
			(xy 377.39189 -256.853962) (xy 377.441504 -256.83449) (xy 377.493466 -256.82263) (xy 377.546616 -256.818647)
			(xy 377.599766 -256.82263) (xy 377.651728 -256.83449) (xy 377.701342 -256.853962) (xy 377.7475 -256.880611)
			(xy 377.789171 -256.913842) (xy 377.825423 -256.952913) (xy 377.855447 -256.99695) (xy 377.878573 -257.044971)
			(xy 377.894283 -257.095901) (xy 377.902226 -257.148605) (xy 377.902724 -257.175254) (xy 377.902226 -257.201903)
			(xy 378.130806 -257.201903) (xy 378.130806 -257.148605) (xy 378.138749 -257.095901) (xy 378.154459 -257.044971)
			(xy 378.177585 -256.99695) (xy 378.207609 -256.952913) (xy 378.243861 -256.913842) (xy 378.285532 -256.880611)
			(xy 378.33169 -256.853962) (xy 378.381304 -256.83449) (xy 378.433266 -256.82263) (xy 378.486416 -256.818647)
			(xy 378.539566 -256.82263) (xy 378.591528 -256.83449) (xy 378.641142 -256.853962) (xy 378.6873 -256.880611)
			(xy 378.728971 -256.913842) (xy 378.765223 -256.952913) (xy 378.795247 -256.99695) (xy 378.818373 -257.044971)
			(xy 378.834083 -257.095901) (xy 378.842026 -257.148605) (xy 378.842524 -257.175254) (xy 378.842026 -257.201903)
			(xy 379.070606 -257.201903) (xy 379.070606 -257.148605) (xy 379.078549 -257.095901) (xy 379.094259 -257.044971)
			(xy 379.117385 -256.99695) (xy 379.147409 -256.952913) (xy 379.183661 -256.913842) (xy 379.225332 -256.880611)
			(xy 379.27149 -256.853962) (xy 379.321104 -256.83449) (xy 379.373066 -256.82263) (xy 379.426216 -256.818647)
			(xy 379.479366 -256.82263) (xy 379.531328 -256.83449) (xy 379.580942 -256.853962) (xy 379.6271 -256.880611)
			(xy 379.668771 -256.913842) (xy 379.705023 -256.952913) (xy 379.735047 -256.99695) (xy 379.758173 -257.044971)
			(xy 379.773883 -257.095901) (xy 379.781826 -257.148605) (xy 379.782324 -257.175254) (xy 379.781826 -257.201903)
			(xy 380.010152 -257.201903) (xy 380.010152 -257.148605) (xy 380.018095 -257.095901) (xy 380.033805 -257.044971)
			(xy 380.056931 -256.99695) (xy 380.086955 -256.952913) (xy 380.123207 -256.913842) (xy 380.164878 -256.880611)
			(xy 380.211036 -256.853962) (xy 380.26065 -256.83449) (xy 380.312612 -256.82263) (xy 380.365762 -256.818647)
			(xy 380.418912 -256.82263) (xy 380.470874 -256.83449) (xy 380.520488 -256.853962) (xy 380.566646 -256.880611)
			(xy 380.608317 -256.913842) (xy 380.644569 -256.952913) (xy 380.674593 -256.99695) (xy 380.697719 -257.044971)
			(xy 380.713429 -257.095901) (xy 380.721372 -257.148605) (xy 380.72187 -257.175254) (xy 380.721372 -257.201903)
			(xy 380.713429 -257.254607) (xy 380.697719 -257.305537) (xy 380.674593 -257.353558) (xy 380.644569 -257.397595)
			(xy 380.608317 -257.436666) (xy 380.566646 -257.469897) (xy 380.520488 -257.496546) (xy 380.470874 -257.516018)
			(xy 380.418912 -257.527878) (xy 380.365762 -257.531862) (xy 380.312612 -257.527878) (xy 380.26065 -257.516018)
			(xy 380.211036 -257.496546) (xy 380.164878 -257.469897) (xy 380.123207 -257.436666) (xy 380.086955 -257.397595)
			(xy 380.056931 -257.353558) (xy 380.033805 -257.305537) (xy 380.018095 -257.254607) (xy 380.010152 -257.201903)
			(xy 379.781826 -257.201903) (xy 379.773883 -257.254607) (xy 379.758173 -257.305537) (xy 379.735047 -257.353558)
			(xy 379.705023 -257.397595) (xy 379.668771 -257.436666) (xy 379.6271 -257.469897) (xy 379.580942 -257.496546)
			(xy 379.531328 -257.516018) (xy 379.479366 -257.527878) (xy 379.426216 -257.531862) (xy 379.373066 -257.527878)
			(xy 379.321104 -257.516018) (xy 379.27149 -257.496546) (xy 379.225332 -257.469897) (xy 379.183661 -257.436666)
			(xy 379.147409 -257.397595) (xy 379.117385 -257.353558) (xy 379.094259 -257.305537) (xy 379.078549 -257.254607)
			(xy 379.070606 -257.201903) (xy 378.842026 -257.201903) (xy 378.834083 -257.254607) (xy 378.818373 -257.305537)
			(xy 378.795247 -257.353558) (xy 378.765223 -257.397595) (xy 378.728971 -257.436666) (xy 378.6873 -257.469897)
			(xy 378.641142 -257.496546) (xy 378.591528 -257.516018) (xy 378.539566 -257.527878) (xy 378.486416 -257.531862)
			(xy 378.433266 -257.527878) (xy 378.381304 -257.516018) (xy 378.33169 -257.496546) (xy 378.285532 -257.469897)
			(xy 378.243861 -257.436666) (xy 378.207609 -257.397595) (xy 378.177585 -257.353558) (xy 378.154459 -257.305537)
			(xy 378.138749 -257.254607) (xy 378.130806 -257.201903) (xy 377.902226 -257.201903) (xy 377.894283 -257.254607)
			(xy 377.878573 -257.305537) (xy 377.855447 -257.353558) (xy 377.825423 -257.397595) (xy 377.789171 -257.436666)
			(xy 377.7475 -257.469897) (xy 377.701342 -257.496546) (xy 377.651728 -257.516018) (xy 377.599766 -257.527878)
			(xy 377.546616 -257.531862) (xy 377.493466 -257.527878) (xy 377.441504 -257.516018) (xy 377.39189 -257.496546)
			(xy 377.345732 -257.469897) (xy 377.304061 -257.436666) (xy 377.267809 -257.397595) (xy 377.237785 -257.353558)
			(xy 377.214659 -257.305537) (xy 377.198949 -257.254607) (xy 377.191006 -257.201903) (xy 376.962426 -257.201903)
			(xy 376.954483 -257.254607) (xy 376.938773 -257.305537) (xy 376.915647 -257.353558) (xy 376.885623 -257.397595)
			(xy 376.849371 -257.436666) (xy 376.8077 -257.469897) (xy 376.761542 -257.496546) (xy 376.711928 -257.516018)
			(xy 376.659966 -257.527878) (xy 376.606816 -257.531862) (xy 376.553666 -257.527878) (xy 376.501704 -257.516018)
			(xy 376.45209 -257.496546) (xy 376.405932 -257.469897) (xy 376.364261 -257.436666) (xy 376.328009 -257.397595)
			(xy 376.297985 -257.353558) (xy 376.274859 -257.305537) (xy 376.259149 -257.254607) (xy 376.251206 -257.201903)
			(xy 376.022372 -257.201903) (xy 376.014429 -257.254607) (xy 375.998719 -257.305537) (xy 375.975593 -257.353558)
			(xy 375.945569 -257.397595) (xy 375.909317 -257.436666) (xy 375.867646 -257.469897) (xy 375.821488 -257.496546)
			(xy 375.771874 -257.516018) (xy 375.719912 -257.527878) (xy 375.666762 -257.531862) (xy 375.613612 -257.527878)
			(xy 375.56165 -257.516018) (xy 375.512036 -257.496546) (xy 375.465878 -257.469897) (xy 375.424207 -257.436666)
			(xy 375.387955 -257.397595) (xy 375.357931 -257.353558) (xy 375.334805 -257.305537) (xy 375.319095 -257.254607)
			(xy 375.311152 -257.201903) (xy 375.082826 -257.201903) (xy 375.074883 -257.254607) (xy 375.059173 -257.305537)
			(xy 375.036047 -257.353558) (xy 375.006023 -257.397595) (xy 374.969771 -257.436666) (xy 374.9281 -257.469897)
			(xy 374.881942 -257.496546) (xy 374.832328 -257.516018) (xy 374.780366 -257.527878) (xy 374.727216 -257.531862)
			(xy 374.674066 -257.527878) (xy 374.622104 -257.516018) (xy 374.57249 -257.496546) (xy 374.526332 -257.469897)
			(xy 374.484661 -257.436666) (xy 374.448409 -257.397595) (xy 374.418385 -257.353558) (xy 374.395259 -257.305537)
			(xy 374.379549 -257.254607) (xy 374.371606 -257.201903) (xy 374.142772 -257.201903) (xy 374.134829 -257.254607)
			(xy 374.119119 -257.305537) (xy 374.095993 -257.353558) (xy 374.065969 -257.397595) (xy 374.029717 -257.436666)
			(xy 373.988046 -257.469897) (xy 373.941888 -257.496546) (xy 373.892274 -257.516018) (xy 373.840312 -257.527878)
			(xy 373.787162 -257.531862) (xy 373.734012 -257.527878) (xy 373.68205 -257.516018) (xy 373.632436 -257.496546)
			(xy 373.586278 -257.469897) (xy 373.544607 -257.436666) (xy 373.508355 -257.397595) (xy 373.478331 -257.353558)
			(xy 373.455205 -257.305537) (xy 373.439495 -257.254607) (xy 373.431552 -257.201903) (xy 373.202972 -257.201903)
			(xy 373.195029 -257.254607) (xy 373.179319 -257.305537) (xy 373.156193 -257.353558) (xy 373.126169 -257.397595)
			(xy 373.089917 -257.436666) (xy 373.048246 -257.469897) (xy 373.002088 -257.496546) (xy 372.952474 -257.516018)
			(xy 372.900512 -257.527878) (xy 372.847362 -257.531862) (xy 372.794212 -257.527878) (xy 372.74225 -257.516018)
			(xy 372.692636 -257.496546) (xy 372.646478 -257.469897) (xy 372.604807 -257.436666) (xy 372.568555 -257.397595)
			(xy 372.538531 -257.353558) (xy 372.515405 -257.305537) (xy 372.499695 -257.254607) (xy 372.491752 -257.201903)
			(xy 372.263426 -257.201903) (xy 372.255483 -257.254607) (xy 372.239773 -257.305537) (xy 372.216647 -257.353558)
			(xy 372.186623 -257.397595) (xy 372.150371 -257.436666) (xy 372.1087 -257.469897) (xy 372.062542 -257.496546)
			(xy 372.012928 -257.516018) (xy 371.960966 -257.527878) (xy 371.907816 -257.531862) (xy 371.854666 -257.527878)
			(xy 371.802704 -257.516018) (xy 371.75309 -257.496546) (xy 371.706932 -257.469897) (xy 371.665261 -257.436666)
			(xy 371.629009 -257.397595) (xy 371.598985 -257.353558) (xy 371.575859 -257.305537) (xy 371.560149 -257.254607)
			(xy 371.552206 -257.201903) (xy 371.323626 -257.201903) (xy 371.315683 -257.254607) (xy 371.299973 -257.305537)
			(xy 371.276847 -257.353558) (xy 371.246823 -257.397595) (xy 371.210571 -257.436666) (xy 371.1689 -257.469897)
			(xy 371.122742 -257.496546) (xy 371.073128 -257.516018) (xy 371.021166 -257.527878) (xy 370.968016 -257.531862)
			(xy 370.914866 -257.527878) (xy 370.862904 -257.516018) (xy 370.81329 -257.496546) (xy 370.767132 -257.469897)
			(xy 370.725461 -257.436666) (xy 370.689209 -257.397595) (xy 370.659185 -257.353558) (xy 370.636059 -257.305537)
			(xy 370.620349 -257.254607) (xy 370.612406 -257.201903) (xy 370.383826 -257.201903) (xy 370.375883 -257.254607)
			(xy 370.360173 -257.305537) (xy 370.337047 -257.353558) (xy 370.307023 -257.397595) (xy 370.270771 -257.436666)
			(xy 370.2291 -257.469897) (xy 370.182942 -257.496546) (xy 370.133328 -257.516018) (xy 370.081366 -257.527878)
			(xy 370.028216 -257.531862) (xy 369.975066 -257.527878) (xy 369.923104 -257.516018) (xy 369.87349 -257.496546)
			(xy 369.827332 -257.469897) (xy 369.785661 -257.436666) (xy 369.749409 -257.397595) (xy 369.719385 -257.353558)
			(xy 369.696259 -257.305537) (xy 369.680549 -257.254607) (xy 369.672606 -257.201903) (xy 369.263225 -257.201903)
			(xy 369.264183 -257.205071) (xy 369.271837 -257.256803) (xy 369.272312 -257.28295) (xy 369.271759 -257.310931)
			(xy 369.262998 -257.366202) (xy 369.245699 -257.419423) (xy 369.220288 -257.469282) (xy 369.187392 -257.514553)
			(xy 369.147818 -257.554121) (xy 369.102543 -257.587013) (xy 369.05268 -257.612417) (xy 368.999457 -257.629709)
			(xy 368.944185 -257.638463) (xy 368.916204 -257.639058) (xy 368.892742 -257.638685) (xy 368.846225 -257.632527)
			(xy 368.800918 -257.620317) (xy 368.757605 -257.602267) (xy 368.737134 -257.590798) (xy 368.723686 -257.583574)
			(xy 368.693952 -257.576713) (xy 368.663519 -257.578937) (xy 368.635099 -257.590048) (xy 368.611226 -257.609055)
			(xy 368.59403 -257.634263) (xy 368.585044 -257.663424) (xy 368.58448 -257.678682) (xy 368.58448 -258.015719)
			(xy 370.142252 -258.015719) (xy 370.142252 -257.962421) (xy 370.150195 -257.909717) (xy 370.165905 -257.858787)
			(xy 370.189031 -257.810766) (xy 370.219055 -257.766729) (xy 370.255307 -257.727658) (xy 370.296978 -257.694427)
			(xy 370.343136 -257.667778) (xy 370.39275 -257.648306) (xy 370.444712 -257.636446) (xy 370.497862 -257.632463)
			(xy 370.551012 -257.636446) (xy 370.602974 -257.648306) (xy 370.652588 -257.667778) (xy 370.698746 -257.694427)
			(xy 370.740417 -257.727658) (xy 370.776669 -257.766729) (xy 370.806693 -257.810766) (xy 370.829819 -257.858787)
			(xy 370.845529 -257.909717) (xy 370.853472 -257.962421) (xy 370.85397 -257.98907) (xy 370.853472 -258.015719)
			(xy 371.082052 -258.015719) (xy 371.082052 -257.962421) (xy 371.089995 -257.909717) (xy 371.105705 -257.858787)
			(xy 371.128831 -257.810766) (xy 371.158855 -257.766729) (xy 371.195107 -257.727658) (xy 371.236778 -257.694427)
			(xy 371.282936 -257.667778) (xy 371.33255 -257.648306) (xy 371.384512 -257.636446) (xy 371.437662 -257.632463)
			(xy 371.490812 -257.636446) (xy 371.542774 -257.648306) (xy 371.592388 -257.667778) (xy 371.638546 -257.694427)
			(xy 371.680217 -257.727658) (xy 371.716469 -257.766729) (xy 371.746493 -257.810766) (xy 371.769619 -257.858787)
			(xy 371.785329 -257.909717) (xy 371.793272 -257.962421) (xy 371.79377 -257.98907) (xy 371.793272 -258.015719)
			(xy 372.021852 -258.015719) (xy 372.021852 -257.962421) (xy 372.029795 -257.909717) (xy 372.045505 -257.858787)
			(xy 372.068631 -257.810766) (xy 372.098655 -257.766729) (xy 372.134907 -257.727658) (xy 372.176578 -257.694427)
			(xy 372.222736 -257.667778) (xy 372.27235 -257.648306) (xy 372.324312 -257.636446) (xy 372.377462 -257.632463)
			(xy 372.430612 -257.636446) (xy 372.482574 -257.648306) (xy 372.532188 -257.667778) (xy 372.578346 -257.694427)
			(xy 372.620017 -257.727658) (xy 372.656269 -257.766729) (xy 372.686293 -257.810766) (xy 372.709419 -257.858787)
			(xy 372.725129 -257.909717) (xy 372.733072 -257.962421) (xy 372.73357 -257.98907) (xy 372.733072 -258.015719)
			(xy 372.961906 -258.015719) (xy 372.961906 -257.962421) (xy 372.969849 -257.909717) (xy 372.985559 -257.858787)
			(xy 373.008685 -257.810766) (xy 373.038709 -257.766729) (xy 373.074961 -257.727658) (xy 373.116632 -257.694427)
			(xy 373.16279 -257.667778) (xy 373.212404 -257.648306) (xy 373.264366 -257.636446) (xy 373.317516 -257.632463)
			(xy 373.370666 -257.636446) (xy 373.422628 -257.648306) (xy 373.472242 -257.667778) (xy 373.5184 -257.694427)
			(xy 373.560071 -257.727658) (xy 373.596323 -257.766729) (xy 373.626347 -257.810766) (xy 373.649473 -257.858787)
			(xy 373.665183 -257.909717) (xy 373.673126 -257.962421) (xy 373.673624 -257.98907) (xy 373.673126 -258.015719)
			(xy 373.901452 -258.015719) (xy 373.901452 -257.962421) (xy 373.909395 -257.909717) (xy 373.925105 -257.858787)
			(xy 373.948231 -257.810766) (xy 373.978255 -257.766729) (xy 374.014507 -257.727658) (xy 374.056178 -257.694427)
			(xy 374.102336 -257.667778) (xy 374.15195 -257.648306) (xy 374.203912 -257.636446) (xy 374.257062 -257.632463)
			(xy 374.310212 -257.636446) (xy 374.362174 -257.648306) (xy 374.411788 -257.667778) (xy 374.457946 -257.694427)
			(xy 374.499617 -257.727658) (xy 374.535869 -257.766729) (xy 374.565893 -257.810766) (xy 374.589019 -257.858787)
			(xy 374.604729 -257.909717) (xy 374.612672 -257.962421) (xy 374.61317 -257.98907) (xy 374.612672 -258.015719)
			(xy 374.841506 -258.015719) (xy 374.841506 -257.962421) (xy 374.849449 -257.909717) (xy 374.865159 -257.858787)
			(xy 374.888285 -257.810766) (xy 374.918309 -257.766729) (xy 374.954561 -257.727658) (xy 374.996232 -257.694427)
			(xy 375.04239 -257.667778) (xy 375.092004 -257.648306) (xy 375.143966 -257.636446) (xy 375.197116 -257.632463)
			(xy 375.250266 -257.636446) (xy 375.302228 -257.648306) (xy 375.351842 -257.667778) (xy 375.398 -257.694427)
			(xy 375.439671 -257.727658) (xy 375.475923 -257.766729) (xy 375.505947 -257.810766) (xy 375.529073 -257.858787)
			(xy 375.544783 -257.909717) (xy 375.552726 -257.962421) (xy 375.553224 -257.98907) (xy 375.552726 -258.015719)
			(xy 375.781052 -258.015719) (xy 375.781052 -257.962421) (xy 375.788995 -257.909717) (xy 375.804705 -257.858787)
			(xy 375.827831 -257.810766) (xy 375.857855 -257.766729) (xy 375.894107 -257.727658) (xy 375.935778 -257.694427)
			(xy 375.981936 -257.667778) (xy 376.03155 -257.648306) (xy 376.083512 -257.636446) (xy 376.136662 -257.632463)
			(xy 376.189812 -257.636446) (xy 376.241774 -257.648306) (xy 376.291388 -257.667778) (xy 376.337546 -257.694427)
			(xy 376.379217 -257.727658) (xy 376.415469 -257.766729) (xy 376.445493 -257.810766) (xy 376.468619 -257.858787)
			(xy 376.484329 -257.909717) (xy 376.492272 -257.962421) (xy 376.49277 -257.98907) (xy 376.492272 -258.015719)
			(xy 376.720852 -258.015719) (xy 376.720852 -257.962421) (xy 376.728795 -257.909717) (xy 376.744505 -257.858787)
			(xy 376.767631 -257.810766) (xy 376.797655 -257.766729) (xy 376.833907 -257.727658) (xy 376.875578 -257.694427)
			(xy 376.921736 -257.667778) (xy 376.97135 -257.648306) (xy 377.023312 -257.636446) (xy 377.076462 -257.632463)
			(xy 377.129612 -257.636446) (xy 377.181574 -257.648306) (xy 377.231188 -257.667778) (xy 377.277346 -257.694427)
			(xy 377.319017 -257.727658) (xy 377.355269 -257.766729) (xy 377.385293 -257.810766) (xy 377.408419 -257.858787)
			(xy 377.424129 -257.909717) (xy 377.432072 -257.962421) (xy 377.43257 -257.98907) (xy 377.432072 -258.015719)
			(xy 377.660652 -258.015719) (xy 377.660652 -257.962421) (xy 377.668595 -257.909717) (xy 377.684305 -257.858787)
			(xy 377.707431 -257.810766) (xy 377.737455 -257.766729) (xy 377.773707 -257.727658) (xy 377.815378 -257.694427)
			(xy 377.861536 -257.667778) (xy 377.91115 -257.648306) (xy 377.963112 -257.636446) (xy 378.016262 -257.632463)
			(xy 378.069412 -257.636446) (xy 378.121374 -257.648306) (xy 378.170988 -257.667778) (xy 378.217146 -257.694427)
			(xy 378.258817 -257.727658) (xy 378.295069 -257.766729) (xy 378.325093 -257.810766) (xy 378.348219 -257.858787)
			(xy 378.363929 -257.909717) (xy 378.371872 -257.962421) (xy 378.37237 -257.98907) (xy 378.371872 -258.015719)
			(xy 378.600452 -258.015719) (xy 378.600452 -257.962421) (xy 378.608395 -257.909717) (xy 378.624105 -257.858787)
			(xy 378.647231 -257.810766) (xy 378.677255 -257.766729) (xy 378.713507 -257.727658) (xy 378.755178 -257.694427)
			(xy 378.801336 -257.667778) (xy 378.85095 -257.648306) (xy 378.902912 -257.636446) (xy 378.956062 -257.632463)
			(xy 379.009212 -257.636446) (xy 379.061174 -257.648306) (xy 379.110788 -257.667778) (xy 379.156946 -257.694427)
			(xy 379.198617 -257.727658) (xy 379.234869 -257.766729) (xy 379.264893 -257.810766) (xy 379.288019 -257.858787)
			(xy 379.303729 -257.909717) (xy 379.311672 -257.962421) (xy 379.31217 -257.98907) (xy 379.311672 -258.015719)
			(xy 379.540506 -258.015719) (xy 379.540506 -257.962421) (xy 379.548449 -257.909717) (xy 379.564159 -257.858787)
			(xy 379.587285 -257.810766) (xy 379.617309 -257.766729) (xy 379.653561 -257.727658) (xy 379.695232 -257.694427)
			(xy 379.74139 -257.667778) (xy 379.791004 -257.648306) (xy 379.842966 -257.636446) (xy 379.896116 -257.632463)
			(xy 379.949266 -257.636446) (xy 380.001228 -257.648306) (xy 380.050842 -257.667778) (xy 380.097 -257.694427)
			(xy 380.138671 -257.727658) (xy 380.174923 -257.766729) (xy 380.204947 -257.810766) (xy 380.228073 -257.858787)
			(xy 380.243783 -257.909717) (xy 380.251726 -257.962421) (xy 380.252224 -257.98907) (xy 380.251726 -258.015719)
			(xy 380.243783 -258.068423) (xy 380.228073 -258.119353) (xy 380.204947 -258.167374) (xy 380.174923 -258.211411)
			(xy 380.138671 -258.250482) (xy 380.097 -258.283713) (xy 380.050842 -258.310362) (xy 380.001228 -258.329834)
			(xy 379.949266 -258.341694) (xy 379.896116 -258.345678) (xy 379.842966 -258.341694) (xy 379.791004 -258.329834)
			(xy 379.74139 -258.310362) (xy 379.695232 -258.283713) (xy 379.653561 -258.250482) (xy 379.617309 -258.211411)
			(xy 379.587285 -258.167374) (xy 379.564159 -258.119353) (xy 379.548449 -258.068423) (xy 379.540506 -258.015719)
			(xy 379.311672 -258.015719) (xy 379.303729 -258.068423) (xy 379.288019 -258.119353) (xy 379.264893 -258.167374)
			(xy 379.234869 -258.211411) (xy 379.198617 -258.250482) (xy 379.156946 -258.283713) (xy 379.110788 -258.310362)
			(xy 379.061174 -258.329834) (xy 379.009212 -258.341694) (xy 378.956062 -258.345678) (xy 378.902912 -258.341694)
			(xy 378.85095 -258.329834) (xy 378.801336 -258.310362) (xy 378.755178 -258.283713) (xy 378.713507 -258.250482)
			(xy 378.677255 -258.211411) (xy 378.647231 -258.167374) (xy 378.624105 -258.119353) (xy 378.608395 -258.068423)
			(xy 378.600452 -258.015719) (xy 378.371872 -258.015719) (xy 378.363929 -258.068423) (xy 378.348219 -258.119353)
			(xy 378.325093 -258.167374) (xy 378.295069 -258.211411) (xy 378.258817 -258.250482) (xy 378.217146 -258.283713)
			(xy 378.170988 -258.310362) (xy 378.121374 -258.329834) (xy 378.069412 -258.341694) (xy 378.016262 -258.345678)
			(xy 377.963112 -258.341694) (xy 377.91115 -258.329834) (xy 377.861536 -258.310362) (xy 377.815378 -258.283713)
			(xy 377.773707 -258.250482) (xy 377.737455 -258.211411) (xy 377.707431 -258.167374) (xy 377.684305 -258.119353)
			(xy 377.668595 -258.068423) (xy 377.660652 -258.015719) (xy 377.432072 -258.015719) (xy 377.424129 -258.068423)
			(xy 377.408419 -258.119353) (xy 377.385293 -258.167374) (xy 377.355269 -258.211411) (xy 377.319017 -258.250482)
			(xy 377.277346 -258.283713) (xy 377.231188 -258.310362) (xy 377.181574 -258.329834) (xy 377.129612 -258.341694)
			(xy 377.076462 -258.345678) (xy 377.023312 -258.341694) (xy 376.97135 -258.329834) (xy 376.921736 -258.310362)
			(xy 376.875578 -258.283713) (xy 376.833907 -258.250482) (xy 376.797655 -258.211411) (xy 376.767631 -258.167374)
			(xy 376.744505 -258.119353) (xy 376.728795 -258.068423) (xy 376.720852 -258.015719) (xy 376.492272 -258.015719)
			(xy 376.484329 -258.068423) (xy 376.468619 -258.119353) (xy 376.445493 -258.167374) (xy 376.415469 -258.211411)
			(xy 376.379217 -258.250482) (xy 376.337546 -258.283713) (xy 376.291388 -258.310362) (xy 376.241774 -258.329834)
			(xy 376.189812 -258.341694) (xy 376.136662 -258.345678) (xy 376.083512 -258.341694) (xy 376.03155 -258.329834)
			(xy 375.981936 -258.310362) (xy 375.935778 -258.283713) (xy 375.894107 -258.250482) (xy 375.857855 -258.211411)
			(xy 375.827831 -258.167374) (xy 375.804705 -258.119353) (xy 375.788995 -258.068423) (xy 375.781052 -258.015719)
			(xy 375.552726 -258.015719) (xy 375.544783 -258.068423) (xy 375.529073 -258.119353) (xy 375.505947 -258.167374)
			(xy 375.475923 -258.211411) (xy 375.439671 -258.250482) (xy 375.398 -258.283713) (xy 375.351842 -258.310362)
			(xy 375.302228 -258.329834) (xy 375.250266 -258.341694) (xy 375.197116 -258.345678) (xy 375.143966 -258.341694)
			(xy 375.092004 -258.329834) (xy 375.04239 -258.310362) (xy 374.996232 -258.283713) (xy 374.954561 -258.250482)
			(xy 374.918309 -258.211411) (xy 374.888285 -258.167374) (xy 374.865159 -258.119353) (xy 374.849449 -258.068423)
			(xy 374.841506 -258.015719) (xy 374.612672 -258.015719) (xy 374.604729 -258.068423) (xy 374.589019 -258.119353)
			(xy 374.565893 -258.167374) (xy 374.535869 -258.211411) (xy 374.499617 -258.250482) (xy 374.457946 -258.283713)
			(xy 374.411788 -258.310362) (xy 374.362174 -258.329834) (xy 374.310212 -258.341694) (xy 374.257062 -258.345678)
			(xy 374.203912 -258.341694) (xy 374.15195 -258.329834) (xy 374.102336 -258.310362) (xy 374.056178 -258.283713)
			(xy 374.014507 -258.250482) (xy 373.978255 -258.211411) (xy 373.948231 -258.167374) (xy 373.925105 -258.119353)
			(xy 373.909395 -258.068423) (xy 373.901452 -258.015719) (xy 373.673126 -258.015719) (xy 373.665183 -258.068423)
			(xy 373.649473 -258.119353) (xy 373.626347 -258.167374) (xy 373.596323 -258.211411) (xy 373.560071 -258.250482)
			(xy 373.5184 -258.283713) (xy 373.472242 -258.310362) (xy 373.422628 -258.329834) (xy 373.370666 -258.341694)
			(xy 373.317516 -258.345678) (xy 373.264366 -258.341694) (xy 373.212404 -258.329834) (xy 373.16279 -258.310362)
			(xy 373.116632 -258.283713) (xy 373.074961 -258.250482) (xy 373.038709 -258.211411) (xy 373.008685 -258.167374)
			(xy 372.985559 -258.119353) (xy 372.969849 -258.068423) (xy 372.961906 -258.015719) (xy 372.733072 -258.015719)
			(xy 372.725129 -258.068423) (xy 372.709419 -258.119353) (xy 372.686293 -258.167374) (xy 372.656269 -258.211411)
			(xy 372.620017 -258.250482) (xy 372.578346 -258.283713) (xy 372.532188 -258.310362) (xy 372.482574 -258.329834)
			(xy 372.430612 -258.341694) (xy 372.377462 -258.345678) (xy 372.324312 -258.341694) (xy 372.27235 -258.329834)
			(xy 372.222736 -258.310362) (xy 372.176578 -258.283713) (xy 372.134907 -258.250482) (xy 372.098655 -258.211411)
			(xy 372.068631 -258.167374) (xy 372.045505 -258.119353) (xy 372.029795 -258.068423) (xy 372.021852 -258.015719)
			(xy 371.793272 -258.015719) (xy 371.785329 -258.068423) (xy 371.769619 -258.119353) (xy 371.746493 -258.167374)
			(xy 371.716469 -258.211411) (xy 371.680217 -258.250482) (xy 371.638546 -258.283713) (xy 371.592388 -258.310362)
			(xy 371.542774 -258.329834) (xy 371.490812 -258.341694) (xy 371.437662 -258.345678) (xy 371.384512 -258.341694)
			(xy 371.33255 -258.329834) (xy 371.282936 -258.310362) (xy 371.236778 -258.283713) (xy 371.195107 -258.250482)
			(xy 371.158855 -258.211411) (xy 371.128831 -258.167374) (xy 371.105705 -258.119353) (xy 371.089995 -258.068423)
			(xy 371.082052 -258.015719) (xy 370.853472 -258.015719) (xy 370.845529 -258.068423) (xy 370.829819 -258.119353)
			(xy 370.806693 -258.167374) (xy 370.776669 -258.211411) (xy 370.740417 -258.250482) (xy 370.698746 -258.283713)
			(xy 370.652588 -258.310362) (xy 370.602974 -258.329834) (xy 370.551012 -258.341694) (xy 370.497862 -258.345678)
			(xy 370.444712 -258.341694) (xy 370.39275 -258.329834) (xy 370.343136 -258.310362) (xy 370.296978 -258.283713)
			(xy 370.255307 -258.250482) (xy 370.219055 -258.211411) (xy 370.189031 -258.167374) (xy 370.165905 -258.119353)
			(xy 370.150195 -258.068423) (xy 370.142252 -258.015719) (xy 368.58448 -258.015719) (xy 368.58448 -258.055618)
			(xy 368.584994 -258.070874) (xy 368.594002 -258.100027) (xy 368.611211 -258.125223) (xy 368.635088 -258.14422)
			(xy 368.663508 -258.155326) (xy 368.693939 -258.157553) (xy 368.723672 -258.150701) (xy 368.737134 -258.143502)
			(xy 368.757606 -258.132035) (xy 368.800918 -258.113985) (xy 368.846225 -258.101776) (xy 368.892742 -258.095618)
			(xy 368.916204 -258.095242) (xy 368.942849 -258.09574) (xy 368.995545 -258.103683) (xy 369.046468 -258.119392)
			(xy 369.094481 -258.142514) (xy 369.138511 -258.172534) (xy 369.177576 -258.208781) (xy 369.210802 -258.250446)
			(xy 369.237447 -258.296597) (xy 369.256916 -258.346204) (xy 369.268775 -258.398158) (xy 369.272757 -258.4513)
			(xy 369.268775 -258.504442) (xy 369.256916 -258.556396) (xy 369.237447 -258.606003) (xy 369.210802 -258.652154)
			(xy 369.177576 -258.693819) (xy 369.138511 -258.730066) (xy 369.094481 -258.760086) (xy 369.046468 -258.783208)
			(xy 368.995545 -258.798917) (xy 368.942849 -258.80686) (xy 368.916204 -258.807458) (xy 368.892742 -258.807085)
			(xy 368.846225 -258.800927) (xy 368.800918 -258.788717) (xy 368.757605 -258.770667) (xy 368.737134 -258.759198)
			(xy 368.723686 -258.751974) (xy 368.693952 -258.745113) (xy 368.663519 -258.747337) (xy 368.635099 -258.758448)
			(xy 368.611226 -258.777455) (xy 368.59403 -258.802663) (xy 368.585671 -258.829789) (xy 370.612152 -258.829789)
			(xy 370.612152 -258.776491) (xy 370.620095 -258.723787) (xy 370.635805 -258.672857) (xy 370.658931 -258.624836)
			(xy 370.688955 -258.580799) (xy 370.725207 -258.541728) (xy 370.766878 -258.508497) (xy 370.813036 -258.481848)
			(xy 370.86265 -258.462376) (xy 370.914612 -258.450516) (xy 370.967762 -258.446533) (xy 371.020912 -258.450516)
			(xy 371.072874 -258.462376) (xy 371.122488 -258.481848) (xy 371.168646 -258.508497) (xy 371.210317 -258.541728)
			(xy 371.246569 -258.580799) (xy 371.276593 -258.624836) (xy 371.299719 -258.672857) (xy 371.315429 -258.723787)
			(xy 371.323372 -258.776491) (xy 371.32387 -258.80314) (xy 371.323372 -258.829789) (xy 371.552206 -258.829789)
			(xy 371.552206 -258.776491) (xy 371.560149 -258.723787) (xy 371.575859 -258.672857) (xy 371.598985 -258.624836)
			(xy 371.629009 -258.580799) (xy 371.665261 -258.541728) (xy 371.706932 -258.508497) (xy 371.75309 -258.481848)
			(xy 371.802704 -258.462376) (xy 371.854666 -258.450516) (xy 371.907816 -258.446533) (xy 371.960966 -258.450516)
			(xy 372.012928 -258.462376) (xy 372.062542 -258.481848) (xy 372.1087 -258.508497) (xy 372.150371 -258.541728)
			(xy 372.186623 -258.580799) (xy 372.216647 -258.624836) (xy 372.239773 -258.672857) (xy 372.255483 -258.723787)
			(xy 372.263426 -258.776491) (xy 372.263924 -258.80314) (xy 372.263426 -258.829789) (xy 372.492006 -258.829789)
			(xy 372.492006 -258.776491) (xy 372.499949 -258.723787) (xy 372.515659 -258.672857) (xy 372.538785 -258.624836)
			(xy 372.568809 -258.580799) (xy 372.605061 -258.541728) (xy 372.646732 -258.508497) (xy 372.69289 -258.481848)
			(xy 372.742504 -258.462376) (xy 372.794466 -258.450516) (xy 372.847616 -258.446533) (xy 372.900766 -258.450516)
			(xy 372.952728 -258.462376) (xy 373.002342 -258.481848) (xy 373.0485 -258.508497) (xy 373.090171 -258.541728)
			(xy 373.126423 -258.580799) (xy 373.156447 -258.624836) (xy 373.179573 -258.672857) (xy 373.195283 -258.723787)
			(xy 373.203226 -258.776491) (xy 373.203724 -258.80314) (xy 373.203226 -258.829789) (xy 373.431806 -258.829789)
			(xy 373.431806 -258.776491) (xy 373.439749 -258.723787) (xy 373.455459 -258.672857) (xy 373.478585 -258.624836)
			(xy 373.508609 -258.580799) (xy 373.544861 -258.541728) (xy 373.586532 -258.508497) (xy 373.63269 -258.481848)
			(xy 373.682304 -258.462376) (xy 373.734266 -258.450516) (xy 373.787416 -258.446533) (xy 373.840566 -258.450516)
			(xy 373.892528 -258.462376) (xy 373.942142 -258.481848) (xy 373.9883 -258.508497) (xy 374.029971 -258.541728)
			(xy 374.066223 -258.580799) (xy 374.096247 -258.624836) (xy 374.119373 -258.672857) (xy 374.135083 -258.723787)
			(xy 374.143026 -258.776491) (xy 374.143524 -258.80314) (xy 374.143026 -258.829789) (xy 374.371606 -258.829789)
			(xy 374.371606 -258.776491) (xy 374.379549 -258.723787) (xy 374.395259 -258.672857) (xy 374.418385 -258.624836)
			(xy 374.448409 -258.580799) (xy 374.484661 -258.541728) (xy 374.526332 -258.508497) (xy 374.57249 -258.481848)
			(xy 374.622104 -258.462376) (xy 374.674066 -258.450516) (xy 374.727216 -258.446533) (xy 374.780366 -258.450516)
			(xy 374.832328 -258.462376) (xy 374.881942 -258.481848) (xy 374.9281 -258.508497) (xy 374.969771 -258.541728)
			(xy 375.006023 -258.580799) (xy 375.036047 -258.624836) (xy 375.059173 -258.672857) (xy 375.074883 -258.723787)
			(xy 375.082826 -258.776491) (xy 375.083324 -258.80314) (xy 375.082826 -258.829789) (xy 375.311406 -258.829789)
			(xy 375.311406 -258.776491) (xy 375.319349 -258.723787) (xy 375.335059 -258.672857) (xy 375.358185 -258.624836)
			(xy 375.388209 -258.580799) (xy 375.424461 -258.541728) (xy 375.466132 -258.508497) (xy 375.51229 -258.481848)
			(xy 375.561904 -258.462376) (xy 375.613866 -258.450516) (xy 375.667016 -258.446533) (xy 375.720166 -258.450516)
			(xy 375.772128 -258.462376) (xy 375.821742 -258.481848) (xy 375.8679 -258.508497) (xy 375.909571 -258.541728)
			(xy 375.945823 -258.580799) (xy 375.975847 -258.624836) (xy 375.998973 -258.672857) (xy 376.014683 -258.723787)
			(xy 376.022626 -258.776491) (xy 376.023124 -258.80314) (xy 376.022626 -258.829789) (xy 376.251206 -258.829789)
			(xy 376.251206 -258.776491) (xy 376.259149 -258.723787) (xy 376.274859 -258.672857) (xy 376.297985 -258.624836)
			(xy 376.328009 -258.580799) (xy 376.364261 -258.541728) (xy 376.405932 -258.508497) (xy 376.45209 -258.481848)
			(xy 376.501704 -258.462376) (xy 376.553666 -258.450516) (xy 376.606816 -258.446533) (xy 376.659966 -258.450516)
			(xy 376.711928 -258.462376) (xy 376.761542 -258.481848) (xy 376.8077 -258.508497) (xy 376.849371 -258.541728)
			(xy 376.885623 -258.580799) (xy 376.915647 -258.624836) (xy 376.938773 -258.672857) (xy 376.954483 -258.723787)
			(xy 376.962426 -258.776491) (xy 376.962924 -258.80314) (xy 376.962426 -258.829789) (xy 377.190752 -258.829789)
			(xy 377.190752 -258.776491) (xy 377.198695 -258.723787) (xy 377.214405 -258.672857) (xy 377.237531 -258.624836)
			(xy 377.267555 -258.580799) (xy 377.303807 -258.541728) (xy 377.345478 -258.508497) (xy 377.391636 -258.481848)
			(xy 377.44125 -258.462376) (xy 377.493212 -258.450516) (xy 377.546362 -258.446533) (xy 377.599512 -258.450516)
			(xy 377.651474 -258.462376) (xy 377.701088 -258.481848) (xy 377.747246 -258.508497) (xy 377.788917 -258.541728)
			(xy 377.825169 -258.580799) (xy 377.855193 -258.624836) (xy 377.878319 -258.672857) (xy 377.894029 -258.723787)
			(xy 377.901972 -258.776491) (xy 377.90247 -258.80314) (xy 377.901972 -258.829789) (xy 378.130806 -258.829789)
			(xy 378.130806 -258.776491) (xy 378.138749 -258.723787) (xy 378.154459 -258.672857) (xy 378.177585 -258.624836)
			(xy 378.207609 -258.580799) (xy 378.243861 -258.541728) (xy 378.285532 -258.508497) (xy 378.33169 -258.481848)
			(xy 378.381304 -258.462376) (xy 378.433266 -258.450516) (xy 378.486416 -258.446533) (xy 378.539566 -258.450516)
			(xy 378.591528 -258.462376) (xy 378.641142 -258.481848) (xy 378.6873 -258.508497) (xy 378.728971 -258.541728)
			(xy 378.765223 -258.580799) (xy 378.795247 -258.624836) (xy 378.818373 -258.672857) (xy 378.834083 -258.723787)
			(xy 378.842026 -258.776491) (xy 378.842524 -258.80314) (xy 378.842026 -258.829789) (xy 379.070606 -258.829789)
			(xy 379.070606 -258.776491) (xy 379.078549 -258.723787) (xy 379.094259 -258.672857) (xy 379.117385 -258.624836)
			(xy 379.147409 -258.580799) (xy 379.183661 -258.541728) (xy 379.225332 -258.508497) (xy 379.27149 -258.481848)
			(xy 379.321104 -258.462376) (xy 379.373066 -258.450516) (xy 379.426216 -258.446533) (xy 379.479366 -258.450516)
			(xy 379.531328 -258.462376) (xy 379.580942 -258.481848) (xy 379.6271 -258.508497) (xy 379.668771 -258.541728)
			(xy 379.705023 -258.580799) (xy 379.735047 -258.624836) (xy 379.758173 -258.672857) (xy 379.773883 -258.723787)
			(xy 379.781826 -258.776491) (xy 379.782324 -258.80314) (xy 379.781826 -258.829789) (xy 380.010406 -258.829789)
			(xy 380.010406 -258.776491) (xy 380.018349 -258.723787) (xy 380.034059 -258.672857) (xy 380.057185 -258.624836)
			(xy 380.087209 -258.580799) (xy 380.123461 -258.541728) (xy 380.165132 -258.508497) (xy 380.21129 -258.481848)
			(xy 380.260904 -258.462376) (xy 380.312866 -258.450516) (xy 380.366016 -258.446533) (xy 380.419166 -258.450516)
			(xy 380.471128 -258.462376) (xy 380.520742 -258.481848) (xy 380.5669 -258.508497) (xy 380.608571 -258.541728)
			(xy 380.644823 -258.580799) (xy 380.674847 -258.624836) (xy 380.697973 -258.672857) (xy 380.713683 -258.723787)
			(xy 380.721626 -258.776491) (xy 380.722124 -258.80314) (xy 380.721626 -258.829789) (xy 380.713683 -258.882493)
			(xy 380.697973 -258.933423) (xy 380.674847 -258.981444) (xy 380.644823 -259.025481) (xy 380.608571 -259.064552)
			(xy 380.5669 -259.097783) (xy 380.520742 -259.124432) (xy 380.471128 -259.143904) (xy 380.419166 -259.155764)
			(xy 380.366016 -259.159748) (xy 380.312866 -259.155764) (xy 380.260904 -259.143904) (xy 380.21129 -259.124432)
			(xy 380.165132 -259.097783) (xy 380.123461 -259.064552) (xy 380.087209 -259.025481) (xy 380.057185 -258.981444)
			(xy 380.034059 -258.933423) (xy 380.018349 -258.882493) (xy 380.010406 -258.829789) (xy 379.781826 -258.829789)
			(xy 379.773883 -258.882493) (xy 379.758173 -258.933423) (xy 379.735047 -258.981444) (xy 379.705023 -259.025481)
			(xy 379.668771 -259.064552) (xy 379.6271 -259.097783) (xy 379.580942 -259.124432) (xy 379.531328 -259.143904)
			(xy 379.479366 -259.155764) (xy 379.426216 -259.159748) (xy 379.373066 -259.155764) (xy 379.321104 -259.143904)
			(xy 379.27149 -259.124432) (xy 379.225332 -259.097783) (xy 379.183661 -259.064552) (xy 379.147409 -259.025481)
			(xy 379.117385 -258.981444) (xy 379.094259 -258.933423) (xy 379.078549 -258.882493) (xy 379.070606 -258.829789)
			(xy 378.842026 -258.829789) (xy 378.834083 -258.882493) (xy 378.818373 -258.933423) (xy 378.795247 -258.981444)
			(xy 378.765223 -259.025481) (xy 378.728971 -259.064552) (xy 378.6873 -259.097783) (xy 378.641142 -259.124432)
			(xy 378.591528 -259.143904) (xy 378.539566 -259.155764) (xy 378.486416 -259.159748) (xy 378.433266 -259.155764)
			(xy 378.381304 -259.143904) (xy 378.33169 -259.124432) (xy 378.285532 -259.097783) (xy 378.243861 -259.064552)
			(xy 378.207609 -259.025481) (xy 378.177585 -258.981444) (xy 378.154459 -258.933423) (xy 378.138749 -258.882493)
			(xy 378.130806 -258.829789) (xy 377.901972 -258.829789) (xy 377.894029 -258.882493) (xy 377.878319 -258.933423)
			(xy 377.855193 -258.981444) (xy 377.825169 -259.025481) (xy 377.788917 -259.064552) (xy 377.747246 -259.097783)
			(xy 377.701088 -259.124432) (xy 377.651474 -259.143904) (xy 377.599512 -259.155764) (xy 377.546362 -259.159748)
			(xy 377.493212 -259.155764) (xy 377.44125 -259.143904) (xy 377.391636 -259.124432) (xy 377.345478 -259.097783)
			(xy 377.303807 -259.064552) (xy 377.267555 -259.025481) (xy 377.237531 -258.981444) (xy 377.214405 -258.933423)
			(xy 377.198695 -258.882493) (xy 377.190752 -258.829789) (xy 376.962426 -258.829789) (xy 376.954483 -258.882493)
			(xy 376.938773 -258.933423) (xy 376.915647 -258.981444) (xy 376.885623 -259.025481) (xy 376.849371 -259.064552)
			(xy 376.8077 -259.097783) (xy 376.761542 -259.124432) (xy 376.711928 -259.143904) (xy 376.659966 -259.155764)
			(xy 376.606816 -259.159748) (xy 376.553666 -259.155764) (xy 376.501704 -259.143904) (xy 376.45209 -259.124432)
			(xy 376.405932 -259.097783) (xy 376.364261 -259.064552) (xy 376.328009 -259.025481) (xy 376.297985 -258.981444)
			(xy 376.274859 -258.933423) (xy 376.259149 -258.882493) (xy 376.251206 -258.829789) (xy 376.022626 -258.829789)
			(xy 376.014683 -258.882493) (xy 375.998973 -258.933423) (xy 375.975847 -258.981444) (xy 375.945823 -259.025481)
			(xy 375.909571 -259.064552) (xy 375.8679 -259.097783) (xy 375.821742 -259.124432) (xy 375.772128 -259.143904)
			(xy 375.720166 -259.155764) (xy 375.667016 -259.159748) (xy 375.613866 -259.155764) (xy 375.561904 -259.143904)
			(xy 375.51229 -259.124432) (xy 375.466132 -259.097783) (xy 375.424461 -259.064552) (xy 375.388209 -259.025481)
			(xy 375.358185 -258.981444) (xy 375.335059 -258.933423) (xy 375.319349 -258.882493) (xy 375.311406 -258.829789)
			(xy 375.082826 -258.829789) (xy 375.074883 -258.882493) (xy 375.059173 -258.933423) (xy 375.036047 -258.981444)
			(xy 375.006023 -259.025481) (xy 374.969771 -259.064552) (xy 374.9281 -259.097783) (xy 374.881942 -259.124432)
			(xy 374.832328 -259.143904) (xy 374.780366 -259.155764) (xy 374.727216 -259.159748) (xy 374.674066 -259.155764)
			(xy 374.622104 -259.143904) (xy 374.57249 -259.124432) (xy 374.526332 -259.097783) (xy 374.484661 -259.064552)
			(xy 374.448409 -259.025481) (xy 374.418385 -258.981444) (xy 374.395259 -258.933423) (xy 374.379549 -258.882493)
			(xy 374.371606 -258.829789) (xy 374.143026 -258.829789) (xy 374.135083 -258.882493) (xy 374.119373 -258.933423)
			(xy 374.096247 -258.981444) (xy 374.066223 -259.025481) (xy 374.029971 -259.064552) (xy 373.9883 -259.097783)
			(xy 373.942142 -259.124432) (xy 373.892528 -259.143904) (xy 373.840566 -259.155764) (xy 373.787416 -259.159748)
			(xy 373.734266 -259.155764) (xy 373.682304 -259.143904) (xy 373.63269 -259.124432) (xy 373.586532 -259.097783)
			(xy 373.544861 -259.064552) (xy 373.508609 -259.025481) (xy 373.478585 -258.981444) (xy 373.455459 -258.933423)
			(xy 373.439749 -258.882493) (xy 373.431806 -258.829789) (xy 373.203226 -258.829789) (xy 373.195283 -258.882493)
			(xy 373.179573 -258.933423) (xy 373.156447 -258.981444) (xy 373.126423 -259.025481) (xy 373.090171 -259.064552)
			(xy 373.0485 -259.097783) (xy 373.002342 -259.124432) (xy 372.952728 -259.143904) (xy 372.900766 -259.155764)
			(xy 372.847616 -259.159748) (xy 372.794466 -259.155764) (xy 372.742504 -259.143904) (xy 372.69289 -259.124432)
			(xy 372.646732 -259.097783) (xy 372.605061 -259.064552) (xy 372.568809 -259.025481) (xy 372.538785 -258.981444)
			(xy 372.515659 -258.933423) (xy 372.499949 -258.882493) (xy 372.492006 -258.829789) (xy 372.263426 -258.829789)
			(xy 372.255483 -258.882493) (xy 372.239773 -258.933423) (xy 372.216647 -258.981444) (xy 372.186623 -259.025481)
			(xy 372.150371 -259.064552) (xy 372.1087 -259.097783) (xy 372.062542 -259.124432) (xy 372.012928 -259.143904)
			(xy 371.960966 -259.155764) (xy 371.907816 -259.159748) (xy 371.854666 -259.155764) (xy 371.802704 -259.143904)
			(xy 371.75309 -259.124432) (xy 371.706932 -259.097783) (xy 371.665261 -259.064552) (xy 371.629009 -259.025481)
			(xy 371.598985 -258.981444) (xy 371.575859 -258.933423) (xy 371.560149 -258.882493) (xy 371.552206 -258.829789)
			(xy 371.323372 -258.829789) (xy 371.315429 -258.882493) (xy 371.299719 -258.933423) (xy 371.276593 -258.981444)
			(xy 371.246569 -259.025481) (xy 371.210317 -259.064552) (xy 371.168646 -259.097783) (xy 371.122488 -259.124432)
			(xy 371.072874 -259.143904) (xy 371.020912 -259.155764) (xy 370.967762 -259.159748) (xy 370.914612 -259.155764)
			(xy 370.86265 -259.143904) (xy 370.813036 -259.124432) (xy 370.766878 -259.097783) (xy 370.725207 -259.064552)
			(xy 370.688955 -259.025481) (xy 370.658931 -258.981444) (xy 370.635805 -258.933423) (xy 370.620095 -258.882493)
			(xy 370.612152 -258.829789) (xy 368.585671 -258.829789) (xy 368.585044 -258.831824) (xy 368.58448 -258.847082)
			(xy 368.58448 -259.352288) (xy 368.585042 -259.367498) (xy 368.593994 -259.396572) (xy 368.611106 -259.421723)
			(xy 368.634864 -259.440722) (xy 368.663162 -259.451887) (xy 368.693493 -259.454226) (xy 368.723168 -259.447534)
			(xy 368.736626 -259.440426) (xy 368.763759 -259.425611) (xy 368.821876 -259.404555) (xy 368.882757 -259.393854)
			(xy 368.913664 -259.393182) (xy 368.941652 -259.393699) (xy 368.996938 -259.402451) (xy 369.050175 -259.419743)
			(xy 369.100051 -259.445151) (xy 369.145338 -259.478049) (xy 369.184921 -259.517627) (xy 369.217825 -259.56291)
			(xy 369.243239 -259.612783) (xy 369.253256 -259.643605) (xy 370.142252 -259.643605) (xy 370.142252 -259.590307)
			(xy 370.150195 -259.537603) (xy 370.165905 -259.486673) (xy 370.189031 -259.438652) (xy 370.219055 -259.394615)
			(xy 370.255307 -259.355544) (xy 370.296978 -259.322313) (xy 370.343136 -259.295664) (xy 370.39275 -259.276192)
			(xy 370.444712 -259.264332) (xy 370.497862 -259.260349) (xy 370.551012 -259.264332) (xy 370.602974 -259.276192)
			(xy 370.652588 -259.295664) (xy 370.698746 -259.322313) (xy 370.740417 -259.355544) (xy 370.776669 -259.394615)
			(xy 370.806693 -259.438652) (xy 370.829819 -259.486673) (xy 370.845529 -259.537603) (xy 370.853472 -259.590307)
			(xy 370.85397 -259.616956) (xy 370.853472 -259.643605) (xy 371.082052 -259.643605) (xy 371.082052 -259.590307)
			(xy 371.089995 -259.537603) (xy 371.105705 -259.486673) (xy 371.128831 -259.438652) (xy 371.158855 -259.394615)
			(xy 371.195107 -259.355544) (xy 371.236778 -259.322313) (xy 371.282936 -259.295664) (xy 371.33255 -259.276192)
			(xy 371.384512 -259.264332) (xy 371.437662 -259.260349) (xy 371.490812 -259.264332) (xy 371.542774 -259.276192)
			(xy 371.592388 -259.295664) (xy 371.638546 -259.322313) (xy 371.680217 -259.355544) (xy 371.716469 -259.394615)
			(xy 371.746493 -259.438652) (xy 371.769619 -259.486673) (xy 371.785329 -259.537603) (xy 371.793272 -259.590307)
			(xy 371.79377 -259.616956) (xy 371.793272 -259.643605) (xy 372.021852 -259.643605) (xy 372.021852 -259.590307)
			(xy 372.029795 -259.537603) (xy 372.045505 -259.486673) (xy 372.068631 -259.438652) (xy 372.098655 -259.394615)
			(xy 372.134907 -259.355544) (xy 372.176578 -259.322313) (xy 372.222736 -259.295664) (xy 372.27235 -259.276192)
			(xy 372.324312 -259.264332) (xy 372.377462 -259.260349) (xy 372.430612 -259.264332) (xy 372.482574 -259.276192)
			(xy 372.532188 -259.295664) (xy 372.578346 -259.322313) (xy 372.620017 -259.355544) (xy 372.656269 -259.394615)
			(xy 372.686293 -259.438652) (xy 372.709419 -259.486673) (xy 372.725129 -259.537603) (xy 372.733072 -259.590307)
			(xy 372.73357 -259.616956) (xy 372.733072 -259.643605) (xy 372.961652 -259.643605) (xy 372.961652 -259.590307)
			(xy 372.969595 -259.537603) (xy 372.985305 -259.486673) (xy 373.008431 -259.438652) (xy 373.038455 -259.394615)
			(xy 373.074707 -259.355544) (xy 373.116378 -259.322313) (xy 373.162536 -259.295664) (xy 373.21215 -259.276192)
			(xy 373.264112 -259.264332) (xy 373.317262 -259.260349) (xy 373.370412 -259.264332) (xy 373.422374 -259.276192)
			(xy 373.471988 -259.295664) (xy 373.518146 -259.322313) (xy 373.559817 -259.355544) (xy 373.596069 -259.394615)
			(xy 373.626093 -259.438652) (xy 373.649219 -259.486673) (xy 373.664929 -259.537603) (xy 373.672872 -259.590307)
			(xy 373.67337 -259.616956) (xy 373.672872 -259.643605) (xy 373.901452 -259.643605) (xy 373.901452 -259.590307)
			(xy 373.909395 -259.537603) (xy 373.925105 -259.486673) (xy 373.948231 -259.438652) (xy 373.978255 -259.394615)
			(xy 374.014507 -259.355544) (xy 374.056178 -259.322313) (xy 374.102336 -259.295664) (xy 374.15195 -259.276192)
			(xy 374.203912 -259.264332) (xy 374.257062 -259.260349) (xy 374.310212 -259.264332) (xy 374.362174 -259.276192)
			(xy 374.411788 -259.295664) (xy 374.457946 -259.322313) (xy 374.499617 -259.355544) (xy 374.535869 -259.394615)
			(xy 374.565893 -259.438652) (xy 374.589019 -259.486673) (xy 374.604729 -259.537603) (xy 374.612672 -259.590307)
			(xy 374.61317 -259.616956) (xy 374.612672 -259.643605) (xy 374.841252 -259.643605) (xy 374.841252 -259.590307)
			(xy 374.849195 -259.537603) (xy 374.864905 -259.486673) (xy 374.888031 -259.438652) (xy 374.918055 -259.394615)
			(xy 374.954307 -259.355544) (xy 374.995978 -259.322313) (xy 375.042136 -259.295664) (xy 375.09175 -259.276192)
			(xy 375.143712 -259.264332) (xy 375.196862 -259.260349) (xy 375.250012 -259.264332) (xy 375.301974 -259.276192)
			(xy 375.351588 -259.295664) (xy 375.397746 -259.322313) (xy 375.439417 -259.355544) (xy 375.475669 -259.394615)
			(xy 375.505693 -259.438652) (xy 375.528819 -259.486673) (xy 375.544529 -259.537603) (xy 375.552472 -259.590307)
			(xy 375.55297 -259.616956) (xy 375.552472 -259.643605) (xy 375.781052 -259.643605) (xy 375.781052 -259.590307)
			(xy 375.788995 -259.537603) (xy 375.804705 -259.486673) (xy 375.827831 -259.438652) (xy 375.857855 -259.394615)
			(xy 375.894107 -259.355544) (xy 375.935778 -259.322313) (xy 375.981936 -259.295664) (xy 376.03155 -259.276192)
			(xy 376.083512 -259.264332) (xy 376.136662 -259.260349) (xy 376.189812 -259.264332) (xy 376.241774 -259.276192)
			(xy 376.291388 -259.295664) (xy 376.337546 -259.322313) (xy 376.379217 -259.355544) (xy 376.415469 -259.394615)
			(xy 376.445493 -259.438652) (xy 376.468619 -259.486673) (xy 376.484329 -259.537603) (xy 376.492272 -259.590307)
			(xy 376.49277 -259.616956) (xy 376.492272 -259.643605) (xy 376.720852 -259.643605) (xy 376.720852 -259.590307)
			(xy 376.728795 -259.537603) (xy 376.744505 -259.486673) (xy 376.767631 -259.438652) (xy 376.797655 -259.394615)
			(xy 376.833907 -259.355544) (xy 376.875578 -259.322313) (xy 376.921736 -259.295664) (xy 376.97135 -259.276192)
			(xy 377.023312 -259.264332) (xy 377.076462 -259.260349) (xy 377.129612 -259.264332) (xy 377.181574 -259.276192)
			(xy 377.231188 -259.295664) (xy 377.277346 -259.322313) (xy 377.319017 -259.355544) (xy 377.355269 -259.394615)
			(xy 377.385293 -259.438652) (xy 377.408419 -259.486673) (xy 377.424129 -259.537603) (xy 377.432072 -259.590307)
			(xy 377.43257 -259.616956) (xy 377.432072 -259.643605) (xy 377.660652 -259.643605) (xy 377.660652 -259.590307)
			(xy 377.668595 -259.537603) (xy 377.684305 -259.486673) (xy 377.707431 -259.438652) (xy 377.737455 -259.394615)
			(xy 377.773707 -259.355544) (xy 377.815378 -259.322313) (xy 377.861536 -259.295664) (xy 377.91115 -259.276192)
			(xy 377.963112 -259.264332) (xy 378.016262 -259.260349) (xy 378.069412 -259.264332) (xy 378.121374 -259.276192)
			(xy 378.170988 -259.295664) (xy 378.217146 -259.322313) (xy 378.258817 -259.355544) (xy 378.295069 -259.394615)
			(xy 378.325093 -259.438652) (xy 378.348219 -259.486673) (xy 378.363929 -259.537603) (xy 378.371872 -259.590307)
			(xy 378.37237 -259.616956) (xy 378.371872 -259.643605) (xy 378.600452 -259.643605) (xy 378.600452 -259.590307)
			(xy 378.608395 -259.537603) (xy 378.624105 -259.486673) (xy 378.647231 -259.438652) (xy 378.677255 -259.394615)
			(xy 378.713507 -259.355544) (xy 378.755178 -259.322313) (xy 378.801336 -259.295664) (xy 378.85095 -259.276192)
			(xy 378.902912 -259.264332) (xy 378.956062 -259.260349) (xy 379.009212 -259.264332) (xy 379.061174 -259.276192)
			(xy 379.110788 -259.295664) (xy 379.156946 -259.322313) (xy 379.198617 -259.355544) (xy 379.234869 -259.394615)
			(xy 379.264893 -259.438652) (xy 379.288019 -259.486673) (xy 379.303729 -259.537603) (xy 379.311672 -259.590307)
			(xy 379.31217 -259.616956) (xy 379.311672 -259.643605) (xy 379.540252 -259.643605) (xy 379.540252 -259.590307)
			(xy 379.548195 -259.537603) (xy 379.563905 -259.486673) (xy 379.587031 -259.438652) (xy 379.617055 -259.394615)
			(xy 379.653307 -259.355544) (xy 379.694978 -259.322313) (xy 379.741136 -259.295664) (xy 379.79075 -259.276192)
			(xy 379.842712 -259.264332) (xy 379.895862 -259.260349) (xy 379.949012 -259.264332) (xy 380.000974 -259.276192)
			(xy 380.050588 -259.295664) (xy 380.096746 -259.322313) (xy 380.138417 -259.355544) (xy 380.174669 -259.394615)
			(xy 380.204693 -259.438652) (xy 380.227819 -259.486673) (xy 380.243529 -259.537603) (xy 380.251472 -259.590307)
			(xy 380.25197 -259.616956) (xy 380.251472 -259.643605) (xy 380.243529 -259.696309) (xy 380.227819 -259.747239)
			(xy 380.204693 -259.79526) (xy 380.174669 -259.839297) (xy 380.138417 -259.878368) (xy 380.096746 -259.911599)
			(xy 380.050588 -259.938248) (xy 380.000974 -259.95772) (xy 379.949012 -259.96958) (xy 379.895862 -259.973564)
			(xy 379.842712 -259.96958) (xy 379.79075 -259.95772) (xy 379.741136 -259.938248) (xy 379.694978 -259.911599)
			(xy 379.653307 -259.878368) (xy 379.617055 -259.839297) (xy 379.587031 -259.79526) (xy 379.563905 -259.747239)
			(xy 379.548195 -259.696309) (xy 379.540252 -259.643605) (xy 379.311672 -259.643605) (xy 379.303729 -259.696309)
			(xy 379.288019 -259.747239) (xy 379.264893 -259.79526) (xy 379.234869 -259.839297) (xy 379.198617 -259.878368)
			(xy 379.156946 -259.911599) (xy 379.110788 -259.938248) (xy 379.061174 -259.95772) (xy 379.009212 -259.96958)
			(xy 378.956062 -259.973564) (xy 378.902912 -259.96958) (xy 378.85095 -259.95772) (xy 378.801336 -259.938248)
			(xy 378.755178 -259.911599) (xy 378.713507 -259.878368) (xy 378.677255 -259.839297) (xy 378.647231 -259.79526)
			(xy 378.624105 -259.747239) (xy 378.608395 -259.696309) (xy 378.600452 -259.643605) (xy 378.371872 -259.643605)
			(xy 378.363929 -259.696309) (xy 378.348219 -259.747239) (xy 378.325093 -259.79526) (xy 378.295069 -259.839297)
			(xy 378.258817 -259.878368) (xy 378.217146 -259.911599) (xy 378.170988 -259.938248) (xy 378.121374 -259.95772)
			(xy 378.069412 -259.96958) (xy 378.016262 -259.973564) (xy 377.963112 -259.96958) (xy 377.91115 -259.95772)
			(xy 377.861536 -259.938248) (xy 377.815378 -259.911599) (xy 377.773707 -259.878368) (xy 377.737455 -259.839297)
			(xy 377.707431 -259.79526) (xy 377.684305 -259.747239) (xy 377.668595 -259.696309) (xy 377.660652 -259.643605)
			(xy 377.432072 -259.643605) (xy 377.424129 -259.696309) (xy 377.408419 -259.747239) (xy 377.385293 -259.79526)
			(xy 377.355269 -259.839297) (xy 377.319017 -259.878368) (xy 377.277346 -259.911599) (xy 377.231188 -259.938248)
			(xy 377.181574 -259.95772) (xy 377.129612 -259.96958) (xy 377.076462 -259.973564) (xy 377.023312 -259.96958)
			(xy 376.97135 -259.95772) (xy 376.921736 -259.938248) (xy 376.875578 -259.911599) (xy 376.833907 -259.878368)
			(xy 376.797655 -259.839297) (xy 376.767631 -259.79526) (xy 376.744505 -259.747239) (xy 376.728795 -259.696309)
			(xy 376.720852 -259.643605) (xy 376.492272 -259.643605) (xy 376.484329 -259.696309) (xy 376.468619 -259.747239)
			(xy 376.445493 -259.79526) (xy 376.415469 -259.839297) (xy 376.379217 -259.878368) (xy 376.337546 -259.911599)
			(xy 376.291388 -259.938248) (xy 376.241774 -259.95772) (xy 376.189812 -259.96958) (xy 376.136662 -259.973564)
			(xy 376.083512 -259.96958) (xy 376.03155 -259.95772) (xy 375.981936 -259.938248) (xy 375.935778 -259.911599)
			(xy 375.894107 -259.878368) (xy 375.857855 -259.839297) (xy 375.827831 -259.79526) (xy 375.804705 -259.747239)
			(xy 375.788995 -259.696309) (xy 375.781052 -259.643605) (xy 375.552472 -259.643605) (xy 375.544529 -259.696309)
			(xy 375.528819 -259.747239) (xy 375.505693 -259.79526) (xy 375.475669 -259.839297) (xy 375.439417 -259.878368)
			(xy 375.397746 -259.911599) (xy 375.351588 -259.938248) (xy 375.301974 -259.95772) (xy 375.250012 -259.96958)
			(xy 375.196862 -259.973564) (xy 375.143712 -259.96958) (xy 375.09175 -259.95772) (xy 375.042136 -259.938248)
			(xy 374.995978 -259.911599) (xy 374.954307 -259.878368) (xy 374.918055 -259.839297) (xy 374.888031 -259.79526)
			(xy 374.864905 -259.747239) (xy 374.849195 -259.696309) (xy 374.841252 -259.643605) (xy 374.612672 -259.643605)
			(xy 374.604729 -259.696309) (xy 374.589019 -259.747239) (xy 374.565893 -259.79526) (xy 374.535869 -259.839297)
			(xy 374.499617 -259.878368) (xy 374.457946 -259.911599) (xy 374.411788 -259.938248) (xy 374.362174 -259.95772)
			(xy 374.310212 -259.96958) (xy 374.257062 -259.973564) (xy 374.203912 -259.96958) (xy 374.15195 -259.95772)
			(xy 374.102336 -259.938248) (xy 374.056178 -259.911599) (xy 374.014507 -259.878368) (xy 373.978255 -259.839297)
			(xy 373.948231 -259.79526) (xy 373.925105 -259.747239) (xy 373.909395 -259.696309) (xy 373.901452 -259.643605)
			(xy 373.672872 -259.643605) (xy 373.664929 -259.696309) (xy 373.649219 -259.747239) (xy 373.626093 -259.79526)
			(xy 373.596069 -259.839297) (xy 373.559817 -259.878368) (xy 373.518146 -259.911599) (xy 373.471988 -259.938248)
			(xy 373.422374 -259.95772) (xy 373.370412 -259.96958) (xy 373.317262 -259.973564) (xy 373.264112 -259.96958)
			(xy 373.21215 -259.95772) (xy 373.162536 -259.938248) (xy 373.116378 -259.911599) (xy 373.074707 -259.878368)
			(xy 373.038455 -259.839297) (xy 373.008431 -259.79526) (xy 372.985305 -259.747239) (xy 372.969595 -259.696309)
			(xy 372.961652 -259.643605) (xy 372.733072 -259.643605) (xy 372.725129 -259.696309) (xy 372.709419 -259.747239)
			(xy 372.686293 -259.79526) (xy 372.656269 -259.839297) (xy 372.620017 -259.878368) (xy 372.578346 -259.911599)
			(xy 372.532188 -259.938248) (xy 372.482574 -259.95772) (xy 372.430612 -259.96958) (xy 372.377462 -259.973564)
			(xy 372.324312 -259.96958) (xy 372.27235 -259.95772) (xy 372.222736 -259.938248) (xy 372.176578 -259.911599)
			(xy 372.134907 -259.878368) (xy 372.098655 -259.839297) (xy 372.068631 -259.79526) (xy 372.045505 -259.747239)
			(xy 372.029795 -259.696309) (xy 372.021852 -259.643605) (xy 371.793272 -259.643605) (xy 371.785329 -259.696309)
			(xy 371.769619 -259.747239) (xy 371.746493 -259.79526) (xy 371.716469 -259.839297) (xy 371.680217 -259.878368)
			(xy 371.638546 -259.911599) (xy 371.592388 -259.938248) (xy 371.542774 -259.95772) (xy 371.490812 -259.96958)
			(xy 371.437662 -259.973564) (xy 371.384512 -259.96958) (xy 371.33255 -259.95772) (xy 371.282936 -259.938248)
			(xy 371.236778 -259.911599) (xy 371.195107 -259.878368) (xy 371.158855 -259.839297) (xy 371.128831 -259.79526)
			(xy 371.105705 -259.747239) (xy 371.089995 -259.696309) (xy 371.082052 -259.643605) (xy 370.853472 -259.643605)
			(xy 370.845529 -259.696309) (xy 370.829819 -259.747239) (xy 370.806693 -259.79526) (xy 370.776669 -259.839297)
			(xy 370.740417 -259.878368) (xy 370.698746 -259.911599) (xy 370.652588 -259.938248) (xy 370.602974 -259.95772)
			(xy 370.551012 -259.96958) (xy 370.497862 -259.973564) (xy 370.444712 -259.96958) (xy 370.39275 -259.95772)
			(xy 370.343136 -259.938248) (xy 370.296978 -259.911599) (xy 370.255307 -259.878368) (xy 370.219055 -259.839297)
			(xy 370.189031 -259.79526) (xy 370.165905 -259.747239) (xy 370.150195 -259.696309) (xy 370.142252 -259.643605)
			(xy 369.253256 -259.643605) (xy 369.260539 -259.666017) (xy 369.269297 -259.721303) (xy 369.269772 -259.74929)
			(xy 369.269238 -259.777366) (xy 369.260416 -259.83282) (xy 369.243004 -259.886204) (xy 369.217434 -259.936195)
			(xy 369.184338 -259.981557) (xy 369.144536 -260.021165) (xy 369.099014 -260.05404) (xy 369.048899 -260.079367)
			(xy 368.995431 -260.096519) (xy 368.967766 -260.101334) (xy 368.953993 -260.103924) (xy 368.928521 -260.115586)
			(xy 368.907173 -260.133727) (xy 368.891553 -260.156983) (xy 368.882834 -260.183606) (xy 368.881673 -260.211597)
			(xy 368.888155 -260.238851) (xy 368.901794 -260.263322) (xy 368.911378 -260.273546) (xy 369.095253 -260.457421)
			(xy 369.672606 -260.457421) (xy 369.672606 -260.404123) (xy 369.680549 -260.351419) (xy 369.696259 -260.300489)
			(xy 369.719385 -260.252468) (xy 369.749409 -260.208431) (xy 369.785661 -260.16936) (xy 369.827332 -260.136129)
			(xy 369.87349 -260.10948) (xy 369.923104 -260.090008) (xy 369.975066 -260.078148) (xy 370.028216 -260.074165)
			(xy 370.081366 -260.078148) (xy 370.133328 -260.090008) (xy 370.182942 -260.10948) (xy 370.2291 -260.136129)
			(xy 370.270771 -260.16936) (xy 370.307023 -260.208431) (xy 370.337047 -260.252468) (xy 370.360173 -260.300489)
			(xy 370.375883 -260.351419) (xy 370.383826 -260.404123) (xy 370.384324 -260.430772) (xy 370.383826 -260.457421)
			(xy 370.612406 -260.457421) (xy 370.612406 -260.404123) (xy 370.620349 -260.351419) (xy 370.636059 -260.300489)
			(xy 370.659185 -260.252468) (xy 370.689209 -260.208431) (xy 370.725461 -260.16936) (xy 370.767132 -260.136129)
			(xy 370.81329 -260.10948) (xy 370.862904 -260.090008) (xy 370.914866 -260.078148) (xy 370.968016 -260.074165)
			(xy 371.021166 -260.078148) (xy 371.073128 -260.090008) (xy 371.122742 -260.10948) (xy 371.1689 -260.136129)
			(xy 371.210571 -260.16936) (xy 371.246823 -260.208431) (xy 371.276847 -260.252468) (xy 371.299973 -260.300489)
			(xy 371.315683 -260.351419) (xy 371.323626 -260.404123) (xy 371.324124 -260.430772) (xy 371.323626 -260.457421)
			(xy 371.552206 -260.457421) (xy 371.552206 -260.404123) (xy 371.560149 -260.351419) (xy 371.575859 -260.300489)
			(xy 371.598985 -260.252468) (xy 371.629009 -260.208431) (xy 371.665261 -260.16936) (xy 371.706932 -260.136129)
			(xy 371.75309 -260.10948) (xy 371.802704 -260.090008) (xy 371.854666 -260.078148) (xy 371.907816 -260.074165)
			(xy 371.960966 -260.078148) (xy 372.012928 -260.090008) (xy 372.062542 -260.10948) (xy 372.1087 -260.136129)
			(xy 372.150371 -260.16936) (xy 372.186623 -260.208431) (xy 372.216647 -260.252468) (xy 372.239773 -260.300489)
			(xy 372.255483 -260.351419) (xy 372.263426 -260.404123) (xy 372.263924 -260.430772) (xy 372.263426 -260.457421)
			(xy 372.492006 -260.457421) (xy 372.492006 -260.404123) (xy 372.499949 -260.351419) (xy 372.515659 -260.300489)
			(xy 372.538785 -260.252468) (xy 372.568809 -260.208431) (xy 372.605061 -260.16936) (xy 372.646732 -260.136129)
			(xy 372.69289 -260.10948) (xy 372.742504 -260.090008) (xy 372.794466 -260.078148) (xy 372.847616 -260.074165)
			(xy 372.900766 -260.078148) (xy 372.952728 -260.090008) (xy 373.002342 -260.10948) (xy 373.0485 -260.136129)
			(xy 373.090171 -260.16936) (xy 373.126423 -260.208431) (xy 373.156447 -260.252468) (xy 373.179573 -260.300489)
			(xy 373.195283 -260.351419) (xy 373.203226 -260.404123) (xy 373.203724 -260.430772) (xy 373.203226 -260.457421)
			(xy 373.431806 -260.457421) (xy 373.431806 -260.404123) (xy 373.439749 -260.351419) (xy 373.455459 -260.300489)
			(xy 373.478585 -260.252468) (xy 373.508609 -260.208431) (xy 373.544861 -260.16936) (xy 373.586532 -260.136129)
			(xy 373.63269 -260.10948) (xy 373.682304 -260.090008) (xy 373.734266 -260.078148) (xy 373.787416 -260.074165)
			(xy 373.840566 -260.078148) (xy 373.892528 -260.090008) (xy 373.942142 -260.10948) (xy 373.9883 -260.136129)
			(xy 374.029971 -260.16936) (xy 374.066223 -260.208431) (xy 374.096247 -260.252468) (xy 374.119373 -260.300489)
			(xy 374.135083 -260.351419) (xy 374.143026 -260.404123) (xy 374.143524 -260.430772) (xy 374.143026 -260.457421)
			(xy 374.371352 -260.457421) (xy 374.371352 -260.404123) (xy 374.379295 -260.351419) (xy 374.395005 -260.300489)
			(xy 374.418131 -260.252468) (xy 374.448155 -260.208431) (xy 374.484407 -260.16936) (xy 374.526078 -260.136129)
			(xy 374.572236 -260.10948) (xy 374.62185 -260.090008) (xy 374.673812 -260.078148) (xy 374.726962 -260.074165)
			(xy 374.780112 -260.078148) (xy 374.832074 -260.090008) (xy 374.881688 -260.10948) (xy 374.927846 -260.136129)
			(xy 374.969517 -260.16936) (xy 375.005769 -260.208431) (xy 375.035793 -260.252468) (xy 375.058919 -260.300489)
			(xy 375.074629 -260.351419) (xy 375.082572 -260.404123) (xy 375.08307 -260.430772) (xy 375.082572 -260.457421)
			(xy 375.311406 -260.457421) (xy 375.311406 -260.404123) (xy 375.319349 -260.351419) (xy 375.335059 -260.300489)
			(xy 375.358185 -260.252468) (xy 375.388209 -260.208431) (xy 375.424461 -260.16936) (xy 375.466132 -260.136129)
			(xy 375.51229 -260.10948) (xy 375.561904 -260.090008) (xy 375.613866 -260.078148) (xy 375.667016 -260.074165)
			(xy 375.720166 -260.078148) (xy 375.772128 -260.090008) (xy 375.821742 -260.10948) (xy 375.8679 -260.136129)
			(xy 375.909571 -260.16936) (xy 375.945823 -260.208431) (xy 375.975847 -260.252468) (xy 375.998973 -260.300489)
			(xy 376.014683 -260.351419) (xy 376.022626 -260.404123) (xy 376.023124 -260.430772) (xy 376.022626 -260.457421)
			(xy 376.251206 -260.457421) (xy 376.251206 -260.404123) (xy 376.259149 -260.351419) (xy 376.274859 -260.300489)
			(xy 376.297985 -260.252468) (xy 376.328009 -260.208431) (xy 376.364261 -260.16936) (xy 376.405932 -260.136129)
			(xy 376.45209 -260.10948) (xy 376.501704 -260.090008) (xy 376.553666 -260.078148) (xy 376.606816 -260.074165)
			(xy 376.659966 -260.078148) (xy 376.711928 -260.090008) (xy 376.761542 -260.10948) (xy 376.8077 -260.136129)
			(xy 376.849371 -260.16936) (xy 376.885623 -260.208431) (xy 376.915647 -260.252468) (xy 376.938773 -260.300489)
			(xy 376.954483 -260.351419) (xy 376.962426 -260.404123) (xy 376.962924 -260.430772) (xy 376.962426 -260.457421)
			(xy 377.191006 -260.457421) (xy 377.191006 -260.404123) (xy 377.198949 -260.351419) (xy 377.214659 -260.300489)
			(xy 377.237785 -260.252468) (xy 377.267809 -260.208431) (xy 377.304061 -260.16936) (xy 377.345732 -260.136129)
			(xy 377.39189 -260.10948) (xy 377.441504 -260.090008) (xy 377.493466 -260.078148) (xy 377.546616 -260.074165)
			(xy 377.599766 -260.078148) (xy 377.651728 -260.090008) (xy 377.701342 -260.10948) (xy 377.7475 -260.136129)
			(xy 377.789171 -260.16936) (xy 377.825423 -260.208431) (xy 377.855447 -260.252468) (xy 377.878573 -260.300489)
			(xy 377.894283 -260.351419) (xy 377.902226 -260.404123) (xy 377.902724 -260.430772) (xy 377.902226 -260.457421)
			(xy 378.130806 -260.457421) (xy 378.130806 -260.404123) (xy 378.138749 -260.351419) (xy 378.154459 -260.300489)
			(xy 378.177585 -260.252468) (xy 378.207609 -260.208431) (xy 378.243861 -260.16936) (xy 378.285532 -260.136129)
			(xy 378.33169 -260.10948) (xy 378.381304 -260.090008) (xy 378.433266 -260.078148) (xy 378.486416 -260.074165)
			(xy 378.539566 -260.078148) (xy 378.591528 -260.090008) (xy 378.641142 -260.10948) (xy 378.6873 -260.136129)
			(xy 378.728971 -260.16936) (xy 378.765223 -260.208431) (xy 378.795247 -260.252468) (xy 378.818373 -260.300489)
			(xy 378.834083 -260.351419) (xy 378.842026 -260.404123) (xy 378.842524 -260.430772) (xy 378.842026 -260.457421)
			(xy 379.070606 -260.457421) (xy 379.070606 -260.404123) (xy 379.078549 -260.351419) (xy 379.094259 -260.300489)
			(xy 379.117385 -260.252468) (xy 379.147409 -260.208431) (xy 379.183661 -260.16936) (xy 379.225332 -260.136129)
			(xy 379.27149 -260.10948) (xy 379.321104 -260.090008) (xy 379.373066 -260.078148) (xy 379.426216 -260.074165)
			(xy 379.479366 -260.078148) (xy 379.531328 -260.090008) (xy 379.580942 -260.10948) (xy 379.6271 -260.136129)
			(xy 379.668771 -260.16936) (xy 379.705023 -260.208431) (xy 379.735047 -260.252468) (xy 379.758173 -260.300489)
			(xy 379.773883 -260.351419) (xy 379.781826 -260.404123) (xy 379.782324 -260.430772) (xy 379.781826 -260.457421)
			(xy 380.010406 -260.457421) (xy 380.010406 -260.404123) (xy 380.018349 -260.351419) (xy 380.034059 -260.300489)
			(xy 380.057185 -260.252468) (xy 380.087209 -260.208431) (xy 380.123461 -260.16936) (xy 380.165132 -260.136129)
			(xy 380.21129 -260.10948) (xy 380.260904 -260.090008) (xy 380.312866 -260.078148) (xy 380.366016 -260.074165)
			(xy 380.419166 -260.078148) (xy 380.471128 -260.090008) (xy 380.520742 -260.10948) (xy 380.5669 -260.136129)
			(xy 380.608571 -260.16936) (xy 380.644823 -260.208431) (xy 380.674847 -260.252468) (xy 380.697973 -260.300489)
			(xy 380.713683 -260.351419) (xy 380.721626 -260.404123) (xy 380.722124 -260.430772) (xy 380.721626 -260.457421)
			(xy 380.713683 -260.510125) (xy 380.697973 -260.561055) (xy 380.674847 -260.609076) (xy 380.644823 -260.653113)
			(xy 380.608571 -260.692184) (xy 380.5669 -260.725415) (xy 380.520742 -260.752064) (xy 380.471128 -260.771536)
			(xy 380.419166 -260.783396) (xy 380.366016 -260.78738) (xy 380.312866 -260.783396) (xy 380.260904 -260.771536)
			(xy 380.21129 -260.752064) (xy 380.165132 -260.725415) (xy 380.123461 -260.692184) (xy 380.087209 -260.653113)
			(xy 380.057185 -260.609076) (xy 380.034059 -260.561055) (xy 380.018349 -260.510125) (xy 380.010406 -260.457421)
			(xy 379.781826 -260.457421) (xy 379.773883 -260.510125) (xy 379.758173 -260.561055) (xy 379.735047 -260.609076)
			(xy 379.705023 -260.653113) (xy 379.668771 -260.692184) (xy 379.6271 -260.725415) (xy 379.580942 -260.752064)
			(xy 379.531328 -260.771536) (xy 379.479366 -260.783396) (xy 379.426216 -260.78738) (xy 379.373066 -260.783396)
			(xy 379.321104 -260.771536) (xy 379.27149 -260.752064) (xy 379.225332 -260.725415) (xy 379.183661 -260.692184)
			(xy 379.147409 -260.653113) (xy 379.117385 -260.609076) (xy 379.094259 -260.561055) (xy 379.078549 -260.510125)
			(xy 379.070606 -260.457421) (xy 378.842026 -260.457421) (xy 378.834083 -260.510125) (xy 378.818373 -260.561055)
			(xy 378.795247 -260.609076) (xy 378.765223 -260.653113) (xy 378.728971 -260.692184) (xy 378.6873 -260.725415)
			(xy 378.641142 -260.752064) (xy 378.591528 -260.771536) (xy 378.539566 -260.783396) (xy 378.486416 -260.78738)
			(xy 378.433266 -260.783396) (xy 378.381304 -260.771536) (xy 378.33169 -260.752064) (xy 378.285532 -260.725415)
			(xy 378.243861 -260.692184) (xy 378.207609 -260.653113) (xy 378.177585 -260.609076) (xy 378.154459 -260.561055)
			(xy 378.138749 -260.510125) (xy 378.130806 -260.457421) (xy 377.902226 -260.457421) (xy 377.894283 -260.510125)
			(xy 377.878573 -260.561055) (xy 377.855447 -260.609076) (xy 377.825423 -260.653113) (xy 377.789171 -260.692184)
			(xy 377.7475 -260.725415) (xy 377.701342 -260.752064) (xy 377.651728 -260.771536) (xy 377.599766 -260.783396)
			(xy 377.546616 -260.78738) (xy 377.493466 -260.783396) (xy 377.441504 -260.771536) (xy 377.39189 -260.752064)
			(xy 377.345732 -260.725415) (xy 377.304061 -260.692184) (xy 377.267809 -260.653113) (xy 377.237785 -260.609076)
			(xy 377.214659 -260.561055) (xy 377.198949 -260.510125) (xy 377.191006 -260.457421) (xy 376.962426 -260.457421)
			(xy 376.954483 -260.510125) (xy 376.938773 -260.561055) (xy 376.915647 -260.609076) (xy 376.885623 -260.653113)
			(xy 376.849371 -260.692184) (xy 376.8077 -260.725415) (xy 376.761542 -260.752064) (xy 376.711928 -260.771536)
			(xy 376.659966 -260.783396) (xy 376.606816 -260.78738) (xy 376.553666 -260.783396) (xy 376.501704 -260.771536)
			(xy 376.45209 -260.752064) (xy 376.405932 -260.725415) (xy 376.364261 -260.692184) (xy 376.328009 -260.653113)
			(xy 376.297985 -260.609076) (xy 376.274859 -260.561055) (xy 376.259149 -260.510125) (xy 376.251206 -260.457421)
			(xy 376.022626 -260.457421) (xy 376.014683 -260.510125) (xy 375.998973 -260.561055) (xy 375.975847 -260.609076)
			(xy 375.945823 -260.653113) (xy 375.909571 -260.692184) (xy 375.8679 -260.725415) (xy 375.821742 -260.752064)
			(xy 375.772128 -260.771536) (xy 375.720166 -260.783396) (xy 375.667016 -260.78738) (xy 375.613866 -260.783396)
			(xy 375.561904 -260.771536) (xy 375.51229 -260.752064) (xy 375.466132 -260.725415) (xy 375.424461 -260.692184)
			(xy 375.388209 -260.653113) (xy 375.358185 -260.609076) (xy 375.335059 -260.561055) (xy 375.319349 -260.510125)
			(xy 375.311406 -260.457421) (xy 375.082572 -260.457421) (xy 375.074629 -260.510125) (xy 375.058919 -260.561055)
			(xy 375.035793 -260.609076) (xy 375.005769 -260.653113) (xy 374.969517 -260.692184) (xy 374.927846 -260.725415)
			(xy 374.881688 -260.752064) (xy 374.832074 -260.771536) (xy 374.780112 -260.783396) (xy 374.726962 -260.78738)
			(xy 374.673812 -260.783396) (xy 374.62185 -260.771536) (xy 374.572236 -260.752064) (xy 374.526078 -260.725415)
			(xy 374.484407 -260.692184) (xy 374.448155 -260.653113) (xy 374.418131 -260.609076) (xy 374.395005 -260.561055)
			(xy 374.379295 -260.510125) (xy 374.371352 -260.457421) (xy 374.143026 -260.457421) (xy 374.135083 -260.510125)
			(xy 374.119373 -260.561055) (xy 374.096247 -260.609076) (xy 374.066223 -260.653113) (xy 374.029971 -260.692184)
			(xy 373.9883 -260.725415) (xy 373.942142 -260.752064) (xy 373.892528 -260.771536) (xy 373.840566 -260.783396)
			(xy 373.787416 -260.78738) (xy 373.734266 -260.783396) (xy 373.682304 -260.771536) (xy 373.63269 -260.752064)
			(xy 373.586532 -260.725415) (xy 373.544861 -260.692184) (xy 373.508609 -260.653113) (xy 373.478585 -260.609076)
			(xy 373.455459 -260.561055) (xy 373.439749 -260.510125) (xy 373.431806 -260.457421) (xy 373.203226 -260.457421)
			(xy 373.195283 -260.510125) (xy 373.179573 -260.561055) (xy 373.156447 -260.609076) (xy 373.126423 -260.653113)
			(xy 373.090171 -260.692184) (xy 373.0485 -260.725415) (xy 373.002342 -260.752064) (xy 372.952728 -260.771536)
			(xy 372.900766 -260.783396) (xy 372.847616 -260.78738) (xy 372.794466 -260.783396) (xy 372.742504 -260.771536)
			(xy 372.69289 -260.752064) (xy 372.646732 -260.725415) (xy 372.605061 -260.692184) (xy 372.568809 -260.653113)
			(xy 372.538785 -260.609076) (xy 372.515659 -260.561055) (xy 372.499949 -260.510125) (xy 372.492006 -260.457421)
			(xy 372.263426 -260.457421) (xy 372.255483 -260.510125) (xy 372.239773 -260.561055) (xy 372.216647 -260.609076)
			(xy 372.186623 -260.653113) (xy 372.150371 -260.692184) (xy 372.1087 -260.725415) (xy 372.062542 -260.752064)
			(xy 372.012928 -260.771536) (xy 371.960966 -260.783396) (xy 371.907816 -260.78738) (xy 371.854666 -260.783396)
			(xy 371.802704 -260.771536) (xy 371.75309 -260.752064) (xy 371.706932 -260.725415) (xy 371.665261 -260.692184)
			(xy 371.629009 -260.653113) (xy 371.598985 -260.609076) (xy 371.575859 -260.561055) (xy 371.560149 -260.510125)
			(xy 371.552206 -260.457421) (xy 371.323626 -260.457421) (xy 371.315683 -260.510125) (xy 371.299973 -260.561055)
			(xy 371.276847 -260.609076) (xy 371.246823 -260.653113) (xy 371.210571 -260.692184) (xy 371.1689 -260.725415)
			(xy 371.122742 -260.752064) (xy 371.073128 -260.771536) (xy 371.021166 -260.783396) (xy 370.968016 -260.78738)
			(xy 370.914866 -260.783396) (xy 370.862904 -260.771536) (xy 370.81329 -260.752064) (xy 370.767132 -260.725415)
			(xy 370.725461 -260.692184) (xy 370.689209 -260.653113) (xy 370.659185 -260.609076) (xy 370.636059 -260.561055)
			(xy 370.620349 -260.510125) (xy 370.612406 -260.457421) (xy 370.383826 -260.457421) (xy 370.375883 -260.510125)
			(xy 370.360173 -260.561055) (xy 370.337047 -260.609076) (xy 370.307023 -260.653113) (xy 370.270771 -260.692184)
			(xy 370.2291 -260.725415) (xy 370.182942 -260.752064) (xy 370.133328 -260.771536) (xy 370.081366 -260.783396)
			(xy 370.028216 -260.78738) (xy 369.975066 -260.783396) (xy 369.923104 -260.771536) (xy 369.87349 -260.752064)
			(xy 369.827332 -260.725415) (xy 369.785661 -260.692184) (xy 369.749409 -260.653113) (xy 369.719385 -260.609076)
			(xy 369.696259 -260.561055) (xy 369.680549 -260.510125) (xy 369.672606 -260.457421) (xy 369.095253 -260.457421)
			(xy 369.33124 -260.693408) (xy 369.33124 -260.743954) (xy 369.413536 -260.825996) (xy 369.413536 -261.271491)
			(xy 370.142252 -261.271491) (xy 370.142252 -261.218193) (xy 370.150195 -261.165489) (xy 370.165905 -261.114559)
			(xy 370.189031 -261.066538) (xy 370.219055 -261.022501) (xy 370.255307 -260.98343) (xy 370.296978 -260.950199)
			(xy 370.343136 -260.92355) (xy 370.39275 -260.904078) (xy 370.444712 -260.892218) (xy 370.497862 -260.888235)
			(xy 370.551012 -260.892218) (xy 370.602974 -260.904078) (xy 370.652588 -260.92355) (xy 370.698746 -260.950199)
			(xy 370.740417 -260.98343) (xy 370.776669 -261.022501) (xy 370.806693 -261.066538) (xy 370.829819 -261.114559)
			(xy 370.845529 -261.165489) (xy 370.853472 -261.218193) (xy 370.85397 -261.244842) (xy 370.853472 -261.271491)
			(xy 371.082052 -261.271491) (xy 371.082052 -261.218193) (xy 371.089995 -261.165489) (xy 371.105705 -261.114559)
			(xy 371.128831 -261.066538) (xy 371.158855 -261.022501) (xy 371.195107 -260.98343) (xy 371.236778 -260.950199)
			(xy 371.282936 -260.92355) (xy 371.33255 -260.904078) (xy 371.384512 -260.892218) (xy 371.437662 -260.888235)
			(xy 371.490812 -260.892218) (xy 371.542774 -260.904078) (xy 371.592388 -260.92355) (xy 371.638546 -260.950199)
			(xy 371.680217 -260.98343) (xy 371.716469 -261.022501) (xy 371.746493 -261.066538) (xy 371.769619 -261.114559)
			(xy 371.785329 -261.165489) (xy 371.793272 -261.218193) (xy 371.79377 -261.244842) (xy 371.793272 -261.271491)
			(xy 372.021852 -261.271491) (xy 372.021852 -261.218193) (xy 372.029795 -261.165489) (xy 372.045505 -261.114559)
			(xy 372.068631 -261.066538) (xy 372.098655 -261.022501) (xy 372.134907 -260.98343) (xy 372.176578 -260.950199)
			(xy 372.222736 -260.92355) (xy 372.27235 -260.904078) (xy 372.324312 -260.892218) (xy 372.377462 -260.888235)
			(xy 372.430612 -260.892218) (xy 372.482574 -260.904078) (xy 372.532188 -260.92355) (xy 372.578346 -260.950199)
			(xy 372.620017 -260.98343) (xy 372.656269 -261.022501) (xy 372.686293 -261.066538) (xy 372.709419 -261.114559)
			(xy 372.725129 -261.165489) (xy 372.733072 -261.218193) (xy 372.73357 -261.244842) (xy 372.733072 -261.271491)
			(xy 372.961652 -261.271491) (xy 372.961652 -261.218193) (xy 372.969595 -261.165489) (xy 372.985305 -261.114559)
			(xy 373.008431 -261.066538) (xy 373.038455 -261.022501) (xy 373.074707 -260.98343) (xy 373.116378 -260.950199)
			(xy 373.162536 -260.92355) (xy 373.21215 -260.904078) (xy 373.264112 -260.892218) (xy 373.317262 -260.888235)
			(xy 373.370412 -260.892218) (xy 373.422374 -260.904078) (xy 373.471988 -260.92355) (xy 373.518146 -260.950199)
			(xy 373.559817 -260.98343) (xy 373.596069 -261.022501) (xy 373.626093 -261.066538) (xy 373.649219 -261.114559)
			(xy 373.664929 -261.165489) (xy 373.672872 -261.218193) (xy 373.67337 -261.244842) (xy 373.672872 -261.271491)
			(xy 373.901452 -261.271491) (xy 373.901452 -261.218193) (xy 373.909395 -261.165489) (xy 373.925105 -261.114559)
			(xy 373.948231 -261.066538) (xy 373.978255 -261.022501) (xy 374.014507 -260.98343) (xy 374.056178 -260.950199)
			(xy 374.102336 -260.92355) (xy 374.15195 -260.904078) (xy 374.203912 -260.892218) (xy 374.257062 -260.888235)
			(xy 374.310212 -260.892218) (xy 374.362174 -260.904078) (xy 374.411788 -260.92355) (xy 374.457946 -260.950199)
			(xy 374.499617 -260.98343) (xy 374.535869 -261.022501) (xy 374.565893 -261.066538) (xy 374.589019 -261.114559)
			(xy 374.604729 -261.165489) (xy 374.612672 -261.218193) (xy 374.61317 -261.244842) (xy 374.612672 -261.271491)
			(xy 374.841252 -261.271491) (xy 374.841252 -261.218193) (xy 374.849195 -261.165489) (xy 374.864905 -261.114559)
			(xy 374.888031 -261.066538) (xy 374.918055 -261.022501) (xy 374.954307 -260.98343) (xy 374.995978 -260.950199)
			(xy 375.042136 -260.92355) (xy 375.09175 -260.904078) (xy 375.143712 -260.892218) (xy 375.196862 -260.888235)
			(xy 375.250012 -260.892218) (xy 375.301974 -260.904078) (xy 375.351588 -260.92355) (xy 375.397746 -260.950199)
			(xy 375.439417 -260.98343) (xy 375.475669 -261.022501) (xy 375.505693 -261.066538) (xy 375.528819 -261.114559)
			(xy 375.544529 -261.165489) (xy 375.552472 -261.218193) (xy 375.55297 -261.244842) (xy 375.552472 -261.271491)
			(xy 375.781052 -261.271491) (xy 375.781052 -261.218193) (xy 375.788995 -261.165489) (xy 375.804705 -261.114559)
			(xy 375.827831 -261.066538) (xy 375.857855 -261.022501) (xy 375.894107 -260.98343) (xy 375.935778 -260.950199)
			(xy 375.981936 -260.92355) (xy 376.03155 -260.904078) (xy 376.083512 -260.892218) (xy 376.136662 -260.888235)
			(xy 376.189812 -260.892218) (xy 376.241774 -260.904078) (xy 376.291388 -260.92355) (xy 376.337546 -260.950199)
			(xy 376.379217 -260.98343) (xy 376.415469 -261.022501) (xy 376.445493 -261.066538) (xy 376.468619 -261.114559)
			(xy 376.484329 -261.165489) (xy 376.492272 -261.218193) (xy 376.49277 -261.244842) (xy 376.492272 -261.271491)
			(xy 376.720852 -261.271491) (xy 376.720852 -261.218193) (xy 376.728795 -261.165489) (xy 376.744505 -261.114559)
			(xy 376.767631 -261.066538) (xy 376.797655 -261.022501) (xy 376.833907 -260.98343) (xy 376.875578 -260.950199)
			(xy 376.921736 -260.92355) (xy 376.97135 -260.904078) (xy 377.023312 -260.892218) (xy 377.076462 -260.888235)
			(xy 377.129612 -260.892218) (xy 377.181574 -260.904078) (xy 377.231188 -260.92355) (xy 377.277346 -260.950199)
			(xy 377.319017 -260.98343) (xy 377.355269 -261.022501) (xy 377.385293 -261.066538) (xy 377.408419 -261.114559)
			(xy 377.424129 -261.165489) (xy 377.432072 -261.218193) (xy 377.43257 -261.244842) (xy 377.432072 -261.271491)
			(xy 377.660652 -261.271491) (xy 377.660652 -261.218193) (xy 377.668595 -261.165489) (xy 377.684305 -261.114559)
			(xy 377.707431 -261.066538) (xy 377.737455 -261.022501) (xy 377.773707 -260.98343) (xy 377.815378 -260.950199)
			(xy 377.861536 -260.92355) (xy 377.91115 -260.904078) (xy 377.963112 -260.892218) (xy 378.016262 -260.888235)
			(xy 378.069412 -260.892218) (xy 378.121374 -260.904078) (xy 378.170988 -260.92355) (xy 378.217146 -260.950199)
			(xy 378.258817 -260.98343) (xy 378.295069 -261.022501) (xy 378.325093 -261.066538) (xy 378.348219 -261.114559)
			(xy 378.363929 -261.165489) (xy 378.371872 -261.218193) (xy 378.37237 -261.244842) (xy 378.371872 -261.271491)
			(xy 378.600452 -261.271491) (xy 378.600452 -261.218193) (xy 378.608395 -261.165489) (xy 378.624105 -261.114559)
			(xy 378.647231 -261.066538) (xy 378.677255 -261.022501) (xy 378.713507 -260.98343) (xy 378.755178 -260.950199)
			(xy 378.801336 -260.92355) (xy 378.85095 -260.904078) (xy 378.902912 -260.892218) (xy 378.956062 -260.888235)
			(xy 379.009212 -260.892218) (xy 379.061174 -260.904078) (xy 379.110788 -260.92355) (xy 379.156946 -260.950199)
			(xy 379.198617 -260.98343) (xy 379.234869 -261.022501) (xy 379.264893 -261.066538) (xy 379.288019 -261.114559)
			(xy 379.303729 -261.165489) (xy 379.311672 -261.218193) (xy 379.31217 -261.244842) (xy 379.311672 -261.271491)
			(xy 379.540252 -261.271491) (xy 379.540252 -261.218193) (xy 379.548195 -261.165489) (xy 379.563905 -261.114559)
			(xy 379.587031 -261.066538) (xy 379.617055 -261.022501) (xy 379.653307 -260.98343) (xy 379.694978 -260.950199)
			(xy 379.741136 -260.92355) (xy 379.79075 -260.904078) (xy 379.842712 -260.892218) (xy 379.895862 -260.888235)
			(xy 379.949012 -260.892218) (xy 380.000974 -260.904078) (xy 380.050588 -260.92355) (xy 380.096746 -260.950199)
			(xy 380.138417 -260.98343) (xy 380.174669 -261.022501) (xy 380.204693 -261.066538) (xy 380.227819 -261.114559)
			(xy 380.243529 -261.165489) (xy 380.251472 -261.218193) (xy 380.25197 -261.244842) (xy 380.251472 -261.271491)
			(xy 380.243529 -261.324195) (xy 380.227819 -261.375125) (xy 380.204693 -261.423146) (xy 380.174669 -261.467183)
			(xy 380.138417 -261.506254) (xy 380.096746 -261.539485) (xy 380.050588 -261.566134) (xy 380.000974 -261.585606)
			(xy 379.949012 -261.597466) (xy 379.895862 -261.60145) (xy 379.842712 -261.597466) (xy 379.79075 -261.585606)
			(xy 379.741136 -261.566134) (xy 379.694978 -261.539485) (xy 379.653307 -261.506254) (xy 379.617055 -261.467183)
			(xy 379.587031 -261.423146) (xy 379.563905 -261.375125) (xy 379.548195 -261.324195) (xy 379.540252 -261.271491)
			(xy 379.311672 -261.271491) (xy 379.303729 -261.324195) (xy 379.288019 -261.375125) (xy 379.264893 -261.423146)
			(xy 379.234869 -261.467183) (xy 379.198617 -261.506254) (xy 379.156946 -261.539485) (xy 379.110788 -261.566134)
			(xy 379.061174 -261.585606) (xy 379.009212 -261.597466) (xy 378.956062 -261.60145) (xy 378.902912 -261.597466)
			(xy 378.85095 -261.585606) (xy 378.801336 -261.566134) (xy 378.755178 -261.539485) (xy 378.713507 -261.506254)
			(xy 378.677255 -261.467183) (xy 378.647231 -261.423146) (xy 378.624105 -261.375125) (xy 378.608395 -261.324195)
			(xy 378.600452 -261.271491) (xy 378.371872 -261.271491) (xy 378.363929 -261.324195) (xy 378.348219 -261.375125)
			(xy 378.325093 -261.423146) (xy 378.295069 -261.467183) (xy 378.258817 -261.506254) (xy 378.217146 -261.539485)
			(xy 378.170988 -261.566134) (xy 378.121374 -261.585606) (xy 378.069412 -261.597466) (xy 378.016262 -261.60145)
			(xy 377.963112 -261.597466) (xy 377.91115 -261.585606) (xy 377.861536 -261.566134) (xy 377.815378 -261.539485)
			(xy 377.773707 -261.506254) (xy 377.737455 -261.467183) (xy 377.707431 -261.423146) (xy 377.684305 -261.375125)
			(xy 377.668595 -261.324195) (xy 377.660652 -261.271491) (xy 377.432072 -261.271491) (xy 377.424129 -261.324195)
			(xy 377.408419 -261.375125) (xy 377.385293 -261.423146) (xy 377.355269 -261.467183) (xy 377.319017 -261.506254)
			(xy 377.277346 -261.539485) (xy 377.231188 -261.566134) (xy 377.181574 -261.585606) (xy 377.129612 -261.597466)
			(xy 377.076462 -261.60145) (xy 377.023312 -261.597466) (xy 376.97135 -261.585606) (xy 376.921736 -261.566134)
			(xy 376.875578 -261.539485) (xy 376.833907 -261.506254) (xy 376.797655 -261.467183) (xy 376.767631 -261.423146)
			(xy 376.744505 -261.375125) (xy 376.728795 -261.324195) (xy 376.720852 -261.271491) (xy 376.492272 -261.271491)
			(xy 376.484329 -261.324195) (xy 376.468619 -261.375125) (xy 376.445493 -261.423146) (xy 376.415469 -261.467183)
			(xy 376.379217 -261.506254) (xy 376.337546 -261.539485) (xy 376.291388 -261.566134) (xy 376.241774 -261.585606)
			(xy 376.189812 -261.597466) (xy 376.136662 -261.60145) (xy 376.083512 -261.597466) (xy 376.03155 -261.585606)
			(xy 375.981936 -261.566134) (xy 375.935778 -261.539485) (xy 375.894107 -261.506254) (xy 375.857855 -261.467183)
			(xy 375.827831 -261.423146) (xy 375.804705 -261.375125) (xy 375.788995 -261.324195) (xy 375.781052 -261.271491)
			(xy 375.552472 -261.271491) (xy 375.544529 -261.324195) (xy 375.528819 -261.375125) (xy 375.505693 -261.423146)
			(xy 375.475669 -261.467183) (xy 375.439417 -261.506254) (xy 375.397746 -261.539485) (xy 375.351588 -261.566134)
			(xy 375.301974 -261.585606) (xy 375.250012 -261.597466) (xy 375.196862 -261.60145) (xy 375.143712 -261.597466)
			(xy 375.09175 -261.585606) (xy 375.042136 -261.566134) (xy 374.995978 -261.539485) (xy 374.954307 -261.506254)
			(xy 374.918055 -261.467183) (xy 374.888031 -261.423146) (xy 374.864905 -261.375125) (xy 374.849195 -261.324195)
			(xy 374.841252 -261.271491) (xy 374.612672 -261.271491) (xy 374.604729 -261.324195) (xy 374.589019 -261.375125)
			(xy 374.565893 -261.423146) (xy 374.535869 -261.467183) (xy 374.499617 -261.506254) (xy 374.457946 -261.539485)
			(xy 374.411788 -261.566134) (xy 374.362174 -261.585606) (xy 374.310212 -261.597466) (xy 374.257062 -261.60145)
			(xy 374.203912 -261.597466) (xy 374.15195 -261.585606) (xy 374.102336 -261.566134) (xy 374.056178 -261.539485)
			(xy 374.014507 -261.506254) (xy 373.978255 -261.467183) (xy 373.948231 -261.423146) (xy 373.925105 -261.375125)
			(xy 373.909395 -261.324195) (xy 373.901452 -261.271491) (xy 373.672872 -261.271491) (xy 373.664929 -261.324195)
			(xy 373.649219 -261.375125) (xy 373.626093 -261.423146) (xy 373.596069 -261.467183) (xy 373.559817 -261.506254)
			(xy 373.518146 -261.539485) (xy 373.471988 -261.566134) (xy 373.422374 -261.585606) (xy 373.370412 -261.597466)
			(xy 373.317262 -261.60145) (xy 373.264112 -261.597466) (xy 373.21215 -261.585606) (xy 373.162536 -261.566134)
			(xy 373.116378 -261.539485) (xy 373.074707 -261.506254) (xy 373.038455 -261.467183) (xy 373.008431 -261.423146)
			(xy 372.985305 -261.375125) (xy 372.969595 -261.324195) (xy 372.961652 -261.271491) (xy 372.733072 -261.271491)
			(xy 372.725129 -261.324195) (xy 372.709419 -261.375125) (xy 372.686293 -261.423146) (xy 372.656269 -261.467183)
			(xy 372.620017 -261.506254) (xy 372.578346 -261.539485) (xy 372.532188 -261.566134) (xy 372.482574 -261.585606)
			(xy 372.430612 -261.597466) (xy 372.377462 -261.60145) (xy 372.324312 -261.597466) (xy 372.27235 -261.585606)
			(xy 372.222736 -261.566134) (xy 372.176578 -261.539485) (xy 372.134907 -261.506254) (xy 372.098655 -261.467183)
			(xy 372.068631 -261.423146) (xy 372.045505 -261.375125) (xy 372.029795 -261.324195) (xy 372.021852 -261.271491)
			(xy 371.793272 -261.271491) (xy 371.785329 -261.324195) (xy 371.769619 -261.375125) (xy 371.746493 -261.423146)
			(xy 371.716469 -261.467183) (xy 371.680217 -261.506254) (xy 371.638546 -261.539485) (xy 371.592388 -261.566134)
			(xy 371.542774 -261.585606) (xy 371.490812 -261.597466) (xy 371.437662 -261.60145) (xy 371.384512 -261.597466)
			(xy 371.33255 -261.585606) (xy 371.282936 -261.566134) (xy 371.236778 -261.539485) (xy 371.195107 -261.506254)
			(xy 371.158855 -261.467183) (xy 371.128831 -261.423146) (xy 371.105705 -261.375125) (xy 371.089995 -261.324195)
			(xy 371.082052 -261.271491) (xy 370.853472 -261.271491) (xy 370.845529 -261.324195) (xy 370.829819 -261.375125)
			(xy 370.806693 -261.423146) (xy 370.776669 -261.467183) (xy 370.740417 -261.506254) (xy 370.698746 -261.539485)
			(xy 370.652588 -261.566134) (xy 370.602974 -261.585606) (xy 370.551012 -261.597466) (xy 370.497862 -261.60145)
			(xy 370.444712 -261.597466) (xy 370.39275 -261.585606) (xy 370.343136 -261.566134) (xy 370.296978 -261.539485)
			(xy 370.255307 -261.506254) (xy 370.219055 -261.467183) (xy 370.189031 -261.423146) (xy 370.165905 -261.375125)
			(xy 370.150195 -261.324195) (xy 370.142252 -261.271491) (xy 369.413536 -261.271491) (xy 369.413536 -261.48157)
			(xy 369.722146 -261.790434) (xy 369.729264 -261.796907) (xy 369.746938 -261.804472) (xy 369.766156 -261.805024)
			(xy 369.784235 -261.798487) (xy 369.791742 -261.792466) (xy 369.811387 -261.775615) (xy 369.854634 -261.747183)
			(xy 369.901544 -261.725317) (xy 369.951128 -261.71048) (xy 370.002338 -261.702983) (xy 370.028216 -261.70255)
			(xy 370.056199 -261.7031) (xy 370.111477 -261.711857) (xy 370.164705 -261.729152) (xy 370.214572 -261.754561)
			(xy 370.259851 -261.787456) (xy 370.299427 -261.827029) (xy 370.332326 -261.872306) (xy 370.357738 -261.922171)
			(xy 370.375037 -261.975397) (xy 370.383798 -262.030675) (xy 370.384324 -262.058658) (xy 370.383855 -262.084534)
			(xy 370.376355 -262.135738) (xy 370.361519 -262.185317) (xy 370.339662 -262.232226) (xy 370.311243 -262.275476)
			(xy 370.294408 -262.295132) (xy 370.262658 -262.330946) (xy 370.32946 -262.397748)
		)
		(stroke
			(width 0)
			(type solid)
		)
		(fill yes)
		(layer "In13.Cu")
		(net "PVCCD_HV_CPU0")
	)
	(gr_poly
		(pts
			(xy 122.694446 -261.933182) (xy 122.70441 -261.908128) (xy 122.730799 -261.86111) (xy 122.763974 -261.818608)
			(xy 122.803178 -261.781594) (xy 122.847514 -261.750913) (xy 122.895969 -261.727266) (xy 122.947435 -261.711195)
			(xy 123.000736 -261.703067) (xy 123.054652 -261.703067) (xy 123.107953 -261.711195) (xy 123.159419 -261.727266)
			(xy 123.207874 -261.750913) (xy 123.25221 -261.781594) (xy 123.291414 -261.818608) (xy 123.324589 -261.86111)
			(xy 123.350978 -261.908128) (xy 123.360942 -261.933182) (xy 123.373388 -261.965948) (xy 123.622054 -261.965948)
			(xy 123.6345 -261.933182) (xy 123.644464 -261.908128) (xy 123.670853 -261.86111) (xy 123.704028 -261.818608)
			(xy 123.743232 -261.781594) (xy 123.787568 -261.750913) (xy 123.836023 -261.727266) (xy 123.887489 -261.711195)
			(xy 123.94079 -261.703067) (xy 123.994706 -261.703067) (xy 124.048007 -261.711195) (xy 124.099473 -261.727266)
			(xy 124.147928 -261.750913) (xy 124.192264 -261.781594) (xy 124.231468 -261.818608) (xy 124.264643 -261.86111)
			(xy 124.291032 -261.908128) (xy 124.300996 -261.933182) (xy 124.313442 -261.965948) (xy 124.561854 -261.965948)
			(xy 124.5743 -261.933182) (xy 124.584264 -261.908128) (xy 124.610653 -261.86111) (xy 124.643828 -261.818608)
			(xy 124.683032 -261.781594) (xy 124.727368 -261.750913) (xy 124.775823 -261.727266) (xy 124.827289 -261.711195)
			(xy 124.88059 -261.703067) (xy 124.934506 -261.703067) (xy 124.987807 -261.711195) (xy 125.039273 -261.727266)
			(xy 125.087728 -261.750913) (xy 125.132064 -261.781594) (xy 125.171268 -261.818608) (xy 125.204443 -261.86111)
			(xy 125.230832 -261.908128) (xy 125.240796 -261.933182) (xy 125.253242 -261.965948) (xy 125.5014 -261.965948)
			(xy 125.513846 -261.933182) (xy 125.52381 -261.908128) (xy 125.550199 -261.86111) (xy 125.583374 -261.818608)
			(xy 125.622578 -261.781594) (xy 125.666914 -261.750913) (xy 125.715369 -261.727266) (xy 125.766835 -261.711195)
			(xy 125.820136 -261.703067) (xy 125.874052 -261.703067) (xy 125.927353 -261.711195) (xy 125.978819 -261.727266)
			(xy 126.027274 -261.750913) (xy 126.07161 -261.781594) (xy 126.110814 -261.818608) (xy 126.143989 -261.86111)
			(xy 126.170378 -261.908128) (xy 126.180342 -261.933182) (xy 126.192788 -261.965948) (xy 126.441454 -261.965948)
			(xy 126.4539 -261.933182) (xy 126.463864 -261.908128) (xy 126.490253 -261.86111) (xy 126.523428 -261.818608)
			(xy 126.562632 -261.781594) (xy 126.606968 -261.750913) (xy 126.655423 -261.727266) (xy 126.706889 -261.711195)
			(xy 126.76019 -261.703067) (xy 126.814106 -261.703067) (xy 126.867407 -261.711195) (xy 126.918873 -261.727266)
			(xy 126.967328 -261.750913) (xy 127.011664 -261.781594) (xy 127.050868 -261.818608) (xy 127.084043 -261.86111)
			(xy 127.110432 -261.908128) (xy 127.120396 -261.933182) (xy 127.132842 -261.965948) (xy 127.381254 -261.965948)
			(xy 127.3937 -261.933182) (xy 127.403664 -261.908128) (xy 127.430053 -261.86111) (xy 127.463228 -261.818608)
			(xy 127.502432 -261.781594) (xy 127.546768 -261.750913) (xy 127.595223 -261.727266) (xy 127.646689 -261.711195)
			(xy 127.69999 -261.703067) (xy 127.753906 -261.703067) (xy 127.807207 -261.711195) (xy 127.858673 -261.727266)
			(xy 127.907128 -261.750913) (xy 127.951464 -261.781594) (xy 127.990668 -261.818608) (xy 128.023843 -261.86111)
			(xy 128.050232 -261.908128) (xy 128.060196 -261.933182) (xy 128.072642 -261.965948) (xy 128.321054 -261.965948)
			(xy 128.3335 -261.933182) (xy 128.343464 -261.908128) (xy 128.369853 -261.86111) (xy 128.403028 -261.818608)
			(xy 128.442232 -261.781594) (xy 128.486568 -261.750913) (xy 128.535023 -261.727266) (xy 128.586489 -261.711195)
			(xy 128.63979 -261.703067) (xy 128.693706 -261.703067) (xy 128.747007 -261.711195) (xy 128.798473 -261.727266)
			(xy 128.846928 -261.750913) (xy 128.891264 -261.781594) (xy 128.930468 -261.818608) (xy 128.963643 -261.86111)
			(xy 128.990032 -261.908128) (xy 128.999996 -261.933182) (xy 129.012442 -261.965948) (xy 129.260854 -261.965948)
			(xy 129.2733 -261.933182) (xy 129.283264 -261.908128) (xy 129.309653 -261.86111) (xy 129.342828 -261.818608)
			(xy 129.382032 -261.781594) (xy 129.426368 -261.750913) (xy 129.474823 -261.727266) (xy 129.526289 -261.711195)
			(xy 129.57959 -261.703067) (xy 129.633506 -261.703067) (xy 129.686807 -261.711195) (xy 129.738273 -261.727266)
			(xy 129.786728 -261.750913) (xy 129.831064 -261.781594) (xy 129.870268 -261.818608) (xy 129.903443 -261.86111)
			(xy 129.929832 -261.908128) (xy 129.939796 -261.933182) (xy 129.952242 -261.965948) (xy 130.200654 -261.965948)
			(xy 130.2131 -261.933182) (xy 130.223064 -261.908128) (xy 130.249453 -261.86111) (xy 130.282628 -261.818608)
			(xy 130.321832 -261.781594) (xy 130.366168 -261.750913) (xy 130.414623 -261.727266) (xy 130.466089 -261.711195)
			(xy 130.51939 -261.703067) (xy 130.573306 -261.703067) (xy 130.626607 -261.711195) (xy 130.678073 -261.727266)
			(xy 130.726528 -261.750913) (xy 130.770864 -261.781594) (xy 130.810068 -261.818608) (xy 130.843243 -261.86111)
			(xy 130.869632 -261.908128) (xy 130.879596 -261.933182) (xy 130.892042 -261.965948) (xy 131.140454 -261.965948)
			(xy 131.1529 -261.933182) (xy 131.162864 -261.908128) (xy 131.189253 -261.86111) (xy 131.222428 -261.818608)
			(xy 131.261632 -261.781594) (xy 131.305968 -261.750913) (xy 131.354423 -261.727266) (xy 131.405889 -261.711195)
			(xy 131.45919 -261.703067) (xy 131.513106 -261.703067) (xy 131.566407 -261.711195) (xy 131.617873 -261.727266)
			(xy 131.666328 -261.750913) (xy 131.710664 -261.781594) (xy 131.749868 -261.818608) (xy 131.783043 -261.86111)
			(xy 131.809432 -261.908128) (xy 131.819396 -261.933182) (xy 131.831842 -261.965948) (xy 132.08 -261.965948)
			(xy 132.092446 -261.933182) (xy 132.10241 -261.908128) (xy 132.128799 -261.86111) (xy 132.161974 -261.818608)
			(xy 132.201178 -261.781594) (xy 132.245514 -261.750913) (xy 132.293969 -261.727266) (xy 132.345435 -261.711195)
			(xy 132.398736 -261.703067) (xy 132.452652 -261.703067) (xy 132.505953 -261.711195) (xy 132.557419 -261.727266)
			(xy 132.605874 -261.750913) (xy 132.65021 -261.781594) (xy 132.689414 -261.818608) (xy 132.722589 -261.86111)
			(xy 132.748978 -261.908128) (xy 132.758942 -261.933182) (xy 132.771388 -261.965948) (xy 133.020054 -261.965948)
			(xy 133.0325 -261.933182) (xy 133.042464 -261.908128) (xy 133.068853 -261.86111) (xy 133.102028 -261.818608)
			(xy 133.141232 -261.781594) (xy 133.185568 -261.750913) (xy 133.234023 -261.727266) (xy 133.285489 -261.711195)
			(xy 133.33879 -261.703067) (xy 133.392706 -261.703067) (xy 133.446007 -261.711195) (xy 133.497473 -261.727266)
			(xy 133.545928 -261.750913) (xy 133.590264 -261.781594) (xy 133.629468 -261.818608) (xy 133.662643 -261.86111)
			(xy 133.689032 -261.908128) (xy 133.698996 -261.933182) (xy 133.711442 -261.965948) (xy 133.959854 -261.965948)
			(xy 133.9723 -261.933182) (xy 133.982265 -261.908128) (xy 134.008656 -261.861111) (xy 134.041832 -261.818609)
			(xy 134.081036 -261.781593) (xy 134.125371 -261.75091) (xy 134.173825 -261.72726) (xy 134.225289 -261.711184)
			(xy 134.278589 -261.703049) (xy 134.305548 -261.70255) (xy 134.330788 -261.70299) (xy 134.380761 -261.710133)
			(xy 134.405116 -261.716774) (xy 134.434072 -261.725156) (xy 134.521194 -261.638034) (xy 134.530266 -261.628351)
			(xy 134.543546 -261.605391) (xy 134.550461 -261.579785) (xy 134.550546 -261.553262) (xy 134.543794 -261.527612)
			(xy 134.530662 -261.504568) (xy 134.521702 -261.494778) (xy 134.502599 -261.474674) (xy 134.470232 -261.429644)
			(xy 134.445243 -261.380137) (xy 134.428237 -261.327353) (xy 134.419627 -261.27257) (xy 134.419086 -261.244842)
			(xy 134.419603 -261.216854) (xy 134.428353 -261.161567) (xy 134.445646 -261.10833) (xy 134.471053 -261.058453)
			(xy 134.503951 -261.013166) (xy 134.543529 -260.973583) (xy 134.588812 -260.940679) (xy 134.638685 -260.915264)
			(xy 134.69192 -260.897965) (xy 134.747206 -260.889207) (xy 134.775194 -260.888734) (xy 134.80292 -260.889284)
			(xy 134.857696 -260.897916) (xy 134.910476 -260.914927) (xy 134.959984 -260.939905) (xy 135.005027 -260.972248)
			(xy 135.02513 -260.99135) (xy 135.034875 -261.000363) (xy 135.057931 -261.013498) (xy 135.083593 -261.020247)
			(xy 135.110128 -261.020152) (xy 135.135741 -261.013221) (xy 135.158703 -260.999922) (xy 135.168386 -260.990842)
			(xy 135.211312 -260.947916) (xy 135.220575 -260.93807) (xy 135.23401 -260.914622) (xy 135.240814 -260.888469)
			(xy 135.240508 -260.861447) (xy 135.233115 -260.835454) (xy 135.219154 -260.812316) (xy 135.199605 -260.793658)
			(xy 135.175841 -260.780791) (xy 135.162798 -260.777228) (xy 135.13715 -260.770639) (xy 135.088011 -260.75091)
			(xy 135.042333 -260.724123) (xy 135.001125 -260.690868) (xy 134.965295 -260.65188) (xy 134.935632 -260.608015)
			(xy 134.91279 -260.560243) (xy 134.897273 -260.509615) (xy 134.889422 -260.457248) (xy 134.888986 -260.430772)
			(xy 134.889505 -260.40319) (xy 134.89801 -260.348687) (xy 134.914815 -260.296145) (xy 134.939515 -260.246821)
			(xy 134.971523 -260.201893) (xy 135.010072 -260.162434) (xy 135.054241 -260.129388) (xy 135.102976 -260.103544)
			(xy 135.155112 -260.085519) (xy 135.209402 -260.075745) (xy 135.236966 -260.074664) (xy 135.250086 -260.073961)
			(xy 135.275324 -260.066691) (xy 135.29787 -260.05322) (xy 135.316231 -260.034439) (xy 135.329188 -260.011593)
			(xy 135.335884 -259.986196) (xy 135.33628 -259.973064) (xy 135.33628 -259.260848) (xy 135.335864 -259.24772)
			(xy 135.329156 -259.222334) (xy 135.316197 -259.199498) (xy 135.297843 -259.180722) (xy 135.275308 -259.167246)
			(xy 135.250081 -259.159962) (xy 135.236966 -259.159248) (xy 135.210711 -259.158179) (xy 135.158926 -259.149276)
			(xy 135.109011 -259.132863) (xy 135.062048 -259.109295) (xy 135.019056 -259.079085) (xy 134.980968 -259.042888)
			(xy 134.948611 -259.001488) (xy 134.922685 -258.955784) (xy 134.903755 -258.906768) (xy 134.892229 -258.855503)
			(xy 134.88836 -258.803101) (xy 134.892229 -258.750699) (xy 134.903754 -258.699434) (xy 134.922685 -258.650417)
			(xy 134.94861 -258.604714) (xy 134.980967 -258.563314) (xy 135.019055 -258.527116) (xy 135.062046 -258.496906)
			(xy 135.109009 -258.473338) (xy 135.158924 -258.456925) (xy 135.210709 -258.448021) (xy 135.236966 -258.447032)
			(xy 135.250084 -258.446328) (xy 135.275319 -258.439058) (xy 135.297861 -258.425586) (xy 135.316216 -258.406804)
			(xy 135.329167 -258.383958) (xy 135.335855 -258.358563) (xy 135.33628 -258.345432) (xy 135.33628 -257.632962)
			(xy 135.335866 -257.619833) (xy 135.32916 -257.594444) (xy 135.316202 -257.571605) (xy 135.297847 -257.552826)
			(xy 135.275311 -257.539347) (xy 135.250083 -257.532062) (xy 135.236966 -257.531362) (xy 135.210718 -257.530293)
			(xy 135.158945 -257.521392) (xy 135.109042 -257.504982) (xy 135.06209 -257.481421) (xy 135.019109 -257.451217)
			(xy 134.981031 -257.415028) (xy 134.948681 -257.373638) (xy 134.922762 -257.327946) (xy 134.903836 -257.278941)
			(xy 134.892314 -257.227688) (xy 134.888446 -257.175299) (xy 134.892315 -257.12291) (xy 134.903837 -257.071657)
			(xy 134.922763 -257.022652) (xy 134.948682 -256.97696) (xy 134.981032 -256.93557) (xy 135.019111 -256.899381)
			(xy 135.062092 -256.869178) (xy 135.109044 -256.845617) (xy 135.158947 -256.829207) (xy 135.21072 -256.820307)
			(xy 135.236966 -256.819146) (xy 135.250085 -256.818442) (xy 135.275321 -256.811172) (xy 135.297865 -256.7977)
			(xy 135.316222 -256.778919) (xy 135.329176 -256.756073) (xy 135.335868 -256.730678) (xy 135.33628 -256.717546)
			(xy 135.33628 -256.00533) (xy 135.335874 -255.992195) (xy 135.32918 -255.966792) (xy 135.316226 -255.943937)
			(xy 135.297871 -255.925144) (xy 135.275328 -255.911655) (xy 135.25009 -255.904363) (xy 135.236966 -255.90373)
			(xy 135.210713 -255.902661) (xy 135.15893 -255.893758) (xy 135.109017 -255.877346) (xy 135.062057 -255.85378)
			(xy 135.019067 -255.823571) (xy 134.980981 -255.787375) (xy 134.948625 -255.745978) (xy 134.922701 -255.700276)
			(xy 134.903772 -255.651262) (xy 134.892247 -255.6) (xy 134.888378 -255.547601) (xy 134.892247 -255.495201)
			(xy 134.903771 -255.443939) (xy 134.922701 -255.394925) (xy 134.948625 -255.349223) (xy 134.980981 -255.307826)
			(xy 135.019066 -255.27163) (xy 135.062056 -255.241421) (xy 135.109016 -255.217854) (xy 135.158929 -255.201442)
			(xy 135.210712 -255.192539) (xy 135.236966 -255.191514) (xy 135.250083 -255.19081) (xy 135.275316 -255.18354)
			(xy 135.297856 -255.170067) (xy 135.316208 -255.151285) (xy 135.329155 -255.128439) (xy 135.33584 -255.103044)
			(xy 135.33628 -255.089914) (xy 135.33628 -254.377444) (xy 135.335864 -254.364316) (xy 135.329155 -254.338931)
			(xy 135.316195 -254.316096) (xy 135.297841 -254.297321) (xy 135.275307 -254.283846) (xy 135.250081 -254.276562)
			(xy 135.236966 -254.275844) (xy 135.210712 -254.274775) (xy 135.158927 -254.265872) (xy 135.109012 -254.249459)
			(xy 135.06205 -254.225892) (xy 135.019058 -254.195682) (xy 134.980971 -254.159485) (xy 134.948614 -254.118086)
			(xy 134.922689 -254.072382) (xy 134.903758 -254.023367) (xy 134.892233 -253.972102) (xy 134.888364 -253.919701)
			(xy 134.892233 -253.867299) (xy 134.903758 -253.816035) (xy 134.922688 -253.767019) (xy 134.948613 -253.721316)
			(xy 134.98097 -253.679916) (xy 135.019057 -253.643719) (xy 135.062048 -253.613509) (xy 135.109011 -253.589942)
			(xy 135.158926 -253.573528) (xy 135.21071 -253.564625) (xy 135.236966 -253.563628) (xy 135.250084 -253.562924)
			(xy 135.275318 -253.555654) (xy 135.29786 -253.542181) (xy 135.316214 -253.5234) (xy 135.329164 -253.500554)
			(xy 135.335852 -253.475159) (xy 135.33628 -253.462028) (xy 135.33628 -249.300746) (xy 135.319262 -249.279348)
			(xy 135.291307 -249.232363) (xy 135.270856 -249.181661) (xy 135.25839 -249.128429) (xy 135.254199 -249.073919)
			(xy 135.258384 -249.019407) (xy 135.270845 -248.966175) (xy 135.291291 -248.91547) (xy 135.319241 -248.868483)
			(xy 135.33628 -248.847102) (xy 135.33628 -248.225564) (xy 135.319923 -248.20604) (xy 135.292372 -248.163201)
			(xy 135.271201 -248.116876) (xy 135.256842 -248.068009) (xy 135.249586 -248.017595) (xy 135.249582 -247.966662)
			(xy 135.25683 -247.916247) (xy 135.271181 -247.867377) (xy 135.292345 -247.821049) (xy 135.319888 -247.778206)
			(xy 135.33628 -247.758712) (xy 135.33628 -247.625108) (xy 135.335732 -247.609918) (xy 135.326821 -247.580875)
			(xy 135.309755 -247.555743) (xy 135.286048 -247.536747) (xy 135.257799 -247.525572) (xy 135.227512 -247.523208)
			(xy 135.212582 -247.526048) (xy 135.193522 -247.529984) (xy 135.154827 -247.534182) (xy 135.135366 -247.53443)
			(xy 135.108717 -247.53393) (xy 135.056014 -247.525982) (xy 135.005084 -247.510268) (xy 134.957066 -247.487139)
			(xy 134.91303 -247.457112) (xy 134.873961 -247.420858) (xy 134.840732 -247.379186) (xy 134.814084 -247.333027)
			(xy 134.794613 -247.283412) (xy 134.782753 -247.23145) (xy 134.77877 -247.1783) (xy 134.782753 -247.12515)
			(xy 134.794613 -247.073188) (xy 134.814084 -247.023573) (xy 134.840732 -246.977414) (xy 134.873961 -246.935742)
			(xy 134.91303 -246.899488) (xy 134.957066 -246.869461) (xy 135.005084 -246.846332) (xy 135.056014 -246.830618)
			(xy 135.108717 -246.82267) (xy 135.135366 -246.822214) (xy 135.154828 -246.822444) (xy 135.193525 -246.82664)
			(xy 135.212582 -246.830596) (xy 135.227511 -246.833338) (xy 135.257751 -246.830927) (xy 135.285951 -246.819744)
			(xy 135.309625 -246.800775) (xy 135.326687 -246.775691) (xy 135.335632 -246.746703) (xy 135.33628 -246.731536)
			(xy 135.33628 -246.597932) (xy 135.319925 -246.578408) (xy 135.292379 -246.53557) (xy 135.271213 -246.489246)
			(xy 135.256857 -246.440381) (xy 135.249605 -246.38997) (xy 135.249605 -246.339039) (xy 135.256855 -246.288628)
			(xy 135.271209 -246.239762) (xy 135.292375 -246.193438) (xy 135.31992 -246.150599) (xy 135.33628 -246.13108)
			(xy 135.33628 -245.997476) (xy 135.335728 -245.982289) (xy 135.326811 -245.953255) (xy 135.309744 -245.928131)
			(xy 135.286039 -245.909143) (xy 135.257796 -245.897972) (xy 135.227516 -245.895607) (xy 135.212582 -245.898416)
			(xy 135.193521 -245.902351) (xy 135.154827 -245.906549) (xy 135.135366 -245.906798) (xy 135.108719 -245.906298)
			(xy 135.056021 -245.89835) (xy 135.005096 -245.882638) (xy 134.957082 -245.859511) (xy 134.91305 -245.829487)
			(xy 134.873985 -245.793236) (xy 134.840758 -245.751568) (xy 134.814113 -245.705413) (xy 134.794643 -245.655803)
			(xy 134.782785 -245.603845) (xy 134.778802 -245.5507) (xy 134.782785 -245.497555) (xy 134.794643 -245.445597)
			(xy 134.814113 -245.395987) (xy 134.840758 -245.349832) (xy 134.873985 -245.308164) (xy 134.91305 -245.271913)
			(xy 134.957082 -245.241889) (xy 135.005096 -245.218762) (xy 135.056021 -245.20305) (xy 135.108719 -245.195102)
			(xy 135.135366 -245.194582) (xy 135.154828 -245.194812) (xy 135.193525 -245.199009) (xy 135.212582 -245.202964)
			(xy 135.227509 -245.205706) (xy 135.257747 -245.203296) (xy 135.285943 -245.192112) (xy 135.309613 -245.173142)
			(xy 135.326668 -245.148057) (xy 135.335605 -245.11907) (xy 135.33628 -245.103904) (xy 135.33628 -244.970046)
			(xy 135.319924 -244.950522) (xy 135.292376 -244.907684) (xy 135.271208 -244.86136) (xy 135.256851 -244.812493)
			(xy 135.249597 -244.762081) (xy 135.249595 -244.711149) (xy 135.256844 -244.660736) (xy 135.271197 -244.611869)
			(xy 135.292362 -244.565543) (xy 135.319906 -244.522702) (xy 135.33628 -244.503194) (xy 135.33628 -244.36959)
			(xy 135.33573 -244.354402) (xy 135.326815 -244.325364) (xy 135.309749 -244.300236) (xy 135.286043 -244.281245)
			(xy 135.257797 -244.270072) (xy 135.227514 -244.267707) (xy 135.212582 -244.27053) (xy 135.193522 -244.274466)
			(xy 135.154827 -244.278665) (xy 135.135366 -244.278912) (xy 135.108718 -244.278412) (xy 135.056018 -244.270464)
			(xy 135.005091 -244.254751) (xy 134.957075 -244.231623) (xy 134.913041 -244.201598) (xy 134.873974 -244.165346)
			(xy 134.840746 -244.123676) (xy 134.8141 -244.077519) (xy 134.79463 -244.027907) (xy 134.782771 -243.975947)
			(xy 134.778788 -243.9228) (xy 134.782771 -243.869653) (xy 134.79463 -243.817693) (xy 134.8141 -243.768081)
			(xy 134.840746 -243.721924) (xy 134.873974 -243.680254) (xy 134.913041 -243.644002) (xy 134.957075 -243.613977)
			(xy 135.005091 -243.590849) (xy 135.056018 -243.575136) (xy 135.108718 -243.567188) (xy 135.135366 -243.566696)
			(xy 135.154828 -243.566926) (xy 135.193525 -243.571123) (xy 135.212582 -243.575078) (xy 135.22751 -243.57782)
			(xy 135.257749 -243.57541) (xy 135.285947 -243.564226) (xy 135.309618 -243.545256) (xy 135.326676 -243.520172)
			(xy 135.335617 -243.491185) (xy 135.33628 -243.476018) (xy 135.33628 -243.342414) (xy 135.319926 -243.32289)
			(xy 135.292383 -243.280052) (xy 135.271219 -243.233729) (xy 135.256866 -243.184865) (xy 135.249616 -243.134455)
			(xy 135.249617 -243.083527) (xy 135.25687 -243.033117) (xy 135.271225 -242.984253) (xy 135.292392 -242.937932)
			(xy 135.319937 -242.895095) (xy 135.33628 -242.875562) (xy 135.33628 -242.741704) (xy 135.335732 -242.726514)
			(xy 135.32682 -242.697473) (xy 135.309754 -242.672341) (xy 135.286047 -242.653347) (xy 135.257798 -242.642172)
			(xy 135.227512 -242.639807) (xy 135.212582 -242.642644) (xy 135.193522 -242.64658) (xy 135.154827 -242.650779)
			(xy 135.135366 -242.651026) (xy 135.108717 -242.650526) (xy 135.056015 -242.642578) (xy 135.005086 -242.626864)
			(xy 134.957068 -242.603735) (xy 134.913032 -242.573709) (xy 134.873964 -242.537455) (xy 134.840735 -242.495784)
			(xy 134.814087 -242.449625) (xy 134.794616 -242.400011) (xy 134.782757 -242.348049) (xy 134.778774 -242.2949)
			(xy 134.782757 -242.241751) (xy 134.794616 -242.189789) (xy 134.814087 -242.140175) (xy 134.840735 -242.094016)
			(xy 134.873964 -242.052345) (xy 134.913032 -242.016091) (xy 134.957068 -241.986065) (xy 135.005086 -241.962936)
			(xy 135.056015 -241.947222) (xy 135.108717 -241.939274) (xy 135.135366 -241.93881) (xy 135.154828 -241.93904)
			(xy 135.193525 -241.943238) (xy 135.212582 -241.947192) (xy 135.227511 -241.949934) (xy 135.257751 -241.947523)
			(xy 135.28595 -241.93634) (xy 135.309624 -241.917371) (xy 135.326684 -241.892287) (xy 135.335628 -241.863299)
			(xy 135.33628 -241.848132) (xy 135.33628 -241.714528) (xy 135.319925 -241.695004) (xy 135.29238 -241.652166)
			(xy 135.271214 -241.605843) (xy 135.256859 -241.556978) (xy 135.249608 -241.506566) (xy 135.249608 -241.455637)
			(xy 135.256859 -241.405225) (xy 135.271213 -241.35636) (xy 135.292378 -241.310037) (xy 135.319924 -241.267198)
			(xy 135.33628 -241.247676) (xy 135.33628 -241.114072) (xy 135.335728 -241.098886) (xy 135.32681 -241.069853)
			(xy 135.309743 -241.04473) (xy 135.286038 -241.025742) (xy 135.257796 -241.014572) (xy 135.227516 -241.012207)
			(xy 135.212582 -241.015012) (xy 135.193521 -241.018947) (xy 135.154827 -241.023145) (xy 135.135366 -241.023394)
			(xy 135.108719 -241.022894) (xy 135.056022 -241.014946) (xy 135.005098 -240.999234) (xy 134.957084 -240.976108)
			(xy 134.913052 -240.946084) (xy 134.873987 -240.909833) (xy 134.840761 -240.868166) (xy 134.814116 -240.822011)
			(xy 134.794647 -240.772402) (xy 134.782789 -240.720444) (xy 134.778806 -240.6673) (xy 134.782789 -240.614156)
			(xy 134.794647 -240.562198) (xy 134.814116 -240.512589) (xy 134.840761 -240.466434) (xy 134.873987 -240.424767)
			(xy 134.913052 -240.388516) (xy 134.957084 -240.358492) (xy 135.005098 -240.335366) (xy 135.056022 -240.319654)
			(xy 135.108719 -240.311706) (xy 135.135366 -240.311178) (xy 135.154828 -240.311408) (xy 135.193525 -240.315605)
			(xy 135.212582 -240.31956) (xy 135.227514 -240.322301) (xy 135.25776 -240.319889) (xy 135.285966 -240.308708)
			(xy 135.309649 -240.28974) (xy 135.326723 -240.264658) (xy 135.335685 -240.23567) (xy 135.33628 -240.2205)
			(xy 135.33628 -240.086642) (xy 135.319924 -240.067118) (xy 135.292377 -240.02428) (xy 135.271209 -239.977956)
			(xy 135.256852 -239.92909) (xy 135.249599 -239.878678) (xy 135.249598 -239.827746) (xy 135.256847 -239.777334)
			(xy 135.271201 -239.728467) (xy 135.292365 -239.682141) (xy 135.31991 -239.639301) (xy 135.33628 -239.61979)
			(xy 135.33628 -239.486186) (xy 135.335729 -239.470998) (xy 135.326814 -239.441962) (xy 135.309748 -239.416835)
			(xy 135.286042 -239.397844) (xy 135.257797 -239.386672) (xy 135.227514 -239.384307) (xy 135.212582 -239.387126)
			(xy 135.193522 -239.391062) (xy 135.154827 -239.395261) (xy 135.135366 -239.395508) (xy 135.108718 -239.395008)
			(xy 135.056019 -239.38706) (xy 135.005093 -239.371347) (xy 134.957077 -239.34822) (xy 134.913044 -239.318195)
			(xy 134.873977 -239.281943) (xy 134.84075 -239.240273) (xy 134.814104 -239.194117) (xy 134.794634 -239.144506)
			(xy 134.782775 -239.092546) (xy 134.778792 -239.0394) (xy 134.782775 -238.986254) (xy 134.794634 -238.934294)
			(xy 134.814104 -238.884683) (xy 134.84075 -238.838527) (xy 134.873977 -238.796857) (xy 134.913044 -238.760605)
			(xy 134.957077 -238.73058) (xy 135.005093 -238.707453) (xy 135.056019 -238.69174) (xy 135.108718 -238.683792)
			(xy 135.135366 -238.683292) (xy 135.154828 -238.683522) (xy 135.193525 -238.687719) (xy 135.212582 -238.691674)
			(xy 135.22751 -238.694416) (xy 135.257748 -238.692005) (xy 135.285946 -238.680822) (xy 135.309616 -238.661852)
			(xy 135.326673 -238.636767) (xy 135.335613 -238.60778) (xy 135.33628 -238.592614) (xy 135.33628 -238.45901)
			(xy 135.319927 -238.439486) (xy 135.292384 -238.396649) (xy 135.27122 -238.350326) (xy 135.256868 -238.301462)
			(xy 135.249619 -238.251052) (xy 135.24962 -238.200124) (xy 135.256873 -238.149715) (xy 135.271229 -238.100852)
			(xy 135.292395 -238.05453) (xy 135.319941 -238.011694) (xy 135.33628 -237.992158) (xy 135.33628 -237.8583)
			(xy 135.335731 -237.843111) (xy 135.326818 -237.81407) (xy 135.309753 -237.78894) (xy 135.286046 -237.769946)
			(xy 135.257798 -237.758772) (xy 135.227513 -237.756407) (xy 135.212582 -237.75924) (xy 135.193522 -237.763176)
			(xy 135.154827 -237.767375) (xy 135.135366 -237.767622) (xy 135.108717 -237.767122) (xy 135.056016 -237.759174)
			(xy 135.005087 -237.74346) (xy 134.95707 -237.720332) (xy 134.913035 -237.690306) (xy 134.873967 -237.654052)
			(xy 134.840738 -237.612381) (xy 134.814091 -237.566224) (xy 134.79462 -237.51661) (xy 134.782761 -237.464648)
			(xy 134.778778 -237.4115) (xy 134.782761 -237.358352) (xy 134.79462 -237.30639) (xy 134.814091 -237.256776)
			(xy 134.840738 -237.210619) (xy 134.873967 -237.168948) (xy 134.913035 -237.132694) (xy 134.95707 -237.102668)
			(xy 135.005087 -237.07954) (xy 135.056016 -237.063826) (xy 135.108717 -237.055878) (xy 135.135366 -237.055406)
			(xy 135.154828 -237.055636) (xy 135.193525 -237.059833) (xy 135.212582 -237.063788) (xy 135.22751 -237.06653)
			(xy 135.25775 -237.064119) (xy 135.285949 -237.052936) (xy 135.309622 -237.033967) (xy 135.326682 -237.008882)
			(xy 135.335625 -236.979895) (xy 135.33628 -236.964728) (xy 135.33628 -236.831632) (xy 135.319879 -236.812102)
			(xy 135.292251 -236.769235) (xy 135.271021 -236.722865) (xy 135.256623 -236.673941) (xy 135.249352 -236.623463)
			(xy 135.249358 -236.572464) (xy 135.256638 -236.521988) (xy 135.271046 -236.473067) (xy 135.292286 -236.426701)
			(xy 135.319923 -236.38384) (xy 135.33628 -236.364272) (xy 135.33628 -236.230668) (xy 135.335727 -236.215482)
			(xy 135.326809 -236.18645) (xy 135.309742 -236.161328) (xy 135.286037 -236.142342) (xy 135.257795 -236.131171)
			(xy 135.227517 -236.128807) (xy 135.212582 -236.131608) (xy 135.193521 -236.135543) (xy 135.154827 -236.139741)
			(xy 135.135366 -236.13999) (xy 135.10872 -236.139489) (xy 135.056023 -236.131542) (xy 135.005099 -236.11583)
			(xy 134.957086 -236.092704) (xy 134.913055 -236.06268) (xy 134.873991 -236.02643) (xy 134.840765 -235.984763)
			(xy 134.81412 -235.938609) (xy 134.794651 -235.889) (xy 134.782793 -235.837044) (xy 134.778811 -235.7839)
			(xy 134.782793 -235.730756) (xy 134.794651 -235.6788) (xy 134.81412 -235.629191) (xy 134.840765 -235.583037)
			(xy 134.873991 -235.54137) (xy 134.913055 -235.50512) (xy 134.957086 -235.475096) (xy 135.005099 -235.45197)
			(xy 135.056023 -235.436258) (xy 135.10872 -235.428311) (xy 135.135366 -235.427774) (xy 135.154828 -235.428004)
			(xy 135.193525 -235.432201) (xy 135.212582 -235.436156) (xy 135.227514 -235.438897) (xy 135.257759 -235.436485)
			(xy 135.285965 -235.425304) (xy 135.309648 -235.406336) (xy 135.326721 -235.381254) (xy 135.335682 -235.352266)
			(xy 135.33628 -235.337096) (xy 135.33628 -235.203492) (xy 135.319928 -235.183968) (xy 135.292387 -235.141131)
			(xy 135.271227 -235.094809) (xy 135.256876 -235.045946) (xy 135.249629 -234.995538) (xy 135.249633 -234.944611)
			(xy 135.256887 -234.894204) (xy 135.271245 -234.845343) (xy 135.292412 -234.799024) (xy 135.319959 -234.756191)
			(xy 135.33628 -234.73664) (xy 135.33628 -234.603036) (xy 135.335723 -234.587854) (xy 135.326799 -234.55883)
			(xy 135.309731 -234.533717) (xy 135.286029 -234.514737) (xy 135.257793 -234.503571) (xy 135.22752 -234.501207)
			(xy 135.212582 -234.503976) (xy 135.193521 -234.507911) (xy 135.154827 -234.51211) (xy 135.135366 -234.512358)
			(xy 135.108715 -234.511858) (xy 135.056008 -234.503909) (xy 135.005074 -234.488194) (xy 134.957052 -234.465063)
			(xy 134.913012 -234.435034) (xy 134.873941 -234.398777) (xy 134.840708 -234.357102) (xy 134.814058 -234.310939)
			(xy 134.794586 -234.26132) (xy 134.782726 -234.209354) (xy 134.778742 -234.1562) (xy 134.782726 -234.103046)
			(xy 134.794586 -234.05108) (xy 134.814058 -234.001461) (xy 134.840708 -233.955298) (xy 134.873941 -233.913623)
			(xy 134.913012 -233.877366) (xy 134.957052 -233.847337) (xy 135.005074 -233.824206) (xy 135.056008 -233.808491)
			(xy 135.108715 -233.800542) (xy 135.135366 -233.800142) (xy 135.154828 -233.800372) (xy 135.193525 -233.804569)
			(xy 135.212582 -233.808524) (xy 135.227512 -233.811266) (xy 135.257755 -233.808854) (xy 135.285958 -233.797672)
			(xy 135.309636 -233.778703) (xy 135.326703 -233.75362) (xy 135.335655 -233.724632) (xy 135.33628 -233.709464)
			(xy 135.33628 -233.575606) (xy 135.319927 -233.556082) (xy 135.292385 -233.513245) (xy 135.271222 -233.466922)
			(xy 135.25687 -233.418058) (xy 135.249621 -233.367649) (xy 135.249623 -233.316721) (xy 135.256876 -233.266312)
			(xy 135.271232 -233.21745) (xy 135.292399 -233.171129) (xy 135.319945 -233.128294) (xy 135.33628 -233.108754)
			(xy 135.33628 -232.97515) (xy 135.335725 -232.959966) (xy 135.326803 -232.930939) (xy 135.309736 -232.905822)
			(xy 135.286033 -232.886839) (xy 135.257794 -232.875671) (xy 135.227519 -232.873307) (xy 135.212582 -232.87609)
			(xy 135.193521 -232.880025) (xy 135.154827 -232.884223) (xy 135.135366 -232.884472) (xy 135.108721 -232.883972)
			(xy 135.056027 -232.876025) (xy 135.005106 -232.860313) (xy 134.957095 -232.837188) (xy 134.913066 -232.807166)
			(xy 134.874004 -232.770918) (xy 134.84078 -232.729253) (xy 134.814136 -232.683102) (xy 134.794669 -232.633495)
			(xy 134.782811 -232.581541) (xy 134.778829 -232.5284) (xy 134.782811 -232.475259) (xy 134.794669 -232.423305)
			(xy 134.814136 -232.373698) (xy 134.84078 -232.327547) (xy 134.874004 -232.285882) (xy 134.913066 -232.249634)
			(xy 134.957095 -232.219612) (xy 135.005106 -232.196487) (xy 135.056027 -232.180775) (xy 135.108721 -232.172828)
			(xy 135.135366 -232.172256) (xy 135.154828 -232.172486) (xy 135.193525 -232.176683) (xy 135.212582 -232.180638)
			(xy 135.227513 -232.183379) (xy 135.257757 -232.180968) (xy 135.285961 -232.169786) (xy 135.309641 -232.150818)
			(xy 135.326711 -232.125735) (xy 135.335667 -232.096747) (xy 135.33628 -232.081578) (xy 135.33628 -231.947974)
			(xy 135.319922 -231.92845) (xy 135.29237 -231.885611) (xy 135.271198 -231.839286) (xy 135.256837 -231.790418)
			(xy 135.24958 -231.740003) (xy 135.249575 -231.689069) (xy 135.256822 -231.638653) (xy 135.271173 -231.589782)
			(xy 135.292335 -231.543453) (xy 135.319879 -231.500608) (xy 135.33628 -231.481122) (xy 135.33628 -231.347264)
			(xy 135.335727 -231.332079) (xy 135.326808 -231.303048) (xy 135.30974 -231.277927) (xy 135.286036 -231.258941)
			(xy 135.257795 -231.247771) (xy 135.227517 -231.245407) (xy 135.212582 -231.248204) (xy 135.193521 -231.252139)
			(xy 135.154827 -231.256337) (xy 135.135366 -231.256586) (xy 135.10872 -231.256085) (xy 135.056024 -231.248138)
			(xy 135.005101 -231.232426) (xy 134.957088 -231.2093) (xy 134.913058 -231.179277) (xy 134.873994 -231.143028)
			(xy 134.840768 -231.101361) (xy 134.814124 -231.055208) (xy 134.794655 -231.005599) (xy 134.782797 -230.953643)
			(xy 134.778815 -230.9005) (xy 134.782797 -230.847357) (xy 134.794655 -230.795401) (xy 134.814124 -230.745792)
			(xy 134.840768 -230.699639) (xy 134.873994 -230.657972) (xy 134.913058 -230.621723) (xy 134.957088 -230.5917)
			(xy 135.005101 -230.568574) (xy 135.056024 -230.552862) (xy 135.10872 -230.544915) (xy 135.135366 -230.54437)
			(xy 135.154828 -230.5446) (xy 135.193525 -230.548797) (xy 135.212582 -230.552752) (xy 135.227513 -230.555493)
			(xy 135.257759 -230.553081) (xy 135.285964 -230.5419) (xy 135.309646 -230.522932) (xy 135.326719 -230.49785)
			(xy 135.335678 -230.468862) (xy 135.33628 -230.453692) (xy 135.33628 -230.320088) (xy 135.319928 -230.300564)
			(xy 135.292388 -230.257727) (xy 135.271228 -230.211405) (xy 135.256878 -230.162542) (xy 135.249632 -230.112134)
			(xy 135.249636 -230.061208) (xy 135.256891 -230.010801) (xy 135.271248 -229.961941) (xy 135.292416 -229.915623)
			(xy 135.319963 -229.87279) (xy 135.33628 -229.853236) (xy 135.33628 -229.719632) (xy 135.335722 -229.70445)
			(xy 135.326798 -229.675428) (xy 135.30973 -229.650315) (xy 135.286028 -229.631336) (xy 135.257792 -229.620171)
			(xy 135.227521 -229.617807) (xy 135.212582 -229.620572) (xy 135.193522 -229.624507) (xy 135.154827 -229.628706)
			(xy 135.135366 -229.628954) (xy 135.108715 -229.628454) (xy 135.056009 -229.620505) (xy 135.005076 -229.60479)
			(xy 134.957054 -229.58166) (xy 134.913015 -229.551631) (xy 134.873943 -229.515374) (xy 134.840712 -229.473699)
			(xy 134.814062 -229.427537) (xy 134.79459 -229.377919) (xy 134.78273 -229.325953) (xy 134.778746 -229.2728)
			(xy 134.78273 -229.219647) (xy 134.79459 -229.167681) (xy 134.814062 -229.118063) (xy 134.840712 -229.071901)
			(xy 134.873943 -229.030226) (xy 134.913015 -228.993969) (xy 134.957054 -228.96394) (xy 135.005076 -228.94081)
			(xy 135.056009 -228.925095) (xy 135.108715 -228.917146) (xy 135.135366 -228.916738) (xy 135.154828 -228.916968)
			(xy 135.193525 -228.921165) (xy 135.212582 -228.92512) (xy 135.227512 -228.927862) (xy 135.257754 -228.92545)
			(xy 135.285957 -228.914268) (xy 135.309634 -228.895299) (xy 135.3267 -228.870216) (xy 135.335652 -228.841228)
			(xy 135.33628 -228.82606) (xy 135.33628 -228.692456) (xy 135.319923 -228.672932) (xy 135.292374 -228.630093)
			(xy 135.271204 -228.583769) (xy 135.256846 -228.534902) (xy 135.249591 -228.484489) (xy 135.249588 -228.433556)
			(xy 135.256836 -228.383142) (xy 135.271188 -228.334274) (xy 135.292352 -228.287946) (xy 135.319896 -228.245104)
			(xy 135.33628 -228.225604) (xy 135.33628 -228.091746) (xy 135.335724 -228.076563) (xy 135.326802 -228.047536)
			(xy 135.309734 -228.02242) (xy 135.286032 -228.003438) (xy 135.257793 -227.992271) (xy 135.227519 -227.989907)
			(xy 135.212582 -227.992686) (xy 135.193521 -227.996621) (xy 135.154827 -228.00082) (xy 135.135366 -228.001068)
			(xy 135.108721 -228.000568) (xy 135.056028 -227.992621) (xy 135.005107 -227.976909) (xy 134.957097 -227.953785)
			(xy 134.913069 -227.923763) (xy 134.874007 -227.887515) (xy 134.840783 -227.845851) (xy 134.81414 -227.7997)
			(xy 134.794672 -227.750094) (xy 134.782815 -227.69814) (xy 134.778833 -227.645) (xy 134.782815 -227.59186)
			(xy 134.794672 -227.539906) (xy 134.81414 -227.4903) (xy 134.840783 -227.444149) (xy 134.874007 -227.402485)
			(xy 134.913069 -227.366237) (xy 134.957097 -227.336215) (xy 135.005107 -227.313091) (xy 135.056028 -227.297379)
			(xy 135.108721 -227.289432) (xy 135.135366 -227.288852) (xy 135.154828 -227.289082) (xy 135.193525 -227.293279)
			(xy 135.212582 -227.297234) (xy 135.227513 -227.299975) (xy 135.257756 -227.297564) (xy 135.28596 -227.286382)
			(xy 135.30964 -227.267414) (xy 135.326708 -227.242331) (xy 135.335663 -227.213343) (xy 135.33628 -227.198174)
			(xy 135.33628 -227.06457) (xy 135.319922 -227.045046) (xy 135.292371 -227.002207) (xy 135.271199 -226.955882)
			(xy 135.256839 -226.907014) (xy 135.249583 -226.8566) (xy 135.249578 -226.805666) (xy 135.256825 -226.755251)
			(xy 135.271176 -226.70638) (xy 135.292339 -226.660051) (xy 135.319883 -226.617207) (xy 135.33628 -226.597718)
			(xy 135.33628 -226.464114) (xy 135.335733 -226.448923) (xy 135.326823 -226.419879) (xy 135.309757 -226.394745)
			(xy 135.286049 -226.375748) (xy 135.257799 -226.364572) (xy 135.227511 -226.362208) (xy 135.212582 -226.365054)
			(xy 135.193522 -226.36899) (xy 135.154827 -226.373188) (xy 135.135366 -226.373436) (xy 135.108716 -226.372936)
			(xy 135.056013 -226.364987) (xy 135.005082 -226.349273) (xy 134.957063 -226.326144) (xy 134.913026 -226.296117)
			(xy 134.873957 -226.259862) (xy 134.840727 -226.218189) (xy 134.814078 -226.17203) (xy 134.794607 -226.122414)
			(xy 134.782747 -226.070451) (xy 134.778764 -226.0173) (xy 134.782747 -225.964149) (xy 134.794607 -225.912186)
			(xy 134.814078 -225.86257) (xy 134.840727 -225.816411) (xy 134.873957 -225.774738) (xy 134.913026 -225.738483)
			(xy 134.957063 -225.708456) (xy 135.005082 -225.685327) (xy 135.056013 -225.669613) (xy 135.108716 -225.661664)
			(xy 135.135366 -225.66122) (xy 135.154828 -225.66145) (xy 135.193525 -225.665646) (xy 135.212582 -225.669602)
			(xy 135.227511 -225.672344) (xy 135.257752 -225.669933) (xy 135.285953 -225.65875) (xy 135.309627 -225.639781)
			(xy 135.32669 -225.614697) (xy 135.335637 -225.58571) (xy 135.33628 -225.570542) (xy 135.33628 -225.436684)
			(xy 135.316399 -225.412732) (xy 135.284381 -225.359358) (xy 135.262093 -225.301245) (xy 135.255508 -225.270822)
			(xy 135.252714 -225.255582) (xy 135.190738 -225.193606) (xy 135.180429 -225.183929) (xy 135.155741 -225.17017)
			(xy 135.128225 -225.163713) (xy 135.099994 -225.165053) (xy 135.073213 -225.174088) (xy 135.04994 -225.190124)
			(xy 135.03196 -225.21193) (xy 135.020653 -225.237833) (xy 135.018272 -225.251772) (xy 135.014358 -225.277024)
			(xy 135.000237 -225.326134) (xy 134.979241 -225.372721) (xy 134.951802 -225.415828) (xy 134.918482 -225.45457)
			(xy 134.879967 -225.488152) (xy 134.837047 -225.515883) (xy 134.790604 -225.537195) (xy 134.741591 -225.551649)
			(xy 134.691016 -225.558948) (xy 134.665466 -225.559366) (xy 134.637484 -225.558843) (xy 134.582209 -225.550083)
			(xy 134.528985 -225.532783) (xy 134.479122 -225.507371) (xy 134.433849 -225.474471) (xy 134.39428 -225.434893)
			(xy 134.36139 -225.389613) (xy 134.335988 -225.339745) (xy 134.3187 -225.286517) (xy 134.309951 -225.231241)
			(xy 134.309358 -225.203258) (xy 134.309736 -225.180014) (xy 134.315786 -225.13392) (xy 134.327776 -225.089004)
			(xy 134.336282 -225.067368) (xy 134.345934 -225.044254) (xy 134.173468 -224.745804) (xy 134.14883 -224.742502)
			(xy 134.123469 -224.738698) (xy 134.07412 -224.724753) (xy 134.027282 -224.703873) (xy 133.983924 -224.67649)
			(xy 133.944942 -224.64317) (xy 133.911143 -224.604602) (xy 133.883227 -224.561585) (xy 133.86177 -224.515008)
			(xy 133.847218 -224.465835) (xy 133.839869 -224.415083) (xy 133.839458 -224.389442) (xy 133.839899 -224.363953)
			(xy 133.84718 -224.313498) (xy 133.861584 -224.264597) (xy 133.882818 -224.218251) (xy 133.910446 -224.175409)
			(xy 133.943903 -224.136947) (xy 133.962902 -224.119948) (xy 133.973175 -224.110495) (xy 133.988561 -224.087212)
			(xy 133.997067 -224.060633) (xy 133.998057 -224.032744) (xy 133.991458 -224.005628) (xy 133.977762 -223.981313)
			(xy 133.968236 -223.971104) (xy 133.890258 -223.893126) (xy 133.859016 -223.905826) (xy 133.838054 -223.913902)
			(xy 133.794619 -223.925362) (xy 133.772402 -223.928686) (xy 133.747764 -223.931988) (xy 133.575298 -224.230438)
			(xy 133.58495 -224.253552) (xy 133.593466 -224.275184) (xy 133.605452 -224.320102) (xy 133.611493 -224.366197)
			(xy 133.611874 -224.389442) (xy 133.611376 -224.416091) (xy 133.603433 -224.468795) (xy 133.587723 -224.519725)
			(xy 133.564597 -224.567746) (xy 133.534573 -224.611783) (xy 133.498321 -224.650854) (xy 133.45665 -224.684085)
			(xy 133.410492 -224.710734) (xy 133.360878 -224.730206) (xy 133.308916 -224.742066) (xy 133.255766 -224.74605)
			(xy 133.202616 -224.742066) (xy 133.150654 -224.730206) (xy 133.10104 -224.710734) (xy 133.054882 -224.684085)
			(xy 133.013211 -224.650854) (xy 132.976959 -224.611783) (xy 132.946935 -224.567746) (xy 132.923809 -224.519725)
			(xy 132.908099 -224.468795) (xy 132.900156 -224.416091) (xy 132.899658 -224.389442) (xy 132.900107 -224.363817)
			(xy 132.90746 -224.313096) (xy 132.922005 -224.263953) (xy 132.943442 -224.217401) (xy 132.971329 -224.174401)
			(xy 133.00509 -224.135842) (xy 133.044028 -224.102518) (xy 133.08734 -224.075119) (xy 133.134131 -224.054208)
			(xy 133.183436 -224.040219) (xy 133.208776 -224.036382) (xy 133.233414 -224.03308) (xy 133.40588 -223.734376)
			(xy 133.396482 -223.711262) (xy 133.387972 -223.689672) (xy 133.375986 -223.64484) (xy 133.369934 -223.598829)
			(xy 133.369558 -223.575626) (xy 133.369919 -223.552838) (xy 133.37573 -223.507633) (xy 133.387261 -223.463539)
			(xy 133.395466 -223.442276) (xy 133.408166 -223.411034) (xy 133.04774 -223.050608) (xy 133.044692 -223.048322)
			(xy 133.023336 -223.031996) (xy 132.985324 -222.993988) (xy 132.969 -222.97263) (xy 132.966714 -222.969582)
			(xy 132.89788 -222.900748) (xy 132.874004 -222.90278) (xy 132.851956 -222.904686) (xy 132.807742 -222.906718)
			(xy 132.785612 -222.906844) (xy 132.750432 -222.906563) (xy 132.680257 -222.901475) (xy 132.645404 -222.896684)
			(xy 132.634982 -222.920844) (xy 132.608066 -222.966055) (xy 132.574791 -223.006814) (xy 132.535882 -223.042234)
			(xy 132.492186 -223.071544) (xy 132.444652 -223.094106) (xy 132.394316 -223.109429) (xy 132.342274 -223.11718)
			(xy 132.315966 -223.117664) (xy 132.287946 -223.117146) (xy 132.232595 -223.108377) (xy 132.179302 -223.091047)
			(xy 132.129381 -223.065582) (xy 132.084066 -223.032611) (xy 132.044475 -222.992949) (xy 132.011585 -222.947575)
			(xy 131.986209 -222.897609) (xy 131.968974 -222.844284) (xy 131.964176 -222.816674) (xy 131.957318 -222.773748)
			(xy 131.734814 -222.773748) (xy 131.727956 -222.816674) (xy 131.7231 -222.844271) (xy 131.705859 -222.897584)
			(xy 131.680483 -222.94754) (xy 131.647598 -222.992906) (xy 131.608015 -223.032564) (xy 131.56271 -223.065534)
			(xy 131.512801 -223.091004) (xy 131.459521 -223.108344) (xy 131.404182 -223.117128) (xy 131.376166 -223.117664)
			(xy 131.349855 -223.117196) (xy 131.297806 -223.109458) (xy 131.247463 -223.094143) (xy 131.199923 -223.071583)
			(xy 131.156223 -223.04227) (xy 131.117313 -223.006844) (xy 131.084044 -222.966075) (xy 131.057138 -222.920852)
			(xy 131.046728 -222.896684) (xy 131.011748 -222.901488) (xy 130.941319 -222.906572) (xy 130.906012 -222.906844)
			(xy 130.870832 -222.906563) (xy 130.800657 -222.901475) (xy 130.765804 -222.896684) (xy 130.755382 -222.920844)
			(xy 130.728466 -222.966055) (xy 130.695191 -223.006814) (xy 130.656282 -223.042234) (xy 130.612586 -223.071544)
			(xy 130.565052 -223.094106) (xy 130.514716 -223.109429) (xy 130.462674 -223.11718) (xy 130.436366 -223.117664)
			(xy 130.408346 -223.117146) (xy 130.352995 -223.108377) (xy 130.299702 -223.091047) (xy 130.249781 -223.065582)
			(xy 130.204466 -223.032611) (xy 130.164875 -222.992949) (xy 130.131985 -222.947575) (xy 130.106609 -222.897609)
			(xy 130.089374 -222.844284) (xy 130.084576 -222.816674) (xy 130.077718 -222.773748) (xy 129.855214 -222.773748)
			(xy 129.848356 -222.816674) (xy 129.8435 -222.844271) (xy 129.826259 -222.897584) (xy 129.800883 -222.94754)
			(xy 129.767998 -222.992906) (xy 129.728415 -223.032564) (xy 129.68311 -223.065534) (xy 129.633201 -223.091004)
			(xy 129.579921 -223.108344) (xy 129.524582 -223.117128) (xy 129.496566 -223.117664) (xy 129.470255 -223.117196)
			(xy 129.418206 -223.109458) (xy 129.367863 -223.094143) (xy 129.320323 -223.071583) (xy 129.276623 -223.04227)
			(xy 129.237713 -223.006844) (xy 129.204444 -222.966075) (xy 129.177538 -222.920852) (xy 129.167128 -222.896684)
			(xy 129.132148 -222.901488) (xy 129.061719 -222.906572) (xy 129.026412 -222.906844) (xy 128.991232 -222.906563)
			(xy 128.921057 -222.901475) (xy 128.886204 -222.896684) (xy 128.875782 -222.920844) (xy 128.848866 -222.966055)
			(xy 128.815591 -223.006814) (xy 128.776682 -223.042234) (xy 128.732986 -223.071544) (xy 128.685452 -223.094106)
			(xy 128.635116 -223.109429) (xy 128.583074 -223.11718) (xy 128.556766 -223.117664) (xy 128.528746 -223.117146)
			(xy 128.473395 -223.108377) (xy 128.420102 -223.091047) (xy 128.370181 -223.065582) (xy 128.324866 -223.032611)
			(xy 128.285275 -222.992949) (xy 128.252385 -222.947575) (xy 128.227009 -222.897609) (xy 128.209774 -222.844284)
			(xy 128.204976 -222.816674) (xy 128.198118 -222.773748) (xy 127.975614 -222.773748) (xy 127.968756 -222.816674)
			(xy 127.9639 -222.844271) (xy 127.946659 -222.897584) (xy 127.921283 -222.94754) (xy 127.888398 -222.992906)
			(xy 127.848815 -223.032564) (xy 127.80351 -223.065534) (xy 127.753601 -223.091004) (xy 127.700321 -223.108344)
			(xy 127.644982 -223.117128) (xy 127.616966 -223.117664) (xy 127.590655 -223.117196) (xy 127.538606 -223.109458)
			(xy 127.488263 -223.094143) (xy 127.440723 -223.071583) (xy 127.397023 -223.04227) (xy 127.358113 -223.006844)
			(xy 127.324844 -222.966075) (xy 127.297938 -222.920852) (xy 127.287528 -222.896684) (xy 127.252548 -222.901488)
			(xy 127.182119 -222.906572) (xy 127.146812 -222.906844) (xy 127.111632 -222.906563) (xy 127.041457 -222.901475)
			(xy 127.006604 -222.896684) (xy 126.996182 -222.920844) (xy 126.969266 -222.966055) (xy 126.935991 -223.006814)
			(xy 126.897082 -223.042234) (xy 126.853386 -223.071544) (xy 126.805852 -223.094106) (xy 126.755516 -223.109429)
			(xy 126.703474 -223.11718) (xy 126.677166 -223.117664) (xy 126.649146 -223.117146) (xy 126.593795 -223.108377)
			(xy 126.540502 -223.091047) (xy 126.490581 -223.065582) (xy 126.445266 -223.032611) (xy 126.405675 -222.992949)
			(xy 126.372785 -222.947575) (xy 126.347409 -222.897609) (xy 126.330174 -222.844284) (xy 126.325376 -222.816674)
			(xy 126.318518 -222.773748) (xy 126.096014 -222.773748) (xy 126.089156 -222.816674) (xy 126.0843 -222.844271)
			(xy 126.067059 -222.897584) (xy 126.041683 -222.94754) (xy 126.008798 -222.992906) (xy 125.969215 -223.032564)
			(xy 125.92391 -223.065534) (xy 125.874001 -223.091004) (xy 125.820721 -223.108344) (xy 125.765382 -223.117128)
			(xy 125.737366 -223.117664) (xy 125.711055 -223.117196) (xy 125.659006 -223.109458) (xy 125.608663 -223.094143)
			(xy 125.561123 -223.071583) (xy 125.517423 -223.04227) (xy 125.478513 -223.006844) (xy 125.445244 -222.966075)
			(xy 125.418338 -222.920852) (xy 125.407928 -222.896684) (xy 125.372948 -222.901488) (xy 125.302519 -222.906572)
			(xy 125.267212 -222.906844) (xy 125.232032 -222.906563) (xy 125.161857 -222.901475) (xy 125.127004 -222.896684)
			(xy 125.116582 -222.920844) (xy 125.089666 -222.966055) (xy 125.056391 -223.006814) (xy 125.017482 -223.042234)
			(xy 124.973786 -223.071544) (xy 124.926252 -223.094106) (xy 124.875916 -223.109429) (xy 124.823874 -223.11718)
			(xy 124.797566 -223.117664) (xy 124.769546 -223.117146) (xy 124.714195 -223.108377) (xy 124.660902 -223.091047)
			(xy 124.610981 -223.065582) (xy 124.565666 -223.032611) (xy 124.526075 -222.992949) (xy 124.493185 -222.947575)
			(xy 124.467809 -222.897609) (xy 124.450574 -222.844284) (xy 124.445776 -222.816674) (xy 124.438918 -222.773748)
			(xy 124.216414 -222.773748) (xy 124.209556 -222.816674) (xy 124.2047 -222.844271) (xy 124.187459 -222.897584)
			(xy 124.162083 -222.94754) (xy 124.129198 -222.992906) (xy 124.089615 -223.032564) (xy 124.04431 -223.065534)
			(xy 123.994401 -223.091004) (xy 123.941121 -223.108344) (xy 123.885782 -223.117128) (xy 123.857766 -223.117664)
			(xy 123.831455 -223.117196) (xy 123.779406 -223.109458) (xy 123.729063 -223.094143) (xy 123.681523 -223.071583)
			(xy 123.637823 -223.04227) (xy 123.598913 -223.006844) (xy 123.565644 -222.966075) (xy 123.538738 -222.920852)
			(xy 123.528328 -222.896684) (xy 123.493348 -222.901488) (xy 123.422919 -222.906572) (xy 123.387612 -222.906844)
			(xy 123.352432 -222.906563) (xy 123.282257 -222.901475) (xy 123.247404 -222.896684) (xy 123.236982 -222.920844)
			(xy 123.210066 -222.966055) (xy 123.176791 -223.006814) (xy 123.137882 -223.042234) (xy 123.094186 -223.071544)
			(xy 123.046652 -223.094106) (xy 122.996316 -223.109429) (xy 122.944274 -223.11718) (xy 122.917966 -223.117664)
			(xy 122.889946 -223.117146) (xy 122.834595 -223.108377) (xy 122.781302 -223.091047) (xy 122.731381 -223.065582)
			(xy 122.686066 -223.032611) (xy 122.646475 -222.992949) (xy 122.613585 -222.947575) (xy 122.588209 -222.897609)
			(xy 122.570974 -222.844284) (xy 122.566176 -222.816674) (xy 122.559318 -222.773748) (xy 122.336814 -222.773748)
			(xy 122.329956 -222.816674) (xy 122.3251 -222.844271) (xy 122.307859 -222.897584) (xy 122.282483 -222.94754)
			(xy 122.249598 -222.992906) (xy 122.210015 -223.032564) (xy 122.16471 -223.065534) (xy 122.114801 -223.091004)
			(xy 122.061521 -223.108344) (xy 122.006182 -223.117128) (xy 121.978166 -223.117664) (xy 121.951855 -223.117196)
			(xy 121.899806 -223.109458) (xy 121.849463 -223.094143) (xy 121.801923 -223.071583) (xy 121.758223 -223.04227)
			(xy 121.719313 -223.006844) (xy 121.686044 -222.966075) (xy 121.659138 -222.920852) (xy 121.648728 -222.896684)
			(xy 121.613748 -222.901488) (xy 121.543319 -222.906572) (xy 121.508012 -222.906844) (xy 121.472832 -222.906563)
			(xy 121.402657 -222.901475) (xy 121.367804 -222.896684) (xy 121.357382 -222.920844) (xy 121.330466 -222.966055)
			(xy 121.297191 -223.006814) (xy 121.258282 -223.042234) (xy 121.214586 -223.071544) (xy 121.167052 -223.094106)
			(xy 121.116716 -223.109429) (xy 121.064674 -223.11718) (xy 121.038366 -223.117664) (xy 121.010487 -223.117129)
			(xy 120.955408 -223.10845) (xy 120.902355 -223.091294) (xy 120.852623 -223.066081) (xy 120.807428 -223.033426)
			(xy 120.767874 -222.994126) (xy 120.734927 -222.949144) (xy 120.709392 -222.899576) (xy 120.691894 -222.846635)
			(xy 120.68683 -222.819214) (xy 120.68429 -222.802958) (xy 120.624854 -222.743522) (xy 120.614449 -222.733781)
			(xy 120.589529 -222.719974) (xy 120.561763 -222.713592) (xy 120.533315 -222.715131) (xy 120.5064 -222.724471)
			(xy 120.483115 -222.740886) (xy 120.465272 -222.763097) (xy 120.454262 -222.789373) (xy 120.452134 -222.803466)
			(xy 120.448625 -222.829109) (xy 120.435155 -222.87908) (xy 120.414594 -222.926575) (xy 120.387377 -222.970595)
			(xy 120.354076 -223.010214) (xy 120.315392 -223.044595) (xy 120.27214 -223.073017) (xy 120.22523 -223.094881)
			(xy 120.17565 -223.109726) (xy 120.124443 -223.117239) (xy 120.098566 -223.117664) (xy 120.070584 -223.117141)
			(xy 120.015309 -223.108381) (xy 119.962085 -223.091081) (xy 119.912223 -223.065669) (xy 119.86695 -223.032768)
			(xy 119.827381 -222.993191) (xy 119.794491 -222.947911) (xy 119.769089 -222.898043) (xy 119.751801 -222.844815)
			(xy 119.743053 -222.789538) (xy 119.742458 -222.761556) (xy 119.742919 -222.735678) (xy 119.750407 -222.684465)
			(xy 119.765233 -222.634878) (xy 119.787084 -222.58796) (xy 119.8155 -222.544702) (xy 119.849882 -222.506015)
			(xy 119.889504 -222.472716) (xy 119.933531 -222.445506) (xy 119.981035 -222.42496) (xy 120.031014 -222.41151)
			(xy 120.056656 -222.407988) (xy 120.070726 -222.40583) (xy 120.09695 -222.394791) (xy 120.119111 -222.376945)
			(xy 120.135489 -222.353677) (xy 120.144811 -222.326795) (xy 120.146356 -222.298384) (xy 120.140002 -222.270649)
			(xy 120.126243 -222.245744) (xy 120.1166 -222.235268) (xy 120.051322 -222.16999) (xy 120.041042 -222.160348)
			(xy 120.016441 -222.146619) (xy 119.989026 -222.140127) (xy 119.96088 -222.141364) (xy 119.93414 -222.150237)
			(xy 119.910838 -222.166073) (xy 119.901462 -222.176594) (xy 119.88445 -222.196141) (xy 119.845739 -222.230588)
			(xy 119.802446 -222.259063) (xy 119.755484 -222.280965) (xy 119.705845 -222.295831) (xy 119.654575 -222.303348)
			(xy 119.628666 -222.303848) (xy 119.600684 -222.303297) (xy 119.545408 -222.294538) (xy 119.492183 -222.277241)
			(xy 119.442319 -222.251831) (xy 119.397042 -222.218935) (xy 119.357469 -222.179362) (xy 119.324572 -222.134086)
			(xy 119.299162 -222.084223) (xy 119.281864 -222.030998) (xy 119.273104 -221.975722) (xy 119.272558 -221.94774)
			(xy 119.273022 -221.921828) (xy 119.280532 -221.870552) (xy 119.295397 -221.820907) (xy 119.317305 -221.773943)
			(xy 119.345792 -221.730652) (xy 119.380256 -221.691949) (xy 119.399812 -221.674944) (xy 119.410325 -221.665557)
			(xy 119.426173 -221.642262) (xy 119.435055 -221.615524) (xy 119.436294 -221.587377) (xy 119.429797 -221.559962)
			(xy 119.416058 -221.535365) (xy 119.406416 -221.525084) (xy 119.38508 -221.503748) (xy 119.38508 -221.450154)
			(xy 119.32285 -221.450154) (xy 119.312436 -221.455234) (xy 119.288319 -221.466206) (xy 119.237655 -221.481702)
			(xy 119.185257 -221.489542) (xy 119.158766 -221.490032) (xy 119.130784 -221.489481) (xy 119.075509 -221.480721)
			(xy 119.022285 -221.463424) (xy 118.972422 -221.438015) (xy 118.927147 -221.405118) (xy 118.887575 -221.365545)
			(xy 118.85468 -221.320269) (xy 118.829272 -221.270405) (xy 118.811976 -221.217181) (xy 118.803219 -221.161906)
			(xy 118.802658 -221.133924) (xy 118.803032 -221.110679) (xy 118.809073 -221.064582) (xy 118.821056 -221.019662)
			(xy 118.829582 -220.998034) (xy 118.839234 -220.97492) (xy 118.666768 -220.676216) (xy 118.641876 -220.672914)
			(xy 118.616517 -220.669107) (xy 118.567174 -220.655156) (xy 118.520341 -220.634273) (xy 118.476988 -220.606887)
			(xy 118.438012 -220.573567) (xy 118.404218 -220.535) (xy 118.376305 -220.491985) (xy 118.354851 -220.445411)
			(xy 118.3403 -220.396242) (xy 118.332951 -220.345493) (xy 118.332504 -220.319854) (xy 118.333002 -220.293205)
			(xy 118.340945 -220.240501) (xy 118.356655 -220.189571) (xy 118.379781 -220.14155) (xy 118.409805 -220.097513)
			(xy 118.446057 -220.058442) (xy 118.487728 -220.025211) (xy 118.533886 -219.998562) (xy 118.5835 -219.97909)
			(xy 118.635462 -219.96723) (xy 118.688612 -219.963247) (xy 118.741762 -219.96723) (xy 118.793724 -219.97909)
			(xy 118.843338 -219.998562) (xy 118.889496 -220.025211) (xy 118.931167 -220.058442) (xy 118.967419 -220.097513)
			(xy 118.997443 -220.14155) (xy 119.020569 -220.189571) (xy 119.036279 -220.240501) (xy 119.044222 -220.293205)
			(xy 119.04472 -220.319854) (xy 119.044325 -220.343056) (xy 119.038262 -220.389062) (xy 119.026285 -220.433893)
			(xy 119.017796 -220.45549) (xy 119.008398 -220.478604) (xy 119.181118 -220.777562) (xy 119.205756 -220.780864)
			(xy 119.218418 -220.78267) (xy 119.243462 -220.787885) (xy 119.255794 -220.791278) (xy 119.268829 -220.794546)
			(xy 119.29569 -220.794875) (xy 119.321708 -220.788187) (xy 119.345081 -220.774945) (xy 119.364191 -220.756065)
			(xy 119.377716 -220.732854) (xy 119.384719 -220.70692) (xy 119.38508 -220.693488) (xy 119.38508 -220.579696)
			(xy 119.366102 -220.56122) (xy 119.333273 -220.519658) (xy 119.306959 -220.473694) (xy 119.28774 -220.424341)
			(xy 119.276037 -220.372686) (xy 119.272111 -220.319868) (xy 119.276047 -220.267051) (xy 119.287758 -220.215399)
			(xy 119.306987 -220.166049) (xy 119.333309 -220.12009) (xy 119.366145 -220.078533) (xy 119.38508 -220.060012)
			(xy 119.38508 -219.946474) (xy 119.384668 -219.933046) (xy 119.377662 -219.907119) (xy 119.364141 -219.883913)
			(xy 119.34504 -219.865034) (xy 119.321679 -219.851785) (xy 119.295672 -219.845082) (xy 119.268817 -219.845388)
			(xy 119.255794 -219.848684) (xy 119.232032 -219.854977) (xy 119.183343 -219.861729) (xy 119.158766 -219.862146)
			(xy 119.132116 -219.861646) (xy 119.07941 -219.853697) (xy 119.028479 -219.837982) (xy 118.980458 -219.814853)
			(xy 118.93642 -219.784825) (xy 118.897349 -219.748569) (xy 118.864118 -219.706895) (xy 118.837469 -219.660734)
			(xy 118.817997 -219.611117) (xy 118.806137 -219.559152) (xy 118.802154 -219.506) (xy 118.806137 -219.452848)
			(xy 118.817997 -219.400883) (xy 118.837469 -219.351266) (xy 118.864118 -219.305105) (xy 118.897349 -219.263431)
			(xy 118.93642 -219.227175) (xy 118.980458 -219.197147) (xy 119.028479 -219.174018) (xy 119.07941 -219.158303)
			(xy 119.132116 -219.150354) (xy 119.158766 -219.14993) (xy 119.183344 -219.15034) (xy 119.232034 -219.157089)
			(xy 119.255794 -219.163392) (xy 119.268829 -219.16666) (xy 119.295692 -219.166989) (xy 119.321711 -219.160301)
			(xy 119.345085 -219.147059) (xy 119.364198 -219.12818) (xy 119.377725 -219.104969) (xy 119.384731 -219.079034)
			(xy 119.38508 -219.065602) (xy 119.38508 -218.952318) (xy 119.366058 -218.933835) (xy 119.333149 -218.892244)
			(xy 119.306766 -218.846236) (xy 119.287493 -218.796825) (xy 119.275756 -218.745104) (xy 119.271813 -218.692215)
			(xy 119.275752 -218.639325) (xy 119.287485 -218.587603) (xy 119.306753 -218.538191) (xy 119.333132 -218.492181)
			(xy 119.366038 -218.450587) (xy 119.38508 -218.432126) (xy 119.38508 -218.318842) (xy 119.384664 -218.305417)
			(xy 119.377653 -218.279497) (xy 119.364131 -218.2563) (xy 119.345031 -218.237427) (xy 119.321674 -218.224183)
			(xy 119.295672 -218.217482) (xy 119.268823 -218.217787) (xy 119.255794 -218.221052) (xy 119.232032 -218.227345)
			(xy 119.183343 -218.234098) (xy 119.158766 -218.234514) (xy 119.130784 -218.233963) (xy 119.075511 -218.225203)
			(xy 119.022288 -218.207906) (xy 118.972426 -218.182496) (xy 118.927153 -218.149599) (xy 118.887582 -218.110026)
			(xy 118.854689 -218.06475) (xy 118.829283 -218.014886) (xy 118.81199 -217.961662) (xy 118.803235 -217.906388)
			(xy 118.802658 -217.878406) (xy 118.803033 -217.855161) (xy 118.809077 -217.809065) (xy 118.821062 -217.764146)
			(xy 118.829582 -217.742516) (xy 118.839234 -217.719402) (xy 118.666768 -217.420698) (xy 118.641876 -217.417396)
			(xy 118.616518 -217.413589) (xy 118.567175 -217.399638) (xy 118.520344 -217.378754) (xy 118.476993 -217.351368)
			(xy 118.438018 -217.318048) (xy 118.404226 -217.279481) (xy 118.376315 -217.236466) (xy 118.354863 -217.189892)
			(xy 118.340314 -217.140722) (xy 118.332968 -217.089974) (xy 118.332504 -217.064336) (xy 118.333002 -217.037687)
			(xy 118.340945 -216.984983) (xy 118.356655 -216.934053) (xy 118.379781 -216.886032) (xy 118.409805 -216.841995)
			(xy 118.446057 -216.802924) (xy 118.487728 -216.769693) (xy 118.533886 -216.743044) (xy 118.5835 -216.723572)
			(xy 118.635462 -216.711712) (xy 118.688612 -216.707729) (xy 118.741762 -216.711712) (xy 118.793724 -216.723572)
			(xy 118.843338 -216.743044) (xy 118.889496 -216.769693) (xy 118.931167 -216.802924) (xy 118.967419 -216.841995)
			(xy 118.997443 -216.886032) (xy 119.020569 -216.934053) (xy 119.036279 -216.984983) (xy 119.044222 -217.037687)
			(xy 119.04472 -217.064336) (xy 119.044326 -217.087538) (xy 119.038265 -217.133545) (xy 119.02629 -217.178377)
			(xy 119.017796 -217.199972) (xy 119.008398 -217.223086) (xy 119.181118 -217.522044) (xy 119.205756 -217.525346)
			(xy 119.218419 -217.527152) (xy 119.243462 -217.532366) (xy 119.255794 -217.53576) (xy 119.268828 -217.539028)
			(xy 119.295688 -217.539358) (xy 119.321705 -217.53267) (xy 119.345076 -217.519427) (xy 119.364184 -217.500547)
			(xy 119.377705 -217.477336) (xy 119.384704 -217.451401) (xy 119.38508 -217.43797) (xy 119.38508 -217.324178)
			(xy 119.366096 -217.305702) (xy 119.333255 -217.264138) (xy 119.30693 -217.21817) (xy 119.287699 -217.168812)
			(xy 119.275987 -217.117151) (xy 119.272051 -217.064325) (xy 119.275979 -217.011498) (xy 119.287684 -216.959835)
			(xy 119.306908 -216.910474) (xy 119.333228 -216.864503) (xy 119.366063 -216.822934) (xy 119.38508 -216.804494)
			(xy 119.38508 -216.690956) (xy 119.384666 -216.677529) (xy 119.377657 -216.651607) (xy 119.364135 -216.628406)
			(xy 119.345035 -216.60953) (xy 119.321676 -216.596284) (xy 119.295672 -216.589582) (xy 119.26882 -216.589888)
			(xy 119.255794 -216.593166) (xy 119.232032 -216.599459) (xy 119.183343 -216.606211) (xy 119.158766 -216.606628)
			(xy 119.132117 -216.606128) (xy 119.079414 -216.59818) (xy 119.028485 -216.582466) (xy 118.980467 -216.559337)
			(xy 118.936431 -216.52931) (xy 118.897363 -216.493056) (xy 118.864133 -216.451385) (xy 118.837486 -216.405226)
			(xy 118.818015 -216.355612) (xy 118.806155 -216.303649) (xy 118.802172 -216.2505) (xy 118.806155 -216.197351)
			(xy 118.818015 -216.145388) (xy 118.837486 -216.095774) (xy 118.864133 -216.049615) (xy 118.897363 -216.007944)
			(xy 118.936431 -215.97169) (xy 118.980467 -215.941663) (xy 119.028485 -215.918534) (xy 119.079414 -215.90282)
			(xy 119.132117 -215.894872) (xy 119.158766 -215.894412) (xy 119.183344 -215.894821) (xy 119.232035 -215.901571)
			(xy 119.255794 -215.907874) (xy 119.268829 -215.911142) (xy 119.29569 -215.911471) (xy 119.321707 -215.904783)
			(xy 119.34508 -215.891541) (xy 119.36419 -215.872661) (xy 119.377714 -215.84945) (xy 119.384716 -215.823516)
			(xy 119.38508 -215.810084) (xy 119.38508 -215.6968) (xy 119.366059 -215.678317) (xy 119.333153 -215.636727)
			(xy 119.306773 -215.590719) (xy 119.287502 -215.54131) (xy 119.275767 -215.48959) (xy 119.271826 -215.436703)
			(xy 119.275766 -215.383815) (xy 119.287501 -215.332096) (xy 119.30677 -215.282686) (xy 119.33315 -215.236678)
			(xy 119.366056 -215.195087) (xy 119.38508 -215.176608) (xy 119.38508 -215.062816) (xy 119.384637 -215.049407)
			(xy 119.377584 -215.023531) (xy 119.36404 -215.000382) (xy 119.344938 -214.981556) (xy 119.321594 -214.96835)
			(xy 119.295618 -214.961675) (xy 119.268799 -214.96199) (xy 119.255794 -214.96528) (xy 119.231909 -214.971603)
			(xy 119.182963 -214.978354) (xy 119.158258 -214.978742) (xy 119.130276 -214.97819) (xy 119.075002 -214.96943)
			(xy 119.021778 -214.952132) (xy 118.971916 -214.926722) (xy 118.926641 -214.893826) (xy 118.887069 -214.854253)
			(xy 118.854174 -214.808978) (xy 118.828765 -214.759114) (xy 118.811468 -214.70589) (xy 118.802709 -214.650616)
			(xy 118.80215 -214.622634) (xy 118.80269 -214.594818) (xy 118.811348 -214.539864) (xy 118.828443 -214.486923)
			(xy 118.840504 -214.461852) (xy 118.852442 -214.438484) (xy 118.668038 -214.08898) (xy 118.64213 -214.085678)
			(xy 118.61677 -214.081874) (xy 118.567422 -214.067929) (xy 118.520586 -214.047048) (xy 118.477229 -214.019664)
			(xy 118.43825 -213.986344) (xy 118.404453 -213.947776) (xy 118.37654 -213.904759) (xy 118.355086 -213.858182)
			(xy 118.340536 -213.80901) (xy 118.333191 -213.758258) (xy 118.332758 -213.732618) (xy 118.333256 -213.705969)
			(xy 118.341199 -213.653265) (xy 118.356909 -213.602335) (xy 118.380035 -213.554314) (xy 118.410059 -213.510277)
			(xy 118.446311 -213.471206) (xy 118.487982 -213.437975) (xy 118.53414 -213.411326) (xy 118.583754 -213.391854)
			(xy 118.635716 -213.379994) (xy 118.688866 -213.376011) (xy 118.742016 -213.379994) (xy 118.793978 -213.391854)
			(xy 118.843592 -213.411326) (xy 118.88975 -213.437975) (xy 118.931421 -213.471206) (xy 118.967673 -213.510277)
			(xy 118.997697 -213.554314) (xy 119.020823 -213.602335) (xy 119.036533 -213.653265) (xy 119.044476 -213.705969)
			(xy 119.044974 -213.732618) (xy 119.044438 -213.760435) (xy 119.035787 -213.815392) (xy 119.018699 -213.868337)
			(xy 119.00662 -213.8934) (xy 118.994682 -213.916768) (xy 119.179086 -214.266272) (xy 119.204994 -214.269574)
			(xy 119.217847 -214.271365) (xy 119.243273 -214.276578) (xy 119.255794 -214.279988) (xy 119.268811 -214.283253)
			(xy 119.295637 -214.283591) (xy 119.321625 -214.276931) (xy 119.344982 -214.263732) (xy 119.364095 -214.244905)
			(xy 119.377645 -214.22175) (xy 119.384697 -214.195865) (xy 119.38508 -214.182452) (xy 119.38508 -213.99246)
			(xy 119.366097 -213.973984) (xy 119.333259 -213.932421) (xy 119.306936 -213.886454) (xy 119.287708 -213.837096)
			(xy 119.275998 -213.785437) (xy 119.272064 -213.732612) (xy 119.275994 -213.679788) (xy 119.287701 -213.628127)
			(xy 119.306926 -213.578769) (xy 119.333246 -213.5328) (xy 119.366081 -213.491234) (xy 119.38508 -213.472776)
			(xy 119.38508 -209.718148) (xy 101.52888 -191.861948) (xy 91.529154 -191.861948) (xy 91.516708 -191.894206)
			(xy 91.502738 -191.925702) (xy 91.496898 -191.93844) (xy 91.491714 -191.96597) (xy 91.494215 -191.993871)
			(xy 91.504212 -192.020039) (xy 91.520949 -192.042502) (xy 91.543166 -192.059565) (xy 91.569187 -192.06994)
			(xy 91.597049 -192.072847) (xy 91.610942 -192.07099) (xy 91.626945 -192.068396) (xy 91.659247 -192.065597)
			(xy 91.675458 -192.065402) (xy 91.702711 -192.065862) (xy 91.756662 -192.073613) (xy 91.808961 -192.088964)
			(xy 91.858543 -192.111601) (xy 91.904399 -192.141064) (xy 91.945594 -192.176754) (xy 91.981292 -192.217943)
			(xy 92.010764 -192.263793) (xy 92.03341 -192.31337) (xy 92.048771 -192.365666) (xy 92.056532 -192.419616)
			(xy 92.056537 -192.474121) (xy 92.048784 -192.528072) (xy 92.033432 -192.580371) (xy 92.010794 -192.629952)
			(xy 91.981329 -192.675807) (xy 91.945639 -192.717002) (xy 91.904449 -192.752698) (xy 91.858598 -192.782169)
			(xy 91.80902 -192.804814) (xy 91.756723 -192.820173) (xy 91.702773 -192.827933) (xy 91.648268 -192.827936)
			(xy 91.594317 -192.820182) (xy 91.542019 -192.804829) (xy 91.492438 -192.782189) (xy 91.446584 -192.752723)
			(xy 91.40539 -192.717031) (xy 91.369695 -192.67584) (xy 91.340226 -192.629989) (xy 91.317582 -192.58041)
			(xy 91.302225 -192.528113) (xy 91.294466 -192.474163) (xy 91.29395 -192.44691) (xy 91.294512 -192.417588)
			(xy 91.303524 -192.359639) (xy 91.321276 -192.303744) (xy 91.333828 -192.277238) (xy 91.339672 -192.264493)
			(xy 91.344862 -192.23695) (xy 91.342365 -192.209034) (xy 91.33237 -192.182849) (xy 91.315631 -192.160369)
			(xy 91.293409 -192.143289) (xy 91.267379 -192.132897) (xy 91.239504 -192.129975) (xy 91.225624 -192.13195)
			(xy 91.20962 -192.134542) (xy 91.177319 -192.137338) (xy 91.161108 -192.137538) (xy 91.132475 -192.137026)
			(xy 91.075851 -192.128468) (xy 91.021141 -192.111544) (xy 90.969576 -192.086634) (xy 90.922313 -192.054297)
			(xy 90.880414 -192.015259) (xy 90.844819 -191.970398) (xy 90.816329 -191.92072) (xy 90.805508 -191.894206)
			(xy 90.793062 -191.861948) (xy 89.10828 -191.861948) (xy 83.551014 -186.304682) (xy 83.540234 -186.294591)
			(xy 83.514281 -186.280538) (xy 83.485393 -186.274486) (xy 83.455981 -186.276941) (xy 83.428497 -186.287698)
			(xy 83.405232 -186.30586) (xy 83.396328 -186.317636) (xy 83.379001 -186.341083) (xy 83.338409 -186.38293)
			(xy 83.291924 -186.418115) (xy 83.266534 -186.432444) (xy 83.254724 -186.439315) (xy 83.234984 -186.458191)
			(xy 83.220953 -186.481624) (xy 83.213635 -186.507938) (xy 83.213552 -186.535251) (xy 83.220712 -186.561608)
			(xy 83.234601 -186.585126) (xy 83.254227 -186.604121) (xy 83.266026 -186.611006) (xy 83.291297 -186.625498)
			(xy 83.337513 -186.66096) (xy 83.377795 -186.703041) (xy 83.411205 -186.75076) (xy 83.436965 -186.803008)
			(xy 83.454475 -186.858567) (xy 83.463328 -186.916143) (xy 83.463892 -186.94527) (xy 83.463406 -186.972521)
			(xy 83.45565 -187.026469) (xy 83.440295 -187.078764) (xy 83.417653 -187.128341) (xy 83.388187 -187.174191)
			(xy 83.352496 -187.215382) (xy 83.311305 -187.251073) (xy 83.265455 -187.280539) (xy 83.215878 -187.303181)
			(xy 83.163583 -187.318536) (xy 83.109635 -187.326292) (xy 83.055133 -187.326292) (xy 83.001185 -187.318536)
			(xy 82.94889 -187.303181) (xy 82.899313 -187.280539) (xy 82.853463 -187.251073) (xy 82.812272 -187.215382)
			(xy 82.776581 -187.174191) (xy 82.747115 -187.128341) (xy 82.724473 -187.078764) (xy 82.709118 -187.026469)
			(xy 82.701362 -186.972521) (xy 82.700876 -186.94527) (xy 82.701415 -186.915954) (xy 82.710392 -186.858013)
			(xy 82.72813 -186.802129) (xy 82.754211 -186.749617) (xy 82.788021 -186.701714) (xy 82.828762 -186.65955)
			(xy 82.875477 -186.624117) (xy 82.901028 -186.609736) (xy 82.912829 -186.602861) (xy 82.932553 -186.583982)
			(xy 82.94657 -186.560553) (xy 82.953879 -186.534247) (xy 82.953959 -186.506945) (xy 82.946804 -186.480597)
			(xy 82.932924 -186.457086) (xy 82.913311 -186.438092) (xy 82.901536 -186.431174) (xy 82.876263 -186.416682)
			(xy 82.830044 -186.38122) (xy 82.789757 -186.33914) (xy 82.756341 -186.291421) (xy 82.730573 -186.239174)
			(xy 82.713053 -186.183615) (xy 82.704189 -186.126038) (xy 82.70367 -186.09691) (xy 82.70411 -186.070909)
			(xy 82.711174 -186.019388) (xy 82.725172 -185.969305) (xy 82.745844 -185.921588) (xy 82.772808 -185.877122)
			(xy 82.805563 -185.836731) (xy 82.843501 -185.801165) (xy 82.864452 -185.78576) (xy 82.876186 -185.776804)
			(xy 82.894344 -185.753545) (xy 82.905106 -185.726071) (xy 82.907576 -185.696667) (xy 82.901547 -185.667783)
			(xy 82.887523 -185.641822) (xy 82.877406 -185.631074) (xy 80.16748 -182.921148) (xy 80.16748 -168.087548)
			(xy 72.9107 -160.830768) (xy 72.08012 -160.830768) (xy 70.86854 -162.042348) (xy 68.91274 -162.042348)
			(xy 68.13804 -161.267648) (xy 63.52032 -161.267648) (xy 62.60338 -162.184588) (xy 62.60338 -164.634926)
			(xy 69.007995 -164.634926) (xy 69.012017 -164.549206) (xy 69.024048 -164.464238) (xy 69.043984 -164.380771)
			(xy 69.071647 -164.299537) (xy 69.106796 -164.221251) (xy 69.149122 -164.1466) (xy 69.198251 -164.076241)
			(xy 69.253754 -164.010791) (xy 69.315141 -163.950827) (xy 69.381874 -163.896874) (xy 69.453366 -163.849407)
			(xy 69.528988 -163.808843) (xy 69.608077 -163.775539) (xy 69.689937 -163.749787) (xy 69.773848 -163.731814)
			(xy 69.859074 -163.721778) (xy 69.944866 -163.719766) (xy 70.030468 -163.725797) (xy 70.11513 -163.739817)
			(xy 70.198107 -163.761703) (xy 70.27867 -163.791264) (xy 70.35611 -163.828238) (xy 70.429749 -163.872302)
			(xy 70.498937 -163.923068) (xy 70.563068 -163.980089) (xy 70.621577 -164.042865) (xy 70.67395 -164.110845)
			(xy 70.719728 -164.18343) (xy 70.758508 -164.259982) (xy 70.789949 -164.33983) (xy 70.813775 -164.422271)
			(xy 70.829776 -164.506581) (xy 70.837811 -164.592019) (xy 70.838314 -164.634926) (xy 70.837811 -164.677833)
			(xy 70.829776 -164.763271) (xy 70.813775 -164.847581) (xy 70.789949 -164.930022) (xy 70.758508 -165.00987)
			(xy 70.719728 -165.086422) (xy 70.67395 -165.159007) (xy 70.621577 -165.226987) (xy 70.563068 -165.289763)
			(xy 70.498937 -165.346784) (xy 70.429749 -165.39755) (xy 70.35611 -165.441614) (xy 70.27867 -165.478588)
			(xy 70.198107 -165.508149) (xy 70.11513 -165.530035) (xy 70.030468 -165.544055) (xy 69.944866 -165.550086)
			(xy 69.859074 -165.548074) (xy 69.773848 -165.538038) (xy 69.689937 -165.520065) (xy 69.608077 -165.494313)
			(xy 69.528988 -165.461009) (xy 69.453366 -165.420445) (xy 69.381874 -165.372978) (xy 69.315141 -165.319025)
			(xy 69.253754 -165.259061) (xy 69.198251 -165.193611) (xy 69.149122 -165.123252) (xy 69.106796 -165.048601)
			(xy 69.071647 -164.970315) (xy 69.043984 -164.889081) (xy 69.024048 -164.805614) (xy 69.012017 -164.720646)
			(xy 69.007995 -164.634926) (xy 62.60338 -164.634926) (xy 62.60338 -166.67727) (xy 69.034402 -166.67727)
			(xy 69.034402 -166.592574) (xy 69.042453 -166.50826) (xy 69.058482 -166.425094) (xy 69.082343 -166.343827)
			(xy 69.113822 -166.265197) (xy 69.152633 -166.189916) (xy 69.198423 -166.118664) (xy 69.250779 -166.052088)
			(xy 69.309227 -165.99079) (xy 69.373237 -165.935325) (xy 69.442229 -165.886196) (xy 69.515579 -165.843847)
			(xy 69.592622 -165.808663) (xy 69.672661 -165.780961) (xy 69.75497 -165.760993) (xy 69.838805 -165.74894)
			(xy 69.923406 -165.74491) (xy 70.008007 -165.74894) (xy 70.091842 -165.760993) (xy 70.174151 -165.780961)
			(xy 70.25419 -165.808663) (xy 70.331233 -165.843847) (xy 70.404583 -165.886196) (xy 70.473575 -165.935325)
			(xy 70.537585 -165.99079) (xy 70.596033 -166.052088) (xy 70.648389 -166.118664) (xy 70.694179 -166.189916)
			(xy 70.73299 -166.265197) (xy 70.764469 -166.343827) (xy 70.78833 -166.425094) (xy 70.804359 -166.50826)
			(xy 70.81241 -166.592574) (xy 70.812914 -166.634922) (xy 70.81241 -166.67727) (xy 70.804359 -166.761584)
			(xy 70.78833 -166.84475) (xy 70.764469 -166.926017) (xy 70.73299 -167.004647) (xy 70.694179 -167.079928)
			(xy 70.648389 -167.15118) (xy 70.596033 -167.217756) (xy 70.537585 -167.279054) (xy 70.473575 -167.334519)
			(xy 70.404583 -167.383648) (xy 70.331233 -167.425997) (xy 70.25419 -167.461181) (xy 70.174151 -167.488883)
			(xy 70.091842 -167.508851) (xy 70.008007 -167.520904) (xy 69.923406 -167.524935) (xy 69.838805 -167.520904)
			(xy 69.75497 -167.508851) (xy 69.672661 -167.488883) (xy 69.592622 -167.461181) (xy 69.515579 -167.425997)
			(xy 69.442229 -167.383648) (xy 69.373237 -167.334519) (xy 69.309227 -167.279054) (xy 69.250779 -167.217756)
			(xy 69.198423 -167.15118) (xy 69.152633 -167.079928) (xy 69.113822 -167.004647) (xy 69.082343 -166.926017)
			(xy 69.058482 -166.84475) (xy 69.042453 -166.761584) (xy 69.034402 -166.67727) (xy 62.60338 -166.67727)
			(xy 62.60338 -170.071288) (xy 63.340488 -170.808396) (xy 66.212212 -170.808396) (xy 66.667888 -170.808396)
			(xy 67.587622 -171.72813) (xy 67.598037 -171.737888) (xy 67.622991 -171.751715) (xy 67.650796 -171.758096)
			(xy 67.679282 -171.756533) (xy 67.706222 -171.747147) (xy 67.729512 -171.730672) (xy 67.747332 -171.708394)
			(xy 67.758292 -171.682055) (xy 67.760342 -171.667932) (xy 67.765804 -171.625102) (xy 67.783979 -171.54069)
			(xy 67.810248 -171.458436) (xy 67.844365 -171.379114) (xy 67.886009 -171.303473) (xy 67.934786 -171.232222)
			(xy 67.990239 -171.166035) (xy 68.051844 -171.105532) (xy 68.119024 -171.051285) (xy 68.191143 -171.003802)
			(xy 68.267525 -170.963533) (xy 68.34745 -170.930855) (xy 68.430165 -170.906076) (xy 68.514893 -170.88943)
			(xy 68.600834 -170.881072) (xy 68.644008 -170.880532) (xy 68.68511 -170.880993) (xy 68.766964 -170.888578)
			(xy 68.847769 -170.903684) (xy 68.926835 -170.926182) (xy 69.003488 -170.955879) (xy 69.077073 -170.992522)
			(xy 69.146964 -171.035799) (xy 69.212564 -171.08534) (xy 69.273312 -171.140722) (xy 69.328691 -171.201473)
			(xy 69.378228 -171.267076) (xy 69.421501 -171.336969) (xy 69.45814 -171.410556) (xy 69.487833 -171.487211)
			(xy 69.510327 -171.566278) (xy 69.525428 -171.647084) (xy 69.53301 -171.728938) (xy 69.533516 -171.77004)
			(xy 69.728593 -171.77004) (xy 69.732615 -171.68432) (xy 69.744646 -171.599352) (xy 69.764582 -171.515885)
			(xy 69.792245 -171.434651) (xy 69.827394 -171.356365) (xy 69.86972 -171.281714) (xy 69.918849 -171.211355)
			(xy 69.974352 -171.145905) (xy 70.035739 -171.085941) (xy 70.102472 -171.031988) (xy 70.173964 -170.984521)
			(xy 70.249586 -170.943957) (xy 70.328675 -170.910653) (xy 70.410535 -170.884901) (xy 70.494446 -170.866928)
			(xy 70.579672 -170.856892) (xy 70.665464 -170.85488) (xy 70.751066 -170.860911) (xy 70.835728 -170.874931)
			(xy 70.918705 -170.896817) (xy 70.999268 -170.926378) (xy 71.076708 -170.963352) (xy 71.150347 -171.007416)
			(xy 71.219535 -171.058182) (xy 71.283666 -171.115203) (xy 71.342175 -171.177979) (xy 71.394548 -171.245959)
			(xy 71.440326 -171.318544) (xy 71.479106 -171.395096) (xy 71.510547 -171.474944) (xy 71.534373 -171.557385)
			(xy 71.550374 -171.641695) (xy 71.558409 -171.727133) (xy 71.558912 -171.77004) (xy 71.558409 -171.812947)
			(xy 71.550374 -171.898385) (xy 71.534373 -171.982695) (xy 71.510547 -172.065136) (xy 71.479106 -172.144984)
			(xy 71.440326 -172.221536) (xy 71.394548 -172.294121) (xy 71.342175 -172.362101) (xy 71.283666 -172.424877)
			(xy 71.219535 -172.481898) (xy 71.150347 -172.532664) (xy 71.102999 -172.560996) (xy 74.79233 -172.560996)
			(xy 74.796401 -172.505374) (xy 74.808527 -172.450937) (xy 74.82845 -172.398846) (xy 74.855746 -172.350211)
			(xy 74.889832 -172.306068) (xy 74.929981 -172.267359) (xy 74.975339 -172.234908) (xy 75.024939 -172.209407)
			(xy 75.077723 -172.1914) (xy 75.132566 -172.18127) (xy 75.1883 -172.179233) (xy 75.243737 -172.185333)
			(xy 75.297694 -172.199439) (xy 75.349023 -172.221251) (xy 75.396629 -172.250305) (xy 75.439497 -172.28598)
			(xy 75.476714 -172.327517) (xy 75.507487 -172.37403) (xy 75.531159 -172.424527) (xy 75.547227 -172.477934)
			(xy 75.555347 -172.53311) (xy 75.555856 -172.560996) (xy 75.555347 -172.588882) (xy 75.547227 -172.644058)
			(xy 75.531159 -172.697465) (xy 75.507487 -172.747962) (xy 75.476714 -172.794475) (xy 75.439497 -172.836012)
			(xy 75.396629 -172.871687) (xy 75.349023 -172.900741) (xy 75.297694 -172.922553) (xy 75.243737 -172.936659)
			(xy 75.1883 -172.942759) (xy 75.132566 -172.940722) (xy 75.077723 -172.930592) (xy 75.024939 -172.912585)
			(xy 74.975339 -172.887084) (xy 74.929981 -172.854633) (xy 74.889832 -172.815924) (xy 74.855746 -172.771781)
			(xy 74.82845 -172.723146) (xy 74.808527 -172.671055) (xy 74.796401 -172.616618) (xy 74.79233 -172.560996)
			(xy 71.102999 -172.560996) (xy 71.076708 -172.576728) (xy 70.999268 -172.613702) (xy 70.918705 -172.643263)
			(xy 70.835728 -172.665149) (xy 70.751066 -172.679169) (xy 70.665464 -172.6852) (xy 70.579672 -172.683188)
			(xy 70.494446 -172.673152) (xy 70.410535 -172.655179) (xy 70.328675 -172.629427) (xy 70.249586 -172.596123)
			(xy 70.173964 -172.555559) (xy 70.102472 -172.508092) (xy 70.035739 -172.454139) (xy 69.974352 -172.394175)
			(xy 69.918849 -172.328725) (xy 69.86972 -172.258366) (xy 69.827394 -172.183715) (xy 69.792245 -172.105429)
			(xy 69.764582 -172.024195) (xy 69.744646 -171.940728) (xy 69.732615 -171.85576) (xy 69.728593 -171.77004)
			(xy 69.533516 -171.77004) (xy 69.533003 -171.813213) (xy 69.524633 -171.899153) (xy 69.507976 -171.983877)
			(xy 69.483189 -172.066589) (xy 69.450505 -172.14651) (xy 69.410231 -172.222889) (xy 69.362746 -172.295006)
			(xy 69.308498 -172.362183) (xy 69.247996 -172.423789) (xy 69.18181 -172.479242) (xy 69.110563 -172.528022)
			(xy 69.034924 -172.56967) (xy 68.955607 -172.603793) (xy 68.873356 -172.630071) (xy 68.788947 -172.648256)
			(xy 68.746116 -172.653706) (xy 68.732017 -172.65583) (xy 68.70572 -172.666822) (xy 68.683482 -172.684648)
			(xy 68.667031 -172.707922) (xy 68.657647 -172.734834) (xy 68.65606 -172.763291) (xy 68.662392 -172.79108)
			(xy 68.676152 -172.81604) (xy 68.685918 -172.826426) (xy 69.861176 -174.001684) (xy 74.085958 -174.001684)
			(xy 74.086447 -173.963039) (xy 74.094267 -173.886145) (xy 74.109825 -173.810437) (xy 74.132963 -173.736691)
			(xy 74.163443 -173.665664) (xy 74.200952 -173.598086) (xy 74.245106 -173.534648) (xy 74.295451 -173.476004)
			(xy 74.35147 -173.422753) (xy 74.412589 -173.375443) (xy 74.478182 -173.334559) (xy 74.547573 -173.300521)
			(xy 74.620053 -173.273678) (xy 74.694876 -173.254305) (xy 74.771275 -173.242601) (xy 74.848466 -173.238686)
			(xy 74.925657 -173.242601) (xy 75.002056 -173.254305) (xy 75.076879 -173.273678) (xy 75.149359 -173.300521)
			(xy 75.21875 -173.334559) (xy 75.284343 -173.375443) (xy 75.345462 -173.422753) (xy 75.401481 -173.476004)
			(xy 75.451826 -173.534648) (xy 75.49598 -173.598086) (xy 75.533489 -173.665664) (xy 75.563969 -173.736691)
			(xy 75.587107 -173.810437) (xy 75.602665 -173.886145) (xy 75.610485 -173.963039) (xy 75.610974 -174.001684)
			(xy 75.610466 -174.041827) (xy 75.602041 -174.121668) (xy 75.585273 -174.200183) (xy 75.560346 -174.2765)
			(xy 75.527537 -174.349776) (xy 75.487209 -174.419197) (xy 75.439809 -174.483997) (xy 75.385862 -174.543456)
			(xy 75.325966 -174.596917) (xy 75.260782 -174.643787) (xy 75.226164 -174.664116) (xy 75.218447 -174.668897)
			(xy 75.206768 -174.682781) (xy 75.200661 -174.699864) (xy 75.200889 -174.718005) (xy 75.203812 -174.7266)
			(xy 75.212092 -174.748773) (xy 75.223721 -174.794653) (xy 75.2296 -174.841619) (xy 75.229974 -174.865284)
			(xy 75.229488 -174.892535) (xy 75.221732 -174.946483) (xy 75.206377 -174.998778) (xy 75.183735 -175.048355)
			(xy 75.154269 -175.094205) (xy 75.118578 -175.135396) (xy 75.077387 -175.171087) (xy 75.031537 -175.200553)
			(xy 74.98196 -175.223195) (xy 74.929665 -175.23855) (xy 74.875717 -175.246306) (xy 74.821215 -175.246306)
			(xy 74.767267 -175.23855) (xy 74.714972 -175.223195) (xy 74.665395 -175.200553) (xy 74.619545 -175.171087)
			(xy 74.578354 -175.135396) (xy 74.542663 -175.094205) (xy 74.513197 -175.048355) (xy 74.490555 -174.998778)
			(xy 74.4752 -174.946483) (xy 74.467444 -174.892535) (xy 74.466958 -174.865284) (xy 74.467305 -174.841617)
			(xy 74.473177 -174.794648) (xy 74.484829 -174.74877) (xy 74.49312 -174.7266) (xy 74.496022 -174.718006)
			(xy 74.496217 -174.69988) (xy 74.49011 -174.682812) (xy 74.47846 -174.668924) (xy 74.470768 -174.664116)
			(xy 74.436131 -174.64382) (xy 74.370958 -174.596936) (xy 74.31107 -174.543466) (xy 74.257131 -174.484)
			(xy 74.209737 -174.419196) (xy 74.169414 -174.349772) (xy 74.136606 -174.276497) (xy 74.111678 -174.20018)
			(xy 74.094905 -174.121667) (xy 74.086473 -174.041826) (xy 74.085958 -174.001684) (xy 69.861176 -174.001684)
			(xy 71.39813 -175.538638) (xy 72.724008 -175.538638) (xy 72.728079 -175.483016) (xy 72.740205 -175.428579)
			(xy 72.760128 -175.376488) (xy 72.787424 -175.327853) (xy 72.82151 -175.28371) (xy 72.861659 -175.245001)
			(xy 72.907017 -175.21255) (xy 72.956617 -175.187049) (xy 73.009401 -175.169042) (xy 73.064244 -175.158912)
			(xy 73.119978 -175.156875) (xy 73.175415 -175.162975) (xy 73.229372 -175.177081) (xy 73.280701 -175.198893)
			(xy 73.328307 -175.227947) (xy 73.371175 -175.263622) (xy 73.408392 -175.305159) (xy 73.439165 -175.351672)
			(xy 73.462837 -175.402169) (xy 73.478905 -175.455576) (xy 73.487025 -175.510752) (xy 73.487534 -175.538638)
			(xy 73.487025 -175.566524) (xy 73.478905 -175.6217) (xy 73.462837 -175.675107) (xy 73.439165 -175.725604)
			(xy 73.408392 -175.772117) (xy 73.371175 -175.813654) (xy 73.328307 -175.849329) (xy 73.280701 -175.878383)
			(xy 73.229372 -175.900195) (xy 73.175415 -175.914301) (xy 73.119978 -175.920401) (xy 73.064244 -175.918364)
			(xy 73.009401 -175.908234) (xy 72.956617 -175.890227) (xy 72.907017 -175.864726) (xy 72.861659 -175.832275)
			(xy 72.82151 -175.793566) (xy 72.787424 -175.749423) (xy 72.760128 -175.700788) (xy 72.740205 -175.648697)
			(xy 72.728079 -175.59426) (xy 72.724008 -175.538638) (xy 71.39813 -175.538638) (xy 73.53808 -177.678588)
			(xy 73.53808 -179.111148) (xy 73.684382 -179.111148) (xy 73.688453 -179.055526) (xy 73.700579 -179.001089)
			(xy 73.720502 -178.948998) (xy 73.747798 -178.900363) (xy 73.781884 -178.85622) (xy 73.822033 -178.817511)
			(xy 73.867391 -178.78506) (xy 73.916991 -178.759559) (xy 73.969775 -178.741552) (xy 74.024618 -178.731422)
			(xy 74.080352 -178.729385) (xy 74.135789 -178.735485) (xy 74.189746 -178.749591) (xy 74.241075 -178.771403)
			(xy 74.288681 -178.800457) (xy 74.331549 -178.836132) (xy 74.368766 -178.877669) (xy 74.399539 -178.924182)
			(xy 74.423211 -178.974679) (xy 74.439279 -179.028086) (xy 74.447399 -179.083262) (xy 74.447908 -179.111148)
			(xy 74.447399 -179.139034) (xy 74.439279 -179.19421) (xy 74.423211 -179.247617) (xy 74.399539 -179.298114)
			(xy 74.368766 -179.344627) (xy 74.331549 -179.386164) (xy 74.288681 -179.421839) (xy 74.241075 -179.450893)
			(xy 74.189746 -179.472705) (xy 74.135789 -179.486811) (xy 74.080352 -179.492911) (xy 74.024618 -179.490874)
			(xy 73.969775 -179.480744) (xy 73.916991 -179.462737) (xy 73.867391 -179.437236) (xy 73.822033 -179.404785)
			(xy 73.781884 -179.366076) (xy 73.747798 -179.321933) (xy 73.720502 -179.273298) (xy 73.700579 -179.221207)
			(xy 73.688453 -179.16677) (xy 73.684382 -179.111148) (xy 73.53808 -179.111148) (xy 73.53808 -181.7116)
			(xy 75.379324 -181.7116) (xy 75.383395 -181.655978) (xy 75.395521 -181.601541) (xy 75.415444 -181.54945)
			(xy 75.44274 -181.500815) (xy 75.476826 -181.456672) (xy 75.516975 -181.417963) (xy 75.562333 -181.385512)
			(xy 75.611933 -181.360011) (xy 75.664717 -181.342004) (xy 75.71956 -181.331874) (xy 75.775294 -181.329837)
			(xy 75.830731 -181.335937) (xy 75.884688 -181.350043) (xy 75.936017 -181.371855) (xy 75.983623 -181.400909)
			(xy 76.026491 -181.436584) (xy 76.063708 -181.478121) (xy 76.094481 -181.524634) (xy 76.118153 -181.575131)
			(xy 76.134221 -181.628538) (xy 76.142341 -181.683714) (xy 76.14285 -181.7116) (xy 76.142341 -181.739486)
			(xy 76.134221 -181.794662) (xy 76.118153 -181.848069) (xy 76.094481 -181.898566) (xy 76.063708 -181.945079)
			(xy 76.026491 -181.986616) (xy 75.983623 -182.022291) (xy 75.936017 -182.051345) (xy 75.884688 -182.073157)
			(xy 75.830731 -182.087263) (xy 75.775294 -182.093363) (xy 75.71956 -182.091326) (xy 75.664717 -182.081196)
			(xy 75.611933 -182.063189) (xy 75.562333 -182.037688) (xy 75.516975 -182.005237) (xy 75.476826 -181.966528)
			(xy 75.44274 -181.922385) (xy 75.415444 -181.87375) (xy 75.395521 -181.821659) (xy 75.383395 -181.767222)
			(xy 75.379324 -181.7116) (xy 73.53808 -181.7116) (xy 73.53808 -181.981348) (xy 74.753978 -183.197246)
			(xy 75.07808 -183.197246) (xy 75.082151 -183.141624) (xy 75.094277 -183.087187) (xy 75.1142 -183.035096)
			(xy 75.141496 -182.986461) (xy 75.175582 -182.942318) (xy 75.215731 -182.903609) (xy 75.261089 -182.871158)
			(xy 75.310689 -182.845657) (xy 75.363473 -182.82765) (xy 75.418316 -182.81752) (xy 75.47405 -182.815483)
			(xy 75.529487 -182.821583) (xy 75.583444 -182.835689) (xy 75.634773 -182.857501) (xy 75.682379 -182.886555)
			(xy 75.725247 -182.92223) (xy 75.762464 -182.963767) (xy 75.793237 -183.01028) (xy 75.816909 -183.060777)
			(xy 75.832977 -183.114184) (xy 75.841097 -183.16936) (xy 75.841606 -183.197246) (xy 75.841097 -183.225132)
			(xy 75.832977 -183.280308) (xy 75.816909 -183.333715) (xy 75.793237 -183.384212) (xy 75.762464 -183.430725)
			(xy 75.725247 -183.472262) (xy 75.682379 -183.507937) (xy 75.634773 -183.536991) (xy 75.583444 -183.558803)
			(xy 75.529487 -183.572909) (xy 75.47405 -183.579009) (xy 75.418316 -183.576972) (xy 75.363473 -183.566842)
			(xy 75.310689 -183.548835) (xy 75.261089 -183.523334) (xy 75.215731 -183.490883) (xy 75.175582 -183.452174)
			(xy 75.141496 -183.408031) (xy 75.1142 -183.359396) (xy 75.094277 -183.307305) (xy 75.082151 -183.252868)
			(xy 75.07808 -183.197246) (xy 74.753978 -183.197246) (xy 76.460604 -184.903872) (xy 76.98689 -184.903872)
			(xy 76.990961 -184.84825) (xy 77.003087 -184.793813) (xy 77.02301 -184.741722) (xy 77.050306 -184.693087)
			(xy 77.084392 -184.648944) (xy 77.124541 -184.610235) (xy 77.169899 -184.577784) (xy 77.219499 -184.552283)
			(xy 77.272283 -184.534276) (xy 77.327126 -184.524146) (xy 77.38286 -184.522109) (xy 77.438297 -184.528209)
			(xy 77.492254 -184.542315) (xy 77.543583 -184.564127) (xy 77.591189 -184.593181) (xy 77.634057 -184.628856)
			(xy 77.671274 -184.670393) (xy 77.702047 -184.716906) (xy 77.725719 -184.767403) (xy 77.741787 -184.82081)
			(xy 77.749907 -184.875986) (xy 77.750416 -184.903872) (xy 77.749907 -184.931758) (xy 77.741787 -184.986934)
			(xy 77.725719 -185.040341) (xy 77.702047 -185.090838) (xy 77.671274 -185.137351) (xy 77.634057 -185.178888)
			(xy 77.591189 -185.214563) (xy 77.543583 -185.243617) (xy 77.492254 -185.265429) (xy 77.438297 -185.279535)
			(xy 77.38286 -185.285635) (xy 77.327126 -185.283598) (xy 77.272283 -185.273468) (xy 77.219499 -185.255461)
			(xy 77.169899 -185.22996) (xy 77.124541 -185.197509) (xy 77.084392 -185.1588) (xy 77.050306 -185.114657)
			(xy 77.02301 -185.066022) (xy 77.003087 -185.013931) (xy 76.990961 -184.959494) (xy 76.98689 -184.903872)
			(xy 76.460604 -184.903872) (xy 78.557882 -187.00115) (xy 80.78546 -187.00115) (xy 80.789531 -186.945528)
			(xy 80.801657 -186.891091) (xy 80.82158 -186.839) (xy 80.848876 -186.790365) (xy 80.882962 -186.746222)
			(xy 80.923111 -186.707513) (xy 80.968469 -186.675062) (xy 81.018069 -186.649561) (xy 81.070853 -186.631554)
			(xy 81.125696 -186.621424) (xy 81.18143 -186.619387) (xy 81.236867 -186.625487) (xy 81.290824 -186.639593)
			(xy 81.342153 -186.661405) (xy 81.389759 -186.690459) (xy 81.432627 -186.726134) (xy 81.469844 -186.767671)
			(xy 81.500617 -186.814184) (xy 81.524289 -186.864681) (xy 81.540357 -186.918088) (xy 81.548477 -186.973264)
			(xy 81.548986 -187.00115) (xy 81.548477 -187.029036) (xy 81.540357 -187.084212) (xy 81.524289 -187.137619)
			(xy 81.500617 -187.188116) (xy 81.469844 -187.234629) (xy 81.432627 -187.276166) (xy 81.389759 -187.311841)
			(xy 81.342153 -187.340895) (xy 81.290824 -187.362707) (xy 81.236867 -187.376813) (xy 81.18143 -187.382913)
			(xy 81.125696 -187.380876) (xy 81.070853 -187.370746) (xy 81.018069 -187.352739) (xy 80.968469 -187.327238)
			(xy 80.923111 -187.294787) (xy 80.882962 -187.256078) (xy 80.848876 -187.211935) (xy 80.82158 -187.1633)
			(xy 80.801657 -187.111209) (xy 80.789531 -187.056772) (xy 80.78546 -187.00115) (xy 78.557882 -187.00115)
			(xy 80.97012 -189.413388) (xy 80.974184 -189.416182) (xy 80.99591 -189.431068) (xy 81.035432 -189.465874)
			(xy 81.069781 -189.505795) (xy 81.08442 -189.527688) (xy 81.164176 -189.607444) (xy 85.075266 -189.607444)
			(xy 85.079337 -189.551822) (xy 85.091463 -189.497385) (xy 85.111386 -189.445294) (xy 85.138682 -189.396659)
			(xy 85.172768 -189.352516) (xy 85.212917 -189.313807) (xy 85.258275 -189.281356) (xy 85.307875 -189.255855)
			(xy 85.360659 -189.237848) (xy 85.415502 -189.227718) (xy 85.471236 -189.225681) (xy 85.526673 -189.231781)
			(xy 85.58063 -189.245887) (xy 85.631959 -189.267699) (xy 85.679565 -189.296753) (xy 85.722433 -189.332428)
			(xy 85.75965 -189.373965) (xy 85.790423 -189.420478) (xy 85.814095 -189.470975) (xy 85.830163 -189.524382)
			(xy 85.838283 -189.579558) (xy 85.838792 -189.607444) (xy 85.838283 -189.63533) (xy 85.830163 -189.690506)
			(xy 85.814095 -189.743913) (xy 85.790423 -189.79441) (xy 85.75965 -189.840923) (xy 85.722433 -189.88246)
			(xy 85.679565 -189.918135) (xy 85.631959 -189.947189) (xy 85.58063 -189.969001) (xy 85.526673 -189.983107)
			(xy 85.471236 -189.989207) (xy 85.415502 -189.98717) (xy 85.360659 -189.97704) (xy 85.307875 -189.959033)
			(xy 85.258275 -189.933532) (xy 85.212917 -189.901081) (xy 85.172768 -189.862372) (xy 85.138682 -189.818229)
			(xy 85.111386 -189.769594) (xy 85.091463 -189.717503) (xy 85.079337 -189.663066) (xy 85.075266 -189.607444)
			(xy 81.164176 -189.607444) (xy 83.41868 -191.861948) (xy 88.009982 -191.861948) (xy 88.014053 -191.806326)
			(xy 88.026179 -191.751889) (xy 88.046102 -191.699798) (xy 88.073398 -191.651163) (xy 88.107484 -191.60702)
			(xy 88.147633 -191.568311) (xy 88.192991 -191.53586) (xy 88.242591 -191.510359) (xy 88.295375 -191.492352)
			(xy 88.350218 -191.482222) (xy 88.405952 -191.480185) (xy 88.461389 -191.486285) (xy 88.515346 -191.500391)
			(xy 88.566675 -191.522203) (xy 88.614281 -191.551257) (xy 88.657149 -191.586932) (xy 88.694366 -191.628469)
			(xy 88.725139 -191.674982) (xy 88.748811 -191.725479) (xy 88.764879 -191.778886) (xy 88.772999 -191.834062)
			(xy 88.773508 -191.861948) (xy 88.772999 -191.889834) (xy 88.764879 -191.94501) (xy 88.748811 -191.998417)
			(xy 88.725139 -192.048914) (xy 88.694366 -192.095427) (xy 88.657149 -192.136964) (xy 88.614281 -192.172639)
			(xy 88.566675 -192.201693) (xy 88.515346 -192.223505) (xy 88.461389 -192.237611) (xy 88.405952 -192.243711)
			(xy 88.350218 -192.241674) (xy 88.295375 -192.231544) (xy 88.242591 -192.213537) (xy 88.192991 -192.188036)
			(xy 88.147633 -192.155585) (xy 88.107484 -192.116876) (xy 88.073398 -192.072733) (xy 88.046102 -192.024098)
			(xy 88.026179 -191.972007) (xy 88.014053 -191.91757) (xy 88.009982 -191.861948) (xy 83.41868 -191.861948)
			(xy 86.59368 -195.036948) (xy 97.76968 -195.036948) (xy 111.889794 -209.157062) (xy 111.889794 -213.732618)
			(xy 114.573558 -213.732618) (xy 114.574056 -213.705969) (xy 114.581999 -213.653265) (xy 114.597709 -213.602335)
			(xy 114.620835 -213.554314) (xy 114.650859 -213.510277) (xy 114.687111 -213.471206) (xy 114.728782 -213.437975)
			(xy 114.77494 -213.411326) (xy 114.824554 -213.391854) (xy 114.876516 -213.379994) (xy 114.929666 -213.376011)
			(xy 114.982816 -213.379994) (xy 115.034778 -213.391854) (xy 115.084392 -213.411326) (xy 115.13055 -213.437975)
			(xy 115.172221 -213.471206) (xy 115.208473 -213.510277) (xy 115.238497 -213.554314) (xy 115.261623 -213.602335)
			(xy 115.277333 -213.653265) (xy 115.285276 -213.705969) (xy 115.285774 -213.732618) (xy 115.285252 -213.759267)
			(xy 115.513856 -213.759267) (xy 115.513856 -213.705969) (xy 115.521799 -213.653265) (xy 115.537509 -213.602335)
			(xy 115.560635 -213.554314) (xy 115.590659 -213.510277) (xy 115.626911 -213.471206) (xy 115.668582 -213.437975)
			(xy 115.71474 -213.411326) (xy 115.764354 -213.391854) (xy 115.816316 -213.379994) (xy 115.869466 -213.376011)
			(xy 115.922616 -213.379994) (xy 115.974578 -213.391854) (xy 116.024192 -213.411326) (xy 116.07035 -213.437975)
			(xy 116.112021 -213.471206) (xy 116.148273 -213.510277) (xy 116.178297 -213.554314) (xy 116.201423 -213.602335)
			(xy 116.217133 -213.653265) (xy 116.225076 -213.705969) (xy 116.225574 -213.732618) (xy 116.453158 -213.732618)
			(xy 116.453656 -213.705969) (xy 116.461599 -213.653265) (xy 116.477309 -213.602335) (xy 116.500435 -213.554314)
			(xy 116.530459 -213.510277) (xy 116.566711 -213.471206) (xy 116.608382 -213.437975) (xy 116.65454 -213.411326)
			(xy 116.704154 -213.391854) (xy 116.756116 -213.379994) (xy 116.809266 -213.376011) (xy 116.862416 -213.379994)
			(xy 116.914378 -213.391854) (xy 116.963992 -213.411326) (xy 117.01015 -213.437975) (xy 117.051821 -213.471206)
			(xy 117.088073 -213.510277) (xy 117.118097 -213.554314) (xy 117.141223 -213.602335) (xy 117.156933 -213.653265)
			(xy 117.164876 -213.705969) (xy 117.165374 -213.732618) (xy 117.164852 -213.759267) (xy 117.393456 -213.759267)
			(xy 117.393456 -213.705969) (xy 117.401399 -213.653265) (xy 117.417109 -213.602335) (xy 117.440235 -213.554314)
			(xy 117.470259 -213.510277) (xy 117.506511 -213.471206) (xy 117.548182 -213.437975) (xy 117.59434 -213.411326)
			(xy 117.643954 -213.391854) (xy 117.695916 -213.379994) (xy 117.749066 -213.376011) (xy 117.802216 -213.379994)
			(xy 117.854178 -213.391854) (xy 117.903792 -213.411326) (xy 117.94995 -213.437975) (xy 117.991621 -213.471206)
			(xy 118.027873 -213.510277) (xy 118.057897 -213.554314) (xy 118.081023 -213.602335) (xy 118.096733 -213.653265)
			(xy 118.104676 -213.705969) (xy 118.105174 -213.732618) (xy 118.104676 -213.759267) (xy 118.096733 -213.811971)
			(xy 118.081023 -213.862901) (xy 118.057897 -213.910922) (xy 118.027873 -213.954959) (xy 117.991621 -213.99403)
			(xy 117.94995 -214.027261) (xy 117.903792 -214.05391) (xy 117.854178 -214.073382) (xy 117.802216 -214.085242)
			(xy 117.749066 -214.089226) (xy 117.695916 -214.085242) (xy 117.643954 -214.073382) (xy 117.59434 -214.05391)
			(xy 117.548182 -214.027261) (xy 117.506511 -213.99403) (xy 117.470259 -213.954959) (xy 117.440235 -213.910922)
			(xy 117.417109 -213.862901) (xy 117.401399 -213.811971) (xy 117.393456 -213.759267) (xy 117.164852 -213.759267)
			(xy 117.164829 -213.760435) (xy 117.156187 -213.815393) (xy 117.139099 -213.868337) (xy 117.12702 -213.8934)
			(xy 117.115082 -213.916768) (xy 117.299486 -214.266272) (xy 117.325394 -214.269574) (xy 117.350743 -214.27343)
			(xy 117.400079 -214.287384) (xy 117.446905 -214.308268) (xy 117.490252 -214.335651) (xy 117.529225 -214.368966)
			(xy 117.563018 -214.407526) (xy 117.590933 -214.450532) (xy 117.612393 -214.497097) (xy 117.626954 -214.546258)
			(xy 117.634315 -214.596998) (xy 117.634766 -214.622634) (xy 117.634268 -214.649283) (xy 117.626325 -214.701987)
			(xy 117.610615 -214.752917) (xy 117.587489 -214.800938) (xy 117.557465 -214.844975) (xy 117.521213 -214.884046)
			(xy 117.479542 -214.917277) (xy 117.433384 -214.943926) (xy 117.38377 -214.963398) (xy 117.331808 -214.975258)
			(xy 117.278658 -214.979242) (xy 117.225508 -214.975258) (xy 117.173546 -214.963398) (xy 117.123932 -214.943926)
			(xy 117.077774 -214.917277) (xy 117.036103 -214.884046) (xy 116.999851 -214.844975) (xy 116.969827 -214.800938)
			(xy 116.946701 -214.752917) (xy 116.930991 -214.701987) (xy 116.923048 -214.649283) (xy 116.92255 -214.622634)
			(xy 116.923074 -214.594816) (xy 116.931725 -214.539858) (xy 116.94882 -214.486914) (xy 116.960904 -214.461852)
			(xy 116.972842 -214.438484) (xy 116.788438 -214.08898) (xy 116.76253 -214.085678) (xy 116.737176 -214.081849)
			(xy 116.687836 -214.067896) (xy 116.641007 -214.047011) (xy 116.597657 -214.019626) (xy 116.558683 -213.986308)
			(xy 116.524889 -213.947745) (xy 116.496976 -213.904734) (xy 116.475518 -213.858165) (xy 116.460961 -213.809)
			(xy 116.453606 -213.758255) (xy 116.453158 -213.732618) (xy 116.225574 -213.732618) (xy 116.225076 -213.759267)
			(xy 116.217133 -213.811971) (xy 116.201423 -213.862901) (xy 116.178297 -213.910922) (xy 116.148273 -213.954959)
			(xy 116.112021 -213.99403) (xy 116.07035 -214.027261) (xy 116.024192 -214.05391) (xy 115.974578 -214.073382)
			(xy 115.922616 -214.085242) (xy 115.869466 -214.089226) (xy 115.816316 -214.085242) (xy 115.764354 -214.073382)
			(xy 115.71474 -214.05391) (xy 115.668582 -214.027261) (xy 115.626911 -213.99403) (xy 115.590659 -213.954959)
			(xy 115.560635 -213.910922) (xy 115.537509 -213.862901) (xy 115.521799 -213.811971) (xy 115.513856 -213.759267)
			(xy 115.285252 -213.759267) (xy 115.285229 -213.760435) (xy 115.276587 -213.815393) (xy 115.259499 -213.868337)
			(xy 115.24742 -213.8934) (xy 115.235482 -213.916768) (xy 115.419886 -214.266272) (xy 115.445794 -214.269574)
			(xy 115.471143 -214.27343) (xy 115.520479 -214.287384) (xy 115.567305 -214.308268) (xy 115.610652 -214.335651)
			(xy 115.649625 -214.368966) (xy 115.683418 -214.407526) (xy 115.711333 -214.450532) (xy 115.732793 -214.497097)
			(xy 115.747354 -214.546258) (xy 115.754715 -214.596998) (xy 115.755166 -214.622634) (xy 115.754668 -214.649283)
			(xy 115.746725 -214.701987) (xy 115.731015 -214.752917) (xy 115.707889 -214.800938) (xy 115.677865 -214.844975)
			(xy 115.641613 -214.884046) (xy 115.599942 -214.917277) (xy 115.553784 -214.943926) (xy 115.50417 -214.963398)
			(xy 115.452208 -214.975258) (xy 115.399058 -214.979242) (xy 115.345908 -214.975258) (xy 115.293946 -214.963398)
			(xy 115.244332 -214.943926) (xy 115.198174 -214.917277) (xy 115.156503 -214.884046) (xy 115.120251 -214.844975)
			(xy 115.090227 -214.800938) (xy 115.067101 -214.752917) (xy 115.051391 -214.701987) (xy 115.043448 -214.649283)
			(xy 115.04295 -214.622634) (xy 115.043474 -214.594816) (xy 115.052125 -214.539858) (xy 115.06922 -214.486914)
			(xy 115.081304 -214.461852) (xy 115.093242 -214.438484) (xy 114.908838 -214.08898) (xy 114.88293 -214.085678)
			(xy 114.857576 -214.081849) (xy 114.808236 -214.067896) (xy 114.761407 -214.047011) (xy 114.718057 -214.019626)
			(xy 114.679083 -213.986308) (xy 114.645289 -213.947745) (xy 114.617376 -213.904734) (xy 114.595918 -213.858165)
			(xy 114.581361 -213.809) (xy 114.574006 -213.758255) (xy 114.573558 -213.732618) (xy 111.889794 -213.732618)
			(xy 111.889794 -214.29218) (xy 111.907845 -214.310546) (xy 111.939006 -214.351542) (xy 111.963942 -214.396597)
			(xy 111.982133 -214.444771) (xy 111.993199 -214.495063) (xy 111.99691 -214.5464) (xy 112.223127 -214.5464)
			(xy 112.227109 -214.49326) (xy 112.238966 -214.441306) (xy 112.258434 -214.3917) (xy 112.285077 -214.345549)
			(xy 112.3183 -214.303883) (xy 112.357362 -214.267635) (xy 112.401389 -214.237613) (xy 112.449399 -214.214487)
			(xy 112.50032 -214.198775) (xy 112.553013 -214.190827) (xy 112.579658 -214.190326) (xy 112.604683 -214.190766)
			(xy 112.65424 -214.197769) (xy 112.702328 -214.211643) (xy 112.747999 -214.232115) (xy 112.790354 -214.258781)
			(xy 112.828556 -214.291115) (xy 112.861854 -214.328481) (xy 112.876076 -214.349076) (xy 113.22304 -214.349076)
			(xy 113.237301 -214.328509) (xy 113.270592 -214.29114) (xy 113.308787 -214.258801) (xy 113.351134 -214.232129)
			(xy 113.396799 -214.21165) (xy 113.444882 -214.197767) (xy 113.494435 -214.190753) (xy 113.519458 -214.190326)
			(xy 113.546114 -214.190728) (xy 113.59883 -214.198668) (xy 113.649775 -214.214377) (xy 113.697809 -214.237504)
			(xy 113.741859 -214.267532) (xy 113.780941 -214.303791) (xy 113.814182 -214.34547) (xy 113.84084 -214.391638)
			(xy 113.860318 -214.441263) (xy 113.872182 -214.493238) (xy 113.876166 -214.5464) (xy 113.872182 -214.599562)
			(xy 113.860318 -214.651537) (xy 113.84084 -214.701162) (xy 113.814182 -214.74733) (xy 113.780941 -214.789009)
			(xy 113.741859 -214.825268) (xy 113.697809 -214.855296) (xy 113.649775 -214.878423) (xy 113.598831 -214.894132)
			(xy 113.546114 -214.902072) (xy 113.519458 -214.902542) (xy 113.494432 -214.902136) (xy 113.444875 -214.895123)
			(xy 113.396788 -214.88124) (xy 113.351117 -214.860762) (xy 113.308764 -214.834092) (xy 113.270561 -214.801755)
			(xy 113.237263 -214.764388) (xy 113.22304 -214.743792) (xy 112.876076 -214.743792) (xy 112.86189 -214.764414)
			(xy 112.828585 -214.801778) (xy 112.790375 -214.834111) (xy 112.748015 -214.860775) (xy 112.702339 -214.881245)
			(xy 112.654246 -214.895118) (xy 112.604685 -214.902121) (xy 112.579658 -214.902542) (xy 112.553013 -214.901973)
			(xy 112.50032 -214.894025) (xy 112.449399 -214.878313) (xy 112.401389 -214.855187) (xy 112.357362 -214.825165)
			(xy 112.3183 -214.788917) (xy 112.285077 -214.747251) (xy 112.258434 -214.7011) (xy 112.238966 -214.651494)
			(xy 112.227109 -214.59954) (xy 112.223127 -214.5464) (xy 111.99691 -214.5464) (xy 111.996912 -214.546424)
			(xy 111.993193 -214.597784) (xy 111.982119 -214.648074) (xy 111.963922 -214.696247) (xy 111.93898 -214.741298)
			(xy 111.907814 -214.78229) (xy 111.889794 -214.800688) (xy 111.889794 -214.994744) (xy 111.890185 -215.008077)
			(xy 111.897083 -215.033835) (xy 111.910423 -215.056925) (xy 111.929292 -215.075766) (xy 111.952401 -215.089073)
			(xy 111.978169 -215.095934) (xy 112.004835 -215.095881) (xy 112.01781 -215.092788) (xy 112.040432 -215.087081)
			(xy 112.086684 -215.08096) (xy 112.110012 -215.080596) (xy 112.13666 -215.081094) (xy 112.189362 -215.08904)
			(xy 112.24029 -215.104751) (xy 112.288309 -215.127876) (xy 112.332344 -215.1579) (xy 112.371413 -215.194152)
			(xy 112.404642 -215.235822) (xy 112.43129 -215.281979) (xy 112.450761 -215.331591) (xy 112.462621 -215.383552)
			(xy 112.466604 -215.4367) (xy 112.464607 -215.463353) (xy 112.694202 -215.463353) (xy 112.694202 -215.410055)
			(xy 112.702145 -215.357351) (xy 112.717855 -215.306421) (xy 112.740981 -215.2584) (xy 112.771005 -215.214363)
			(xy 112.807257 -215.175292) (xy 112.848928 -215.142061) (xy 112.895086 -215.115412) (xy 112.9447 -215.09594)
			(xy 112.996662 -215.08408) (xy 113.049812 -215.080097) (xy 113.102962 -215.08408) (xy 113.154924 -215.09594)
			(xy 113.204538 -215.115412) (xy 113.250696 -215.142061) (xy 113.292367 -215.175292) (xy 113.328619 -215.214363)
			(xy 113.358643 -215.2584) (xy 113.381769 -215.306421) (xy 113.397479 -215.357351) (xy 113.405422 -215.410055)
			(xy 113.40592 -215.436704) (xy 113.633504 -215.436704) (xy 113.633884 -215.411073) (xy 113.64122 -215.360338)
			(xy 113.655757 -215.31118) (xy 113.677193 -215.264615) (xy 113.705085 -215.221605) (xy 113.738857 -215.18304)
			(xy 113.77781 -215.149717) (xy 113.82114 -215.122324) (xy 113.86795 -215.101428) (xy 113.917273 -215.087461)
			(xy 113.942622 -215.083644) (xy 113.96726 -215.080342) (xy 114.13998 -214.781638) (xy 114.130328 -214.758524)
			(xy 114.121822 -214.736888) (xy 114.109831 -214.691972) (xy 114.103782 -214.645878) (xy 114.103404 -214.622634)
			(xy 114.103902 -214.595985) (xy 114.111845 -214.543281) (xy 114.127555 -214.492351) (xy 114.150681 -214.44433)
			(xy 114.180705 -214.400293) (xy 114.216957 -214.361222) (xy 114.258628 -214.327991) (xy 114.304786 -214.301342)
			(xy 114.3544 -214.28187) (xy 114.406362 -214.27001) (xy 114.459512 -214.266027) (xy 114.512662 -214.27001)
			(xy 114.564624 -214.28187) (xy 114.614238 -214.301342) (xy 114.660396 -214.327991) (xy 114.702067 -214.361222)
			(xy 114.738319 -214.400293) (xy 114.768343 -214.44433) (xy 114.791469 -214.492351) (xy 114.807179 -214.543281)
			(xy 114.815122 -214.595985) (xy 114.81562 -214.622634) (xy 114.815163 -214.648263) (xy 114.807835 -214.698993)
			(xy 114.793308 -214.748148) (xy 114.771881 -214.794712) (xy 114.743998 -214.837721) (xy 114.710235 -214.876287)
			(xy 114.671289 -214.909611) (xy 114.627967 -214.937006) (xy 114.581165 -214.957905) (xy 114.531848 -214.971875)
			(xy 114.506502 -214.975694) (xy 114.481864 -214.978996) (xy 114.309144 -215.2777) (xy 114.318796 -215.300814)
			(xy 114.327315 -215.322445) (xy 114.339301 -215.367363) (xy 114.345345 -215.413459) (xy 114.34572 -215.436704)
			(xy 114.345222 -215.463353) (xy 114.573802 -215.463353) (xy 114.573802 -215.410055) (xy 114.581745 -215.357351)
			(xy 114.597455 -215.306421) (xy 114.620581 -215.2584) (xy 114.650605 -215.214363) (xy 114.686857 -215.175292)
			(xy 114.728528 -215.142061) (xy 114.774686 -215.115412) (xy 114.8243 -215.09594) (xy 114.876262 -215.08408)
			(xy 114.929412 -215.080097) (xy 114.982562 -215.08408) (xy 115.034524 -215.09594) (xy 115.084138 -215.115412)
			(xy 115.130296 -215.142061) (xy 115.171967 -215.175292) (xy 115.208219 -215.214363) (xy 115.238243 -215.2584)
			(xy 115.261369 -215.306421) (xy 115.277079 -215.357351) (xy 115.285022 -215.410055) (xy 115.28552 -215.436704)
			(xy 115.513104 -215.436704) (xy 115.513484 -215.411073) (xy 115.52082 -215.360338) (xy 115.535357 -215.31118)
			(xy 115.556793 -215.264615) (xy 115.584685 -215.221605) (xy 115.618457 -215.18304) (xy 115.65741 -215.149717)
			(xy 115.70074 -215.122324) (xy 115.74755 -215.101428) (xy 115.796873 -215.087461) (xy 115.822222 -215.083644)
			(xy 115.84686 -215.080342) (xy 116.019326 -214.781638) (xy 116.009674 -214.758524) (xy 116.001165 -214.736889)
			(xy 115.989176 -214.691973) (xy 115.983128 -214.645879) (xy 115.98275 -214.622634) (xy 115.983248 -214.595985)
			(xy 115.991191 -214.543281) (xy 116.006901 -214.492351) (xy 116.030027 -214.44433) (xy 116.060051 -214.400293)
			(xy 116.096303 -214.361222) (xy 116.137974 -214.327991) (xy 116.184132 -214.301342) (xy 116.233746 -214.28187)
			(xy 116.285708 -214.27001) (xy 116.338858 -214.266027) (xy 116.392008 -214.27001) (xy 116.44397 -214.28187)
			(xy 116.493584 -214.301342) (xy 116.539742 -214.327991) (xy 116.581413 -214.361222) (xy 116.617665 -214.400293)
			(xy 116.647689 -214.44433) (xy 116.670815 -214.492351) (xy 116.686525 -214.543281) (xy 116.694468 -214.595985)
			(xy 116.694966 -214.622634) (xy 116.694469 -214.648261) (xy 116.687143 -214.698988) (xy 116.672618 -214.74814)
			(xy 116.651194 -214.794701) (xy 116.623315 -214.837708) (xy 116.589557 -214.876273) (xy 116.550617 -214.909599)
			(xy 116.507301 -214.936995) (xy 116.460503 -214.957897) (xy 116.411192 -214.971872) (xy 116.385848 -214.975694)
			(xy 116.36121 -214.978996) (xy 116.188744 -215.2777) (xy 116.198396 -215.300814) (xy 116.206915 -215.322445)
			(xy 116.218901 -215.367363) (xy 116.224945 -215.413459) (xy 116.22532 -215.436704) (xy 116.224822 -215.463353)
			(xy 116.453402 -215.463353) (xy 116.453402 -215.410055) (xy 116.461345 -215.357351) (xy 116.477055 -215.306421)
			(xy 116.500181 -215.2584) (xy 116.530205 -215.214363) (xy 116.566457 -215.175292) (xy 116.608128 -215.142061)
			(xy 116.654286 -215.115412) (xy 116.7039 -215.09594) (xy 116.755862 -215.08408) (xy 116.809012 -215.080097)
			(xy 116.862162 -215.08408) (xy 116.914124 -215.09594) (xy 116.963738 -215.115412) (xy 117.009896 -215.142061)
			(xy 117.051567 -215.175292) (xy 117.087819 -215.214363) (xy 117.117843 -215.2584) (xy 117.140969 -215.306421)
			(xy 117.156679 -215.357351) (xy 117.164622 -215.410055) (xy 117.16512 -215.436704) (xy 117.392704 -215.436704)
			(xy 117.393084 -215.411073) (xy 117.40042 -215.360338) (xy 117.414957 -215.31118) (xy 117.436393 -215.264615)
			(xy 117.464285 -215.221605) (xy 117.498057 -215.18304) (xy 117.53701 -215.149717) (xy 117.58034 -215.122324)
			(xy 117.62715 -215.101428) (xy 117.676473 -215.087461) (xy 117.701822 -215.083644) (xy 117.72646 -215.080342)
			(xy 117.898926 -214.781638) (xy 117.889274 -214.758524) (xy 117.880765 -214.736889) (xy 117.868776 -214.691973)
			(xy 117.862728 -214.645879) (xy 117.86235 -214.622634) (xy 117.862848 -214.595985) (xy 117.870791 -214.543281)
			(xy 117.886501 -214.492351) (xy 117.909627 -214.44433) (xy 117.939651 -214.400293) (xy 117.975903 -214.361222)
			(xy 118.017574 -214.327991) (xy 118.063732 -214.301342) (xy 118.113346 -214.28187) (xy 118.165308 -214.27001)
			(xy 118.218458 -214.266027) (xy 118.271608 -214.27001) (xy 118.32357 -214.28187) (xy 118.373184 -214.301342)
			(xy 118.419342 -214.327991) (xy 118.461013 -214.361222) (xy 118.497265 -214.400293) (xy 118.527289 -214.44433)
			(xy 118.550415 -214.492351) (xy 118.566125 -214.543281) (xy 118.574068 -214.595985) (xy 118.574566 -214.622634)
			(xy 118.574069 -214.648261) (xy 118.566743 -214.698988) (xy 118.552218 -214.74814) (xy 118.530794 -214.794701)
			(xy 118.502915 -214.837708) (xy 118.469157 -214.876273) (xy 118.430217 -214.909599) (xy 118.386901 -214.936995)
			(xy 118.340103 -214.957897) (xy 118.290792 -214.971872) (xy 118.265448 -214.975694) (xy 118.24081 -214.978996)
			(xy 118.068344 -215.2777) (xy 118.077996 -215.300814) (xy 118.086515 -215.322445) (xy 118.098501 -215.367363)
			(xy 118.104545 -215.413459) (xy 118.10492 -215.436704) (xy 118.104422 -215.463353) (xy 118.333002 -215.463353)
			(xy 118.333002 -215.410055) (xy 118.340945 -215.357351) (xy 118.356655 -215.306421) (xy 118.379781 -215.2584)
			(xy 118.409805 -215.214363) (xy 118.446057 -215.175292) (xy 118.487728 -215.142061) (xy 118.533886 -215.115412)
			(xy 118.5835 -215.09594) (xy 118.635462 -215.08408) (xy 118.688612 -215.080097) (xy 118.741762 -215.08408)
			(xy 118.793724 -215.09594) (xy 118.843338 -215.115412) (xy 118.889496 -215.142061) (xy 118.931167 -215.175292)
			(xy 118.967419 -215.214363) (xy 118.997443 -215.2584) (xy 119.020569 -215.306421) (xy 119.036279 -215.357351)
			(xy 119.044222 -215.410055) (xy 119.04472 -215.436704) (xy 119.044222 -215.463353) (xy 119.036279 -215.516057)
			(xy 119.020569 -215.566987) (xy 118.997443 -215.615008) (xy 118.967419 -215.659045) (xy 118.931167 -215.698116)
			(xy 118.889496 -215.731347) (xy 118.843338 -215.757996) (xy 118.793724 -215.777468) (xy 118.741762 -215.789328)
			(xy 118.688612 -215.793312) (xy 118.635462 -215.789328) (xy 118.5835 -215.777468) (xy 118.533886 -215.757996)
			(xy 118.487728 -215.731347) (xy 118.446057 -215.698116) (xy 118.409805 -215.659045) (xy 118.379781 -215.615008)
			(xy 118.356655 -215.566987) (xy 118.340945 -215.516057) (xy 118.333002 -215.463353) (xy 118.104422 -215.463353)
			(xy 118.096479 -215.516057) (xy 118.080769 -215.566987) (xy 118.057643 -215.615008) (xy 118.027619 -215.659045)
			(xy 117.991367 -215.698116) (xy 117.949696 -215.731347) (xy 117.903538 -215.757996) (xy 117.853924 -215.777468)
			(xy 117.801962 -215.789328) (xy 117.748812 -215.793312) (xy 117.695662 -215.789328) (xy 117.6437 -215.777468)
			(xy 117.594086 -215.757996) (xy 117.547928 -215.731347) (xy 117.506257 -215.698116) (xy 117.470005 -215.659045)
			(xy 117.439981 -215.615008) (xy 117.416855 -215.566987) (xy 117.401145 -215.516057) (xy 117.393202 -215.463353)
			(xy 117.392704 -215.436704) (xy 117.16512 -215.436704) (xy 117.164622 -215.463353) (xy 117.156679 -215.516057)
			(xy 117.140969 -215.566987) (xy 117.117843 -215.615008) (xy 117.087819 -215.659045) (xy 117.051567 -215.698116)
			(xy 117.009896 -215.731347) (xy 116.963738 -215.757996) (xy 116.914124 -215.777468) (xy 116.862162 -215.789328)
			(xy 116.809012 -215.793312) (xy 116.755862 -215.789328) (xy 116.7039 -215.777468) (xy 116.654286 -215.757996)
			(xy 116.608128 -215.731347) (xy 116.566457 -215.698116) (xy 116.530205 -215.659045) (xy 116.500181 -215.615008)
			(xy 116.477055 -215.566987) (xy 116.461345 -215.516057) (xy 116.453402 -215.463353) (xy 116.224822 -215.463353)
			(xy 116.216879 -215.516057) (xy 116.201169 -215.566987) (xy 116.178043 -215.615008) (xy 116.148019 -215.659045)
			(xy 116.111767 -215.698116) (xy 116.070096 -215.731347) (xy 116.023938 -215.757996) (xy 115.974324 -215.777468)
			(xy 115.922362 -215.789328) (xy 115.869212 -215.793312) (xy 115.816062 -215.789328) (xy 115.7641 -215.777468)
			(xy 115.714486 -215.757996) (xy 115.668328 -215.731347) (xy 115.626657 -215.698116) (xy 115.590405 -215.659045)
			(xy 115.560381 -215.615008) (xy 115.537255 -215.566987) (xy 115.521545 -215.516057) (xy 115.513602 -215.463353)
			(xy 115.513104 -215.436704) (xy 115.28552 -215.436704) (xy 115.285022 -215.463353) (xy 115.277079 -215.516057)
			(xy 115.261369 -215.566987) (xy 115.238243 -215.615008) (xy 115.208219 -215.659045) (xy 115.171967 -215.698116)
			(xy 115.130296 -215.731347) (xy 115.084138 -215.757996) (xy 115.034524 -215.777468) (xy 114.982562 -215.789328)
			(xy 114.929412 -215.793312) (xy 114.876262 -215.789328) (xy 114.8243 -215.777468) (xy 114.774686 -215.757996)
			(xy 114.728528 -215.731347) (xy 114.686857 -215.698116) (xy 114.650605 -215.659045) (xy 114.620581 -215.615008)
			(xy 114.597455 -215.566987) (xy 114.581745 -215.516057) (xy 114.573802 -215.463353) (xy 114.345222 -215.463353)
			(xy 114.337279 -215.516057) (xy 114.321569 -215.566987) (xy 114.298443 -215.615008) (xy 114.268419 -215.659045)
			(xy 114.232167 -215.698116) (xy 114.190496 -215.731347) (xy 114.144338 -215.757996) (xy 114.094724 -215.777468)
			(xy 114.042762 -215.789328) (xy 113.989612 -215.793312) (xy 113.936462 -215.789328) (xy 113.8845 -215.777468)
			(xy 113.834886 -215.757996) (xy 113.788728 -215.731347) (xy 113.747057 -215.698116) (xy 113.710805 -215.659045)
			(xy 113.680781 -215.615008) (xy 113.657655 -215.566987) (xy 113.641945 -215.516057) (xy 113.634002 -215.463353)
			(xy 113.633504 -215.436704) (xy 113.40592 -215.436704) (xy 113.405422 -215.463353) (xy 113.397479 -215.516057)
			(xy 113.381769 -215.566987) (xy 113.358643 -215.615008) (xy 113.328619 -215.659045) (xy 113.292367 -215.698116)
			(xy 113.250696 -215.731347) (xy 113.204538 -215.757996) (xy 113.154924 -215.777468) (xy 113.102962 -215.789328)
			(xy 113.049812 -215.793312) (xy 112.996662 -215.789328) (xy 112.9447 -215.777468) (xy 112.895086 -215.757996)
			(xy 112.848928 -215.731347) (xy 112.807257 -215.698116) (xy 112.771005 -215.659045) (xy 112.740981 -215.615008)
			(xy 112.717855 -215.566987) (xy 112.702145 -215.516057) (xy 112.694202 -215.463353) (xy 112.464607 -215.463353)
			(xy 112.462621 -215.489848) (xy 112.450761 -215.541809) (xy 112.43129 -215.591421) (xy 112.404642 -215.637578)
			(xy 112.371413 -215.679248) (xy 112.332344 -215.7155) (xy 112.288309 -215.745524) (xy 112.24029 -215.768649)
			(xy 112.189362 -215.78436) (xy 112.13666 -215.792306) (xy 112.110012 -215.792812) (xy 112.086686 -215.792415)
			(xy 112.040436 -215.786304) (xy 112.01781 -215.78062) (xy 112.004839 -215.777538) (xy 111.978185 -215.777508)
			(xy 111.952433 -215.784381) (xy 111.92934 -215.797688) (xy 111.910479 -215.816521) (xy 111.897138 -215.839596)
			(xy 111.890228 -215.865337) (xy 111.889794 -215.878664) (xy 111.889794 -215.996266) (xy 111.907846 -216.014632)
			(xy 111.939009 -216.055628) (xy 111.963947 -216.100683) (xy 111.982139 -216.148859) (xy 111.993208 -216.199152)
			(xy 111.996922 -216.250514) (xy 111.994992 -216.277169) (xy 112.224302 -216.277169) (xy 112.224302 -216.223871)
			(xy 112.232245 -216.171167) (xy 112.247955 -216.120237) (xy 112.271081 -216.072216) (xy 112.301105 -216.028179)
			(xy 112.337357 -215.989108) (xy 112.379028 -215.955877) (xy 112.425186 -215.929228) (xy 112.4748 -215.909756)
			(xy 112.526762 -215.897896) (xy 112.579912 -215.893913) (xy 112.633062 -215.897896) (xy 112.685024 -215.909756)
			(xy 112.734638 -215.929228) (xy 112.780796 -215.955877) (xy 112.822467 -215.989108) (xy 112.858719 -216.028179)
			(xy 112.888743 -216.072216) (xy 112.911869 -216.120237) (xy 112.927579 -216.171167) (xy 112.935522 -216.223871)
			(xy 112.93602 -216.25052) (xy 112.935522 -216.277169) (xy 113.164356 -216.277169) (xy 113.164356 -216.223871)
			(xy 113.172299 -216.171167) (xy 113.188009 -216.120237) (xy 113.211135 -216.072216) (xy 113.241159 -216.028179)
			(xy 113.277411 -215.989108) (xy 113.319082 -215.955877) (xy 113.36524 -215.929228) (xy 113.414854 -215.909756)
			(xy 113.466816 -215.897896) (xy 113.519966 -215.893913) (xy 113.573116 -215.897896) (xy 113.625078 -215.909756)
			(xy 113.674692 -215.929228) (xy 113.72085 -215.955877) (xy 113.762521 -215.989108) (xy 113.798773 -216.028179)
			(xy 113.828797 -216.072216) (xy 113.851923 -216.120237) (xy 113.867633 -216.171167) (xy 113.875576 -216.223871)
			(xy 113.876074 -216.25052) (xy 113.875576 -216.277169) (xy 114.104156 -216.277169) (xy 114.104156 -216.223871)
			(xy 114.112099 -216.171167) (xy 114.127809 -216.120237) (xy 114.150935 -216.072216) (xy 114.180959 -216.028179)
			(xy 114.217211 -215.989108) (xy 114.258882 -215.955877) (xy 114.30504 -215.929228) (xy 114.354654 -215.909756)
			(xy 114.406616 -215.897896) (xy 114.459766 -215.893913) (xy 114.512916 -215.897896) (xy 114.564878 -215.909756)
			(xy 114.614492 -215.929228) (xy 114.66065 -215.955877) (xy 114.702321 -215.989108) (xy 114.738573 -216.028179)
			(xy 114.768597 -216.072216) (xy 114.791723 -216.120237) (xy 114.807433 -216.171167) (xy 114.815376 -216.223871)
			(xy 114.815874 -216.25052) (xy 114.815376 -216.277169) (xy 115.043702 -216.277169) (xy 115.043702 -216.223871)
			(xy 115.051645 -216.171167) (xy 115.067355 -216.120237) (xy 115.090481 -216.072216) (xy 115.120505 -216.028179)
			(xy 115.156757 -215.989108) (xy 115.198428 -215.955877) (xy 115.244586 -215.929228) (xy 115.2942 -215.909756)
			(xy 115.346162 -215.897896) (xy 115.399312 -215.893913) (xy 115.452462 -215.897896) (xy 115.504424 -215.909756)
			(xy 115.554038 -215.929228) (xy 115.600196 -215.955877) (xy 115.641867 -215.989108) (xy 115.678119 -216.028179)
			(xy 115.708143 -216.072216) (xy 115.731269 -216.120237) (xy 115.746979 -216.171167) (xy 115.754922 -216.223871)
			(xy 115.75542 -216.25052) (xy 115.754922 -216.277169) (xy 115.983756 -216.277169) (xy 115.983756 -216.223871)
			(xy 115.991699 -216.171167) (xy 116.007409 -216.120237) (xy 116.030535 -216.072216) (xy 116.060559 -216.028179)
			(xy 116.096811 -215.989108) (xy 116.138482 -215.955877) (xy 116.18464 -215.929228) (xy 116.234254 -215.909756)
			(xy 116.286216 -215.897896) (xy 116.339366 -215.893913) (xy 116.392516 -215.897896) (xy 116.444478 -215.909756)
			(xy 116.494092 -215.929228) (xy 116.54025 -215.955877) (xy 116.581921 -215.989108) (xy 116.618173 -216.028179)
			(xy 116.648197 -216.072216) (xy 116.671323 -216.120237) (xy 116.687033 -216.171167) (xy 116.694976 -216.223871)
			(xy 116.695474 -216.25052) (xy 116.694976 -216.277169) (xy 116.923556 -216.277169) (xy 116.923556 -216.223871)
			(xy 116.931499 -216.171167) (xy 116.947209 -216.120237) (xy 116.970335 -216.072216) (xy 117.000359 -216.028179)
			(xy 117.036611 -215.989108) (xy 117.078282 -215.955877) (xy 117.12444 -215.929228) (xy 117.174054 -215.909756)
			(xy 117.226016 -215.897896) (xy 117.279166 -215.893913) (xy 117.332316 -215.897896) (xy 117.384278 -215.909756)
			(xy 117.433892 -215.929228) (xy 117.48005 -215.955877) (xy 117.521721 -215.989108) (xy 117.557973 -216.028179)
			(xy 117.587997 -216.072216) (xy 117.611123 -216.120237) (xy 117.626833 -216.171167) (xy 117.634776 -216.223871)
			(xy 117.635274 -216.25052) (xy 117.634776 -216.277169) (xy 117.863356 -216.277169) (xy 117.863356 -216.223871)
			(xy 117.871299 -216.171167) (xy 117.887009 -216.120237) (xy 117.910135 -216.072216) (xy 117.940159 -216.028179)
			(xy 117.976411 -215.989108) (xy 118.018082 -215.955877) (xy 118.06424 -215.929228) (xy 118.113854 -215.909756)
			(xy 118.165816 -215.897896) (xy 118.218966 -215.893913) (xy 118.272116 -215.897896) (xy 118.324078 -215.909756)
			(xy 118.373692 -215.929228) (xy 118.41985 -215.955877) (xy 118.461521 -215.989108) (xy 118.497773 -216.028179)
			(xy 118.527797 -216.072216) (xy 118.550923 -216.120237) (xy 118.566633 -216.171167) (xy 118.574576 -216.223871)
			(xy 118.575074 -216.25052) (xy 118.574576 -216.277169) (xy 118.566633 -216.329873) (xy 118.550923 -216.380803)
			(xy 118.527797 -216.428824) (xy 118.497773 -216.472861) (xy 118.461521 -216.511932) (xy 118.41985 -216.545163)
			(xy 118.373692 -216.571812) (xy 118.324078 -216.591284) (xy 118.272116 -216.603144) (xy 118.218966 -216.607128)
			(xy 118.165816 -216.603144) (xy 118.113854 -216.591284) (xy 118.06424 -216.571812) (xy 118.018082 -216.545163)
			(xy 117.976411 -216.511932) (xy 117.940159 -216.472861) (xy 117.910135 -216.428824) (xy 117.887009 -216.380803)
			(xy 117.871299 -216.329873) (xy 117.863356 -216.277169) (xy 117.634776 -216.277169) (xy 117.626833 -216.329873)
			(xy 117.611123 -216.380803) (xy 117.587997 -216.428824) (xy 117.557973 -216.472861) (xy 117.521721 -216.511932)
			(xy 117.48005 -216.545163) (xy 117.433892 -216.571812) (xy 117.384278 -216.591284) (xy 117.332316 -216.603144)
			(xy 117.279166 -216.607128) (xy 117.226016 -216.603144) (xy 117.174054 -216.591284) (xy 117.12444 -216.571812)
			(xy 117.078282 -216.545163) (xy 117.036611 -216.511932) (xy 117.000359 -216.472861) (xy 116.970335 -216.428824)
			(xy 116.947209 -216.380803) (xy 116.931499 -216.329873) (xy 116.923556 -216.277169) (xy 116.694976 -216.277169)
			(xy 116.687033 -216.329873) (xy 116.671323 -216.380803) (xy 116.648197 -216.428824) (xy 116.618173 -216.472861)
			(xy 116.581921 -216.511932) (xy 116.54025 -216.545163) (xy 116.494092 -216.571812) (xy 116.444478 -216.591284)
			(xy 116.392516 -216.603144) (xy 116.339366 -216.607128) (xy 116.286216 -216.603144) (xy 116.234254 -216.591284)
			(xy 116.18464 -216.571812) (xy 116.138482 -216.545163) (xy 116.096811 -216.511932) (xy 116.060559 -216.472861)
			(xy 116.030535 -216.428824) (xy 116.007409 -216.380803) (xy 115.991699 -216.329873) (xy 115.983756 -216.277169)
			(xy 115.754922 -216.277169) (xy 115.746979 -216.329873) (xy 115.731269 -216.380803) (xy 115.708143 -216.428824)
			(xy 115.678119 -216.472861) (xy 115.641867 -216.511932) (xy 115.600196 -216.545163) (xy 115.554038 -216.571812)
			(xy 115.504424 -216.591284) (xy 115.452462 -216.603144) (xy 115.399312 -216.607128) (xy 115.346162 -216.603144)
			(xy 115.2942 -216.591284) (xy 115.244586 -216.571812) (xy 115.198428 -216.545163) (xy 115.156757 -216.511932)
			(xy 115.120505 -216.472861) (xy 115.090481 -216.428824) (xy 115.067355 -216.380803) (xy 115.051645 -216.329873)
			(xy 115.043702 -216.277169) (xy 114.815376 -216.277169) (xy 114.807433 -216.329873) (xy 114.791723 -216.380803)
			(xy 114.768597 -216.428824) (xy 114.738573 -216.472861) (xy 114.702321 -216.511932) (xy 114.66065 -216.545163)
			(xy 114.614492 -216.571812) (xy 114.564878 -216.591284) (xy 114.512916 -216.603144) (xy 114.459766 -216.607128)
			(xy 114.406616 -216.603144) (xy 114.354654 -216.591284) (xy 114.30504 -216.571812) (xy 114.258882 -216.545163)
			(xy 114.217211 -216.511932) (xy 114.180959 -216.472861) (xy 114.150935 -216.428824) (xy 114.127809 -216.380803)
			(xy 114.112099 -216.329873) (xy 114.104156 -216.277169) (xy 113.875576 -216.277169) (xy 113.867633 -216.329873)
			(xy 113.851923 -216.380803) (xy 113.828797 -216.428824) (xy 113.798773 -216.472861) (xy 113.762521 -216.511932)
			(xy 113.72085 -216.545163) (xy 113.674692 -216.571812) (xy 113.625078 -216.591284) (xy 113.573116 -216.603144)
			(xy 113.519966 -216.607128) (xy 113.466816 -216.603144) (xy 113.414854 -216.591284) (xy 113.36524 -216.571812)
			(xy 113.319082 -216.545163) (xy 113.277411 -216.511932) (xy 113.241159 -216.472861) (xy 113.211135 -216.428824)
			(xy 113.188009 -216.380803) (xy 113.172299 -216.329873) (xy 113.164356 -216.277169) (xy 112.935522 -216.277169)
			(xy 112.927579 -216.329873) (xy 112.911869 -216.380803) (xy 112.888743 -216.428824) (xy 112.858719 -216.472861)
			(xy 112.822467 -216.511932) (xy 112.780796 -216.545163) (xy 112.734638 -216.571812) (xy 112.685024 -216.591284)
			(xy 112.633062 -216.603144) (xy 112.579912 -216.607128) (xy 112.526762 -216.603144) (xy 112.4748 -216.591284)
			(xy 112.425186 -216.571812) (xy 112.379028 -216.545163) (xy 112.337357 -216.511932) (xy 112.301105 -216.472861)
			(xy 112.271081 -216.428824) (xy 112.247955 -216.380803) (xy 112.232245 -216.329873) (xy 112.224302 -216.277169)
			(xy 111.994992 -216.277169) (xy 111.993204 -216.301876) (xy 111.982131 -216.352168) (xy 111.963935 -216.400342)
			(xy 111.938994 -216.445395) (xy 111.907828 -216.486389) (xy 111.889794 -216.504774) (xy 111.889794 -216.622376)
			(xy 111.890189 -216.635706) (xy 111.897092 -216.661457) (xy 111.910434 -216.684539) (xy 111.929302 -216.703374)
			(xy 111.952406 -216.716675) (xy 111.978169 -216.723534) (xy 112.004829 -216.723482) (xy 112.01781 -216.72042)
			(xy 112.040494 -216.7147) (xy 112.086875 -216.708579) (xy 112.110266 -216.708228) (xy 112.136916 -216.708699)
			(xy 112.189622 -216.716638) (xy 112.240555 -216.732345) (xy 112.288578 -216.755467) (xy 112.332619 -216.78549)
			(xy 112.371692 -216.821741) (xy 112.404926 -216.863412) (xy 112.431578 -216.90957) (xy 112.451052 -216.959185)
			(xy 112.462913 -217.011149) (xy 112.466896 -217.0643) (xy 112.466893 -217.064336) (xy 112.693704 -217.064336)
			(xy 112.694202 -217.037687) (xy 112.702145 -216.984983) (xy 112.717855 -216.934053) (xy 112.740981 -216.886032)
			(xy 112.771005 -216.841995) (xy 112.807257 -216.802924) (xy 112.848928 -216.769693) (xy 112.895086 -216.743044)
			(xy 112.9447 -216.723572) (xy 112.996662 -216.711712) (xy 113.049812 -216.707729) (xy 113.102962 -216.711712)
			(xy 113.154924 -216.723572) (xy 113.204538 -216.743044) (xy 113.250696 -216.769693) (xy 113.292367 -216.802924)
			(xy 113.328619 -216.841995) (xy 113.358643 -216.886032) (xy 113.381769 -216.934053) (xy 113.397479 -216.984983)
			(xy 113.405422 -217.037687) (xy 113.40592 -217.064336) (xy 113.405549 -217.08754) (xy 113.405096 -217.090985)
			(xy 113.634256 -217.090985) (xy 113.634256 -217.037687) (xy 113.642199 -216.984983) (xy 113.657909 -216.934053)
			(xy 113.681035 -216.886032) (xy 113.711059 -216.841995) (xy 113.747311 -216.802924) (xy 113.788982 -216.769693)
			(xy 113.83514 -216.743044) (xy 113.884754 -216.723572) (xy 113.936716 -216.711712) (xy 113.989866 -216.707729)
			(xy 114.043016 -216.711712) (xy 114.094978 -216.723572) (xy 114.144592 -216.743044) (xy 114.19075 -216.769693)
			(xy 114.232421 -216.802924) (xy 114.268673 -216.841995) (xy 114.298697 -216.886032) (xy 114.321823 -216.934053)
			(xy 114.337533 -216.984983) (xy 114.345476 -217.037687) (xy 114.345974 -217.064336) (xy 114.573304 -217.064336)
			(xy 114.573802 -217.037687) (xy 114.581745 -216.984983) (xy 114.597455 -216.934053) (xy 114.620581 -216.886032)
			(xy 114.650605 -216.841995) (xy 114.686857 -216.802924) (xy 114.728528 -216.769693) (xy 114.774686 -216.743044)
			(xy 114.8243 -216.723572) (xy 114.876262 -216.711712) (xy 114.929412 -216.707729) (xy 114.982562 -216.711712)
			(xy 115.034524 -216.723572) (xy 115.084138 -216.743044) (xy 115.130296 -216.769693) (xy 115.171967 -216.802924)
			(xy 115.208219 -216.841995) (xy 115.238243 -216.886032) (xy 115.261369 -216.934053) (xy 115.277079 -216.984983)
			(xy 115.285022 -217.037687) (xy 115.28552 -217.064336) (xy 115.285149 -217.08754) (xy 115.284696 -217.090985)
			(xy 115.513856 -217.090985) (xy 115.513856 -217.037687) (xy 115.521799 -216.984983) (xy 115.537509 -216.934053)
			(xy 115.560635 -216.886032) (xy 115.590659 -216.841995) (xy 115.626911 -216.802924) (xy 115.668582 -216.769693)
			(xy 115.71474 -216.743044) (xy 115.764354 -216.723572) (xy 115.816316 -216.711712) (xy 115.869466 -216.707729)
			(xy 115.922616 -216.711712) (xy 115.974578 -216.723572) (xy 116.024192 -216.743044) (xy 116.07035 -216.769693)
			(xy 116.112021 -216.802924) (xy 116.148273 -216.841995) (xy 116.178297 -216.886032) (xy 116.201423 -216.934053)
			(xy 116.217133 -216.984983) (xy 116.225076 -217.037687) (xy 116.225574 -217.064336) (xy 116.452904 -217.064336)
			(xy 116.453402 -217.037687) (xy 116.461345 -216.984983) (xy 116.477055 -216.934053) (xy 116.500181 -216.886032)
			(xy 116.530205 -216.841995) (xy 116.566457 -216.802924) (xy 116.608128 -216.769693) (xy 116.654286 -216.743044)
			(xy 116.7039 -216.723572) (xy 116.755862 -216.711712) (xy 116.809012 -216.707729) (xy 116.862162 -216.711712)
			(xy 116.914124 -216.723572) (xy 116.963738 -216.743044) (xy 117.009896 -216.769693) (xy 117.051567 -216.802924)
			(xy 117.087819 -216.841995) (xy 117.117843 -216.886032) (xy 117.140969 -216.934053) (xy 117.156679 -216.984983)
			(xy 117.164622 -217.037687) (xy 117.16512 -217.064336) (xy 117.164749 -217.08754) (xy 117.164296 -217.090985)
			(xy 117.393456 -217.090985) (xy 117.393456 -217.037687) (xy 117.401399 -216.984983) (xy 117.417109 -216.934053)
			(xy 117.440235 -216.886032) (xy 117.470259 -216.841995) (xy 117.506511 -216.802924) (xy 117.548182 -216.769693)
			(xy 117.59434 -216.743044) (xy 117.643954 -216.723572) (xy 117.695916 -216.711712) (xy 117.749066 -216.707729)
			(xy 117.802216 -216.711712) (xy 117.854178 -216.723572) (xy 117.903792 -216.743044) (xy 117.94995 -216.769693)
			(xy 117.991621 -216.802924) (xy 118.027873 -216.841995) (xy 118.057897 -216.886032) (xy 118.081023 -216.934053)
			(xy 118.096733 -216.984983) (xy 118.104676 -217.037687) (xy 118.105174 -217.064336) (xy 118.104676 -217.090985)
			(xy 118.096733 -217.143689) (xy 118.081023 -217.194619) (xy 118.057897 -217.24264) (xy 118.027873 -217.286677)
			(xy 117.991621 -217.325748) (xy 117.94995 -217.358979) (xy 117.903792 -217.385628) (xy 117.854178 -217.4051)
			(xy 117.802216 -217.41696) (xy 117.749066 -217.420944) (xy 117.695916 -217.41696) (xy 117.643954 -217.4051)
			(xy 117.59434 -217.385628) (xy 117.548182 -217.358979) (xy 117.506511 -217.325748) (xy 117.470259 -217.286677)
			(xy 117.440235 -217.24264) (xy 117.417109 -217.194619) (xy 117.401399 -217.143689) (xy 117.393456 -217.090985)
			(xy 117.164296 -217.090985) (xy 117.158695 -217.13355) (xy 117.146708 -217.178383) (xy 117.138196 -217.199972)
			(xy 117.128798 -217.223086) (xy 117.301518 -217.522044) (xy 117.326156 -217.525346) (xy 117.351494 -217.529193)
			(xy 117.400796 -217.543184) (xy 117.447585 -217.564096) (xy 117.490895 -217.591496) (xy 117.529831 -217.624818)
			(xy 117.563592 -217.663376) (xy 117.591479 -217.706373) (xy 117.612918 -217.752922) (xy 117.627466 -217.802063)
			(xy 117.634822 -217.852782) (xy 117.635274 -217.878406) (xy 117.634776 -217.905055) (xy 117.626833 -217.957759)
			(xy 117.611123 -218.008689) (xy 117.587997 -218.05671) (xy 117.557973 -218.100747) (xy 117.521721 -218.139818)
			(xy 117.48005 -218.173049) (xy 117.433892 -218.199698) (xy 117.384278 -218.21917) (xy 117.332316 -218.23103)
			(xy 117.279166 -218.235014) (xy 117.226016 -218.23103) (xy 117.174054 -218.21917) (xy 117.12444 -218.199698)
			(xy 117.078282 -218.173049) (xy 117.036611 -218.139818) (xy 117.000359 -218.100747) (xy 116.970335 -218.05671)
			(xy 116.947209 -218.008689) (xy 116.931499 -217.957759) (xy 116.923556 -217.905055) (xy 116.923058 -217.878406)
			(xy 116.923432 -217.855161) (xy 116.929477 -217.809066) (xy 116.941465 -217.764148) (xy 116.949982 -217.742516)
			(xy 116.959634 -217.719402) (xy 116.787168 -217.420698) (xy 116.762276 -217.417396) (xy 116.736918 -217.413592)
			(xy 116.687579 -217.399633) (xy 116.640752 -217.378743) (xy 116.597404 -217.351354) (xy 116.558431 -217.318033)
			(xy 116.524638 -217.279467) (xy 116.496725 -217.236455) (xy 116.475268 -217.189885) (xy 116.46071 -217.140719)
			(xy 116.453353 -217.089974) (xy 116.452904 -217.064336) (xy 116.225574 -217.064336) (xy 116.225076 -217.090985)
			(xy 116.217133 -217.143689) (xy 116.201423 -217.194619) (xy 116.178297 -217.24264) (xy 116.148273 -217.286677)
			(xy 116.112021 -217.325748) (xy 116.07035 -217.358979) (xy 116.024192 -217.385628) (xy 115.974578 -217.4051)
			(xy 115.922616 -217.41696) (xy 115.869466 -217.420944) (xy 115.816316 -217.41696) (xy 115.764354 -217.4051)
			(xy 115.71474 -217.385628) (xy 115.668582 -217.358979) (xy 115.626911 -217.325748) (xy 115.590659 -217.286677)
			(xy 115.560635 -217.24264) (xy 115.537509 -217.194619) (xy 115.521799 -217.143689) (xy 115.513856 -217.090985)
			(xy 115.284696 -217.090985) (xy 115.279095 -217.13355) (xy 115.267108 -217.178383) (xy 115.258596 -217.199972)
			(xy 115.249198 -217.223086) (xy 115.421918 -217.522044) (xy 115.446556 -217.525346) (xy 115.471894 -217.529193)
			(xy 115.521196 -217.543184) (xy 115.567985 -217.564096) (xy 115.611295 -217.591496) (xy 115.650231 -217.624818)
			(xy 115.683992 -217.663376) (xy 115.711879 -217.706373) (xy 115.733318 -217.752922) (xy 115.747866 -217.802063)
			(xy 115.755222 -217.852782) (xy 115.755674 -217.878406) (xy 115.755176 -217.905055) (xy 115.747233 -217.957759)
			(xy 115.731523 -218.008689) (xy 115.708397 -218.05671) (xy 115.678373 -218.100747) (xy 115.642121 -218.139818)
			(xy 115.60045 -218.173049) (xy 115.554292 -218.199698) (xy 115.504678 -218.21917) (xy 115.452716 -218.23103)
			(xy 115.399566 -218.235014) (xy 115.346416 -218.23103) (xy 115.294454 -218.21917) (xy 115.24484 -218.199698)
			(xy 115.198682 -218.173049) (xy 115.157011 -218.139818) (xy 115.120759 -218.100747) (xy 115.090735 -218.05671)
			(xy 115.067609 -218.008689) (xy 115.051899 -217.957759) (xy 115.043956 -217.905055) (xy 115.043458 -217.878406)
			(xy 115.043832 -217.855161) (xy 115.049877 -217.809066) (xy 115.061865 -217.764148) (xy 115.070382 -217.742516)
			(xy 115.080034 -217.719402) (xy 114.907568 -217.420698) (xy 114.882676 -217.417396) (xy 114.857318 -217.413592)
			(xy 114.807979 -217.399633) (xy 114.761152 -217.378743) (xy 114.717804 -217.351354) (xy 114.678831 -217.318033)
			(xy 114.645038 -217.279467) (xy 114.617125 -217.236455) (xy 114.595668 -217.189885) (xy 114.58111 -217.140719)
			(xy 114.573753 -217.089974) (xy 114.573304 -217.064336) (xy 114.345974 -217.064336) (xy 114.345476 -217.090985)
			(xy 114.337533 -217.143689) (xy 114.321823 -217.194619) (xy 114.298697 -217.24264) (xy 114.268673 -217.286677)
			(xy 114.232421 -217.325748) (xy 114.19075 -217.358979) (xy 114.144592 -217.385628) (xy 114.094978 -217.4051)
			(xy 114.043016 -217.41696) (xy 113.989866 -217.420944) (xy 113.936716 -217.41696) (xy 113.884754 -217.4051)
			(xy 113.83514 -217.385628) (xy 113.788982 -217.358979) (xy 113.747311 -217.325748) (xy 113.711059 -217.286677)
			(xy 113.681035 -217.24264) (xy 113.657909 -217.194619) (xy 113.642199 -217.143689) (xy 113.634256 -217.090985)
			(xy 113.405096 -217.090985) (xy 113.399495 -217.13355) (xy 113.387508 -217.178383) (xy 113.378996 -217.199972)
			(xy 113.369598 -217.223086) (xy 113.542318 -217.522044) (xy 113.566956 -217.525346) (xy 113.592294 -217.529193)
			(xy 113.641596 -217.543184) (xy 113.688385 -217.564096) (xy 113.731695 -217.591496) (xy 113.770631 -217.624818)
			(xy 113.804392 -217.663376) (xy 113.832279 -217.706373) (xy 113.853718 -217.752922) (xy 113.868266 -217.802063)
			(xy 113.875622 -217.852782) (xy 113.876074 -217.878406) (xy 113.875576 -217.905055) (xy 113.867633 -217.957759)
			(xy 113.851923 -218.008689) (xy 113.828797 -218.05671) (xy 113.798773 -218.100747) (xy 113.762521 -218.139818)
			(xy 113.72085 -218.173049) (xy 113.674692 -218.199698) (xy 113.625078 -218.21917) (xy 113.573116 -218.23103)
			(xy 113.519966 -218.235014) (xy 113.466816 -218.23103) (xy 113.414854 -218.21917) (xy 113.36524 -218.199698)
			(xy 113.319082 -218.173049) (xy 113.277411 -218.139818) (xy 113.241159 -218.100747) (xy 113.211135 -218.05671)
			(xy 113.188009 -218.008689) (xy 113.172299 -217.957759) (xy 113.164356 -217.905055) (xy 113.163858 -217.878406)
			(xy 113.164232 -217.855161) (xy 113.170277 -217.809066) (xy 113.182265 -217.764148) (xy 113.190782 -217.742516)
			(xy 113.200434 -217.719402) (xy 113.027968 -217.420698) (xy 113.003076 -217.417396) (xy 112.977718 -217.413592)
			(xy 112.928379 -217.399633) (xy 112.881552 -217.378743) (xy 112.838204 -217.351354) (xy 112.799231 -217.318033)
			(xy 112.765438 -217.279467) (xy 112.737525 -217.236455) (xy 112.716068 -217.189885) (xy 112.70151 -217.140719)
			(xy 112.694153 -217.089974) (xy 112.693704 -217.064336) (xy 112.466893 -217.064336) (xy 112.462913 -217.117451)
			(xy 112.451052 -217.169415) (xy 112.431578 -217.21903) (xy 112.404926 -217.265188) (xy 112.371692 -217.306859)
			(xy 112.332619 -217.34311) (xy 112.288578 -217.373133) (xy 112.240555 -217.396255) (xy 112.189622 -217.411962)
			(xy 112.136916 -217.419901) (xy 112.110266 -217.420444) (xy 112.086876 -217.42006) (xy 112.040498 -217.413949)
			(xy 112.01781 -217.408252) (xy 112.004836 -217.405171) (xy 111.978177 -217.405143) (xy 111.95242 -217.412015)
			(xy 111.929319 -217.42532) (xy 111.910449 -217.444151) (xy 111.897096 -217.467224) (xy 111.89017 -217.492967)
			(xy 111.889794 -217.506296) (xy 111.889794 -217.624406) (xy 111.907809 -217.642764) (xy 111.938906 -217.683732)
			(xy 111.963788 -217.728747) (xy 111.98194 -217.776871) (xy 111.992984 -217.827104) (xy 111.996691 -217.878404)
			(xy 111.992983 -217.929704) (xy 111.981938 -217.979938) (xy 111.963785 -218.028061) (xy 111.938901 -218.073075)
			(xy 111.907804 -218.114043) (xy 111.889794 -218.132406) (xy 111.889794 -218.250262) (xy 111.890187 -218.263593)
			(xy 111.897088 -218.289347) (xy 111.910429 -218.312432) (xy 111.929298 -218.331271) (xy 111.952404 -218.344574)
			(xy 111.978169 -218.351434) (xy 112.004831 -218.351381) (xy 112.01781 -218.348306) (xy 112.028975 -218.345384)
			(xy 112.051599 -218.340811) (xy 112.063022 -218.339162) (xy 112.08766 -218.33586) (xy 112.260126 -218.036902)
			(xy 112.250728 -218.013788) (xy 112.242287 -217.992227) (xy 112.230412 -217.947472) (xy 112.224424 -217.901558)
			(xy 112.224058 -217.878406) (xy 112.224556 -217.851757) (xy 112.232499 -217.799053) (xy 112.248209 -217.748123)
			(xy 112.271335 -217.700102) (xy 112.301359 -217.656065) (xy 112.337611 -217.616994) (xy 112.379282 -217.583763)
			(xy 112.42544 -217.557114) (xy 112.475054 -217.537642) (xy 112.527016 -217.525782) (xy 112.580166 -217.521799)
			(xy 112.633316 -217.525782) (xy 112.685278 -217.537642) (xy 112.734892 -217.557114) (xy 112.78105 -217.583763)
			(xy 112.822721 -217.616994) (xy 112.858973 -217.656065) (xy 112.888997 -217.700102) (xy 112.912123 -217.748123)
			(xy 112.927833 -217.799053) (xy 112.935776 -217.851757) (xy 112.936274 -217.878406) (xy 112.935826 -217.904055)
			(xy 112.928464 -217.954822) (xy 112.913893 -218.004007) (xy 112.892414 -218.050592) (xy 112.864474 -218.093613)
			(xy 112.830648 -218.132179) (xy 112.791639 -218.165491) (xy 112.748253 -218.192862) (xy 112.701388 -218.213723)
			(xy 112.652015 -218.227643) (xy 112.626648 -218.231466) (xy 112.601756 -218.234768) (xy 112.429544 -218.533218)
			(xy 112.439196 -218.556332) (xy 112.447712 -218.577964) (xy 112.459699 -218.622882) (xy 112.465743 -218.668977)
			(xy 112.46612 -218.692222) (xy 113.633758 -218.692222) (xy 113.634194 -218.666593) (xy 113.641527 -218.615863)
			(xy 113.656059 -218.566708) (xy 113.677489 -218.520146) (xy 113.705375 -218.477138) (xy 113.739141 -218.438573)
			(xy 113.778087 -218.405248) (xy 113.82141 -218.377853) (xy 113.868213 -218.356954) (xy 113.91753 -218.342982)
			(xy 113.942876 -218.339162) (xy 113.967514 -218.33586) (xy 114.13998 -218.037156) (xy 114.130582 -218.014042)
			(xy 114.122078 -217.992451) (xy 114.110107 -217.947616) (xy 114.10405 -217.901608) (xy 114.103658 -217.878406)
			(xy 114.104156 -217.851757) (xy 114.112099 -217.799053) (xy 114.127809 -217.748123) (xy 114.150935 -217.700102)
			(xy 114.180959 -217.656065) (xy 114.217211 -217.616994) (xy 114.258882 -217.583763) (xy 114.30504 -217.557114)
			(xy 114.354654 -217.537642) (xy 114.406616 -217.525782) (xy 114.459766 -217.521799) (xy 114.512916 -217.525782)
			(xy 114.564878 -217.537642) (xy 114.614492 -217.557114) (xy 114.66065 -217.583763) (xy 114.702321 -217.616994)
			(xy 114.738573 -217.656065) (xy 114.768597 -217.700102) (xy 114.791723 -217.748123) (xy 114.807433 -217.799053)
			(xy 114.815376 -217.851757) (xy 114.815874 -217.878406) (xy 114.815402 -217.904045) (xy 114.808059 -217.954793)
			(xy 114.793513 -218.003963) (xy 114.772063 -218.050538) (xy 114.744153 -218.093554) (xy 114.710362 -218.132122)
			(xy 114.671387 -218.165443) (xy 114.628035 -218.192828) (xy 114.581204 -218.213711) (xy 114.53186 -218.22766)
			(xy 114.506502 -218.231466) (xy 114.48161 -218.234768) (xy 114.309398 -218.533218) (xy 114.31905 -218.556332)
			(xy 114.327572 -218.577962) (xy 114.339557 -218.622881) (xy 114.3456 -218.668977) (xy 114.345974 -218.692222)
			(xy 115.513104 -218.692222) (xy 115.5135 -218.666591) (xy 115.520834 -218.615857) (xy 115.535368 -218.5667)
			(xy 115.556802 -218.520135) (xy 115.584693 -218.477125) (xy 115.618463 -218.438559) (xy 115.657414 -218.405236)
			(xy 115.700743 -218.377843) (xy 115.747552 -218.356946) (xy 115.796873 -218.342979) (xy 115.822222 -218.339162)
			(xy 115.84686 -218.33586) (xy 116.019326 -218.036902) (xy 116.009928 -218.013788) (xy 116.001484 -217.992227)
			(xy 115.989591 -217.947476) (xy 115.983612 -217.901559) (xy 115.983258 -217.878406) (xy 115.983756 -217.851757)
			(xy 115.991699 -217.799053) (xy 116.007409 -217.748123) (xy 116.030535 -217.700102) (xy 116.060559 -217.656065)
			(xy 116.096811 -217.616994) (xy 116.138482 -217.583763) (xy 116.18464 -217.557114) (xy 116.234254 -217.537642)
			(xy 116.286216 -217.525782) (xy 116.339366 -217.521799) (xy 116.392516 -217.525782) (xy 116.444478 -217.537642)
			(xy 116.494092 -217.557114) (xy 116.54025 -217.583763) (xy 116.581921 -217.616994) (xy 116.618173 -217.656065)
			(xy 116.648197 -217.700102) (xy 116.671323 -217.748123) (xy 116.687033 -217.799053) (xy 116.694976 -217.851757)
			(xy 116.695474 -217.878406) (xy 116.69506 -217.904057) (xy 116.687698 -217.954829) (xy 116.673125 -218.004019)
			(xy 116.651645 -218.050609) (xy 116.623701 -218.093634) (xy 116.589873 -218.132203) (xy 116.550859 -218.165519)
			(xy 116.507469 -218.192892) (xy 116.4606 -218.213755) (xy 116.411222 -218.227677) (xy 116.385848 -218.231466)
			(xy 116.360956 -218.234768) (xy 116.188744 -218.533218) (xy 116.198396 -218.556332) (xy 116.20692 -218.577961)
			(xy 116.218904 -218.62288) (xy 116.224946 -218.668977) (xy 116.22532 -218.692222) (xy 116.224822 -218.718871)
			(xy 116.453402 -218.718871) (xy 116.453402 -218.665573) (xy 116.461345 -218.612869) (xy 116.477055 -218.561939)
			(xy 116.500181 -218.513918) (xy 116.530205 -218.469881) (xy 116.566457 -218.43081) (xy 116.608128 -218.397579)
			(xy 116.654286 -218.37093) (xy 116.7039 -218.351458) (xy 116.755862 -218.339598) (xy 116.809012 -218.335615)
			(xy 116.862162 -218.339598) (xy 116.914124 -218.351458) (xy 116.963738 -218.37093) (xy 117.009896 -218.397579)
			(xy 117.051567 -218.43081) (xy 117.087819 -218.469881) (xy 117.117843 -218.513918) (xy 117.140969 -218.561939)
			(xy 117.156679 -218.612869) (xy 117.164622 -218.665573) (xy 117.16512 -218.692222) (xy 117.392704 -218.692222)
			(xy 117.3931 -218.666591) (xy 117.400434 -218.615857) (xy 117.414968 -218.5667) (xy 117.436402 -218.520135)
			(xy 117.464293 -218.477125) (xy 117.498063 -218.438559) (xy 117.537014 -218.405236) (xy 117.580343 -218.377843)
			(xy 117.627152 -218.356946) (xy 117.676473 -218.342979) (xy 117.701822 -218.339162) (xy 117.72646 -218.33586)
			(xy 117.898926 -218.036902) (xy 117.889528 -218.013788) (xy 117.881084 -217.992227) (xy 117.869191 -217.947476)
			(xy 117.863212 -217.901559) (xy 117.862858 -217.878406) (xy 117.863356 -217.851757) (xy 117.871299 -217.799053)
			(xy 117.887009 -217.748123) (xy 117.910135 -217.700102) (xy 117.940159 -217.656065) (xy 117.976411 -217.616994)
			(xy 118.018082 -217.583763) (xy 118.06424 -217.557114) (xy 118.113854 -217.537642) (xy 118.165816 -217.525782)
			(xy 118.218966 -217.521799) (xy 118.272116 -217.525782) (xy 118.324078 -217.537642) (xy 118.373692 -217.557114)
			(xy 118.41985 -217.583763) (xy 118.461521 -217.616994) (xy 118.497773 -217.656065) (xy 118.527797 -217.700102)
			(xy 118.550923 -217.748123) (xy 118.566633 -217.799053) (xy 118.574576 -217.851757) (xy 118.575074 -217.878406)
			(xy 118.57466 -217.904057) (xy 118.567298 -217.954829) (xy 118.552725 -218.004019) (xy 118.531245 -218.050609)
			(xy 118.503301 -218.093634) (xy 118.469473 -218.132203) (xy 118.430459 -218.165519) (xy 118.387069 -218.192892)
			(xy 118.3402 -218.213755) (xy 118.290822 -218.227677) (xy 118.265448 -218.231466) (xy 118.240556 -218.234768)
			(xy 118.068344 -218.533218) (xy 118.077996 -218.556332) (xy 118.08652 -218.577961) (xy 118.098504 -218.62288)
			(xy 118.104546 -218.668977) (xy 118.10492 -218.692222) (xy 118.104422 -218.718871) (xy 118.333002 -218.718871)
			(xy 118.333002 -218.665573) (xy 118.340945 -218.612869) (xy 118.356655 -218.561939) (xy 118.379781 -218.513918)
			(xy 118.409805 -218.469881) (xy 118.446057 -218.43081) (xy 118.487728 -218.397579) (xy 118.533886 -218.37093)
			(xy 118.5835 -218.351458) (xy 118.635462 -218.339598) (xy 118.688612 -218.335615) (xy 118.741762 -218.339598)
			(xy 118.793724 -218.351458) (xy 118.843338 -218.37093) (xy 118.889496 -218.397579) (xy 118.931167 -218.43081)
			(xy 118.967419 -218.469881) (xy 118.997443 -218.513918) (xy 119.020569 -218.561939) (xy 119.036279 -218.612869)
			(xy 119.044222 -218.665573) (xy 119.04472 -218.692222) (xy 119.044222 -218.718871) (xy 119.036279 -218.771575)
			(xy 119.020569 -218.822505) (xy 118.997443 -218.870526) (xy 118.967419 -218.914563) (xy 118.931167 -218.953634)
			(xy 118.889496 -218.986865) (xy 118.843338 -219.013514) (xy 118.793724 -219.032986) (xy 118.741762 -219.044846)
			(xy 118.688612 -219.04883) (xy 118.635462 -219.044846) (xy 118.5835 -219.032986) (xy 118.533886 -219.013514)
			(xy 118.487728 -218.986865) (xy 118.446057 -218.953634) (xy 118.409805 -218.914563) (xy 118.379781 -218.870526)
			(xy 118.356655 -218.822505) (xy 118.340945 -218.771575) (xy 118.333002 -218.718871) (xy 118.104422 -218.718871)
			(xy 118.096479 -218.771575) (xy 118.080769 -218.822505) (xy 118.057643 -218.870526) (xy 118.027619 -218.914563)
			(xy 117.991367 -218.953634) (xy 117.949696 -218.986865) (xy 117.903538 -219.013514) (xy 117.853924 -219.032986)
			(xy 117.801962 -219.044846) (xy 117.748812 -219.04883) (xy 117.695662 -219.044846) (xy 117.6437 -219.032986)
			(xy 117.594086 -219.013514) (xy 117.547928 -218.986865) (xy 117.506257 -218.953634) (xy 117.470005 -218.914563)
			(xy 117.439981 -218.870526) (xy 117.416855 -218.822505) (xy 117.401145 -218.771575) (xy 117.393202 -218.718871)
			(xy 117.392704 -218.692222) (xy 117.16512 -218.692222) (xy 117.164622 -218.718871) (xy 117.156679 -218.771575)
			(xy 117.140969 -218.822505) (xy 117.117843 -218.870526) (xy 117.087819 -218.914563) (xy 117.051567 -218.953634)
			(xy 117.009896 -218.986865) (xy 116.963738 -219.013514) (xy 116.914124 -219.032986) (xy 116.862162 -219.044846)
			(xy 116.809012 -219.04883) (xy 116.755862 -219.044846) (xy 116.7039 -219.032986) (xy 116.654286 -219.013514)
			(xy 116.608128 -218.986865) (xy 116.566457 -218.953634) (xy 116.530205 -218.914563) (xy 116.500181 -218.870526)
			(xy 116.477055 -218.822505) (xy 116.461345 -218.771575) (xy 116.453402 -218.718871) (xy 116.224822 -218.718871)
			(xy 116.216879 -218.771575) (xy 116.201169 -218.822505) (xy 116.178043 -218.870526) (xy 116.148019 -218.914563)
			(xy 116.111767 -218.953634) (xy 116.070096 -218.986865) (xy 116.023938 -219.013514) (xy 115.974324 -219.032986)
			(xy 115.922362 -219.044846) (xy 115.869212 -219.04883) (xy 115.816062 -219.044846) (xy 115.7641 -219.032986)
			(xy 115.714486 -219.013514) (xy 115.668328 -218.986865) (xy 115.626657 -218.953634) (xy 115.590405 -218.914563)
			(xy 115.560381 -218.870526) (xy 115.537255 -218.822505) (xy 115.521545 -218.771575) (xy 115.513602 -218.718871)
			(xy 115.513104 -218.692222) (xy 114.345974 -218.692222) (xy 114.345476 -218.718871) (xy 114.337533 -218.771575)
			(xy 114.321823 -218.822505) (xy 114.298697 -218.870526) (xy 114.268673 -218.914563) (xy 114.232421 -218.953634)
			(xy 114.19075 -218.986865) (xy 114.144592 -219.013514) (xy 114.094978 -219.032986) (xy 114.043016 -219.044846)
			(xy 113.989866 -219.04883) (xy 113.936716 -219.044846) (xy 113.884754 -219.032986) (xy 113.83514 -219.013514)
			(xy 113.788982 -218.986865) (xy 113.747311 -218.953634) (xy 113.711059 -218.914563) (xy 113.681035 -218.870526)
			(xy 113.657909 -218.822505) (xy 113.642199 -218.771575) (xy 113.634256 -218.718871) (xy 113.633758 -218.692222)
			(xy 112.46612 -218.692222) (xy 112.465569 -218.720204) (xy 112.456812 -218.77548) (xy 112.439515 -218.828704)
			(xy 112.414106 -218.878568) (xy 112.38121 -218.923844) (xy 112.341636 -218.963417) (xy 112.29636 -218.996312)
			(xy 112.246495 -219.021719) (xy 112.19327 -219.039014) (xy 112.137994 -219.04777) (xy 112.110012 -219.04833)
			(xy 112.086686 -219.047932) (xy 112.040436 -219.04182) (xy 112.01781 -219.036138) (xy 112.00483 -219.033096)
			(xy 111.978181 -219.033068) (xy 111.952433 -219.039938) (xy 111.929339 -219.053238) (xy 111.910475 -219.072061)
			(xy 111.897124 -219.095125) (xy 111.890198 -219.120858) (xy 111.889794 -219.134182) (xy 111.889794 -219.251784)
			(xy 111.907845 -219.27015) (xy 111.939005 -219.311146) (xy 111.963941 -219.3562) (xy 111.982131 -219.404375)
			(xy 111.993197 -219.454666) (xy 111.996909 -219.506027) (xy 111.994978 -219.532687) (xy 112.224556 -219.532687)
			(xy 112.224556 -219.479389) (xy 112.232499 -219.426685) (xy 112.248209 -219.375755) (xy 112.271335 -219.327734)
			(xy 112.301359 -219.283697) (xy 112.337611 -219.244626) (xy 112.379282 -219.211395) (xy 112.42544 -219.184746)
			(xy 112.475054 -219.165274) (xy 112.527016 -219.153414) (xy 112.580166 -219.149431) (xy 112.633316 -219.153414)
			(xy 112.685278 -219.165274) (xy 112.734892 -219.184746) (xy 112.78105 -219.211395) (xy 112.822721 -219.244626)
			(xy 112.858973 -219.283697) (xy 112.888997 -219.327734) (xy 112.912123 -219.375755) (xy 112.927833 -219.426685)
			(xy 112.935776 -219.479389) (xy 112.936274 -219.506038) (xy 112.935776 -219.532687) (xy 113.164356 -219.532687)
			(xy 113.164356 -219.479389) (xy 113.172299 -219.426685) (xy 113.188009 -219.375755) (xy 113.211135 -219.327734)
			(xy 113.241159 -219.283697) (xy 113.277411 -219.244626) (xy 113.319082 -219.211395) (xy 113.36524 -219.184746)
			(xy 113.414854 -219.165274) (xy 113.466816 -219.153414) (xy 113.519966 -219.149431) (xy 113.573116 -219.153414)
			(xy 113.625078 -219.165274) (xy 113.674692 -219.184746) (xy 113.72085 -219.211395) (xy 113.762521 -219.244626)
			(xy 113.798773 -219.283697) (xy 113.828797 -219.327734) (xy 113.851923 -219.375755) (xy 113.867633 -219.426685)
			(xy 113.875576 -219.479389) (xy 113.876074 -219.506038) (xy 113.875576 -219.532687) (xy 114.104156 -219.532687)
			(xy 114.104156 -219.479389) (xy 114.112099 -219.426685) (xy 114.127809 -219.375755) (xy 114.150935 -219.327734)
			(xy 114.180959 -219.283697) (xy 114.217211 -219.244626) (xy 114.258882 -219.211395) (xy 114.30504 -219.184746)
			(xy 114.354654 -219.165274) (xy 114.406616 -219.153414) (xy 114.459766 -219.149431) (xy 114.512916 -219.153414)
			(xy 114.564878 -219.165274) (xy 114.614492 -219.184746) (xy 114.66065 -219.211395) (xy 114.702321 -219.244626)
			(xy 114.738573 -219.283697) (xy 114.768597 -219.327734) (xy 114.791723 -219.375755) (xy 114.807433 -219.426685)
			(xy 114.815376 -219.479389) (xy 114.815874 -219.506038) (xy 114.815376 -219.532687) (xy 115.043956 -219.532687)
			(xy 115.043956 -219.479389) (xy 115.051899 -219.426685) (xy 115.067609 -219.375755) (xy 115.090735 -219.327734)
			(xy 115.120759 -219.283697) (xy 115.157011 -219.244626) (xy 115.198682 -219.211395) (xy 115.24484 -219.184746)
			(xy 115.294454 -219.165274) (xy 115.346416 -219.153414) (xy 115.399566 -219.149431) (xy 115.452716 -219.153414)
			(xy 115.504678 -219.165274) (xy 115.554292 -219.184746) (xy 115.60045 -219.211395) (xy 115.642121 -219.244626)
			(xy 115.678373 -219.283697) (xy 115.708397 -219.327734) (xy 115.731523 -219.375755) (xy 115.747233 -219.426685)
			(xy 115.755176 -219.479389) (xy 115.755674 -219.506038) (xy 115.755176 -219.532687) (xy 115.983756 -219.532687)
			(xy 115.983756 -219.479389) (xy 115.991699 -219.426685) (xy 116.007409 -219.375755) (xy 116.030535 -219.327734)
			(xy 116.060559 -219.283697) (xy 116.096811 -219.244626) (xy 116.138482 -219.211395) (xy 116.18464 -219.184746)
			(xy 116.234254 -219.165274) (xy 116.286216 -219.153414) (xy 116.339366 -219.149431) (xy 116.392516 -219.153414)
			(xy 116.444478 -219.165274) (xy 116.494092 -219.184746) (xy 116.54025 -219.211395) (xy 116.581921 -219.244626)
			(xy 116.618173 -219.283697) (xy 116.648197 -219.327734) (xy 116.671323 -219.375755) (xy 116.687033 -219.426685)
			(xy 116.694976 -219.479389) (xy 116.695474 -219.506038) (xy 116.694976 -219.532687) (xy 116.923556 -219.532687)
			(xy 116.923556 -219.479389) (xy 116.931499 -219.426685) (xy 116.947209 -219.375755) (xy 116.970335 -219.327734)
			(xy 117.000359 -219.283697) (xy 117.036611 -219.244626) (xy 117.078282 -219.211395) (xy 117.12444 -219.184746)
			(xy 117.174054 -219.165274) (xy 117.226016 -219.153414) (xy 117.279166 -219.149431) (xy 117.332316 -219.153414)
			(xy 117.384278 -219.165274) (xy 117.433892 -219.184746) (xy 117.48005 -219.211395) (xy 117.521721 -219.244626)
			(xy 117.557973 -219.283697) (xy 117.587997 -219.327734) (xy 117.611123 -219.375755) (xy 117.626833 -219.426685)
			(xy 117.634776 -219.479389) (xy 117.635274 -219.506038) (xy 117.634776 -219.532687) (xy 117.863356 -219.532687)
			(xy 117.863356 -219.479389) (xy 117.871299 -219.426685) (xy 117.887009 -219.375755) (xy 117.910135 -219.327734)
			(xy 117.940159 -219.283697) (xy 117.976411 -219.244626) (xy 118.018082 -219.211395) (xy 118.06424 -219.184746)
			(xy 118.113854 -219.165274) (xy 118.165816 -219.153414) (xy 118.218966 -219.149431) (xy 118.272116 -219.153414)
			(xy 118.324078 -219.165274) (xy 118.373692 -219.184746) (xy 118.41985 -219.211395) (xy 118.461521 -219.244626)
			(xy 118.497773 -219.283697) (xy 118.527797 -219.327734) (xy 118.550923 -219.375755) (xy 118.566633 -219.426685)
			(xy 118.574576 -219.479389) (xy 118.575074 -219.506038) (xy 118.574576 -219.532687) (xy 118.566633 -219.585391)
			(xy 118.550923 -219.636321) (xy 118.527797 -219.684342) (xy 118.497773 -219.728379) (xy 118.461521 -219.76745)
			(xy 118.41985 -219.800681) (xy 118.373692 -219.82733) (xy 118.324078 -219.846802) (xy 118.272116 -219.858662)
			(xy 118.218966 -219.862646) (xy 118.165816 -219.858662) (xy 118.113854 -219.846802) (xy 118.06424 -219.82733)
			(xy 118.018082 -219.800681) (xy 117.976411 -219.76745) (xy 117.940159 -219.728379) (xy 117.910135 -219.684342)
			(xy 117.887009 -219.636321) (xy 117.871299 -219.585391) (xy 117.863356 -219.532687) (xy 117.634776 -219.532687)
			(xy 117.626833 -219.585391) (xy 117.611123 -219.636321) (xy 117.587997 -219.684342) (xy 117.557973 -219.728379)
			(xy 117.521721 -219.76745) (xy 117.48005 -219.800681) (xy 117.433892 -219.82733) (xy 117.384278 -219.846802)
			(xy 117.332316 -219.858662) (xy 117.279166 -219.862646) (xy 117.226016 -219.858662) (xy 117.174054 -219.846802)
			(xy 117.12444 -219.82733) (xy 117.078282 -219.800681) (xy 117.036611 -219.76745) (xy 117.000359 -219.728379)
			(xy 116.970335 -219.684342) (xy 116.947209 -219.636321) (xy 116.931499 -219.585391) (xy 116.923556 -219.532687)
			(xy 116.694976 -219.532687) (xy 116.687033 -219.585391) (xy 116.671323 -219.636321) (xy 116.648197 -219.684342)
			(xy 116.618173 -219.728379) (xy 116.581921 -219.76745) (xy 116.54025 -219.800681) (xy 116.494092 -219.82733)
			(xy 116.444478 -219.846802) (xy 116.392516 -219.858662) (xy 116.339366 -219.862646) (xy 116.286216 -219.858662)
			(xy 116.234254 -219.846802) (xy 116.18464 -219.82733) (xy 116.138482 -219.800681) (xy 116.096811 -219.76745)
			(xy 116.060559 -219.728379) (xy 116.030535 -219.684342) (xy 116.007409 -219.636321) (xy 115.991699 -219.585391)
			(xy 115.983756 -219.532687) (xy 115.755176 -219.532687) (xy 115.747233 -219.585391) (xy 115.731523 -219.636321)
			(xy 115.708397 -219.684342) (xy 115.678373 -219.728379) (xy 115.642121 -219.76745) (xy 115.60045 -219.800681)
			(xy 115.554292 -219.82733) (xy 115.504678 -219.846802) (xy 115.452716 -219.858662) (xy 115.399566 -219.862646)
			(xy 115.346416 -219.858662) (xy 115.294454 -219.846802) (xy 115.24484 -219.82733) (xy 115.198682 -219.800681)
			(xy 115.157011 -219.76745) (xy 115.120759 -219.728379) (xy 115.090735 -219.684342) (xy 115.067609 -219.636321)
			(xy 115.051899 -219.585391) (xy 115.043956 -219.532687) (xy 114.815376 -219.532687) (xy 114.807433 -219.585391)
			(xy 114.791723 -219.636321) (xy 114.768597 -219.684342) (xy 114.738573 -219.728379) (xy 114.702321 -219.76745)
			(xy 114.66065 -219.800681) (xy 114.614492 -219.82733) (xy 114.564878 -219.846802) (xy 114.512916 -219.858662)
			(xy 114.459766 -219.862646) (xy 114.406616 -219.858662) (xy 114.354654 -219.846802) (xy 114.30504 -219.82733)
			(xy 114.258882 -219.800681) (xy 114.217211 -219.76745) (xy 114.180959 -219.728379) (xy 114.150935 -219.684342)
			(xy 114.127809 -219.636321) (xy 114.112099 -219.585391) (xy 114.104156 -219.532687) (xy 113.875576 -219.532687)
			(xy 113.867633 -219.585391) (xy 113.851923 -219.636321) (xy 113.828797 -219.684342) (xy 113.798773 -219.728379)
			(xy 113.762521 -219.76745) (xy 113.72085 -219.800681) (xy 113.674692 -219.82733) (xy 113.625078 -219.846802)
			(xy 113.573116 -219.858662) (xy 113.519966 -219.862646) (xy 113.466816 -219.858662) (xy 113.414854 -219.846802)
			(xy 113.36524 -219.82733) (xy 113.319082 -219.800681) (xy 113.277411 -219.76745) (xy 113.241159 -219.728379)
			(xy 113.211135 -219.684342) (xy 113.188009 -219.636321) (xy 113.172299 -219.585391) (xy 113.164356 -219.532687)
			(xy 112.935776 -219.532687) (xy 112.927833 -219.585391) (xy 112.912123 -219.636321) (xy 112.888997 -219.684342)
			(xy 112.858973 -219.728379) (xy 112.822721 -219.76745) (xy 112.78105 -219.800681) (xy 112.734892 -219.82733)
			(xy 112.685278 -219.846802) (xy 112.633316 -219.858662) (xy 112.580166 -219.862646) (xy 112.527016 -219.858662)
			(xy 112.475054 -219.846802) (xy 112.42544 -219.82733) (xy 112.379282 -219.800681) (xy 112.337611 -219.76745)
			(xy 112.301359 -219.728379) (xy 112.271335 -219.684342) (xy 112.248209 -219.636321) (xy 112.232499 -219.585391)
			(xy 112.224556 -219.532687) (xy 111.994978 -219.532687) (xy 111.993189 -219.557387) (xy 111.982116 -219.607676)
			(xy 111.963918 -219.655848) (xy 111.938976 -219.700899) (xy 111.90781 -219.74189) (xy 111.889794 -219.760292)
			(xy 111.889794 -219.877894) (xy 111.890191 -219.891222) (xy 111.897097 -219.916969) (xy 111.91044 -219.940046)
			(xy 111.929307 -219.958878) (xy 111.95241 -219.972177) (xy 111.978169 -219.979034) (xy 112.004826 -219.978982)
			(xy 112.01781 -219.975938) (xy 112.040494 -219.970218) (xy 112.086875 -219.964096) (xy 112.110266 -219.963746)
			(xy 112.136922 -219.964217) (xy 112.18964 -219.972158) (xy 112.240585 -219.987868) (xy 112.288619 -220.010996)
			(xy 112.33267 -220.041026) (xy 112.371752 -220.077285) (xy 112.404994 -220.118965) (xy 112.431652 -220.165134)
			(xy 112.45113 -220.214761) (xy 112.462994 -220.266737) (xy 112.466975 -220.319854) (xy 112.693704 -220.319854)
			(xy 112.694202 -220.293205) (xy 112.702145 -220.240501) (xy 112.717855 -220.189571) (xy 112.740981 -220.14155)
			(xy 112.771005 -220.097513) (xy 112.807257 -220.058442) (xy 112.848928 -220.025211) (xy 112.895086 -219.998562)
			(xy 112.9447 -219.97909) (xy 112.996662 -219.96723) (xy 113.049812 -219.963247) (xy 113.102962 -219.96723)
			(xy 113.154924 -219.97909) (xy 113.204538 -219.998562) (xy 113.250696 -220.025211) (xy 113.292367 -220.058442)
			(xy 113.328619 -220.097513) (xy 113.358643 -220.14155) (xy 113.381769 -220.189571) (xy 113.397479 -220.240501)
			(xy 113.405422 -220.293205) (xy 113.40592 -220.319854) (xy 113.405523 -220.343057) (xy 113.40507 -220.346503)
			(xy 113.634256 -220.346503) (xy 113.634256 -220.293205) (xy 113.642199 -220.240501) (xy 113.657909 -220.189571)
			(xy 113.681035 -220.14155) (xy 113.711059 -220.097513) (xy 113.747311 -220.058442) (xy 113.788982 -220.025211)
			(xy 113.83514 -219.998562) (xy 113.884754 -219.97909) (xy 113.936716 -219.96723) (xy 113.989866 -219.963247)
			(xy 114.043016 -219.96723) (xy 114.094978 -219.97909) (xy 114.144592 -219.998562) (xy 114.19075 -220.025211)
			(xy 114.232421 -220.058442) (xy 114.268673 -220.097513) (xy 114.298697 -220.14155) (xy 114.321823 -220.189571)
			(xy 114.337533 -220.240501) (xy 114.345476 -220.293205) (xy 114.345974 -220.319854) (xy 114.573304 -220.319854)
			(xy 114.573802 -220.293205) (xy 114.581745 -220.240501) (xy 114.597455 -220.189571) (xy 114.620581 -220.14155)
			(xy 114.650605 -220.097513) (xy 114.686857 -220.058442) (xy 114.728528 -220.025211) (xy 114.774686 -219.998562)
			(xy 114.8243 -219.97909) (xy 114.876262 -219.96723) (xy 114.929412 -219.963247) (xy 114.982562 -219.96723)
			(xy 115.034524 -219.97909) (xy 115.084138 -219.998562) (xy 115.130296 -220.025211) (xy 115.171967 -220.058442)
			(xy 115.208219 -220.097513) (xy 115.238243 -220.14155) (xy 115.261369 -220.189571) (xy 115.277079 -220.240501)
			(xy 115.285022 -220.293205) (xy 115.28552 -220.319854) (xy 115.285123 -220.343057) (xy 115.28467 -220.346503)
			(xy 115.513856 -220.346503) (xy 115.513856 -220.293205) (xy 115.521799 -220.240501) (xy 115.537509 -220.189571)
			(xy 115.560635 -220.14155) (xy 115.590659 -220.097513) (xy 115.626911 -220.058442) (xy 115.668582 -220.025211)
			(xy 115.71474 -219.998562) (xy 115.764354 -219.97909) (xy 115.816316 -219.96723) (xy 115.869466 -219.963247)
			(xy 115.922616 -219.96723) (xy 115.974578 -219.97909) (xy 116.024192 -219.998562) (xy 116.07035 -220.025211)
			(xy 116.112021 -220.058442) (xy 116.148273 -220.097513) (xy 116.178297 -220.14155) (xy 116.201423 -220.189571)
			(xy 116.217133 -220.240501) (xy 116.225076 -220.293205) (xy 116.225574 -220.319854) (xy 116.452904 -220.319854)
			(xy 116.453402 -220.293205) (xy 116.461345 -220.240501) (xy 116.477055 -220.189571) (xy 116.500181 -220.14155)
			(xy 116.530205 -220.097513) (xy 116.566457 -220.058442) (xy 116.608128 -220.025211) (xy 116.654286 -219.998562)
			(xy 116.7039 -219.97909) (xy 116.755862 -219.96723) (xy 116.809012 -219.963247) (xy 116.862162 -219.96723)
			(xy 116.914124 -219.97909) (xy 116.963738 -219.998562) (xy 117.009896 -220.025211) (xy 117.051567 -220.058442)
			(xy 117.087819 -220.097513) (xy 117.117843 -220.14155) (xy 117.140969 -220.189571) (xy 117.156679 -220.240501)
			(xy 117.164622 -220.293205) (xy 117.16512 -220.319854) (xy 117.164723 -220.343057) (xy 117.16427 -220.346503)
			(xy 117.393456 -220.346503) (xy 117.393456 -220.293205) (xy 117.401399 -220.240501) (xy 117.417109 -220.189571)
			(xy 117.440235 -220.14155) (xy 117.470259 -220.097513) (xy 117.506511 -220.058442) (xy 117.548182 -220.025211)
			(xy 117.59434 -219.998562) (xy 117.643954 -219.97909) (xy 117.695916 -219.96723) (xy 117.749066 -219.963247)
			(xy 117.802216 -219.96723) (xy 117.854178 -219.97909) (xy 117.903792 -219.998562) (xy 117.94995 -220.025211)
			(xy 117.991621 -220.058442) (xy 118.027873 -220.097513) (xy 118.057897 -220.14155) (xy 118.081023 -220.189571)
			(xy 118.096733 -220.240501) (xy 118.104676 -220.293205) (xy 118.105174 -220.319854) (xy 118.104676 -220.346503)
			(xy 118.096733 -220.399207) (xy 118.081023 -220.450137) (xy 118.057897 -220.498158) (xy 118.027873 -220.542195)
			(xy 117.991621 -220.581266) (xy 117.94995 -220.614497) (xy 117.903792 -220.641146) (xy 117.854178 -220.660618)
			(xy 117.802216 -220.672478) (xy 117.749066 -220.676462) (xy 117.695916 -220.672478) (xy 117.643954 -220.660618)
			(xy 117.59434 -220.641146) (xy 117.548182 -220.614497) (xy 117.506511 -220.581266) (xy 117.470259 -220.542195)
			(xy 117.440235 -220.498158) (xy 117.417109 -220.450137) (xy 117.401399 -220.399207) (xy 117.393456 -220.346503)
			(xy 117.16427 -220.346503) (xy 117.15868 -220.389067) (xy 117.146703 -220.4339) (xy 117.138196 -220.45549)
			(xy 117.128798 -220.478604) (xy 117.301518 -220.777562) (xy 117.326156 -220.780864) (xy 117.351497 -220.784693)
			(xy 117.400801 -220.798686) (xy 117.447591 -220.819599) (xy 117.490901 -220.847) (xy 117.529838 -220.880325)
			(xy 117.563598 -220.918885) (xy 117.591485 -220.961884) (xy 117.612923 -221.008436) (xy 117.627469 -221.057579)
			(xy 117.634824 -221.108299) (xy 117.635274 -221.133924) (xy 117.634776 -221.160573) (xy 117.626833 -221.213277)
			(xy 117.611123 -221.264207) (xy 117.587997 -221.312228) (xy 117.557973 -221.356265) (xy 117.521721 -221.395336)
			(xy 117.48005 -221.428567) (xy 117.433892 -221.455216) (xy 117.384278 -221.474688) (xy 117.332316 -221.486548)
			(xy 117.279166 -221.490532) (xy 117.226016 -221.486548) (xy 117.174054 -221.474688) (xy 117.12444 -221.455216)
			(xy 117.078282 -221.428567) (xy 117.036611 -221.395336) (xy 117.000359 -221.356265) (xy 116.970335 -221.312228)
			(xy 116.947209 -221.264207) (xy 116.931499 -221.213277) (xy 116.923556 -221.160573) (xy 116.923058 -221.133924)
			(xy 116.923437 -221.110679) (xy 116.92948 -221.064584) (xy 116.941466 -221.019666) (xy 116.949982 -220.998034)
			(xy 116.959634 -220.97492) (xy 116.787168 -220.676216) (xy 116.762276 -220.672914) (xy 116.736921 -220.669093)
			(xy 116.687584 -220.655134) (xy 116.640757 -220.634246) (xy 116.59741 -220.606859) (xy 116.558437 -220.573539)
			(xy 116.524645 -220.534976) (xy 116.496731 -220.491966) (xy 116.475273 -220.445398) (xy 116.460714 -220.396234)
			(xy 116.453354 -220.345491) (xy 116.452904 -220.319854) (xy 116.225574 -220.319854) (xy 116.225076 -220.346503)
			(xy 116.217133 -220.399207) (xy 116.201423 -220.450137) (xy 116.178297 -220.498158) (xy 116.148273 -220.542195)
			(xy 116.112021 -220.581266) (xy 116.07035 -220.614497) (xy 116.024192 -220.641146) (xy 115.974578 -220.660618)
			(xy 115.922616 -220.672478) (xy 115.869466 -220.676462) (xy 115.816316 -220.672478) (xy 115.764354 -220.660618)
			(xy 115.71474 -220.641146) (xy 115.668582 -220.614497) (xy 115.626911 -220.581266) (xy 115.590659 -220.542195)
			(xy 115.560635 -220.498158) (xy 115.537509 -220.450137) (xy 115.521799 -220.399207) (xy 115.513856 -220.346503)
			(xy 115.28467 -220.346503) (xy 115.27908 -220.389067) (xy 115.267103 -220.4339) (xy 115.258596 -220.45549)
			(xy 115.249198 -220.478604) (xy 115.421918 -220.777562) (xy 115.446556 -220.780864) (xy 115.471897 -220.784693)
			(xy 115.521201 -220.798686) (xy 115.567991 -220.819599) (xy 115.611301 -220.847) (xy 115.650238 -220.880325)
			(xy 115.683998 -220.918885) (xy 115.711885 -220.961884) (xy 115.733323 -221.008436) (xy 115.747869 -221.057579)
			(xy 115.755224 -221.108299) (xy 115.755674 -221.133924) (xy 115.755176 -221.160573) (xy 115.747233 -221.213277)
			(xy 115.731523 -221.264207) (xy 115.708397 -221.312228) (xy 115.678373 -221.356265) (xy 115.642121 -221.395336)
			(xy 115.60045 -221.428567) (xy 115.554292 -221.455216) (xy 115.504678 -221.474688) (xy 115.452716 -221.486548)
			(xy 115.399566 -221.490532) (xy 115.346416 -221.486548) (xy 115.294454 -221.474688) (xy 115.24484 -221.455216)
			(xy 115.198682 -221.428567) (xy 115.157011 -221.395336) (xy 115.120759 -221.356265) (xy 115.090735 -221.312228)
			(xy 115.067609 -221.264207) (xy 115.051899 -221.213277) (xy 115.043956 -221.160573) (xy 115.043458 -221.133924)
			(xy 115.043837 -221.110679) (xy 115.04988 -221.064584) (xy 115.061866 -221.019666) (xy 115.070382 -220.998034)
			(xy 115.080034 -220.97492) (xy 114.907568 -220.676216) (xy 114.882676 -220.672914) (xy 114.857321 -220.669093)
			(xy 114.807984 -220.655134) (xy 114.761157 -220.634246) (xy 114.71781 -220.606859) (xy 114.678837 -220.573539)
			(xy 114.645045 -220.534976) (xy 114.617131 -220.491966) (xy 114.595673 -220.445398) (xy 114.581114 -220.396234)
			(xy 114.573754 -220.345491) (xy 114.573304 -220.319854) (xy 114.345974 -220.319854) (xy 114.345476 -220.346503)
			(xy 114.337533 -220.399207) (xy 114.321823 -220.450137) (xy 114.298697 -220.498158) (xy 114.268673 -220.542195)
			(xy 114.232421 -220.581266) (xy 114.19075 -220.614497) (xy 114.144592 -220.641146) (xy 114.094978 -220.660618)
			(xy 114.043016 -220.672478) (xy 113.989866 -220.676462) (xy 113.936716 -220.672478) (xy 113.884754 -220.660618)
			(xy 113.83514 -220.641146) (xy 113.788982 -220.614497) (xy 113.747311 -220.581266) (xy 113.711059 -220.542195)
			(xy 113.681035 -220.498158) (xy 113.657909 -220.450137) (xy 113.642199 -220.399207) (xy 113.634256 -220.346503)
			(xy 113.40507 -220.346503) (xy 113.39948 -220.389067) (xy 113.387503 -220.4339) (xy 113.378996 -220.45549)
			(xy 113.369598 -220.478604) (xy 113.542318 -220.777562) (xy 113.566956 -220.780864) (xy 113.592297 -220.784693)
			(xy 113.641601 -220.798686) (xy 113.688391 -220.819599) (xy 113.731701 -220.847) (xy 113.770638 -220.880325)
			(xy 113.804398 -220.918885) (xy 113.832285 -220.961884) (xy 113.853723 -221.008436) (xy 113.868269 -221.057579)
			(xy 113.875624 -221.108299) (xy 113.876074 -221.133924) (xy 113.875576 -221.160573) (xy 113.867633 -221.213277)
			(xy 113.851923 -221.264207) (xy 113.828797 -221.312228) (xy 113.798773 -221.356265) (xy 113.762521 -221.395336)
			(xy 113.72085 -221.428567) (xy 113.674692 -221.455216) (xy 113.625078 -221.474688) (xy 113.573116 -221.486548)
			(xy 113.519966 -221.490532) (xy 113.466816 -221.486548) (xy 113.414854 -221.474688) (xy 113.36524 -221.455216)
			(xy 113.319082 -221.428567) (xy 113.277411 -221.395336) (xy 113.241159 -221.356265) (xy 113.211135 -221.312228)
			(xy 113.188009 -221.264207) (xy 113.172299 -221.213277) (xy 113.164356 -221.160573) (xy 113.163858 -221.133924)
			(xy 113.164237 -221.110679) (xy 113.17028 -221.064584) (xy 113.182266 -221.019666) (xy 113.190782 -220.998034)
			(xy 113.200434 -220.97492) (xy 113.027968 -220.676216) (xy 113.003076 -220.672914) (xy 112.977721 -220.669093)
			(xy 112.928384 -220.655134) (xy 112.881557 -220.634246) (xy 112.83821 -220.606859) (xy 112.799237 -220.573539)
			(xy 112.765445 -220.534976) (xy 112.737531 -220.491966) (xy 112.716073 -220.445398) (xy 112.701514 -220.396234)
			(xy 112.694154 -220.345491) (xy 112.693704 -220.319854) (xy 112.466975 -220.319854) (xy 112.466978 -220.3199)
			(xy 112.462994 -220.373063) (xy 112.45113 -220.425039) (xy 112.431652 -220.474666) (xy 112.404994 -220.520835)
			(xy 112.371752 -220.562515) (xy 112.33267 -220.598774) (xy 112.288619 -220.628804) (xy 112.240585 -220.651932)
			(xy 112.18964 -220.667642) (xy 112.136922 -220.675583) (xy 112.110266 -220.675962) (xy 112.086876 -220.675578)
			(xy 112.040498 -220.669468) (xy 112.01781 -220.66377) (xy 112.004837 -220.660689) (xy 111.97818 -220.66066)
			(xy 111.952424 -220.667533) (xy 111.929325 -220.680839) (xy 111.910458 -220.69967) (xy 111.897108 -220.722743)
			(xy 111.890186 -220.748486) (xy 111.889794 -220.761814) (xy 111.889794 -220.87967) (xy 111.907846 -220.898036)
			(xy 111.939008 -220.939032) (xy 111.963946 -220.984087) (xy 111.982138 -221.032263) (xy 111.993206 -221.082555)
			(xy 111.996919 -221.133917) (xy 111.993201 -221.185278) (xy 111.982128 -221.23557) (xy 111.963931 -221.283743)
			(xy 111.93899 -221.328796) (xy 111.907824 -221.36979) (xy 111.889794 -221.388178) (xy 111.889794 -221.50578)
			(xy 111.890189 -221.51911) (xy 111.897093 -221.54486) (xy 111.910435 -221.56794) (xy 111.929303 -221.586775)
			(xy 111.952407 -221.600076) (xy 111.978169 -221.606934) (xy 112.004828 -221.606882) (xy 112.01781 -221.603824)
			(xy 112.028975 -221.600902) (xy 112.051599 -221.596328) (xy 112.063022 -221.59468) (xy 112.08766 -221.591378)
			(xy 112.260126 -221.29242) (xy 112.250728 -221.269306) (xy 112.242286 -221.247745) (xy 112.230408 -221.202991)
			(xy 112.224418 -221.157076) (xy 112.224058 -221.133924) (xy 112.224556 -221.107275) (xy 112.232499 -221.054571)
			(xy 112.248209 -221.003641) (xy 112.271335 -220.95562) (xy 112.301359 -220.911583) (xy 112.337611 -220.872512)
			(xy 112.379282 -220.839281) (xy 112.42544 -220.812632) (xy 112.475054 -220.79316) (xy 112.527016 -220.7813)
			(xy 112.580166 -220.777317) (xy 112.633316 -220.7813) (xy 112.685278 -220.79316) (xy 112.734892 -220.812632)
			(xy 112.78105 -220.839281) (xy 112.822721 -220.872512) (xy 112.858973 -220.911583) (xy 112.888997 -220.95562)
			(xy 112.912123 -221.003641) (xy 112.927833 -221.054571) (xy 112.935776 -221.107275) (xy 112.936274 -221.133924)
			(xy 112.935825 -221.159572) (xy 112.92846 -221.210337) (xy 112.913888 -221.25952) (xy 112.892408 -221.306103)
			(xy 112.864467 -221.349121) (xy 112.830642 -221.387685) (xy 112.791633 -221.420996) (xy 112.748247 -221.448365)
			(xy 112.701384 -221.469224) (xy 112.652012 -221.483143) (xy 112.626648 -221.486984) (xy 112.601756 -221.490286)
			(xy 112.429544 -221.788736) (xy 112.439196 -221.81185) (xy 112.447711 -221.833482) (xy 112.459696 -221.8784)
			(xy 112.465737 -221.924495) (xy 112.46612 -221.94774) (xy 112.465594 -221.974389) (xy 112.694202 -221.974389)
			(xy 112.694202 -221.921091) (xy 112.702145 -221.868387) (xy 112.717855 -221.817457) (xy 112.740981 -221.769436)
			(xy 112.771005 -221.725399) (xy 112.807257 -221.686328) (xy 112.848928 -221.653097) (xy 112.895086 -221.626448)
			(xy 112.9447 -221.606976) (xy 112.996662 -221.595116) (xy 113.049812 -221.591133) (xy 113.102962 -221.595116)
			(xy 113.154924 -221.606976) (xy 113.204538 -221.626448) (xy 113.250696 -221.653097) (xy 113.292367 -221.686328)
			(xy 113.328619 -221.725399) (xy 113.358643 -221.769436) (xy 113.381769 -221.817457) (xy 113.397479 -221.868387)
			(xy 113.405422 -221.921091) (xy 113.40592 -221.94774) (xy 113.633758 -221.94774) (xy 113.634211 -221.922112)
			(xy 113.641541 -221.871382) (xy 113.656071 -221.822228) (xy 113.677499 -221.775665) (xy 113.705383 -221.732657)
			(xy 113.739146 -221.694092) (xy 113.778091 -221.660767) (xy 113.821413 -221.633372) (xy 113.868215 -221.612472)
			(xy 113.91753 -221.5985) (xy 113.942876 -221.59468) (xy 113.967514 -221.591378) (xy 114.13998 -221.292674)
			(xy 114.130582 -221.26956) (xy 114.122083 -221.247967) (xy 114.11011 -221.203133) (xy 114.104051 -221.157126)
			(xy 114.103658 -221.133924) (xy 114.104156 -221.107275) (xy 114.112099 -221.054571) (xy 114.127809 -221.003641)
			(xy 114.150935 -220.95562) (xy 114.180959 -220.911583) (xy 114.217211 -220.872512) (xy 114.258882 -220.839281)
			(xy 114.30504 -220.812632) (xy 114.354654 -220.79316) (xy 114.406616 -220.7813) (xy 114.459766 -220.777317)
			(xy 114.512916 -220.7813) (xy 114.564878 -220.79316) (xy 114.614492 -220.812632) (xy 114.66065 -220.839281)
			(xy 114.702321 -220.872512) (xy 114.738573 -220.911583) (xy 114.768597 -220.95562) (xy 114.791723 -221.003641)
			(xy 114.807433 -221.054571) (xy 114.815376 -221.107275) (xy 114.815874 -221.133924) (xy 114.815418 -221.159563)
			(xy 114.808073 -221.210312) (xy 114.793524 -221.259483) (xy 114.772072 -221.306058) (xy 114.744161 -221.349074)
			(xy 114.710368 -221.387641) (xy 114.671391 -221.420962) (xy 114.628038 -221.448347) (xy 114.581205 -221.469229)
			(xy 114.531861 -221.483178) (xy 114.506502 -221.486984) (xy 114.48161 -221.490286) (xy 114.309398 -221.788736)
			(xy 114.31905 -221.81185) (xy 114.327577 -221.833478) (xy 114.339561 -221.878398) (xy 114.345601 -221.924495)
			(xy 114.345974 -221.94774) (xy 114.345476 -221.974389) (xy 114.574056 -221.974389) (xy 114.574056 -221.921091)
			(xy 114.581999 -221.868387) (xy 114.597709 -221.817457) (xy 114.620835 -221.769436) (xy 114.650859 -221.725399)
			(xy 114.687111 -221.686328) (xy 114.728782 -221.653097) (xy 114.77494 -221.626448) (xy 114.824554 -221.606976)
			(xy 114.876516 -221.595116) (xy 114.929666 -221.591133) (xy 114.982816 -221.595116) (xy 115.034778 -221.606976)
			(xy 115.084392 -221.626448) (xy 115.13055 -221.653097) (xy 115.172221 -221.686328) (xy 115.208473 -221.725399)
			(xy 115.238497 -221.769436) (xy 115.261623 -221.817457) (xy 115.277333 -221.868387) (xy 115.285276 -221.921091)
			(xy 115.285774 -221.94774) (xy 115.513104 -221.94774) (xy 115.513517 -221.92211) (xy 115.520848 -221.871376)
			(xy 115.53538 -221.822219) (xy 115.556812 -221.775654) (xy 115.5847 -221.732644) (xy 115.618469 -221.694079)
			(xy 115.657419 -221.660755) (xy 115.700746 -221.633361) (xy 115.747553 -221.612465) (xy 115.796874 -221.598497)
			(xy 115.822222 -221.59468) (xy 115.84686 -221.591378) (xy 116.019326 -221.29242) (xy 116.009928 -221.269306)
			(xy 116.00146 -221.247754) (xy 115.989575 -221.202998) (xy 115.983607 -221.157078) (xy 115.983258 -221.133924)
			(xy 115.983756 -221.107275) (xy 115.991699 -221.054571) (xy 116.007409 -221.003641) (xy 116.030535 -220.95562)
			(xy 116.060559 -220.911583) (xy 116.096811 -220.872512) (xy 116.138482 -220.839281) (xy 116.18464 -220.812632)
			(xy 116.234254 -220.79316) (xy 116.286216 -220.7813) (xy 116.339366 -220.777317) (xy 116.392516 -220.7813)
			(xy 116.444478 -220.79316) (xy 116.494092 -220.812632) (xy 116.54025 -220.839281) (xy 116.581921 -220.872512)
			(xy 116.618173 -220.911583) (xy 116.648197 -220.95562) (xy 116.671323 -221.003641) (xy 116.687033 -221.054571)
			(xy 116.694976 -221.107275) (xy 116.695474 -221.133924) (xy 116.695077 -221.159576) (xy 116.687712 -221.210348)
			(xy 116.673137 -221.259539) (xy 116.651654 -221.306128) (xy 116.623709 -221.349153) (xy 116.589878 -221.387723)
			(xy 116.550864 -221.421038) (xy 116.507472 -221.448411) (xy 116.460602 -221.469274) (xy 116.411223 -221.483195)
			(xy 116.385848 -221.486984) (xy 116.360956 -221.490286) (xy 116.188744 -221.788736) (xy 116.198396 -221.81185)
			(xy 116.206925 -221.833477) (xy 116.218907 -221.878397) (xy 116.224947 -221.924494) (xy 116.22532 -221.94774)
			(xy 116.224822 -221.974389) (xy 116.453402 -221.974389) (xy 116.453402 -221.921091) (xy 116.461345 -221.868387)
			(xy 116.477055 -221.817457) (xy 116.500181 -221.769436) (xy 116.530205 -221.725399) (xy 116.566457 -221.686328)
			(xy 116.608128 -221.653097) (xy 116.654286 -221.626448) (xy 116.7039 -221.606976) (xy 116.755862 -221.595116)
			(xy 116.809012 -221.591133) (xy 116.862162 -221.595116) (xy 116.914124 -221.606976) (xy 116.963738 -221.626448)
			(xy 117.009896 -221.653097) (xy 117.051567 -221.686328) (xy 117.087819 -221.725399) (xy 117.117843 -221.769436)
			(xy 117.140969 -221.817457) (xy 117.156679 -221.868387) (xy 117.164622 -221.921091) (xy 117.16512 -221.94774)
			(xy 117.392704 -221.94774) (xy 117.393117 -221.92211) (xy 117.400448 -221.871376) (xy 117.41498 -221.822219)
			(xy 117.436412 -221.775654) (xy 117.4643 -221.732644) (xy 117.498069 -221.694079) (xy 117.537019 -221.660755)
			(xy 117.580346 -221.633361) (xy 117.627153 -221.612465) (xy 117.676474 -221.598497) (xy 117.701822 -221.59468)
			(xy 117.72646 -221.591378) (xy 117.898926 -221.29242) (xy 117.889528 -221.269306) (xy 117.88106 -221.247754)
			(xy 117.869175 -221.202998) (xy 117.863207 -221.157078) (xy 117.862858 -221.133924) (xy 117.863356 -221.107275)
			(xy 117.871299 -221.054571) (xy 117.887009 -221.003641) (xy 117.910135 -220.95562) (xy 117.940159 -220.911583)
			(xy 117.976411 -220.872512) (xy 118.018082 -220.839281) (xy 118.06424 -220.812632) (xy 118.113854 -220.79316)
			(xy 118.165816 -220.7813) (xy 118.218966 -220.777317) (xy 118.272116 -220.7813) (xy 118.324078 -220.79316)
			(xy 118.373692 -220.812632) (xy 118.41985 -220.839281) (xy 118.461521 -220.872512) (xy 118.497773 -220.911583)
			(xy 118.527797 -220.95562) (xy 118.550923 -221.003641) (xy 118.566633 -221.054571) (xy 118.574576 -221.107275)
			(xy 118.575074 -221.133924) (xy 118.574677 -221.159576) (xy 118.567312 -221.210348) (xy 118.552737 -221.259539)
			(xy 118.531254 -221.306128) (xy 118.503309 -221.349153) (xy 118.469478 -221.387723) (xy 118.430464 -221.421038)
			(xy 118.387072 -221.448411) (xy 118.340202 -221.469274) (xy 118.290823 -221.483195) (xy 118.265448 -221.486984)
			(xy 118.240556 -221.490286) (xy 118.068344 -221.788736) (xy 118.077996 -221.81185) (xy 118.086525 -221.833477)
			(xy 118.098507 -221.878397) (xy 118.104547 -221.924494) (xy 118.10492 -221.94774) (xy 118.104422 -221.974389)
			(xy 118.333002 -221.974389) (xy 118.333002 -221.921091) (xy 118.340945 -221.868387) (xy 118.356655 -221.817457)
			(xy 118.379781 -221.769436) (xy 118.409805 -221.725399) (xy 118.446057 -221.686328) (xy 118.487728 -221.653097)
			(xy 118.533886 -221.626448) (xy 118.5835 -221.606976) (xy 118.635462 -221.595116) (xy 118.688612 -221.591133)
			(xy 118.741762 -221.595116) (xy 118.793724 -221.606976) (xy 118.843338 -221.626448) (xy 118.889496 -221.653097)
			(xy 118.931167 -221.686328) (xy 118.967419 -221.725399) (xy 118.997443 -221.769436) (xy 119.020569 -221.817457)
			(xy 119.036279 -221.868387) (xy 119.044222 -221.921091) (xy 119.04472 -221.94774) (xy 119.044222 -221.974389)
			(xy 119.036279 -222.027093) (xy 119.020569 -222.078023) (xy 118.997443 -222.126044) (xy 118.967419 -222.170081)
			(xy 118.931167 -222.209152) (xy 118.889496 -222.242383) (xy 118.843338 -222.269032) (xy 118.793724 -222.288504)
			(xy 118.741762 -222.300364) (xy 118.688612 -222.304348) (xy 118.635462 -222.300364) (xy 118.5835 -222.288504)
			(xy 118.533886 -222.269032) (xy 118.487728 -222.242383) (xy 118.446057 -222.209152) (xy 118.409805 -222.170081)
			(xy 118.379781 -222.126044) (xy 118.356655 -222.078023) (xy 118.340945 -222.027093) (xy 118.333002 -221.974389)
			(xy 118.104422 -221.974389) (xy 118.096479 -222.027093) (xy 118.080769 -222.078023) (xy 118.057643 -222.126044)
			(xy 118.027619 -222.170081) (xy 117.991367 -222.209152) (xy 117.949696 -222.242383) (xy 117.903538 -222.269032)
			(xy 117.853924 -222.288504) (xy 117.801962 -222.300364) (xy 117.748812 -222.304348) (xy 117.695662 -222.300364)
			(xy 117.6437 -222.288504) (xy 117.594086 -222.269032) (xy 117.547928 -222.242383) (xy 117.506257 -222.209152)
			(xy 117.470005 -222.170081) (xy 117.439981 -222.126044) (xy 117.416855 -222.078023) (xy 117.401145 -222.027093)
			(xy 117.393202 -221.974389) (xy 117.392704 -221.94774) (xy 117.16512 -221.94774) (xy 117.164622 -221.974389)
			(xy 117.156679 -222.027093) (xy 117.140969 -222.078023) (xy 117.117843 -222.126044) (xy 117.087819 -222.170081)
			(xy 117.051567 -222.209152) (xy 117.009896 -222.242383) (xy 116.963738 -222.269032) (xy 116.914124 -222.288504)
			(xy 116.862162 -222.300364) (xy 116.809012 -222.304348) (xy 116.755862 -222.300364) (xy 116.7039 -222.288504)
			(xy 116.654286 -222.269032) (xy 116.608128 -222.242383) (xy 116.566457 -222.209152) (xy 116.530205 -222.170081)
			(xy 116.500181 -222.126044) (xy 116.477055 -222.078023) (xy 116.461345 -222.027093) (xy 116.453402 -221.974389)
			(xy 116.224822 -221.974389) (xy 116.216879 -222.027093) (xy 116.201169 -222.078023) (xy 116.178043 -222.126044)
			(xy 116.148019 -222.170081) (xy 116.111767 -222.209152) (xy 116.070096 -222.242383) (xy 116.023938 -222.269032)
			(xy 115.974324 -222.288504) (xy 115.922362 -222.300364) (xy 115.869212 -222.304348) (xy 115.816062 -222.300364)
			(xy 115.7641 -222.288504) (xy 115.714486 -222.269032) (xy 115.668328 -222.242383) (xy 115.626657 -222.209152)
			(xy 115.590405 -222.170081) (xy 115.560381 -222.126044) (xy 115.537255 -222.078023) (xy 115.521545 -222.027093)
			(xy 115.513602 -221.974389) (xy 115.513104 -221.94774) (xy 115.285774 -221.94774) (xy 115.285276 -221.974389)
			(xy 115.277333 -222.027093) (xy 115.261623 -222.078023) (xy 115.238497 -222.126044) (xy 115.208473 -222.170081)
			(xy 115.172221 -222.209152) (xy 115.13055 -222.242383) (xy 115.084392 -222.269032) (xy 115.034778 -222.288504)
			(xy 114.982816 -222.300364) (xy 114.929666 -222.304348) (xy 114.876516 -222.300364) (xy 114.824554 -222.288504)
			(xy 114.77494 -222.269032) (xy 114.728782 -222.242383) (xy 114.687111 -222.209152) (xy 114.650859 -222.170081)
			(xy 114.620835 -222.126044) (xy 114.597709 -222.078023) (xy 114.581999 -222.027093) (xy 114.574056 -221.974389)
			(xy 114.345476 -221.974389) (xy 114.337533 -222.027093) (xy 114.321823 -222.078023) (xy 114.298697 -222.126044)
			(xy 114.268673 -222.170081) (xy 114.232421 -222.209152) (xy 114.19075 -222.242383) (xy 114.144592 -222.269032)
			(xy 114.094978 -222.288504) (xy 114.043016 -222.300364) (xy 113.989866 -222.304348) (xy 113.936716 -222.300364)
			(xy 113.884754 -222.288504) (xy 113.83514 -222.269032) (xy 113.788982 -222.242383) (xy 113.747311 -222.209152)
			(xy 113.711059 -222.170081) (xy 113.681035 -222.126044) (xy 113.657909 -222.078023) (xy 113.642199 -222.027093)
			(xy 113.634256 -221.974389) (xy 113.633758 -221.94774) (xy 113.40592 -221.94774) (xy 113.405422 -221.974389)
			(xy 113.397479 -222.027093) (xy 113.381769 -222.078023) (xy 113.358643 -222.126044) (xy 113.328619 -222.170081)
			(xy 113.292367 -222.209152) (xy 113.250696 -222.242383) (xy 113.204538 -222.269032) (xy 113.154924 -222.288504)
			(xy 113.102962 -222.300364) (xy 113.049812 -222.304348) (xy 112.996662 -222.300364) (xy 112.9447 -222.288504)
			(xy 112.895086 -222.269032) (xy 112.848928 -222.242383) (xy 112.807257 -222.209152) (xy 112.771005 -222.170081)
			(xy 112.740981 -222.126044) (xy 112.717855 -222.078023) (xy 112.702145 -222.027093) (xy 112.694202 -221.974389)
			(xy 112.465594 -221.974389) (xy 112.465568 -221.975721) (xy 112.456808 -222.030994) (xy 112.43951 -222.084217)
			(xy 112.4141 -222.134078) (xy 112.381204 -222.179352) (xy 112.34163 -222.218922) (xy 112.296355 -222.251815)
			(xy 112.246491 -222.277221) (xy 112.193267 -222.294515) (xy 112.137993 -222.30327) (xy 112.110012 -222.303848)
			(xy 112.086686 -222.30345) (xy 112.040436 -222.297339) (xy 112.01781 -222.291656) (xy 112.004836 -222.288575)
			(xy 111.978178 -222.288546) (xy 111.952421 -222.295419) (xy 111.929321 -222.308724) (xy 111.910451 -222.327555)
			(xy 111.897099 -222.350628) (xy 111.890174 -222.376371) (xy 111.889794 -222.3897) (xy 111.889794 -222.507302)
			(xy 111.907851 -222.525668) (xy 111.939023 -222.566666) (xy 111.96397 -222.611724) (xy 111.98217 -222.659903)
			(xy 111.993247 -222.710201) (xy 111.996968 -222.761569) (xy 111.995043 -222.788205) (xy 112.224556 -222.788205)
			(xy 112.224556 -222.734907) (xy 112.232499 -222.682203) (xy 112.248209 -222.631273) (xy 112.271335 -222.583252)
			(xy 112.301359 -222.539215) (xy 112.337611 -222.500144) (xy 112.379282 -222.466913) (xy 112.42544 -222.440264)
			(xy 112.475054 -222.420792) (xy 112.527016 -222.408932) (xy 112.580166 -222.404949) (xy 112.633316 -222.408932)
			(xy 112.685278 -222.420792) (xy 112.734892 -222.440264) (xy 112.78105 -222.466913) (xy 112.822721 -222.500144)
			(xy 112.858973 -222.539215) (xy 112.888997 -222.583252) (xy 112.912123 -222.631273) (xy 112.927833 -222.682203)
			(xy 112.935776 -222.734907) (xy 112.936274 -222.761556) (xy 112.935776 -222.788205) (xy 113.164356 -222.788205)
			(xy 113.164356 -222.734907) (xy 113.172299 -222.682203) (xy 113.188009 -222.631273) (xy 113.211135 -222.583252)
			(xy 113.241159 -222.539215) (xy 113.277411 -222.500144) (xy 113.319082 -222.466913) (xy 113.36524 -222.440264)
			(xy 113.414854 -222.420792) (xy 113.466816 -222.408932) (xy 113.519966 -222.404949) (xy 113.573116 -222.408932)
			(xy 113.625078 -222.420792) (xy 113.674692 -222.440264) (xy 113.72085 -222.466913) (xy 113.762521 -222.500144)
			(xy 113.798773 -222.539215) (xy 113.828797 -222.583252) (xy 113.851923 -222.631273) (xy 113.867633 -222.682203)
			(xy 113.875576 -222.734907) (xy 113.876074 -222.761556) (xy 113.875576 -222.788205) (xy 114.104156 -222.788205)
			(xy 114.104156 -222.734907) (xy 114.112099 -222.682203) (xy 114.127809 -222.631273) (xy 114.150935 -222.583252)
			(xy 114.180959 -222.539215) (xy 114.217211 -222.500144) (xy 114.258882 -222.466913) (xy 114.30504 -222.440264)
			(xy 114.354654 -222.420792) (xy 114.406616 -222.408932) (xy 114.459766 -222.404949) (xy 114.512916 -222.408932)
			(xy 114.564878 -222.420792) (xy 114.614492 -222.440264) (xy 114.66065 -222.466913) (xy 114.702321 -222.500144)
			(xy 114.738573 -222.539215) (xy 114.768597 -222.583252) (xy 114.791723 -222.631273) (xy 114.807433 -222.682203)
			(xy 114.815376 -222.734907) (xy 114.815874 -222.761556) (xy 114.815376 -222.788205) (xy 115.043956 -222.788205)
			(xy 115.043956 -222.734907) (xy 115.051899 -222.682203) (xy 115.067609 -222.631273) (xy 115.090735 -222.583252)
			(xy 115.120759 -222.539215) (xy 115.157011 -222.500144) (xy 115.198682 -222.466913) (xy 115.24484 -222.440264)
			(xy 115.294454 -222.420792) (xy 115.346416 -222.408932) (xy 115.399566 -222.404949) (xy 115.452716 -222.408932)
			(xy 115.504678 -222.420792) (xy 115.554292 -222.440264) (xy 115.60045 -222.466913) (xy 115.642121 -222.500144)
			(xy 115.678373 -222.539215) (xy 115.708397 -222.583252) (xy 115.731523 -222.631273) (xy 115.747233 -222.682203)
			(xy 115.755176 -222.734907) (xy 115.755674 -222.761556) (xy 115.755176 -222.788205) (xy 115.983756 -222.788205)
			(xy 115.983756 -222.734907) (xy 115.991699 -222.682203) (xy 116.007409 -222.631273) (xy 116.030535 -222.583252)
			(xy 116.060559 -222.539215) (xy 116.096811 -222.500144) (xy 116.138482 -222.466913) (xy 116.18464 -222.440264)
			(xy 116.234254 -222.420792) (xy 116.286216 -222.408932) (xy 116.339366 -222.404949) (xy 116.392516 -222.408932)
			(xy 116.444478 -222.420792) (xy 116.494092 -222.440264) (xy 116.54025 -222.466913) (xy 116.581921 -222.500144)
			(xy 116.618173 -222.539215) (xy 116.648197 -222.583252) (xy 116.671323 -222.631273) (xy 116.687033 -222.682203)
			(xy 116.694976 -222.734907) (xy 116.695474 -222.761556) (xy 116.694976 -222.788205) (xy 116.923556 -222.788205)
			(xy 116.923556 -222.734907) (xy 116.931499 -222.682203) (xy 116.947209 -222.631273) (xy 116.970335 -222.583252)
			(xy 117.000359 -222.539215) (xy 117.036611 -222.500144) (xy 117.078282 -222.466913) (xy 117.12444 -222.440264)
			(xy 117.174054 -222.420792) (xy 117.226016 -222.408932) (xy 117.279166 -222.404949) (xy 117.332316 -222.408932)
			(xy 117.384278 -222.420792) (xy 117.433892 -222.440264) (xy 117.48005 -222.466913) (xy 117.521721 -222.500144)
			(xy 117.557973 -222.539215) (xy 117.587997 -222.583252) (xy 117.611123 -222.631273) (xy 117.626833 -222.682203)
			(xy 117.634776 -222.734907) (xy 117.635274 -222.761556) (xy 117.634776 -222.788205) (xy 117.863356 -222.788205)
			(xy 117.863356 -222.734907) (xy 117.871299 -222.682203) (xy 117.887009 -222.631273) (xy 117.910135 -222.583252)
			(xy 117.940159 -222.539215) (xy 117.976411 -222.500144) (xy 118.018082 -222.466913) (xy 118.06424 -222.440264)
			(xy 118.113854 -222.420792) (xy 118.165816 -222.408932) (xy 118.218966 -222.404949) (xy 118.272116 -222.408932)
			(xy 118.324078 -222.420792) (xy 118.373692 -222.440264) (xy 118.41985 -222.466913) (xy 118.461521 -222.500144)
			(xy 118.497773 -222.539215) (xy 118.527797 -222.583252) (xy 118.550923 -222.631273) (xy 118.566633 -222.682203)
			(xy 118.574576 -222.734907) (xy 118.575074 -222.761556) (xy 118.574576 -222.788205) (xy 118.803156 -222.788205)
			(xy 118.803156 -222.734907) (xy 118.811099 -222.682203) (xy 118.826809 -222.631273) (xy 118.849935 -222.583252)
			(xy 118.879959 -222.539215) (xy 118.916211 -222.500144) (xy 118.957882 -222.466913) (xy 119.00404 -222.440264)
			(xy 119.053654 -222.420792) (xy 119.105616 -222.408932) (xy 119.158766 -222.404949) (xy 119.211916 -222.408932)
			(xy 119.263878 -222.420792) (xy 119.313492 -222.440264) (xy 119.35965 -222.466913) (xy 119.401321 -222.500144)
			(xy 119.437573 -222.539215) (xy 119.467597 -222.583252) (xy 119.490723 -222.631273) (xy 119.506433 -222.682203)
			(xy 119.514376 -222.734907) (xy 119.514874 -222.761556) (xy 119.514376 -222.788205) (xy 119.506433 -222.840909)
			(xy 119.490723 -222.891839) (xy 119.467597 -222.93986) (xy 119.437573 -222.983897) (xy 119.401321 -223.022968)
			(xy 119.35965 -223.056199) (xy 119.313492 -223.082848) (xy 119.263878 -223.10232) (xy 119.211916 -223.11418)
			(xy 119.158766 -223.118164) (xy 119.105616 -223.11418) (xy 119.053654 -223.10232) (xy 119.00404 -223.082848)
			(xy 118.957882 -223.056199) (xy 118.916211 -223.022968) (xy 118.879959 -222.983897) (xy 118.849935 -222.93986)
			(xy 118.826809 -222.891839) (xy 118.811099 -222.840909) (xy 118.803156 -222.788205) (xy 118.574576 -222.788205)
			(xy 118.566633 -222.840909) (xy 118.550923 -222.891839) (xy 118.527797 -222.93986) (xy 118.497773 -222.983897)
			(xy 118.461521 -223.022968) (xy 118.41985 -223.056199) (xy 118.373692 -223.082848) (xy 118.324078 -223.10232)
			(xy 118.272116 -223.11418) (xy 118.218966 -223.118164) (xy 118.165816 -223.11418) (xy 118.113854 -223.10232)
			(xy 118.06424 -223.082848) (xy 118.018082 -223.056199) (xy 117.976411 -223.022968) (xy 117.940159 -222.983897)
			(xy 117.910135 -222.93986) (xy 117.887009 -222.891839) (xy 117.871299 -222.840909) (xy 117.863356 -222.788205)
			(xy 117.634776 -222.788205) (xy 117.626833 -222.840909) (xy 117.611123 -222.891839) (xy 117.587997 -222.93986)
			(xy 117.557973 -222.983897) (xy 117.521721 -223.022968) (xy 117.48005 -223.056199) (xy 117.433892 -223.082848)
			(xy 117.384278 -223.10232) (xy 117.332316 -223.11418) (xy 117.279166 -223.118164) (xy 117.226016 -223.11418)
			(xy 117.174054 -223.10232) (xy 117.12444 -223.082848) (xy 117.078282 -223.056199) (xy 117.036611 -223.022968)
			(xy 117.000359 -222.983897) (xy 116.970335 -222.93986) (xy 116.947209 -222.891839) (xy 116.931499 -222.840909)
			(xy 116.923556 -222.788205) (xy 116.694976 -222.788205) (xy 116.687033 -222.840909) (xy 116.671323 -222.891839)
			(xy 116.648197 -222.93986) (xy 116.618173 -222.983897) (xy 116.581921 -223.022968) (xy 116.54025 -223.056199)
			(xy 116.494092 -223.082848) (xy 116.444478 -223.10232) (xy 116.392516 -223.11418) (xy 116.339366 -223.118164)
			(xy 116.286216 -223.11418) (xy 116.234254 -223.10232) (xy 116.18464 -223.082848) (xy 116.138482 -223.056199)
			(xy 116.096811 -223.022968) (xy 116.060559 -222.983897) (xy 116.030535 -222.93986) (xy 116.007409 -222.891839)
			(xy 115.991699 -222.840909) (xy 115.983756 -222.788205) (xy 115.755176 -222.788205) (xy 115.747233 -222.840909)
			(xy 115.731523 -222.891839) (xy 115.708397 -222.93986) (xy 115.678373 -222.983897) (xy 115.642121 -223.022968)
			(xy 115.60045 -223.056199) (xy 115.554292 -223.082848) (xy 115.504678 -223.10232) (xy 115.452716 -223.11418)
			(xy 115.399566 -223.118164) (xy 115.346416 -223.11418) (xy 115.294454 -223.10232) (xy 115.24484 -223.082848)
			(xy 115.198682 -223.056199) (xy 115.157011 -223.022968) (xy 115.120759 -222.983897) (xy 115.090735 -222.93986)
			(xy 115.067609 -222.891839) (xy 115.051899 -222.840909) (xy 115.043956 -222.788205) (xy 114.815376 -222.788205)
			(xy 114.807433 -222.840909) (xy 114.791723 -222.891839) (xy 114.768597 -222.93986) (xy 114.738573 -222.983897)
			(xy 114.702321 -223.022968) (xy 114.66065 -223.056199) (xy 114.614492 -223.082848) (xy 114.564878 -223.10232)
			(xy 114.512916 -223.11418) (xy 114.459766 -223.118164) (xy 114.406616 -223.11418) (xy 114.354654 -223.10232)
			(xy 114.30504 -223.082848) (xy 114.258882 -223.056199) (xy 114.217211 -223.022968) (xy 114.180959 -222.983897)
			(xy 114.150935 -222.93986) (xy 114.127809 -222.891839) (xy 114.112099 -222.840909) (xy 114.104156 -222.788205)
			(xy 113.875576 -222.788205) (xy 113.867633 -222.840909) (xy 113.851923 -222.891839) (xy 113.828797 -222.93986)
			(xy 113.798773 -222.983897) (xy 113.762521 -223.022968) (xy 113.72085 -223.056199) (xy 113.674692 -223.082848)
			(xy 113.625078 -223.10232) (xy 113.573116 -223.11418) (xy 113.519966 -223.118164) (xy 113.466816 -223.11418)
			(xy 113.414854 -223.10232) (xy 113.36524 -223.082848) (xy 113.319082 -223.056199) (xy 113.277411 -223.022968)
			(xy 113.241159 -222.983897) (xy 113.211135 -222.93986) (xy 113.188009 -222.891839) (xy 113.172299 -222.840909)
			(xy 113.164356 -222.788205) (xy 112.935776 -222.788205) (xy 112.927833 -222.840909) (xy 112.912123 -222.891839)
			(xy 112.888997 -222.93986) (xy 112.858973 -222.983897) (xy 112.822721 -223.022968) (xy 112.78105 -223.056199)
			(xy 112.734892 -223.082848) (xy 112.685278 -223.10232) (xy 112.633316 -223.11418) (xy 112.580166 -223.118164)
			(xy 112.527016 -223.11418) (xy 112.475054 -223.10232) (xy 112.42544 -223.082848) (xy 112.379282 -223.056199)
			(xy 112.337611 -223.022968) (xy 112.301359 -222.983897) (xy 112.271335 -222.93986) (xy 112.248209 -222.891839)
			(xy 112.232499 -222.840909) (xy 112.224556 -222.788205) (xy 111.995043 -222.788205) (xy 111.993256 -222.812938)
			(xy 111.982188 -222.863238) (xy 111.963995 -222.91142) (xy 111.939057 -222.956483) (xy 111.907891 -222.997486)
			(xy 111.889794 -223.01581) (xy 111.889794 -223.133666) (xy 111.890188 -223.146997) (xy 111.897089 -223.17275)
			(xy 111.91043 -223.195834) (xy 111.929299 -223.214671) (xy 111.952405 -223.227975) (xy 111.978169 -223.234834)
			(xy 112.004831 -223.234781) (xy 112.01781 -223.23171) (xy 112.040494 -223.225991) (xy 112.086875 -223.219869)
			(xy 112.110266 -223.219518) (xy 112.136917 -223.219989) (xy 112.189624 -223.227928) (xy 112.240559 -223.243635)
			(xy 112.288583 -223.266759) (xy 112.332625 -223.296782) (xy 112.3717 -223.333034) (xy 112.404934 -223.374706)
			(xy 112.431587 -223.420866) (xy 112.451061 -223.470482) (xy 112.462923 -223.522447) (xy 112.466906 -223.5756)
			(xy 112.462923 -223.628753) (xy 112.451061 -223.680718) (xy 112.431587 -223.730334) (xy 112.404934 -223.776494)
			(xy 112.3717 -223.818166) (xy 112.332625 -223.854418) (xy 112.288583 -223.884441) (xy 112.240559 -223.907565)
			(xy 112.189624 -223.923272) (xy 112.136917 -223.931211) (xy 112.110266 -223.931734) (xy 112.086875 -223.931366)
			(xy 112.040495 -223.925255) (xy 112.01781 -223.919542) (xy 112.00483 -223.9165) (xy 111.978181 -223.916472)
			(xy 111.952433 -223.923342) (xy 111.92934 -223.936642) (xy 111.910476 -223.955465) (xy 111.897127 -223.978529)
			(xy 111.890201 -224.004262) (xy 111.889794 -224.017586) (xy 111.889794 -224.135188) (xy 111.909625 -224.155425)
			(xy 111.943264 -224.201015) (xy 111.969266 -224.251353) (xy 111.986977 -224.305171) (xy 111.99595 -224.361113)
			(xy 111.996474 -224.389442) (xy 112.224058 -224.389442) (xy 112.224512 -224.363814) (xy 112.231843 -224.313084)
			(xy 112.246372 -224.26393) (xy 112.2678 -224.217367) (xy 112.295684 -224.174359) (xy 112.329447 -224.135794)
			(xy 112.368392 -224.102469) (xy 112.411713 -224.075074) (xy 112.458515 -224.054174) (xy 112.50783 -224.040202)
			(xy 112.533176 -224.036382) (xy 112.557814 -224.03308) (xy 112.730026 -223.734376) (xy 112.720628 -223.711516)
			(xy 112.71212 -223.689881) (xy 112.700129 -223.644965) (xy 112.694081 -223.598871) (xy 112.693704 -223.575626)
			(xy 112.694202 -223.548977) (xy 112.702145 -223.496273) (xy 112.717855 -223.445343) (xy 112.740981 -223.397322)
			(xy 112.771005 -223.353285) (xy 112.807257 -223.314214) (xy 112.848928 -223.280983) (xy 112.895086 -223.254334)
			(xy 112.9447 -223.234862) (xy 112.996662 -223.223002) (xy 113.049812 -223.219019) (xy 113.102962 -223.223002)
			(xy 113.154924 -223.234862) (xy 113.204538 -223.254334) (xy 113.250696 -223.280983) (xy 113.292367 -223.314214)
			(xy 113.328619 -223.353285) (xy 113.358643 -223.397322) (xy 113.381769 -223.445343) (xy 113.397479 -223.496273)
			(xy 113.405422 -223.548977) (xy 113.40592 -223.575626) (xy 113.405547 -223.601257) (xy 113.4054 -223.602275)
			(xy 113.634256 -223.602275) (xy 113.634256 -223.548977) (xy 113.642199 -223.496273) (xy 113.657909 -223.445343)
			(xy 113.681035 -223.397322) (xy 113.711059 -223.353285) (xy 113.747311 -223.314214) (xy 113.788982 -223.280983)
			(xy 113.83514 -223.254334) (xy 113.884754 -223.234862) (xy 113.936716 -223.223002) (xy 113.989866 -223.219019)
			(xy 114.043016 -223.223002) (xy 114.094978 -223.234862) (xy 114.144592 -223.254334) (xy 114.19075 -223.280983)
			(xy 114.232421 -223.314214) (xy 114.268673 -223.353285) (xy 114.298697 -223.397322) (xy 114.321823 -223.445343)
			(xy 114.337533 -223.496273) (xy 114.345476 -223.548977) (xy 114.345974 -223.575626) (xy 114.345476 -223.602275)
			(xy 114.337533 -223.654979) (xy 114.321823 -223.705909) (xy 114.298697 -223.75393) (xy 114.268673 -223.797967)
			(xy 114.232421 -223.837038) (xy 114.19075 -223.870269) (xy 114.144592 -223.896918) (xy 114.094978 -223.91639)
			(xy 114.043016 -223.92825) (xy 113.989866 -223.932234) (xy 113.936716 -223.92825) (xy 113.884754 -223.91639)
			(xy 113.83514 -223.896918) (xy 113.788982 -223.870269) (xy 113.747311 -223.837038) (xy 113.711059 -223.797967)
			(xy 113.681035 -223.75393) (xy 113.657909 -223.705909) (xy 113.642199 -223.654979) (xy 113.634256 -223.602275)
			(xy 113.4054 -223.602275) (xy 113.398207 -223.651991) (xy 113.383668 -223.701148) (xy 113.36223 -223.747712)
			(xy 113.334337 -223.790721) (xy 113.300564 -223.829285) (xy 113.261611 -223.862608) (xy 113.218282 -223.890002)
			(xy 113.171473 -223.910899) (xy 113.122151 -223.924868) (xy 113.096802 -223.928686) (xy 113.07191 -223.931988)
			(xy 112.899698 -224.230438) (xy 112.90935 -224.253552) (xy 112.917878 -224.27518) (xy 112.929861 -224.3201)
			(xy 112.935901 -224.366197) (xy 112.936274 -224.389442) (xy 113.163858 -224.389442) (xy 113.164356 -224.362793)
			(xy 113.172299 -224.310089) (xy 113.188009 -224.259159) (xy 113.211135 -224.211138) (xy 113.241159 -224.167101)
			(xy 113.277411 -224.12803) (xy 113.319082 -224.094799) (xy 113.36524 -224.06815) (xy 113.414854 -224.048678)
			(xy 113.466816 -224.036818) (xy 113.519966 -224.032835) (xy 113.573116 -224.036818) (xy 113.625078 -224.048678)
			(xy 113.674692 -224.06815) (xy 113.72085 -224.094799) (xy 113.762521 -224.12803) (xy 113.798773 -224.167101)
			(xy 113.828797 -224.211138) (xy 113.851923 -224.259159) (xy 113.867633 -224.310089) (xy 113.875576 -224.362793)
			(xy 113.876074 -224.389442) (xy 114.103658 -224.389442) (xy 114.104112 -224.363814) (xy 114.111443 -224.313084)
			(xy 114.125972 -224.26393) (xy 114.1474 -224.217367) (xy 114.175284 -224.174359) (xy 114.209047 -224.135794)
			(xy 114.247992 -224.102469) (xy 114.291313 -224.075074) (xy 114.338115 -224.054174) (xy 114.38743 -224.040202)
			(xy 114.412776 -224.036382) (xy 114.437414 -224.03308) (xy 114.60988 -223.734376) (xy 114.600482 -223.711262)
			(xy 114.591984 -223.689669) (xy 114.58001 -223.644835) (xy 114.573951 -223.598828) (xy 114.573558 -223.575626)
			(xy 114.574056 -223.548977) (xy 114.581999 -223.496273) (xy 114.597709 -223.445343) (xy 114.620835 -223.397322)
			(xy 114.650859 -223.353285) (xy 114.687111 -223.314214) (xy 114.728782 -223.280983) (xy 114.77494 -223.254334)
			(xy 114.824554 -223.234862) (xy 114.876516 -223.223002) (xy 114.929666 -223.219019) (xy 114.982816 -223.223002)
			(xy 115.034778 -223.234862) (xy 115.084392 -223.254334) (xy 115.13055 -223.280983) (xy 115.172221 -223.314214)
			(xy 115.208473 -223.353285) (xy 115.238497 -223.397322) (xy 115.261623 -223.445343) (xy 115.277333 -223.496273)
			(xy 115.285276 -223.548977) (xy 115.285774 -223.575626) (xy 115.28532 -223.601265) (xy 115.285174 -223.602275)
			(xy 115.513856 -223.602275) (xy 115.513856 -223.548977) (xy 115.521799 -223.496273) (xy 115.537509 -223.445343)
			(xy 115.560635 -223.397322) (xy 115.590659 -223.353285) (xy 115.626911 -223.314214) (xy 115.668582 -223.280983)
			(xy 115.71474 -223.254334) (xy 115.764354 -223.234862) (xy 115.816316 -223.223002) (xy 115.869466 -223.219019)
			(xy 115.922616 -223.223002) (xy 115.974578 -223.234862) (xy 116.024192 -223.254334) (xy 116.07035 -223.280983)
			(xy 116.112021 -223.314214) (xy 116.148273 -223.353285) (xy 116.178297 -223.397322) (xy 116.201423 -223.445343)
			(xy 116.217133 -223.496273) (xy 116.225076 -223.548977) (xy 116.225574 -223.575626) (xy 116.225076 -223.602275)
			(xy 116.217133 -223.654979) (xy 116.201423 -223.705909) (xy 116.178297 -223.75393) (xy 116.148273 -223.797967)
			(xy 116.112021 -223.837038) (xy 116.07035 -223.870269) (xy 116.024192 -223.896918) (xy 115.974578 -223.91639)
			(xy 115.922616 -223.92825) (xy 115.869466 -223.932234) (xy 115.816316 -223.92825) (xy 115.764354 -223.91639)
			(xy 115.71474 -223.896918) (xy 115.668582 -223.870269) (xy 115.626911 -223.837038) (xy 115.590659 -223.797967)
			(xy 115.560635 -223.75393) (xy 115.537509 -223.705909) (xy 115.521799 -223.654979) (xy 115.513856 -223.602275)
			(xy 115.285174 -223.602275) (xy 115.277975 -223.652014) (xy 115.263426 -223.701185) (xy 115.241973 -223.74776)
			(xy 115.214062 -223.790776) (xy 115.180268 -223.829343) (xy 115.141292 -223.862664) (xy 115.097939 -223.890049)
			(xy 115.051105 -223.910931) (xy 115.001761 -223.92488) (xy 114.976402 -223.928686) (xy 114.95151 -223.931988)
			(xy 114.779298 -224.230438) (xy 114.78895 -224.253552) (xy 114.797478 -224.27518) (xy 114.809461 -224.3201)
			(xy 114.815501 -224.366197) (xy 114.815874 -224.389442) (xy 115.043458 -224.389442) (xy 115.043956 -224.362793)
			(xy 115.051899 -224.310089) (xy 115.067609 -224.259159) (xy 115.090735 -224.211138) (xy 115.120759 -224.167101)
			(xy 115.157011 -224.12803) (xy 115.198682 -224.094799) (xy 115.24484 -224.06815) (xy 115.294454 -224.048678)
			(xy 115.346416 -224.036818) (xy 115.399566 -224.032835) (xy 115.452716 -224.036818) (xy 115.504678 -224.048678)
			(xy 115.554292 -224.06815) (xy 115.60045 -224.094799) (xy 115.642121 -224.12803) (xy 115.678373 -224.167101)
			(xy 115.708397 -224.211138) (xy 115.731523 -224.259159) (xy 115.747233 -224.310089) (xy 115.755176 -224.362793)
			(xy 115.755674 -224.389442) (xy 115.983258 -224.389442) (xy 115.983712 -224.363814) (xy 115.991043 -224.313084)
			(xy 116.005572 -224.26393) (xy 116.027 -224.217367) (xy 116.054884 -224.174359) (xy 116.088647 -224.135794)
			(xy 116.127592 -224.102469) (xy 116.170913 -224.075074) (xy 116.217715 -224.054174) (xy 116.26703 -224.040202)
			(xy 116.292376 -224.036382) (xy 116.317014 -224.03308) (xy 116.489226 -223.734376) (xy 116.479828 -223.711516)
			(xy 116.47132 -223.689881) (xy 116.459329 -223.644965) (xy 116.453281 -223.598871) (xy 116.452904 -223.575626)
			(xy 116.453402 -223.548977) (xy 116.461345 -223.496273) (xy 116.477055 -223.445343) (xy 116.500181 -223.397322)
			(xy 116.530205 -223.353285) (xy 116.566457 -223.314214) (xy 116.608128 -223.280983) (xy 116.654286 -223.254334)
			(xy 116.7039 -223.234862) (xy 116.755862 -223.223002) (xy 116.809012 -223.219019) (xy 116.862162 -223.223002)
			(xy 116.914124 -223.234862) (xy 116.963738 -223.254334) (xy 117.009896 -223.280983) (xy 117.051567 -223.314214)
			(xy 117.087819 -223.353285) (xy 117.117843 -223.397322) (xy 117.140969 -223.445343) (xy 117.156679 -223.496273)
			(xy 117.164622 -223.548977) (xy 117.16512 -223.575626) (xy 117.164747 -223.601257) (xy 117.1646 -223.602275)
			(xy 117.393456 -223.602275) (xy 117.393456 -223.548977) (xy 117.401399 -223.496273) (xy 117.417109 -223.445343)
			(xy 117.440235 -223.397322) (xy 117.470259 -223.353285) (xy 117.506511 -223.314214) (xy 117.548182 -223.280983)
			(xy 117.59434 -223.254334) (xy 117.643954 -223.234862) (xy 117.695916 -223.223002) (xy 117.749066 -223.219019)
			(xy 117.802216 -223.223002) (xy 117.854178 -223.234862) (xy 117.903792 -223.254334) (xy 117.94995 -223.280983)
			(xy 117.991621 -223.314214) (xy 118.027873 -223.353285) (xy 118.057897 -223.397322) (xy 118.081023 -223.445343)
			(xy 118.096733 -223.496273) (xy 118.104676 -223.548977) (xy 118.105174 -223.575626) (xy 118.104676 -223.602275)
			(xy 118.096733 -223.654979) (xy 118.081023 -223.705909) (xy 118.057897 -223.75393) (xy 118.027873 -223.797967)
			(xy 117.991621 -223.837038) (xy 117.94995 -223.870269) (xy 117.903792 -223.896918) (xy 117.854178 -223.91639)
			(xy 117.802216 -223.92825) (xy 117.749066 -223.932234) (xy 117.695916 -223.92825) (xy 117.643954 -223.91639)
			(xy 117.59434 -223.896918) (xy 117.548182 -223.870269) (xy 117.506511 -223.837038) (xy 117.470259 -223.797967)
			(xy 117.440235 -223.75393) (xy 117.417109 -223.705909) (xy 117.401399 -223.654979) (xy 117.393456 -223.602275)
			(xy 117.1646 -223.602275) (xy 117.157407 -223.651991) (xy 117.142868 -223.701148) (xy 117.12143 -223.747712)
			(xy 117.093537 -223.790721) (xy 117.059764 -223.829285) (xy 117.020811 -223.862608) (xy 116.977482 -223.890002)
			(xy 116.930673 -223.910899) (xy 116.881351 -223.924868) (xy 116.856002 -223.928686) (xy 116.83111 -223.931988)
			(xy 116.658898 -224.230438) (xy 116.66855 -224.253552) (xy 116.677078 -224.27518) (xy 116.689061 -224.3201)
			(xy 116.695101 -224.366197) (xy 116.695474 -224.389442) (xy 116.923058 -224.389442) (xy 116.923556 -224.362793)
			(xy 116.931499 -224.310089) (xy 116.947209 -224.259159) (xy 116.970335 -224.211138) (xy 117.000359 -224.167101)
			(xy 117.036611 -224.12803) (xy 117.078282 -224.094799) (xy 117.12444 -224.06815) (xy 117.174054 -224.048678)
			(xy 117.226016 -224.036818) (xy 117.279166 -224.032835) (xy 117.332316 -224.036818) (xy 117.384278 -224.048678)
			(xy 117.433892 -224.06815) (xy 117.48005 -224.094799) (xy 117.521721 -224.12803) (xy 117.557973 -224.167101)
			(xy 117.587997 -224.211138) (xy 117.611123 -224.259159) (xy 117.626833 -224.310089) (xy 117.634776 -224.362793)
			(xy 117.635274 -224.389442) (xy 117.862858 -224.389442) (xy 117.863312 -224.363814) (xy 117.870643 -224.313084)
			(xy 117.885172 -224.26393) (xy 117.9066 -224.217367) (xy 117.934484 -224.174359) (xy 117.968247 -224.135794)
			(xy 118.007192 -224.102469) (xy 118.050513 -224.075074) (xy 118.097315 -224.054174) (xy 118.14663 -224.040202)
			(xy 118.171976 -224.036382) (xy 118.196614 -224.03308) (xy 118.368826 -223.734376) (xy 118.359428 -223.711516)
			(xy 118.35092 -223.689881) (xy 118.338929 -223.644965) (xy 118.332881 -223.598871) (xy 118.332504 -223.575626)
			(xy 118.333002 -223.548977) (xy 118.340945 -223.496273) (xy 118.356655 -223.445343) (xy 118.379781 -223.397322)
			(xy 118.409805 -223.353285) (xy 118.446057 -223.314214) (xy 118.487728 -223.280983) (xy 118.533886 -223.254334)
			(xy 118.5835 -223.234862) (xy 118.635462 -223.223002) (xy 118.688612 -223.219019) (xy 118.741762 -223.223002)
			(xy 118.793724 -223.234862) (xy 118.843338 -223.254334) (xy 118.889496 -223.280983) (xy 118.931167 -223.314214)
			(xy 118.967419 -223.353285) (xy 118.997443 -223.397322) (xy 119.020569 -223.445343) (xy 119.036279 -223.496273)
			(xy 119.044222 -223.548977) (xy 119.04472 -223.575626) (xy 119.044347 -223.601257) (xy 119.0442 -223.602275)
			(xy 119.273056 -223.602275) (xy 119.273056 -223.548977) (xy 119.280999 -223.496273) (xy 119.296709 -223.445343)
			(xy 119.319835 -223.397322) (xy 119.349859 -223.353285) (xy 119.386111 -223.314214) (xy 119.427782 -223.280983)
			(xy 119.47394 -223.254334) (xy 119.523554 -223.234862) (xy 119.575516 -223.223002) (xy 119.628666 -223.219019)
			(xy 119.681816 -223.223002) (xy 119.733778 -223.234862) (xy 119.783392 -223.254334) (xy 119.82955 -223.280983)
			(xy 119.871221 -223.314214) (xy 119.907473 -223.353285) (xy 119.937497 -223.397322) (xy 119.960623 -223.445343)
			(xy 119.976333 -223.496273) (xy 119.984276 -223.548977) (xy 119.984774 -223.575626) (xy 119.984276 -223.602275)
			(xy 119.976333 -223.654979) (xy 119.960623 -223.705909) (xy 119.937497 -223.75393) (xy 119.907473 -223.797967)
			(xy 119.871221 -223.837038) (xy 119.82955 -223.870269) (xy 119.783392 -223.896918) (xy 119.733778 -223.91639)
			(xy 119.681816 -223.92825) (xy 119.628666 -223.932234) (xy 119.575516 -223.92825) (xy 119.523554 -223.91639)
			(xy 119.47394 -223.896918) (xy 119.427782 -223.870269) (xy 119.386111 -223.837038) (xy 119.349859 -223.797967)
			(xy 119.319835 -223.75393) (xy 119.296709 -223.705909) (xy 119.280999 -223.654979) (xy 119.273056 -223.602275)
			(xy 119.0442 -223.602275) (xy 119.037007 -223.651991) (xy 119.022468 -223.701148) (xy 119.00103 -223.747712)
			(xy 118.973137 -223.790721) (xy 118.939364 -223.829285) (xy 118.900411 -223.862608) (xy 118.857082 -223.890002)
			(xy 118.810273 -223.910899) (xy 118.760951 -223.924868) (xy 118.735602 -223.928686) (xy 118.71071 -223.931988)
			(xy 118.538498 -224.230438) (xy 118.54815 -224.253552) (xy 118.556678 -224.27518) (xy 118.568661 -224.3201)
			(xy 118.574701 -224.366197) (xy 118.575074 -224.389442) (xy 118.802658 -224.389442) (xy 118.803156 -224.362793)
			(xy 118.811099 -224.310089) (xy 118.826809 -224.259159) (xy 118.849935 -224.211138) (xy 118.879959 -224.167101)
			(xy 118.916211 -224.12803) (xy 118.957882 -224.094799) (xy 119.00404 -224.06815) (xy 119.053654 -224.048678)
			(xy 119.105616 -224.036818) (xy 119.158766 -224.032835) (xy 119.211916 -224.036818) (xy 119.263878 -224.048678)
			(xy 119.313492 -224.06815) (xy 119.35965 -224.094799) (xy 119.401321 -224.12803) (xy 119.437573 -224.167101)
			(xy 119.467597 -224.211138) (xy 119.490723 -224.259159) (xy 119.506433 -224.310089) (xy 119.514376 -224.362793)
			(xy 119.514874 -224.389442) (xy 119.742458 -224.389442) (xy 119.742912 -224.363814) (xy 119.750243 -224.313084)
			(xy 119.764772 -224.26393) (xy 119.7862 -224.217367) (xy 119.814084 -224.174359) (xy 119.847847 -224.135794)
			(xy 119.886792 -224.102469) (xy 119.930113 -224.075074) (xy 119.976915 -224.054174) (xy 120.02623 -224.040202)
			(xy 120.051576 -224.036382) (xy 120.076214 -224.03308) (xy 120.248426 -223.734376) (xy 120.239028 -223.711516)
			(xy 120.23052 -223.689881) (xy 120.218529 -223.644965) (xy 120.212481 -223.598871) (xy 120.212104 -223.575626)
			(xy 120.212602 -223.548977) (xy 120.220545 -223.496273) (xy 120.236255 -223.445343) (xy 120.259381 -223.397322)
			(xy 120.289405 -223.353285) (xy 120.325657 -223.314214) (xy 120.367328 -223.280983) (xy 120.413486 -223.254334)
			(xy 120.4631 -223.234862) (xy 120.515062 -223.223002) (xy 120.568212 -223.219019) (xy 120.621362 -223.223002)
			(xy 120.673324 -223.234862) (xy 120.722938 -223.254334) (xy 120.769096 -223.280983) (xy 120.810767 -223.314214)
			(xy 120.847019 -223.353285) (xy 120.877043 -223.397322) (xy 120.900169 -223.445343) (xy 120.915879 -223.496273)
			(xy 120.923822 -223.548977) (xy 120.92432 -223.575626) (xy 120.923947 -223.601257) (xy 120.9238 -223.602275)
			(xy 121.152656 -223.602275) (xy 121.152656 -223.548977) (xy 121.160599 -223.496273) (xy 121.176309 -223.445343)
			(xy 121.199435 -223.397322) (xy 121.229459 -223.353285) (xy 121.265711 -223.314214) (xy 121.307382 -223.280983)
			(xy 121.35354 -223.254334) (xy 121.403154 -223.234862) (xy 121.455116 -223.223002) (xy 121.508266 -223.219019)
			(xy 121.561416 -223.223002) (xy 121.613378 -223.234862) (xy 121.662992 -223.254334) (xy 121.70915 -223.280983)
			(xy 121.750821 -223.314214) (xy 121.787073 -223.353285) (xy 121.817097 -223.397322) (xy 121.840223 -223.445343)
			(xy 121.855933 -223.496273) (xy 121.863876 -223.548977) (xy 121.864374 -223.575626) (xy 121.863876 -223.602275)
			(xy 121.855933 -223.654979) (xy 121.840223 -223.705909) (xy 121.817097 -223.75393) (xy 121.787073 -223.797967)
			(xy 121.750821 -223.837038) (xy 121.70915 -223.870269) (xy 121.662992 -223.896918) (xy 121.613378 -223.91639)
			(xy 121.561416 -223.92825) (xy 121.508266 -223.932234) (xy 121.455116 -223.92825) (xy 121.403154 -223.91639)
			(xy 121.35354 -223.896918) (xy 121.307382 -223.870269) (xy 121.265711 -223.837038) (xy 121.229459 -223.797967)
			(xy 121.199435 -223.75393) (xy 121.176309 -223.705909) (xy 121.160599 -223.654979) (xy 121.152656 -223.602275)
			(xy 120.9238 -223.602275) (xy 120.916607 -223.651991) (xy 120.902068 -223.701148) (xy 120.88063 -223.747712)
			(xy 120.852737 -223.790721) (xy 120.818964 -223.829285) (xy 120.780011 -223.862608) (xy 120.736682 -223.890002)
			(xy 120.689873 -223.910899) (xy 120.640551 -223.924868) (xy 120.615202 -223.928686) (xy 120.59031 -223.931988)
			(xy 120.418098 -224.230438) (xy 120.42775 -224.253552) (xy 120.436278 -224.27518) (xy 120.448261 -224.3201)
			(xy 120.454301 -224.366197) (xy 120.454674 -224.389442) (xy 120.682258 -224.389442) (xy 120.682756 -224.362793)
			(xy 120.690699 -224.310089) (xy 120.706409 -224.259159) (xy 120.729535 -224.211138) (xy 120.759559 -224.167101)
			(xy 120.795811 -224.12803) (xy 120.837482 -224.094799) (xy 120.88364 -224.06815) (xy 120.933254 -224.048678)
			(xy 120.985216 -224.036818) (xy 121.038366 -224.032835) (xy 121.091516 -224.036818) (xy 121.143478 -224.048678)
			(xy 121.193092 -224.06815) (xy 121.23925 -224.094799) (xy 121.280921 -224.12803) (xy 121.317173 -224.167101)
			(xy 121.347197 -224.211138) (xy 121.370323 -224.259159) (xy 121.386033 -224.310089) (xy 121.393976 -224.362793)
			(xy 121.394474 -224.389442) (xy 121.622058 -224.389442) (xy 121.622512 -224.363814) (xy 121.629843 -224.313084)
			(xy 121.644372 -224.26393) (xy 121.6658 -224.217367) (xy 121.693684 -224.174359) (xy 121.727447 -224.135794)
			(xy 121.766392 -224.102469) (xy 121.809713 -224.075074) (xy 121.856515 -224.054174) (xy 121.90583 -224.040202)
			(xy 121.931176 -224.036382) (xy 121.955814 -224.03308) (xy 122.128026 -223.734376) (xy 122.118628 -223.711516)
			(xy 122.11012 -223.689881) (xy 122.098129 -223.644965) (xy 122.092081 -223.598871) (xy 122.091704 -223.575626)
			(xy 122.092202 -223.548977) (xy 122.100145 -223.496273) (xy 122.115855 -223.445343) (xy 122.138981 -223.397322)
			(xy 122.169005 -223.353285) (xy 122.205257 -223.314214) (xy 122.246928 -223.280983) (xy 122.293086 -223.254334)
			(xy 122.3427 -223.234862) (xy 122.394662 -223.223002) (xy 122.447812 -223.219019) (xy 122.500962 -223.223002)
			(xy 122.552924 -223.234862) (xy 122.602538 -223.254334) (xy 122.648696 -223.280983) (xy 122.690367 -223.314214)
			(xy 122.726619 -223.353285) (xy 122.756643 -223.397322) (xy 122.779769 -223.445343) (xy 122.795479 -223.496273)
			(xy 122.803422 -223.548977) (xy 122.80392 -223.575626) (xy 122.803547 -223.601257) (xy 122.8034 -223.602275)
			(xy 123.032256 -223.602275) (xy 123.032256 -223.548977) (xy 123.040199 -223.496273) (xy 123.055909 -223.445343)
			(xy 123.079035 -223.397322) (xy 123.109059 -223.353285) (xy 123.145311 -223.314214) (xy 123.186982 -223.280983)
			(xy 123.23314 -223.254334) (xy 123.282754 -223.234862) (xy 123.334716 -223.223002) (xy 123.387866 -223.219019)
			(xy 123.441016 -223.223002) (xy 123.492978 -223.234862) (xy 123.542592 -223.254334) (xy 123.58875 -223.280983)
			(xy 123.630421 -223.314214) (xy 123.666673 -223.353285) (xy 123.696697 -223.397322) (xy 123.719823 -223.445343)
			(xy 123.735533 -223.496273) (xy 123.743476 -223.548977) (xy 123.743974 -223.575626) (xy 123.743476 -223.602275)
			(xy 123.735533 -223.654979) (xy 123.719823 -223.705909) (xy 123.696697 -223.75393) (xy 123.666673 -223.797967)
			(xy 123.630421 -223.837038) (xy 123.58875 -223.870269) (xy 123.542592 -223.896918) (xy 123.492978 -223.91639)
			(xy 123.441016 -223.92825) (xy 123.387866 -223.932234) (xy 123.334716 -223.92825) (xy 123.282754 -223.91639)
			(xy 123.23314 -223.896918) (xy 123.186982 -223.870269) (xy 123.145311 -223.837038) (xy 123.109059 -223.797967)
			(xy 123.079035 -223.75393) (xy 123.055909 -223.705909) (xy 123.040199 -223.654979) (xy 123.032256 -223.602275)
			(xy 122.8034 -223.602275) (xy 122.796207 -223.651991) (xy 122.781668 -223.701148) (xy 122.76023 -223.747712)
			(xy 122.732337 -223.790721) (xy 122.698564 -223.829285) (xy 122.659611 -223.862608) (xy 122.616282 -223.890002)
			(xy 122.569473 -223.910899) (xy 122.520151 -223.924868) (xy 122.494802 -223.928686) (xy 122.46991 -223.931988)
			(xy 122.297698 -224.230438) (xy 122.30735 -224.253552) (xy 122.315878 -224.27518) (xy 122.327861 -224.3201)
			(xy 122.333901 -224.366197) (xy 122.334274 -224.389442) (xy 122.561858 -224.389442) (xy 122.562356 -224.362793)
			(xy 122.570299 -224.310089) (xy 122.586009 -224.259159) (xy 122.609135 -224.211138) (xy 122.639159 -224.167101)
			(xy 122.675411 -224.12803) (xy 122.717082 -224.094799) (xy 122.76324 -224.06815) (xy 122.812854 -224.048678)
			(xy 122.864816 -224.036818) (xy 122.917966 -224.032835) (xy 122.971116 -224.036818) (xy 123.023078 -224.048678)
			(xy 123.072692 -224.06815) (xy 123.11885 -224.094799) (xy 123.160521 -224.12803) (xy 123.196773 -224.167101)
			(xy 123.226797 -224.211138) (xy 123.249923 -224.259159) (xy 123.265633 -224.310089) (xy 123.273576 -224.362793)
			(xy 123.274074 -224.389442) (xy 123.501658 -224.389442) (xy 123.502112 -224.363814) (xy 123.509443 -224.313084)
			(xy 123.523972 -224.26393) (xy 123.5454 -224.217367) (xy 123.573284 -224.174359) (xy 123.607047 -224.135794)
			(xy 123.645992 -224.102469) (xy 123.689313 -224.075074) (xy 123.736115 -224.054174) (xy 123.78543 -224.040202)
			(xy 123.810776 -224.036382) (xy 123.835414 -224.03308) (xy 124.007626 -223.734376) (xy 123.998228 -223.711516)
			(xy 123.98972 -223.689881) (xy 123.977729 -223.644965) (xy 123.971681 -223.598871) (xy 123.971304 -223.575626)
			(xy 123.971802 -223.548977) (xy 123.979745 -223.496273) (xy 123.995455 -223.445343) (xy 124.018581 -223.397322)
			(xy 124.048605 -223.353285) (xy 124.084857 -223.314214) (xy 124.126528 -223.280983) (xy 124.172686 -223.254334)
			(xy 124.2223 -223.234862) (xy 124.274262 -223.223002) (xy 124.327412 -223.219019) (xy 124.380562 -223.223002)
			(xy 124.432524 -223.234862) (xy 124.482138 -223.254334) (xy 124.528296 -223.280983) (xy 124.569967 -223.314214)
			(xy 124.606219 -223.353285) (xy 124.636243 -223.397322) (xy 124.659369 -223.445343) (xy 124.675079 -223.496273)
			(xy 124.683022 -223.548977) (xy 124.68352 -223.575626) (xy 124.683147 -223.601257) (xy 124.683 -223.602275)
			(xy 124.911856 -223.602275) (xy 124.911856 -223.548977) (xy 124.919799 -223.496273) (xy 124.935509 -223.445343)
			(xy 124.958635 -223.397322) (xy 124.988659 -223.353285) (xy 125.024911 -223.314214) (xy 125.066582 -223.280983)
			(xy 125.11274 -223.254334) (xy 125.162354 -223.234862) (xy 125.214316 -223.223002) (xy 125.267466 -223.219019)
			(xy 125.320616 -223.223002) (xy 125.372578 -223.234862) (xy 125.422192 -223.254334) (xy 125.46835 -223.280983)
			(xy 125.510021 -223.314214) (xy 125.546273 -223.353285) (xy 125.576297 -223.397322) (xy 125.599423 -223.445343)
			(xy 125.615133 -223.496273) (xy 125.623076 -223.548977) (xy 125.623574 -223.575626) (xy 125.623076 -223.602275)
			(xy 125.615133 -223.654979) (xy 125.599423 -223.705909) (xy 125.576297 -223.75393) (xy 125.546273 -223.797967)
			(xy 125.510021 -223.837038) (xy 125.46835 -223.870269) (xy 125.422192 -223.896918) (xy 125.372578 -223.91639)
			(xy 125.320616 -223.92825) (xy 125.267466 -223.932234) (xy 125.214316 -223.92825) (xy 125.162354 -223.91639)
			(xy 125.11274 -223.896918) (xy 125.066582 -223.870269) (xy 125.024911 -223.837038) (xy 124.988659 -223.797967)
			(xy 124.958635 -223.75393) (xy 124.935509 -223.705909) (xy 124.919799 -223.654979) (xy 124.911856 -223.602275)
			(xy 124.683 -223.602275) (xy 124.675807 -223.651991) (xy 124.661268 -223.701148) (xy 124.63983 -223.747712)
			(xy 124.611937 -223.790721) (xy 124.578164 -223.829285) (xy 124.539211 -223.862608) (xy 124.495882 -223.890002)
			(xy 124.449073 -223.910899) (xy 124.399751 -223.924868) (xy 124.374402 -223.928686) (xy 124.34951 -223.931988)
			(xy 124.177298 -224.230438) (xy 124.18695 -224.253552) (xy 124.195478 -224.27518) (xy 124.207461 -224.3201)
			(xy 124.213501 -224.366197) (xy 124.213874 -224.389442) (xy 124.441458 -224.389442) (xy 124.441956 -224.362793)
			(xy 124.449899 -224.310089) (xy 124.465609 -224.259159) (xy 124.488735 -224.211138) (xy 124.518759 -224.167101)
			(xy 124.555011 -224.12803) (xy 124.596682 -224.094799) (xy 124.64284 -224.06815) (xy 124.692454 -224.048678)
			(xy 124.744416 -224.036818) (xy 124.797566 -224.032835) (xy 124.850716 -224.036818) (xy 124.902678 -224.048678)
			(xy 124.952292 -224.06815) (xy 124.99845 -224.094799) (xy 125.040121 -224.12803) (xy 125.076373 -224.167101)
			(xy 125.106397 -224.211138) (xy 125.129523 -224.259159) (xy 125.145233 -224.310089) (xy 125.153176 -224.362793)
			(xy 125.153674 -224.389442) (xy 125.381258 -224.389442) (xy 125.381712 -224.363814) (xy 125.389043 -224.313084)
			(xy 125.403572 -224.26393) (xy 125.425 -224.217367) (xy 125.452884 -224.174359) (xy 125.486647 -224.135794)
			(xy 125.525592 -224.102469) (xy 125.568913 -224.075074) (xy 125.615715 -224.054174) (xy 125.66503 -224.040202)
			(xy 125.690376 -224.036382) (xy 125.715014 -224.03308) (xy 125.887226 -223.734376) (xy 125.877828 -223.711516)
			(xy 125.86932 -223.689881) (xy 125.857329 -223.644965) (xy 125.851281 -223.598871) (xy 125.850904 -223.575626)
			(xy 125.851402 -223.548977) (xy 125.859345 -223.496273) (xy 125.875055 -223.445343) (xy 125.898181 -223.397322)
			(xy 125.928205 -223.353285) (xy 125.964457 -223.314214) (xy 126.006128 -223.280983) (xy 126.052286 -223.254334)
			(xy 126.1019 -223.234862) (xy 126.153862 -223.223002) (xy 126.207012 -223.219019) (xy 126.260162 -223.223002)
			(xy 126.312124 -223.234862) (xy 126.361738 -223.254334) (xy 126.407896 -223.280983) (xy 126.449567 -223.314214)
			(xy 126.485819 -223.353285) (xy 126.515843 -223.397322) (xy 126.538969 -223.445343) (xy 126.554679 -223.496273)
			(xy 126.562622 -223.548977) (xy 126.56312 -223.575626) (xy 126.562747 -223.601257) (xy 126.5626 -223.602275)
			(xy 126.791456 -223.602275) (xy 126.791456 -223.548977) (xy 126.799399 -223.496273) (xy 126.815109 -223.445343)
			(xy 126.838235 -223.397322) (xy 126.868259 -223.353285) (xy 126.904511 -223.314214) (xy 126.946182 -223.280983)
			(xy 126.99234 -223.254334) (xy 127.041954 -223.234862) (xy 127.093916 -223.223002) (xy 127.147066 -223.219019)
			(xy 127.200216 -223.223002) (xy 127.252178 -223.234862) (xy 127.301792 -223.254334) (xy 127.34795 -223.280983)
			(xy 127.389621 -223.314214) (xy 127.425873 -223.353285) (xy 127.455897 -223.397322) (xy 127.479023 -223.445343)
			(xy 127.494733 -223.496273) (xy 127.502676 -223.548977) (xy 127.503174 -223.575626) (xy 127.502676 -223.602275)
			(xy 127.494733 -223.654979) (xy 127.479023 -223.705909) (xy 127.455897 -223.75393) (xy 127.425873 -223.797967)
			(xy 127.389621 -223.837038) (xy 127.34795 -223.870269) (xy 127.301792 -223.896918) (xy 127.252178 -223.91639)
			(xy 127.200216 -223.92825) (xy 127.147066 -223.932234) (xy 127.093916 -223.92825) (xy 127.041954 -223.91639)
			(xy 126.99234 -223.896918) (xy 126.946182 -223.870269) (xy 126.904511 -223.837038) (xy 126.868259 -223.797967)
			(xy 126.838235 -223.75393) (xy 126.815109 -223.705909) (xy 126.799399 -223.654979) (xy 126.791456 -223.602275)
			(xy 126.5626 -223.602275) (xy 126.555407 -223.651991) (xy 126.540868 -223.701148) (xy 126.51943 -223.747712)
			(xy 126.491537 -223.790721) (xy 126.457764 -223.829285) (xy 126.418811 -223.862608) (xy 126.375482 -223.890002)
			(xy 126.328673 -223.910899) (xy 126.279351 -223.924868) (xy 126.254002 -223.928686) (xy 126.22911 -223.931988)
			(xy 126.056898 -224.230438) (xy 126.06655 -224.253552) (xy 126.075078 -224.27518) (xy 126.087061 -224.3201)
			(xy 126.093101 -224.366197) (xy 126.093474 -224.389442) (xy 126.321058 -224.389442) (xy 126.321556 -224.362793)
			(xy 126.329499 -224.310089) (xy 126.345209 -224.259159) (xy 126.368335 -224.211138) (xy 126.398359 -224.167101)
			(xy 126.434611 -224.12803) (xy 126.476282 -224.094799) (xy 126.52244 -224.06815) (xy 126.572054 -224.048678)
			(xy 126.624016 -224.036818) (xy 126.677166 -224.032835) (xy 126.730316 -224.036818) (xy 126.782278 -224.048678)
			(xy 126.831892 -224.06815) (xy 126.87805 -224.094799) (xy 126.919721 -224.12803) (xy 126.955973 -224.167101)
			(xy 126.985997 -224.211138) (xy 127.009123 -224.259159) (xy 127.024833 -224.310089) (xy 127.032776 -224.362793)
			(xy 127.033274 -224.389442) (xy 127.260858 -224.389442) (xy 127.261312 -224.363814) (xy 127.268643 -224.313084)
			(xy 127.283172 -224.26393) (xy 127.3046 -224.217367) (xy 127.332484 -224.174359) (xy 127.366247 -224.135794)
			(xy 127.405192 -224.102469) (xy 127.448513 -224.075074) (xy 127.495315 -224.054174) (xy 127.54463 -224.040202)
			(xy 127.569976 -224.036382) (xy 127.594614 -224.03308) (xy 127.766826 -223.734376) (xy 127.757428 -223.711516)
			(xy 127.74892 -223.689881) (xy 127.736929 -223.644965) (xy 127.730881 -223.598871) (xy 127.730504 -223.575626)
			(xy 127.731002 -223.548977) (xy 127.738945 -223.496273) (xy 127.754655 -223.445343) (xy 127.777781 -223.397322)
			(xy 127.807805 -223.353285) (xy 127.844057 -223.314214) (xy 127.885728 -223.280983) (xy 127.931886 -223.254334)
			(xy 127.9815 -223.234862) (xy 128.033462 -223.223002) (xy 128.086612 -223.219019) (xy 128.139762 -223.223002)
			(xy 128.191724 -223.234862) (xy 128.241338 -223.254334) (xy 128.287496 -223.280983) (xy 128.329167 -223.314214)
			(xy 128.365419 -223.353285) (xy 128.395443 -223.397322) (xy 128.418569 -223.445343) (xy 128.434279 -223.496273)
			(xy 128.442222 -223.548977) (xy 128.44272 -223.575626) (xy 128.442347 -223.601257) (xy 128.4422 -223.602275)
			(xy 128.671056 -223.602275) (xy 128.671056 -223.548977) (xy 128.678999 -223.496273) (xy 128.694709 -223.445343)
			(xy 128.717835 -223.397322) (xy 128.747859 -223.353285) (xy 128.784111 -223.314214) (xy 128.825782 -223.280983)
			(xy 128.87194 -223.254334) (xy 128.921554 -223.234862) (xy 128.973516 -223.223002) (xy 129.026666 -223.219019)
			(xy 129.079816 -223.223002) (xy 129.131778 -223.234862) (xy 129.181392 -223.254334) (xy 129.22755 -223.280983)
			(xy 129.269221 -223.314214) (xy 129.305473 -223.353285) (xy 129.335497 -223.397322) (xy 129.358623 -223.445343)
			(xy 129.374333 -223.496273) (xy 129.382276 -223.548977) (xy 129.382774 -223.575626) (xy 129.382276 -223.602275)
			(xy 129.374333 -223.654979) (xy 129.358623 -223.705909) (xy 129.335497 -223.75393) (xy 129.305473 -223.797967)
			(xy 129.269221 -223.837038) (xy 129.22755 -223.870269) (xy 129.181392 -223.896918) (xy 129.131778 -223.91639)
			(xy 129.079816 -223.92825) (xy 129.026666 -223.932234) (xy 128.973516 -223.92825) (xy 128.921554 -223.91639)
			(xy 128.87194 -223.896918) (xy 128.825782 -223.870269) (xy 128.784111 -223.837038) (xy 128.747859 -223.797967)
			(xy 128.717835 -223.75393) (xy 128.694709 -223.705909) (xy 128.678999 -223.654979) (xy 128.671056 -223.602275)
			(xy 128.4422 -223.602275) (xy 128.435007 -223.651991) (xy 128.420468 -223.701148) (xy 128.39903 -223.747712)
			(xy 128.371137 -223.790721) (xy 128.337364 -223.829285) (xy 128.298411 -223.862608) (xy 128.255082 -223.890002)
			(xy 128.208273 -223.910899) (xy 128.158951 -223.924868) (xy 128.133602 -223.928686) (xy 128.10871 -223.931988)
			(xy 127.936498 -224.230438) (xy 127.94615 -224.253552) (xy 127.954678 -224.27518) (xy 127.966661 -224.3201)
			(xy 127.972701 -224.366197) (xy 127.973074 -224.389442) (xy 128.200658 -224.389442) (xy 128.201156 -224.362793)
			(xy 128.209099 -224.310089) (xy 128.224809 -224.259159) (xy 128.247935 -224.211138) (xy 128.277959 -224.167101)
			(xy 128.314211 -224.12803) (xy 128.355882 -224.094799) (xy 128.40204 -224.06815) (xy 128.451654 -224.048678)
			(xy 128.503616 -224.036818) (xy 128.556766 -224.032835) (xy 128.609916 -224.036818) (xy 128.661878 -224.048678)
			(xy 128.711492 -224.06815) (xy 128.75765 -224.094799) (xy 128.799321 -224.12803) (xy 128.835573 -224.167101)
			(xy 128.865597 -224.211138) (xy 128.888723 -224.259159) (xy 128.904433 -224.310089) (xy 128.912376 -224.362793)
			(xy 128.912874 -224.389442) (xy 129.140458 -224.389442) (xy 129.140912 -224.363814) (xy 129.148243 -224.313084)
			(xy 129.162772 -224.26393) (xy 129.1842 -224.217367) (xy 129.212084 -224.174359) (xy 129.245847 -224.135794)
			(xy 129.284792 -224.102469) (xy 129.328113 -224.075074) (xy 129.374915 -224.054174) (xy 129.42423 -224.040202)
			(xy 129.449576 -224.036382) (xy 129.474214 -224.03308) (xy 129.646426 -223.734376) (xy 129.637028 -223.711516)
			(xy 129.62852 -223.689881) (xy 129.616529 -223.644965) (xy 129.610481 -223.598871) (xy 129.610104 -223.575626)
			(xy 129.610602 -223.548977) (xy 129.618545 -223.496273) (xy 129.634255 -223.445343) (xy 129.657381 -223.397322)
			(xy 129.687405 -223.353285) (xy 129.723657 -223.314214) (xy 129.765328 -223.280983) (xy 129.811486 -223.254334)
			(xy 129.8611 -223.234862) (xy 129.913062 -223.223002) (xy 129.966212 -223.219019) (xy 130.019362 -223.223002)
			(xy 130.071324 -223.234862) (xy 130.120938 -223.254334) (xy 130.167096 -223.280983) (xy 130.208767 -223.314214)
			(xy 130.245019 -223.353285) (xy 130.275043 -223.397322) (xy 130.298169 -223.445343) (xy 130.313879 -223.496273)
			(xy 130.321822 -223.548977) (xy 130.32232 -223.575626) (xy 130.321947 -223.601257) (xy 130.3218 -223.602275)
			(xy 130.550656 -223.602275) (xy 130.550656 -223.548977) (xy 130.558599 -223.496273) (xy 130.574309 -223.445343)
			(xy 130.597435 -223.397322) (xy 130.627459 -223.353285) (xy 130.663711 -223.314214) (xy 130.705382 -223.280983)
			(xy 130.75154 -223.254334) (xy 130.801154 -223.234862) (xy 130.853116 -223.223002) (xy 130.906266 -223.219019)
			(xy 130.959416 -223.223002) (xy 131.011378 -223.234862) (xy 131.060992 -223.254334) (xy 131.10715 -223.280983)
			(xy 131.148821 -223.314214) (xy 131.185073 -223.353285) (xy 131.215097 -223.397322) (xy 131.238223 -223.445343)
			(xy 131.253933 -223.496273) (xy 131.261876 -223.548977) (xy 131.262374 -223.575626) (xy 131.261876 -223.602275)
			(xy 131.253933 -223.654979) (xy 131.238223 -223.705909) (xy 131.215097 -223.75393) (xy 131.185073 -223.797967)
			(xy 131.148821 -223.837038) (xy 131.10715 -223.870269) (xy 131.060992 -223.896918) (xy 131.011378 -223.91639)
			(xy 130.959416 -223.92825) (xy 130.906266 -223.932234) (xy 130.853116 -223.92825) (xy 130.801154 -223.91639)
			(xy 130.75154 -223.896918) (xy 130.705382 -223.870269) (xy 130.663711 -223.837038) (xy 130.627459 -223.797967)
			(xy 130.597435 -223.75393) (xy 130.574309 -223.705909) (xy 130.558599 -223.654979) (xy 130.550656 -223.602275)
			(xy 130.3218 -223.602275) (xy 130.314607 -223.651991) (xy 130.300068 -223.701148) (xy 130.27863 -223.747712)
			(xy 130.250737 -223.790721) (xy 130.216964 -223.829285) (xy 130.178011 -223.862608) (xy 130.134682 -223.890002)
			(xy 130.087873 -223.910899) (xy 130.038551 -223.924868) (xy 130.013202 -223.928686) (xy 129.98831 -223.931988)
			(xy 129.816098 -224.230438) (xy 129.82575 -224.253552) (xy 129.834278 -224.27518) (xy 129.846261 -224.3201)
			(xy 129.852301 -224.366197) (xy 129.852674 -224.389442) (xy 130.080258 -224.389442) (xy 130.080756 -224.362793)
			(xy 130.088699 -224.310089) (xy 130.104409 -224.259159) (xy 130.127535 -224.211138) (xy 130.157559 -224.167101)
			(xy 130.193811 -224.12803) (xy 130.235482 -224.094799) (xy 130.28164 -224.06815) (xy 130.331254 -224.048678)
			(xy 130.383216 -224.036818) (xy 130.436366 -224.032835) (xy 130.489516 -224.036818) (xy 130.541478 -224.048678)
			(xy 130.591092 -224.06815) (xy 130.63725 -224.094799) (xy 130.678921 -224.12803) (xy 130.715173 -224.167101)
			(xy 130.745197 -224.211138) (xy 130.768323 -224.259159) (xy 130.784033 -224.310089) (xy 130.791976 -224.362793)
			(xy 130.792474 -224.389442) (xy 131.020058 -224.389442) (xy 131.020512 -224.363814) (xy 131.027843 -224.313084)
			(xy 131.042372 -224.26393) (xy 131.0638 -224.217367) (xy 131.091684 -224.174359) (xy 131.125447 -224.135794)
			(xy 131.164392 -224.102469) (xy 131.207713 -224.075074) (xy 131.254515 -224.054174) (xy 131.30383 -224.040202)
			(xy 131.329176 -224.036382) (xy 131.353814 -224.03308) (xy 131.526026 -223.734376) (xy 131.516628 -223.711262)
			(xy 131.508132 -223.689668) (xy 131.496157 -223.644835) (xy 131.490097 -223.598828) (xy 131.489704 -223.575626)
			(xy 131.490202 -223.548977) (xy 131.498145 -223.496273) (xy 131.513855 -223.445343) (xy 131.536981 -223.397322)
			(xy 131.567005 -223.353285) (xy 131.603257 -223.314214) (xy 131.644928 -223.280983) (xy 131.691086 -223.254334)
			(xy 131.7407 -223.234862) (xy 131.792662 -223.223002) (xy 131.845812 -223.219019) (xy 131.898962 -223.223002)
			(xy 131.950924 -223.234862) (xy 132.000538 -223.254334) (xy 132.046696 -223.280983) (xy 132.088367 -223.314214)
			(xy 132.124619 -223.353285) (xy 132.154643 -223.397322) (xy 132.177769 -223.445343) (xy 132.193479 -223.496273)
			(xy 132.201422 -223.548977) (xy 132.20192 -223.575626) (xy 132.201547 -223.601257) (xy 132.2014 -223.602275)
			(xy 132.430256 -223.602275) (xy 132.430256 -223.548977) (xy 132.438199 -223.496273) (xy 132.453909 -223.445343)
			(xy 132.477035 -223.397322) (xy 132.507059 -223.353285) (xy 132.543311 -223.314214) (xy 132.584982 -223.280983)
			(xy 132.63114 -223.254334) (xy 132.680754 -223.234862) (xy 132.732716 -223.223002) (xy 132.785866 -223.219019)
			(xy 132.839016 -223.223002) (xy 132.890978 -223.234862) (xy 132.940592 -223.254334) (xy 132.98675 -223.280983)
			(xy 133.028421 -223.314214) (xy 133.064673 -223.353285) (xy 133.094697 -223.397322) (xy 133.117823 -223.445343)
			(xy 133.133533 -223.496273) (xy 133.141476 -223.548977) (xy 133.141974 -223.575626) (xy 133.141476 -223.602275)
			(xy 133.133533 -223.654979) (xy 133.117823 -223.705909) (xy 133.094697 -223.75393) (xy 133.064673 -223.797967)
			(xy 133.028421 -223.837038) (xy 132.98675 -223.870269) (xy 132.940592 -223.896918) (xy 132.890978 -223.91639)
			(xy 132.839016 -223.92825) (xy 132.785866 -223.932234) (xy 132.732716 -223.92825) (xy 132.680754 -223.91639)
			(xy 132.63114 -223.896918) (xy 132.584982 -223.870269) (xy 132.543311 -223.837038) (xy 132.507059 -223.797967)
			(xy 132.477035 -223.75393) (xy 132.453909 -223.705909) (xy 132.438199 -223.654979) (xy 132.430256 -223.602275)
			(xy 132.2014 -223.602275) (xy 132.194207 -223.651991) (xy 132.179668 -223.701148) (xy 132.15823 -223.747712)
			(xy 132.130337 -223.790721) (xy 132.096564 -223.829285) (xy 132.057611 -223.862608) (xy 132.014282 -223.890002)
			(xy 131.967473 -223.910899) (xy 131.918151 -223.924868) (xy 131.892802 -223.928686) (xy 131.868164 -223.931988)
			(xy 131.695698 -224.230438) (xy 131.70535 -224.253552) (xy 131.713878 -224.27518) (xy 131.725861 -224.3201)
			(xy 131.731901 -224.366197) (xy 131.732274 -224.389442) (xy 131.959858 -224.389442) (xy 131.960356 -224.362793)
			(xy 131.968299 -224.310089) (xy 131.984009 -224.259159) (xy 132.007135 -224.211138) (xy 132.037159 -224.167101)
			(xy 132.073411 -224.12803) (xy 132.115082 -224.094799) (xy 132.16124 -224.06815) (xy 132.210854 -224.048678)
			(xy 132.262816 -224.036818) (xy 132.315966 -224.032835) (xy 132.369116 -224.036818) (xy 132.421078 -224.048678)
			(xy 132.470692 -224.06815) (xy 132.51685 -224.094799) (xy 132.558521 -224.12803) (xy 132.594773 -224.167101)
			(xy 132.624797 -224.211138) (xy 132.647923 -224.259159) (xy 132.663633 -224.310089) (xy 132.671576 -224.362793)
			(xy 132.672074 -224.389442) (xy 132.671688 -224.412687) (xy 132.665649 -224.458782) (xy 132.653665 -224.5037)
			(xy 132.64515 -224.525332) (xy 132.635498 -224.548446) (xy 132.807964 -224.846896) (xy 132.832602 -224.850198)
			(xy 132.857942 -224.854037) (xy 132.907248 -224.868024) (xy 132.95404 -224.888933) (xy 132.997353 -224.916332)
			(xy 133.036292 -224.949655) (xy 133.070053 -224.988214) (xy 133.09794 -225.031214) (xy 133.119377 -225.077767)
			(xy 133.133921 -225.126911) (xy 133.141272 -225.177632) (xy 133.14172 -225.203258) (xy 133.141222 -225.229907)
			(xy 133.370056 -225.229907) (xy 133.370056 -225.176609) (xy 133.377999 -225.123905) (xy 133.393709 -225.072975)
			(xy 133.416835 -225.024954) (xy 133.446859 -224.980917) (xy 133.483111 -224.941846) (xy 133.524782 -224.908615)
			(xy 133.57094 -224.881966) (xy 133.620554 -224.862494) (xy 133.672516 -224.850634) (xy 133.725666 -224.846651)
			(xy 133.778816 -224.850634) (xy 133.830778 -224.862494) (xy 133.880392 -224.881966) (xy 133.92655 -224.908615)
			(xy 133.968221 -224.941846) (xy 134.004473 -224.980917) (xy 134.034497 -225.024954) (xy 134.057623 -225.072975)
			(xy 134.073333 -225.123905) (xy 134.081276 -225.176609) (xy 134.081774 -225.203258) (xy 134.081276 -225.229907)
			(xy 134.073333 -225.282611) (xy 134.057623 -225.333541) (xy 134.034497 -225.381562) (xy 134.004473 -225.425599)
			(xy 133.968221 -225.46467) (xy 133.92655 -225.497901) (xy 133.880392 -225.52455) (xy 133.830778 -225.544022)
			(xy 133.778816 -225.555882) (xy 133.725666 -225.559866) (xy 133.672516 -225.555882) (xy 133.620554 -225.544022)
			(xy 133.57094 -225.52455) (xy 133.524782 -225.497901) (xy 133.483111 -225.46467) (xy 133.446859 -225.425599)
			(xy 133.416835 -225.381562) (xy 133.393709 -225.333541) (xy 133.377999 -225.282611) (xy 133.370056 -225.229907)
			(xy 133.141222 -225.229907) (xy 133.133279 -225.282611) (xy 133.117569 -225.333541) (xy 133.094443 -225.381562)
			(xy 133.064419 -225.425599) (xy 133.028167 -225.46467) (xy 132.986496 -225.497901) (xy 132.940338 -225.52455)
			(xy 132.890724 -225.544022) (xy 132.838762 -225.555882) (xy 132.785612 -225.559866) (xy 132.732462 -225.555882)
			(xy 132.6805 -225.544022) (xy 132.630886 -225.52455) (xy 132.584728 -225.497901) (xy 132.543057 -225.46467)
			(xy 132.506805 -225.425599) (xy 132.476781 -225.381562) (xy 132.453655 -225.333541) (xy 132.437945 -225.282611)
			(xy 132.430002 -225.229907) (xy 132.429504 -225.203258) (xy 132.429891 -225.180013) (xy 132.435931 -225.133918)
			(xy 132.447914 -225.089) (xy 132.456428 -225.067368) (xy 132.46608 -225.044254) (xy 132.293614 -224.745804)
			(xy 132.268976 -224.742502) (xy 132.243633 -224.73868) (xy 132.194327 -224.72469) (xy 132.147535 -224.703779)
			(xy 132.104223 -224.676378) (xy 132.065284 -224.643052) (xy 132.031523 -224.604491) (xy 132.003637 -224.56149)
			(xy 131.9822 -224.514936) (xy 131.967657 -224.46579) (xy 131.960306 -224.415068) (xy 131.959858 -224.389442)
			(xy 131.732274 -224.389442) (xy 131.731776 -224.416091) (xy 131.723833 -224.468795) (xy 131.708123 -224.519725)
			(xy 131.684997 -224.567746) (xy 131.654973 -224.611783) (xy 131.618721 -224.650854) (xy 131.57705 -224.684085)
			(xy 131.530892 -224.710734) (xy 131.481278 -224.730206) (xy 131.429316 -224.742066) (xy 131.376166 -224.74605)
			(xy 131.323016 -224.742066) (xy 131.271054 -224.730206) (xy 131.22144 -224.710734) (xy 131.175282 -224.684085)
			(xy 131.133611 -224.650854) (xy 131.097359 -224.611783) (xy 131.067335 -224.567746) (xy 131.044209 -224.519725)
			(xy 131.028499 -224.468795) (xy 131.020556 -224.416091) (xy 131.020058 -224.389442) (xy 130.792474 -224.389442)
			(xy 130.792088 -224.412687) (xy 130.786049 -224.458782) (xy 130.774065 -224.5037) (xy 130.76555 -224.525332)
			(xy 130.755898 -224.548446) (xy 130.928364 -224.846896) (xy 130.953002 -224.850198) (xy 130.978342 -224.854037)
			(xy 131.027648 -224.868024) (xy 131.07444 -224.888933) (xy 131.117753 -224.916332) (xy 131.156692 -224.949655)
			(xy 131.190453 -224.988214) (xy 131.21834 -225.031214) (xy 131.239777 -225.077767) (xy 131.254321 -225.126911)
			(xy 131.261672 -225.177632) (xy 131.26212 -225.203258) (xy 131.261622 -225.229907) (xy 131.490202 -225.229907)
			(xy 131.490202 -225.176609) (xy 131.498145 -225.123905) (xy 131.513855 -225.072975) (xy 131.536981 -225.024954)
			(xy 131.567005 -224.980917) (xy 131.603257 -224.941846) (xy 131.644928 -224.908615) (xy 131.691086 -224.881966)
			(xy 131.7407 -224.862494) (xy 131.792662 -224.850634) (xy 131.845812 -224.846651) (xy 131.898962 -224.850634)
			(xy 131.950924 -224.862494) (xy 132.000538 -224.881966) (xy 132.046696 -224.908615) (xy 132.088367 -224.941846)
			(xy 132.124619 -224.980917) (xy 132.154643 -225.024954) (xy 132.177769 -225.072975) (xy 132.193479 -225.123905)
			(xy 132.201422 -225.176609) (xy 132.20192 -225.203258) (xy 132.201422 -225.229907) (xy 132.193479 -225.282611)
			(xy 132.177769 -225.333541) (xy 132.154643 -225.381562) (xy 132.124619 -225.425599) (xy 132.088367 -225.46467)
			(xy 132.046696 -225.497901) (xy 132.000538 -225.52455) (xy 131.950924 -225.544022) (xy 131.898962 -225.555882)
			(xy 131.845812 -225.559866) (xy 131.792662 -225.555882) (xy 131.7407 -225.544022) (xy 131.691086 -225.52455)
			(xy 131.644928 -225.497901) (xy 131.603257 -225.46467) (xy 131.567005 -225.425599) (xy 131.536981 -225.381562)
			(xy 131.513855 -225.333541) (xy 131.498145 -225.282611) (xy 131.490202 -225.229907) (xy 131.261622 -225.229907)
			(xy 131.253679 -225.282611) (xy 131.237969 -225.333541) (xy 131.214843 -225.381562) (xy 131.184819 -225.425599)
			(xy 131.148567 -225.46467) (xy 131.106896 -225.497901) (xy 131.060738 -225.52455) (xy 131.011124 -225.544022)
			(xy 130.959162 -225.555882) (xy 130.906012 -225.559866) (xy 130.852862 -225.555882) (xy 130.8009 -225.544022)
			(xy 130.751286 -225.52455) (xy 130.705128 -225.497901) (xy 130.663457 -225.46467) (xy 130.627205 -225.425599)
			(xy 130.597181 -225.381562) (xy 130.574055 -225.333541) (xy 130.558345 -225.282611) (xy 130.550402 -225.229907)
			(xy 130.549904 -225.203258) (xy 130.550291 -225.180013) (xy 130.556331 -225.133918) (xy 130.568314 -225.089)
			(xy 130.576828 -225.067368) (xy 130.58648 -225.044254) (xy 130.414014 -224.745804) (xy 130.389376 -224.742502)
			(xy 130.364033 -224.73868) (xy 130.314727 -224.72469) (xy 130.267935 -224.703779) (xy 130.224623 -224.676378)
			(xy 130.185684 -224.643052) (xy 130.151923 -224.604491) (xy 130.124037 -224.56149) (xy 130.1026 -224.514936)
			(xy 130.088057 -224.46579) (xy 130.080706 -224.415068) (xy 130.080258 -224.389442) (xy 129.852674 -224.389442)
			(xy 129.852176 -224.416091) (xy 129.844233 -224.468795) (xy 129.828523 -224.519725) (xy 129.805397 -224.567746)
			(xy 129.775373 -224.611783) (xy 129.739121 -224.650854) (xy 129.69745 -224.684085) (xy 129.651292 -224.710734)
			(xy 129.601678 -224.730206) (xy 129.549716 -224.742066) (xy 129.496566 -224.74605) (xy 129.443416 -224.742066)
			(xy 129.391454 -224.730206) (xy 129.34184 -224.710734) (xy 129.295682 -224.684085) (xy 129.254011 -224.650854)
			(xy 129.217759 -224.611783) (xy 129.187735 -224.567746) (xy 129.164609 -224.519725) (xy 129.148899 -224.468795)
			(xy 129.140956 -224.416091) (xy 129.140458 -224.389442) (xy 128.912874 -224.389442) (xy 128.912488 -224.412687)
			(xy 128.906449 -224.458782) (xy 128.894465 -224.5037) (xy 128.88595 -224.525332) (xy 128.876298 -224.548446)
			(xy 129.048764 -224.846896) (xy 129.073402 -224.850198) (xy 129.098742 -224.854037) (xy 129.148048 -224.868024)
			(xy 129.19484 -224.888933) (xy 129.238153 -224.916332) (xy 129.277092 -224.949655) (xy 129.310853 -224.988214)
			(xy 129.33874 -225.031214) (xy 129.360177 -225.077767) (xy 129.374721 -225.126911) (xy 129.382072 -225.177632)
			(xy 129.38252 -225.203258) (xy 129.382022 -225.229907) (xy 129.610602 -225.229907) (xy 129.610602 -225.176609)
			(xy 129.618545 -225.123905) (xy 129.634255 -225.072975) (xy 129.657381 -225.024954) (xy 129.687405 -224.980917)
			(xy 129.723657 -224.941846) (xy 129.765328 -224.908615) (xy 129.811486 -224.881966) (xy 129.8611 -224.862494)
			(xy 129.913062 -224.850634) (xy 129.966212 -224.846651) (xy 130.019362 -224.850634) (xy 130.071324 -224.862494)
			(xy 130.120938 -224.881966) (xy 130.167096 -224.908615) (xy 130.208767 -224.941846) (xy 130.245019 -224.980917)
			(xy 130.275043 -225.024954) (xy 130.298169 -225.072975) (xy 130.313879 -225.123905) (xy 130.321822 -225.176609)
			(xy 130.32232 -225.203258) (xy 130.321822 -225.229907) (xy 130.313879 -225.282611) (xy 130.298169 -225.333541)
			(xy 130.275043 -225.381562) (xy 130.245019 -225.425599) (xy 130.208767 -225.46467) (xy 130.167096 -225.497901)
			(xy 130.120938 -225.52455) (xy 130.071324 -225.544022) (xy 130.019362 -225.555882) (xy 129.966212 -225.559866)
			(xy 129.913062 -225.555882) (xy 129.8611 -225.544022) (xy 129.811486 -225.52455) (xy 129.765328 -225.497901)
			(xy 129.723657 -225.46467) (xy 129.687405 -225.425599) (xy 129.657381 -225.381562) (xy 129.634255 -225.333541)
			(xy 129.618545 -225.282611) (xy 129.610602 -225.229907) (xy 129.382022 -225.229907) (xy 129.374079 -225.282611)
			(xy 129.358369 -225.333541) (xy 129.335243 -225.381562) (xy 129.305219 -225.425599) (xy 129.268967 -225.46467)
			(xy 129.227296 -225.497901) (xy 129.181138 -225.52455) (xy 129.131524 -225.544022) (xy 129.079562 -225.555882)
			(xy 129.026412 -225.559866) (xy 128.973262 -225.555882) (xy 128.9213 -225.544022) (xy 128.871686 -225.52455)
			(xy 128.825528 -225.497901) (xy 128.783857 -225.46467) (xy 128.747605 -225.425599) (xy 128.717581 -225.381562)
			(xy 128.694455 -225.333541) (xy 128.678745 -225.282611) (xy 128.670802 -225.229907) (xy 128.670304 -225.203258)
			(xy 128.670691 -225.180013) (xy 128.676731 -225.133918) (xy 128.688714 -225.089) (xy 128.697228 -225.067368)
			(xy 128.70688 -225.044254) (xy 128.534414 -224.745804) (xy 128.509776 -224.742502) (xy 128.484433 -224.73868)
			(xy 128.435127 -224.72469) (xy 128.388335 -224.703779) (xy 128.345023 -224.676378) (xy 128.306084 -224.643052)
			(xy 128.272323 -224.604491) (xy 128.244437 -224.56149) (xy 128.223 -224.514936) (xy 128.208457 -224.46579)
			(xy 128.201106 -224.415068) (xy 128.200658 -224.389442) (xy 127.973074 -224.389442) (xy 127.972576 -224.416091)
			(xy 127.964633 -224.468795) (xy 127.948923 -224.519725) (xy 127.925797 -224.567746) (xy 127.895773 -224.611783)
			(xy 127.859521 -224.650854) (xy 127.81785 -224.684085) (xy 127.771692 -224.710734) (xy 127.722078 -224.730206)
			(xy 127.670116 -224.742066) (xy 127.616966 -224.74605) (xy 127.563816 -224.742066) (xy 127.511854 -224.730206)
			(xy 127.46224 -224.710734) (xy 127.416082 -224.684085) (xy 127.374411 -224.650854) (xy 127.338159 -224.611783)
			(xy 127.308135 -224.567746) (xy 127.285009 -224.519725) (xy 127.269299 -224.468795) (xy 127.261356 -224.416091)
			(xy 127.260858 -224.389442) (xy 127.033274 -224.389442) (xy 127.032888 -224.412687) (xy 127.026849 -224.458782)
			(xy 127.014865 -224.5037) (xy 127.00635 -224.525332) (xy 126.996698 -224.548446) (xy 127.169164 -224.846896)
			(xy 127.193802 -224.850198) (xy 127.219142 -224.854037) (xy 127.268448 -224.868024) (xy 127.31524 -224.888933)
			(xy 127.358553 -224.916332) (xy 127.397492 -224.949655) (xy 127.431253 -224.988214) (xy 127.45914 -225.031214)
			(xy 127.480577 -225.077767) (xy 127.495121 -225.126911) (xy 127.502472 -225.177632) (xy 127.50292 -225.203258)
			(xy 127.502422 -225.229907) (xy 127.731002 -225.229907) (xy 127.731002 -225.176609) (xy 127.738945 -225.123905)
			(xy 127.754655 -225.072975) (xy 127.777781 -225.024954) (xy 127.807805 -224.980917) (xy 127.844057 -224.941846)
			(xy 127.885728 -224.908615) (xy 127.931886 -224.881966) (xy 127.9815 -224.862494) (xy 128.033462 -224.850634)
			(xy 128.086612 -224.846651) (xy 128.139762 -224.850634) (xy 128.191724 -224.862494) (xy 128.241338 -224.881966)
			(xy 128.287496 -224.908615) (xy 128.329167 -224.941846) (xy 128.365419 -224.980917) (xy 128.395443 -225.024954)
			(xy 128.418569 -225.072975) (xy 128.434279 -225.123905) (xy 128.442222 -225.176609) (xy 128.44272 -225.203258)
			(xy 128.442222 -225.229907) (xy 128.434279 -225.282611) (xy 128.418569 -225.333541) (xy 128.395443 -225.381562)
			(xy 128.365419 -225.425599) (xy 128.329167 -225.46467) (xy 128.287496 -225.497901) (xy 128.241338 -225.52455)
			(xy 128.191724 -225.544022) (xy 128.139762 -225.555882) (xy 128.086612 -225.559866) (xy 128.033462 -225.555882)
			(xy 127.9815 -225.544022) (xy 127.931886 -225.52455) (xy 127.885728 -225.497901) (xy 127.844057 -225.46467)
			(xy 127.807805 -225.425599) (xy 127.777781 -225.381562) (xy 127.754655 -225.333541) (xy 127.738945 -225.282611)
			(xy 127.731002 -225.229907) (xy 127.502422 -225.229907) (xy 127.494479 -225.282611) (xy 127.478769 -225.333541)
			(xy 127.455643 -225.381562) (xy 127.425619 -225.425599) (xy 127.389367 -225.46467) (xy 127.347696 -225.497901)
			(xy 127.301538 -225.52455) (xy 127.251924 -225.544022) (xy 127.199962 -225.555882) (xy 127.146812 -225.559866)
			(xy 127.093662 -225.555882) (xy 127.0417 -225.544022) (xy 126.992086 -225.52455) (xy 126.945928 -225.497901)
			(xy 126.904257 -225.46467) (xy 126.868005 -225.425599) (xy 126.837981 -225.381562) (xy 126.814855 -225.333541)
			(xy 126.799145 -225.282611) (xy 126.791202 -225.229907) (xy 126.790704 -225.203258) (xy 126.791091 -225.180013)
			(xy 126.797131 -225.133918) (xy 126.809114 -225.089) (xy 126.817628 -225.067368) (xy 126.82728 -225.044254)
			(xy 126.654814 -224.745804) (xy 126.630176 -224.742502) (xy 126.604833 -224.73868) (xy 126.555527 -224.72469)
			(xy 126.508735 -224.703779) (xy 126.465423 -224.676378) (xy 126.426484 -224.643052) (xy 126.392723 -224.604491)
			(xy 126.364837 -224.56149) (xy 126.3434 -224.514936) (xy 126.328857 -224.46579) (xy 126.321506 -224.415068)
			(xy 126.321058 -224.389442) (xy 126.093474 -224.389442) (xy 126.092976 -224.416091) (xy 126.085033 -224.468795)
			(xy 126.069323 -224.519725) (xy 126.046197 -224.567746) (xy 126.016173 -224.611783) (xy 125.979921 -224.650854)
			(xy 125.93825 -224.684085) (xy 125.892092 -224.710734) (xy 125.842478 -224.730206) (xy 125.790516 -224.742066)
			(xy 125.737366 -224.74605) (xy 125.684216 -224.742066) (xy 125.632254 -224.730206) (xy 125.58264 -224.710734)
			(xy 125.536482 -224.684085) (xy 125.494811 -224.650854) (xy 125.458559 -224.611783) (xy 125.428535 -224.567746)
			(xy 125.405409 -224.519725) (xy 125.389699 -224.468795) (xy 125.381756 -224.416091) (xy 125.381258 -224.389442)
			(xy 125.153674 -224.389442) (xy 125.153288 -224.412687) (xy 125.147249 -224.458782) (xy 125.135265 -224.5037)
			(xy 125.12675 -224.525332) (xy 125.117098 -224.548446) (xy 125.289564 -224.846896) (xy 125.314202 -224.850198)
			(xy 125.339542 -224.854037) (xy 125.388848 -224.868024) (xy 125.43564 -224.888933) (xy 125.478953 -224.916332)
			(xy 125.517892 -224.949655) (xy 125.551653 -224.988214) (xy 125.57954 -225.031214) (xy 125.600977 -225.077767)
			(xy 125.615521 -225.126911) (xy 125.622872 -225.177632) (xy 125.62332 -225.203258) (xy 125.622822 -225.229907)
			(xy 125.851402 -225.229907) (xy 125.851402 -225.176609) (xy 125.859345 -225.123905) (xy 125.875055 -225.072975)
			(xy 125.898181 -225.024954) (xy 125.928205 -224.980917) (xy 125.964457 -224.941846) (xy 126.006128 -224.908615)
			(xy 126.052286 -224.881966) (xy 126.1019 -224.862494) (xy 126.153862 -224.850634) (xy 126.207012 -224.846651)
			(xy 126.260162 -224.850634) (xy 126.312124 -224.862494) (xy 126.361738 -224.881966) (xy 126.407896 -224.908615)
			(xy 126.449567 -224.941846) (xy 126.485819 -224.980917) (xy 126.515843 -225.024954) (xy 126.538969 -225.072975)
			(xy 126.554679 -225.123905) (xy 126.562622 -225.176609) (xy 126.56312 -225.203258) (xy 126.562622 -225.229907)
			(xy 126.554679 -225.282611) (xy 126.538969 -225.333541) (xy 126.515843 -225.381562) (xy 126.485819 -225.425599)
			(xy 126.449567 -225.46467) (xy 126.407896 -225.497901) (xy 126.361738 -225.52455) (xy 126.312124 -225.544022)
			(xy 126.260162 -225.555882) (xy 126.207012 -225.559866) (xy 126.153862 -225.555882) (xy 126.1019 -225.544022)
			(xy 126.052286 -225.52455) (xy 126.006128 -225.497901) (xy 125.964457 -225.46467) (xy 125.928205 -225.425599)
			(xy 125.898181 -225.381562) (xy 125.875055 -225.333541) (xy 125.859345 -225.282611) (xy 125.851402 -225.229907)
			(xy 125.622822 -225.229907) (xy 125.614879 -225.282611) (xy 125.599169 -225.333541) (xy 125.576043 -225.381562)
			(xy 125.546019 -225.425599) (xy 125.509767 -225.46467) (xy 125.468096 -225.497901) (xy 125.421938 -225.52455)
			(xy 125.372324 -225.544022) (xy 125.320362 -225.555882) (xy 125.267212 -225.559866) (xy 125.214062 -225.555882)
			(xy 125.1621 -225.544022) (xy 125.112486 -225.52455) (xy 125.066328 -225.497901) (xy 125.024657 -225.46467)
			(xy 124.988405 -225.425599) (xy 124.958381 -225.381562) (xy 124.935255 -225.333541) (xy 124.919545 -225.282611)
			(xy 124.911602 -225.229907) (xy 124.911104 -225.203258) (xy 124.911491 -225.180013) (xy 124.917531 -225.133918)
			(xy 124.929514 -225.089) (xy 124.938028 -225.067368) (xy 124.94768 -225.044254) (xy 124.775214 -224.745804)
			(xy 124.750576 -224.742502) (xy 124.725233 -224.73868) (xy 124.675927 -224.72469) (xy 124.629135 -224.703779)
			(xy 124.585823 -224.676378) (xy 124.546884 -224.643052) (xy 124.513123 -224.604491) (xy 124.485237 -224.56149)
			(xy 124.4638 -224.514936) (xy 124.449257 -224.46579) (xy 124.441906 -224.415068) (xy 124.441458 -224.389442)
			(xy 124.213874 -224.389442) (xy 124.213376 -224.416091) (xy 124.205433 -224.468795) (xy 124.189723 -224.519725)
			(xy 124.166597 -224.567746) (xy 124.136573 -224.611783) (xy 124.100321 -224.650854) (xy 124.05865 -224.684085)
			(xy 124.012492 -224.710734) (xy 123.962878 -224.730206) (xy 123.910916 -224.742066) (xy 123.857766 -224.74605)
			(xy 123.804616 -224.742066) (xy 123.752654 -224.730206) (xy 123.70304 -224.710734) (xy 123.656882 -224.684085)
			(xy 123.615211 -224.650854) (xy 123.578959 -224.611783) (xy 123.548935 -224.567746) (xy 123.525809 -224.519725)
			(xy 123.510099 -224.468795) (xy 123.502156 -224.416091) (xy 123.501658 -224.389442) (xy 123.274074 -224.389442)
			(xy 123.273688 -224.412687) (xy 123.267649 -224.458782) (xy 123.255665 -224.5037) (xy 123.24715 -224.525332)
			(xy 123.237498 -224.548446) (xy 123.409964 -224.846896) (xy 123.434602 -224.850198) (xy 123.459942 -224.854037)
			(xy 123.509248 -224.868024) (xy 123.55604 -224.888933) (xy 123.599353 -224.916332) (xy 123.638292 -224.949655)
			(xy 123.672053 -224.988214) (xy 123.69994 -225.031214) (xy 123.721377 -225.077767) (xy 123.735921 -225.126911)
			(xy 123.743272 -225.177632) (xy 123.74372 -225.203258) (xy 123.743222 -225.229907) (xy 123.971802 -225.229907)
			(xy 123.971802 -225.176609) (xy 123.979745 -225.123905) (xy 123.995455 -225.072975) (xy 124.018581 -225.024954)
			(xy 124.048605 -224.980917) (xy 124.084857 -224.941846) (xy 124.126528 -224.908615) (xy 124.172686 -224.881966)
			(xy 124.2223 -224.862494) (xy 124.274262 -224.850634) (xy 124.327412 -224.846651) (xy 124.380562 -224.850634)
			(xy 124.432524 -224.862494) (xy 124.482138 -224.881966) (xy 124.528296 -224.908615) (xy 124.569967 -224.941846)
			(xy 124.606219 -224.980917) (xy 124.636243 -225.024954) (xy 124.659369 -225.072975) (xy 124.675079 -225.123905)
			(xy 124.683022 -225.176609) (xy 124.68352 -225.203258) (xy 124.683022 -225.229907) (xy 124.675079 -225.282611)
			(xy 124.659369 -225.333541) (xy 124.636243 -225.381562) (xy 124.606219 -225.425599) (xy 124.569967 -225.46467)
			(xy 124.528296 -225.497901) (xy 124.482138 -225.52455) (xy 124.432524 -225.544022) (xy 124.380562 -225.555882)
			(xy 124.327412 -225.559866) (xy 124.274262 -225.555882) (xy 124.2223 -225.544022) (xy 124.172686 -225.52455)
			(xy 124.126528 -225.497901) (xy 124.084857 -225.46467) (xy 124.048605 -225.425599) (xy 124.018581 -225.381562)
			(xy 123.995455 -225.333541) (xy 123.979745 -225.282611) (xy 123.971802 -225.229907) (xy 123.743222 -225.229907)
			(xy 123.735279 -225.282611) (xy 123.719569 -225.333541) (xy 123.696443 -225.381562) (xy 123.666419 -225.425599)
			(xy 123.630167 -225.46467) (xy 123.588496 -225.497901) (xy 123.542338 -225.52455) (xy 123.492724 -225.544022)
			(xy 123.440762 -225.555882) (xy 123.387612 -225.559866) (xy 123.334462 -225.555882) (xy 123.2825 -225.544022)
			(xy 123.232886 -225.52455) (xy 123.186728 -225.497901) (xy 123.145057 -225.46467) (xy 123.108805 -225.425599)
			(xy 123.078781 -225.381562) (xy 123.055655 -225.333541) (xy 123.039945 -225.282611) (xy 123.032002 -225.229907)
			(xy 123.031504 -225.203258) (xy 123.031891 -225.180013) (xy 123.037931 -225.133918) (xy 123.049914 -225.089)
			(xy 123.058428 -225.067368) (xy 123.06808 -225.044254) (xy 122.895614 -224.745804) (xy 122.870976 -224.742502)
			(xy 122.845633 -224.73868) (xy 122.796327 -224.72469) (xy 122.749535 -224.703779) (xy 122.706223 -224.676378)
			(xy 122.667284 -224.643052) (xy 122.633523 -224.604491) (xy 122.605637 -224.56149) (xy 122.5842 -224.514936)
			(xy 122.569657 -224.46579) (xy 122.562306 -224.415068) (xy 122.561858 -224.389442) (xy 122.334274 -224.389442)
			(xy 122.333776 -224.416091) (xy 122.325833 -224.468795) (xy 122.310123 -224.519725) (xy 122.286997 -224.567746)
			(xy 122.256973 -224.611783) (xy 122.220721 -224.650854) (xy 122.17905 -224.684085) (xy 122.132892 -224.710734)
			(xy 122.083278 -224.730206) (xy 122.031316 -224.742066) (xy 121.978166 -224.74605) (xy 121.925016 -224.742066)
			(xy 121.873054 -224.730206) (xy 121.82344 -224.710734) (xy 121.777282 -224.684085) (xy 121.735611 -224.650854)
			(xy 121.699359 -224.611783) (xy 121.669335 -224.567746) (xy 121.646209 -224.519725) (xy 121.630499 -224.468795)
			(xy 121.622556 -224.416091) (xy 121.622058 -224.389442) (xy 121.394474 -224.389442) (xy 121.394088 -224.412687)
			(xy 121.388049 -224.458782) (xy 121.376065 -224.5037) (xy 121.36755 -224.525332) (xy 121.357898 -224.548446)
			(xy 121.530364 -224.846896) (xy 121.555002 -224.850198) (xy 121.580342 -224.854037) (xy 121.629648 -224.868024)
			(xy 121.67644 -224.888933) (xy 121.719753 -224.916332) (xy 121.758692 -224.949655) (xy 121.792453 -224.988214)
			(xy 121.82034 -225.031214) (xy 121.841777 -225.077767) (xy 121.856321 -225.126911) (xy 121.863672 -225.177632)
			(xy 121.86412 -225.203258) (xy 121.863622 -225.229907) (xy 122.092202 -225.229907) (xy 122.092202 -225.176609)
			(xy 122.100145 -225.123905) (xy 122.115855 -225.072975) (xy 122.138981 -225.024954) (xy 122.169005 -224.980917)
			(xy 122.205257 -224.941846) (xy 122.246928 -224.908615) (xy 122.293086 -224.881966) (xy 122.3427 -224.862494)
			(xy 122.394662 -224.850634) (xy 122.447812 -224.846651) (xy 122.500962 -224.850634) (xy 122.552924 -224.862494)
			(xy 122.602538 -224.881966) (xy 122.648696 -224.908615) (xy 122.690367 -224.941846) (xy 122.726619 -224.980917)
			(xy 122.756643 -225.024954) (xy 122.779769 -225.072975) (xy 122.795479 -225.123905) (xy 122.803422 -225.176609)
			(xy 122.80392 -225.203258) (xy 122.803422 -225.229907) (xy 122.795479 -225.282611) (xy 122.779769 -225.333541)
			(xy 122.756643 -225.381562) (xy 122.726619 -225.425599) (xy 122.690367 -225.46467) (xy 122.648696 -225.497901)
			(xy 122.602538 -225.52455) (xy 122.552924 -225.544022) (xy 122.500962 -225.555882) (xy 122.447812 -225.559866)
			(xy 122.394662 -225.555882) (xy 122.3427 -225.544022) (xy 122.293086 -225.52455) (xy 122.246928 -225.497901)
			(xy 122.205257 -225.46467) (xy 122.169005 -225.425599) (xy 122.138981 -225.381562) (xy 122.115855 -225.333541)
			(xy 122.100145 -225.282611) (xy 122.092202 -225.229907) (xy 121.863622 -225.229907) (xy 121.855679 -225.282611)
			(xy 121.839969 -225.333541) (xy 121.816843 -225.381562) (xy 121.786819 -225.425599) (xy 121.750567 -225.46467)
			(xy 121.708896 -225.497901) (xy 121.662738 -225.52455) (xy 121.613124 -225.544022) (xy 121.561162 -225.555882)
			(xy 121.508012 -225.559866) (xy 121.454862 -225.555882) (xy 121.4029 -225.544022) (xy 121.353286 -225.52455)
			(xy 121.307128 -225.497901) (xy 121.265457 -225.46467) (xy 121.229205 -225.425599) (xy 121.199181 -225.381562)
			(xy 121.176055 -225.333541) (xy 121.160345 -225.282611) (xy 121.152402 -225.229907) (xy 121.151904 -225.203258)
			(xy 121.152291 -225.180013) (xy 121.158331 -225.133918) (xy 121.170314 -225.089) (xy 121.178828 -225.067368)
			(xy 121.18848 -225.044254) (xy 121.016014 -224.745804) (xy 120.991376 -224.742502) (xy 120.966033 -224.73868)
			(xy 120.916727 -224.72469) (xy 120.869935 -224.703779) (xy 120.826623 -224.676378) (xy 120.787684 -224.643052)
			(xy 120.753923 -224.604491) (xy 120.726037 -224.56149) (xy 120.7046 -224.514936) (xy 120.690057 -224.46579)
			(xy 120.682706 -224.415068) (xy 120.682258 -224.389442) (xy 120.454674 -224.389442) (xy 120.454176 -224.416091)
			(xy 120.446233 -224.468795) (xy 120.430523 -224.519725) (xy 120.407397 -224.567746) (xy 120.377373 -224.611783)
			(xy 120.341121 -224.650854) (xy 120.29945 -224.684085) (xy 120.253292 -224.710734) (xy 120.203678 -224.730206)
			(xy 120.151716 -224.742066) (xy 120.098566 -224.74605) (xy 120.045416 -224.742066) (xy 119.993454 -224.730206)
			(xy 119.94384 -224.710734) (xy 119.897682 -224.684085) (xy 119.856011 -224.650854) (xy 119.819759 -224.611783)
			(xy 119.789735 -224.567746) (xy 119.766609 -224.519725) (xy 119.750899 -224.468795) (xy 119.742956 -224.416091)
			(xy 119.742458 -224.389442) (xy 119.514874 -224.389442) (xy 119.514488 -224.412687) (xy 119.508449 -224.458782)
			(xy 119.496465 -224.5037) (xy 119.48795 -224.525332) (xy 119.478298 -224.548446) (xy 119.650764 -224.846896)
			(xy 119.675402 -224.850198) (xy 119.700742 -224.854037) (xy 119.750048 -224.868024) (xy 119.79684 -224.888933)
			(xy 119.840153 -224.916332) (xy 119.879092 -224.949655) (xy 119.912853 -224.988214) (xy 119.94074 -225.031214)
			(xy 119.962177 -225.077767) (xy 119.976721 -225.126911) (xy 119.984072 -225.177632) (xy 119.98452 -225.203258)
			(xy 119.984022 -225.229907) (xy 120.212602 -225.229907) (xy 120.212602 -225.176609) (xy 120.220545 -225.123905)
			(xy 120.236255 -225.072975) (xy 120.259381 -225.024954) (xy 120.289405 -224.980917) (xy 120.325657 -224.941846)
			(xy 120.367328 -224.908615) (xy 120.413486 -224.881966) (xy 120.4631 -224.862494) (xy 120.515062 -224.850634)
			(xy 120.568212 -224.846651) (xy 120.621362 -224.850634) (xy 120.673324 -224.862494) (xy 120.722938 -224.881966)
			(xy 120.769096 -224.908615) (xy 120.810767 -224.941846) (xy 120.847019 -224.980917) (xy 120.877043 -225.024954)
			(xy 120.900169 -225.072975) (xy 120.915879 -225.123905) (xy 120.923822 -225.176609) (xy 120.92432 -225.203258)
			(xy 120.923822 -225.229907) (xy 120.915879 -225.282611) (xy 120.900169 -225.333541) (xy 120.877043 -225.381562)
			(xy 120.847019 -225.425599) (xy 120.810767 -225.46467) (xy 120.769096 -225.497901) (xy 120.722938 -225.52455)
			(xy 120.673324 -225.544022) (xy 120.621362 -225.555882) (xy 120.568212 -225.559866) (xy 120.515062 -225.555882)
			(xy 120.4631 -225.544022) (xy 120.413486 -225.52455) (xy 120.367328 -225.497901) (xy 120.325657 -225.46467)
			(xy 120.289405 -225.425599) (xy 120.259381 -225.381562) (xy 120.236255 -225.333541) (xy 120.220545 -225.282611)
			(xy 120.212602 -225.229907) (xy 119.984022 -225.229907) (xy 119.976079 -225.282611) (xy 119.960369 -225.333541)
			(xy 119.937243 -225.381562) (xy 119.907219 -225.425599) (xy 119.870967 -225.46467) (xy 119.829296 -225.497901)
			(xy 119.783138 -225.52455) (xy 119.733524 -225.544022) (xy 119.681562 -225.555882) (xy 119.628412 -225.559866)
			(xy 119.575262 -225.555882) (xy 119.5233 -225.544022) (xy 119.473686 -225.52455) (xy 119.427528 -225.497901)
			(xy 119.385857 -225.46467) (xy 119.349605 -225.425599) (xy 119.319581 -225.381562) (xy 119.296455 -225.333541)
			(xy 119.280745 -225.282611) (xy 119.272802 -225.229907) (xy 119.272304 -225.203258) (xy 119.272691 -225.180013)
			(xy 119.278731 -225.133918) (xy 119.290714 -225.089) (xy 119.299228 -225.067368) (xy 119.30888 -225.044254)
			(xy 119.136414 -224.745804) (xy 119.111776 -224.742502) (xy 119.086433 -224.73868) (xy 119.037127 -224.72469)
			(xy 118.990335 -224.703779) (xy 118.947023 -224.676378) (xy 118.908084 -224.643052) (xy 118.874323 -224.604491)
			(xy 118.846437 -224.56149) (xy 118.825 -224.514936) (xy 118.810457 -224.46579) (xy 118.803106 -224.415068)
			(xy 118.802658 -224.389442) (xy 118.575074 -224.389442) (xy 118.574576 -224.416091) (xy 118.566633 -224.468795)
			(xy 118.550923 -224.519725) (xy 118.527797 -224.567746) (xy 118.497773 -224.611783) (xy 118.461521 -224.650854)
			(xy 118.41985 -224.684085) (xy 118.373692 -224.710734) (xy 118.324078 -224.730206) (xy 118.272116 -224.742066)
			(xy 118.218966 -224.74605) (xy 118.165816 -224.742066) (xy 118.113854 -224.730206) (xy 118.06424 -224.710734)
			(xy 118.018082 -224.684085) (xy 117.976411 -224.650854) (xy 117.940159 -224.611783) (xy 117.910135 -224.567746)
			(xy 117.887009 -224.519725) (xy 117.871299 -224.468795) (xy 117.863356 -224.416091) (xy 117.862858 -224.389442)
			(xy 117.635274 -224.389442) (xy 117.634888 -224.412687) (xy 117.628849 -224.458782) (xy 117.616865 -224.5037)
			(xy 117.60835 -224.525332) (xy 117.598698 -224.548446) (xy 117.771164 -224.846896) (xy 117.795802 -224.850198)
			(xy 117.821142 -224.854037) (xy 117.870448 -224.868024) (xy 117.91724 -224.888933) (xy 117.960553 -224.916332)
			(xy 117.999492 -224.949655) (xy 118.033253 -224.988214) (xy 118.06114 -225.031214) (xy 118.082577 -225.077767)
			(xy 118.097121 -225.126911) (xy 118.104472 -225.177632) (xy 118.10492 -225.203258) (xy 118.104422 -225.229907)
			(xy 118.333002 -225.229907) (xy 118.333002 -225.176609) (xy 118.340945 -225.123905) (xy 118.356655 -225.072975)
			(xy 118.379781 -225.024954) (xy 118.409805 -224.980917) (xy 118.446057 -224.941846) (xy 118.487728 -224.908615)
			(xy 118.533886 -224.881966) (xy 118.5835 -224.862494) (xy 118.635462 -224.850634) (xy 118.688612 -224.846651)
			(xy 118.741762 -224.850634) (xy 118.793724 -224.862494) (xy 118.843338 -224.881966) (xy 118.889496 -224.908615)
			(xy 118.931167 -224.941846) (xy 118.967419 -224.980917) (xy 118.997443 -225.024954) (xy 119.020569 -225.072975)
			(xy 119.036279 -225.123905) (xy 119.044222 -225.176609) (xy 119.04472 -225.203258) (xy 119.044222 -225.229907)
			(xy 119.036279 -225.282611) (xy 119.020569 -225.333541) (xy 118.997443 -225.381562) (xy 118.967419 -225.425599)
			(xy 118.931167 -225.46467) (xy 118.889496 -225.497901) (xy 118.843338 -225.52455) (xy 118.793724 -225.544022)
			(xy 118.741762 -225.555882) (xy 118.688612 -225.559866) (xy 118.635462 -225.555882) (xy 118.5835 -225.544022)
			(xy 118.533886 -225.52455) (xy 118.487728 -225.497901) (xy 118.446057 -225.46467) (xy 118.409805 -225.425599)
			(xy 118.379781 -225.381562) (xy 118.356655 -225.333541) (xy 118.340945 -225.282611) (xy 118.333002 -225.229907)
			(xy 118.104422 -225.229907) (xy 118.096479 -225.282611) (xy 118.080769 -225.333541) (xy 118.057643 -225.381562)
			(xy 118.027619 -225.425599) (xy 117.991367 -225.46467) (xy 117.949696 -225.497901) (xy 117.903538 -225.52455)
			(xy 117.853924 -225.544022) (xy 117.801962 -225.555882) (xy 117.748812 -225.559866) (xy 117.695662 -225.555882)
			(xy 117.6437 -225.544022) (xy 117.594086 -225.52455) (xy 117.547928 -225.497901) (xy 117.506257 -225.46467)
			(xy 117.470005 -225.425599) (xy 117.439981 -225.381562) (xy 117.416855 -225.333541) (xy 117.401145 -225.282611)
			(xy 117.393202 -225.229907) (xy 117.392704 -225.203258) (xy 117.393091 -225.180013) (xy 117.399131 -225.133918)
			(xy 117.411114 -225.089) (xy 117.419628 -225.067368) (xy 117.42928 -225.044254) (xy 117.256814 -224.745804)
			(xy 117.232176 -224.742502) (xy 117.206833 -224.73868) (xy 117.157527 -224.72469) (xy 117.110735 -224.703779)
			(xy 117.067423 -224.676378) (xy 117.028484 -224.643052) (xy 116.994723 -224.604491) (xy 116.966837 -224.56149)
			(xy 116.9454 -224.514936) (xy 116.930857 -224.46579) (xy 116.923506 -224.415068) (xy 116.923058 -224.389442)
			(xy 116.695474 -224.389442) (xy 116.694976 -224.416091) (xy 116.687033 -224.468795) (xy 116.671323 -224.519725)
			(xy 116.648197 -224.567746) (xy 116.618173 -224.611783) (xy 116.581921 -224.650854) (xy 116.54025 -224.684085)
			(xy 116.494092 -224.710734) (xy 116.444478 -224.730206) (xy 116.392516 -224.742066) (xy 116.339366 -224.74605)
			(xy 116.286216 -224.742066) (xy 116.234254 -224.730206) (xy 116.18464 -224.710734) (xy 116.138482 -224.684085)
			(xy 116.096811 -224.650854) (xy 116.060559 -224.611783) (xy 116.030535 -224.567746) (xy 116.007409 -224.519725)
			(xy 115.991699 -224.468795) (xy 115.983756 -224.416091) (xy 115.983258 -224.389442) (xy 115.755674 -224.389442)
			(xy 115.755288 -224.412687) (xy 115.749249 -224.458782) (xy 115.737265 -224.5037) (xy 115.72875 -224.525332)
			(xy 115.719098 -224.548446) (xy 115.891564 -224.846896) (xy 115.916202 -224.850198) (xy 115.941542 -224.854037)
			(xy 115.990848 -224.868024) (xy 116.03764 -224.888933) (xy 116.080953 -224.916332) (xy 116.119892 -224.949655)
			(xy 116.153653 -224.988214) (xy 116.18154 -225.031214) (xy 116.202977 -225.077767) (xy 116.217521 -225.126911)
			(xy 116.224872 -225.177632) (xy 116.22532 -225.203258) (xy 116.224822 -225.229907) (xy 116.453402 -225.229907)
			(xy 116.453402 -225.176609) (xy 116.461345 -225.123905) (xy 116.477055 -225.072975) (xy 116.500181 -225.024954)
			(xy 116.530205 -224.980917) (xy 116.566457 -224.941846) (xy 116.608128 -224.908615) (xy 116.654286 -224.881966)
			(xy 116.7039 -224.862494) (xy 116.755862 -224.850634) (xy 116.809012 -224.846651) (xy 116.862162 -224.850634)
			(xy 116.914124 -224.862494) (xy 116.963738 -224.881966) (xy 117.009896 -224.908615) (xy 117.051567 -224.941846)
			(xy 117.087819 -224.980917) (xy 117.117843 -225.024954) (xy 117.140969 -225.072975) (xy 117.156679 -225.123905)
			(xy 117.164622 -225.176609) (xy 117.16512 -225.203258) (xy 117.164622 -225.229907) (xy 117.156679 -225.282611)
			(xy 117.140969 -225.333541) (xy 117.117843 -225.381562) (xy 117.087819 -225.425599) (xy 117.051567 -225.46467)
			(xy 117.009896 -225.497901) (xy 116.963738 -225.52455) (xy 116.914124 -225.544022) (xy 116.862162 -225.555882)
			(xy 116.809012 -225.559866) (xy 116.755862 -225.555882) (xy 116.7039 -225.544022) (xy 116.654286 -225.52455)
			(xy 116.608128 -225.497901) (xy 116.566457 -225.46467) (xy 116.530205 -225.425599) (xy 116.500181 -225.381562)
			(xy 116.477055 -225.333541) (xy 116.461345 -225.282611) (xy 116.453402 -225.229907) (xy 116.224822 -225.229907)
			(xy 116.216879 -225.282611) (xy 116.201169 -225.333541) (xy 116.178043 -225.381562) (xy 116.148019 -225.425599)
			(xy 116.111767 -225.46467) (xy 116.070096 -225.497901) (xy 116.023938 -225.52455) (xy 115.974324 -225.544022)
			(xy 115.922362 -225.555882) (xy 115.869212 -225.559866) (xy 115.816062 -225.555882) (xy 115.7641 -225.544022)
			(xy 115.714486 -225.52455) (xy 115.668328 -225.497901) (xy 115.626657 -225.46467) (xy 115.590405 -225.425599)
			(xy 115.560381 -225.381562) (xy 115.537255 -225.333541) (xy 115.521545 -225.282611) (xy 115.513602 -225.229907)
			(xy 115.513104 -225.203258) (xy 115.513491 -225.180013) (xy 115.519531 -225.133918) (xy 115.531514 -225.089)
			(xy 115.540028 -225.067368) (xy 115.54968 -225.044254) (xy 115.377214 -224.745804) (xy 115.352576 -224.742502)
			(xy 115.327233 -224.73868) (xy 115.277927 -224.72469) (xy 115.231135 -224.703779) (xy 115.187823 -224.676378)
			(xy 115.148884 -224.643052) (xy 115.115123 -224.604491) (xy 115.087237 -224.56149) (xy 115.0658 -224.514936)
			(xy 115.051257 -224.46579) (xy 115.043906 -224.415068) (xy 115.043458 -224.389442) (xy 114.815874 -224.389442)
			(xy 114.815376 -224.416091) (xy 114.807433 -224.468795) (xy 114.791723 -224.519725) (xy 114.768597 -224.567746)
			(xy 114.738573 -224.611783) (xy 114.702321 -224.650854) (xy 114.66065 -224.684085) (xy 114.614492 -224.710734)
			(xy 114.564878 -224.730206) (xy 114.512916 -224.742066) (xy 114.459766 -224.74605) (xy 114.406616 -224.742066)
			(xy 114.354654 -224.730206) (xy 114.30504 -224.710734) (xy 114.258882 -224.684085) (xy 114.217211 -224.650854)
			(xy 114.180959 -224.611783) (xy 114.150935 -224.567746) (xy 114.127809 -224.519725) (xy 114.112099 -224.468795)
			(xy 114.104156 -224.416091) (xy 114.103658 -224.389442) (xy 113.876074 -224.389442) (xy 113.875688 -224.412687)
			(xy 113.869649 -224.458782) (xy 113.857665 -224.5037) (xy 113.84915 -224.525332) (xy 113.839498 -224.548446)
			(xy 114.011964 -224.846896) (xy 114.036602 -224.850198) (xy 114.061942 -224.854037) (xy 114.111248 -224.868024)
			(xy 114.15804 -224.888933) (xy 114.201353 -224.916332) (xy 114.240292 -224.949655) (xy 114.274053 -224.988214)
			(xy 114.30194 -225.031214) (xy 114.323377 -225.077767) (xy 114.337921 -225.126911) (xy 114.345272 -225.177632)
			(xy 114.34572 -225.203258) (xy 114.345222 -225.229907) (xy 114.573802 -225.229907) (xy 114.573802 -225.176609)
			(xy 114.581745 -225.123905) (xy 114.597455 -225.072975) (xy 114.620581 -225.024954) (xy 114.650605 -224.980917)
			(xy 114.686857 -224.941846) (xy 114.728528 -224.908615) (xy 114.774686 -224.881966) (xy 114.8243 -224.862494)
			(xy 114.876262 -224.850634) (xy 114.929412 -224.846651) (xy 114.982562 -224.850634) (xy 115.034524 -224.862494)
			(xy 115.084138 -224.881966) (xy 115.130296 -224.908615) (xy 115.171967 -224.941846) (xy 115.208219 -224.980917)
			(xy 115.238243 -225.024954) (xy 115.261369 -225.072975) (xy 115.277079 -225.123905) (xy 115.285022 -225.176609)
			(xy 115.28552 -225.203258) (xy 115.285022 -225.229907) (xy 115.277079 -225.282611) (xy 115.261369 -225.333541)
			(xy 115.238243 -225.381562) (xy 115.208219 -225.425599) (xy 115.171967 -225.46467) (xy 115.130296 -225.497901)
			(xy 115.084138 -225.52455) (xy 115.034524 -225.544022) (xy 114.982562 -225.555882) (xy 114.929412 -225.559866)
			(xy 114.876262 -225.555882) (xy 114.8243 -225.544022) (xy 114.774686 -225.52455) (xy 114.728528 -225.497901)
			(xy 114.686857 -225.46467) (xy 114.650605 -225.425599) (xy 114.620581 -225.381562) (xy 114.597455 -225.333541)
			(xy 114.581745 -225.282611) (xy 114.573802 -225.229907) (xy 114.345222 -225.229907) (xy 114.337279 -225.282611)
			(xy 114.321569 -225.333541) (xy 114.298443 -225.381562) (xy 114.268419 -225.425599) (xy 114.232167 -225.46467)
			(xy 114.190496 -225.497901) (xy 114.144338 -225.52455) (xy 114.094724 -225.544022) (xy 114.042762 -225.555882)
			(xy 113.989612 -225.559866) (xy 113.936462 -225.555882) (xy 113.8845 -225.544022) (xy 113.834886 -225.52455)
			(xy 113.788728 -225.497901) (xy 113.747057 -225.46467) (xy 113.710805 -225.425599) (xy 113.680781 -225.381562)
			(xy 113.657655 -225.333541) (xy 113.641945 -225.282611) (xy 113.634002 -225.229907) (xy 113.633504 -225.203258)
			(xy 113.633891 -225.180013) (xy 113.639931 -225.133918) (xy 113.651914 -225.089) (xy 113.660428 -225.067368)
			(xy 113.67008 -225.044254) (xy 113.497614 -224.745804) (xy 113.472976 -224.742502) (xy 113.447633 -224.73868)
			(xy 113.398327 -224.72469) (xy 113.351535 -224.703779) (xy 113.308223 -224.676378) (xy 113.269284 -224.643052)
			(xy 113.235523 -224.604491) (xy 113.207637 -224.56149) (xy 113.1862 -224.514936) (xy 113.171657 -224.46579)
			(xy 113.164306 -224.415068) (xy 113.163858 -224.389442) (xy 112.936274 -224.389442) (xy 112.935776 -224.416091)
			(xy 112.927833 -224.468795) (xy 112.912123 -224.519725) (xy 112.888997 -224.567746) (xy 112.858973 -224.611783)
			(xy 112.822721 -224.650854) (xy 112.78105 -224.684085) (xy 112.734892 -224.710734) (xy 112.685278 -224.730206)
			(xy 112.633316 -224.742066) (xy 112.580166 -224.74605) (xy 112.527016 -224.742066) (xy 112.475054 -224.730206)
			(xy 112.42544 -224.710734) (xy 112.379282 -224.684085) (xy 112.337611 -224.650854) (xy 112.301359 -224.611783)
			(xy 112.271335 -224.567746) (xy 112.248209 -224.519725) (xy 112.232499 -224.468795) (xy 112.224556 -224.416091)
			(xy 112.224058 -224.389442) (xy 111.996474 -224.389442) (xy 111.996096 -224.412686) (xy 111.990045 -224.45878)
			(xy 111.978052 -224.503695) (xy 111.96955 -224.525332) (xy 111.959898 -224.548446) (xy 112.132364 -224.846896)
			(xy 112.157002 -224.850198) (xy 112.182348 -224.854017) (xy 112.231665 -224.867987) (xy 112.278469 -224.888886)
			(xy 112.321791 -224.91628) (xy 112.360737 -224.949605) (xy 112.394501 -224.98817) (xy 112.422385 -225.03118)
			(xy 112.443813 -225.077743) (xy 112.458341 -225.126898) (xy 112.46567 -225.177629) (xy 112.46612 -225.203258)
			(xy 112.465628 -225.229907) (xy 112.694202 -225.229907) (xy 112.694202 -225.176609) (xy 112.702145 -225.123905)
			(xy 112.717855 -225.072975) (xy 112.740981 -225.024954) (xy 112.771005 -224.980917) (xy 112.807257 -224.941846)
			(xy 112.848928 -224.908615) (xy 112.895086 -224.881966) (xy 112.9447 -224.862494) (xy 112.996662 -224.850634)
			(xy 113.049812 -224.846651) (xy 113.102962 -224.850634) (xy 113.154924 -224.862494) (xy 113.204538 -224.881966)
			(xy 113.250696 -224.908615) (xy 113.292367 -224.941846) (xy 113.328619 -224.980917) (xy 113.358643 -225.024954)
			(xy 113.381769 -225.072975) (xy 113.397479 -225.123905) (xy 113.405422 -225.176609) (xy 113.40592 -225.203258)
			(xy 113.405422 -225.229907) (xy 113.397479 -225.282611) (xy 113.381769 -225.333541) (xy 113.358643 -225.381562)
			(xy 113.328619 -225.425599) (xy 113.292367 -225.46467) (xy 113.250696 -225.497901) (xy 113.204538 -225.52455)
			(xy 113.154924 -225.544022) (xy 113.102962 -225.555882) (xy 113.049812 -225.559866) (xy 112.996662 -225.555882)
			(xy 112.9447 -225.544022) (xy 112.895086 -225.52455) (xy 112.848928 -225.497901) (xy 112.807257 -225.46467)
			(xy 112.771005 -225.425599) (xy 112.740981 -225.381562) (xy 112.717855 -225.333541) (xy 112.702145 -225.282611)
			(xy 112.694202 -225.229907) (xy 112.465628 -225.229907) (xy 112.465603 -225.231246) (xy 112.456853 -225.286533)
			(xy 112.439561 -225.339771) (xy 112.414153 -225.389648) (xy 112.381255 -225.434936) (xy 112.341677 -225.47452)
			(xy 112.296394 -225.507425) (xy 112.246521 -225.53284) (xy 112.193286 -225.55014) (xy 112.138 -225.558899)
			(xy 112.110012 -225.559366) (xy 112.086686 -225.558968) (xy 112.040436 -225.552857) (xy 112.01781 -225.547174)
			(xy 112.004837 -225.544093) (xy 111.97818 -225.544064) (xy 111.952425 -225.550937) (xy 111.929326 -225.564243)
			(xy 111.910459 -225.583074) (xy 111.89711 -225.606147) (xy 111.890189 -225.63189) (xy 111.889794 -225.645218)
			(xy 111.889794 -225.763074) (xy 111.907845 -225.78144) (xy 111.939008 -225.822436) (xy 111.963944 -225.867491)
			(xy 111.982136 -225.915666) (xy 111.993203 -225.965958) (xy 111.996916 -226.01732) (xy 111.994986 -226.043977)
			(xy 112.224556 -226.043977) (xy 112.224556 -225.990679) (xy 112.232499 -225.937975) (xy 112.248209 -225.887045)
			(xy 112.271335 -225.839024) (xy 112.301359 -225.794987) (xy 112.337611 -225.755916) (xy 112.379282 -225.722685)
			(xy 112.42544 -225.696036) (xy 112.475054 -225.676564) (xy 112.527016 -225.664704) (xy 112.580166 -225.660721)
			(xy 112.633316 -225.664704) (xy 112.685278 -225.676564) (xy 112.734892 -225.696036) (xy 112.78105 -225.722685)
			(xy 112.822721 -225.755916) (xy 112.858973 -225.794987) (xy 112.888997 -225.839024) (xy 112.912123 -225.887045)
			(xy 112.927833 -225.937975) (xy 112.935776 -225.990679) (xy 112.936274 -226.017328) (xy 112.935776 -226.043977)
			(xy 113.164356 -226.043977) (xy 113.164356 -225.990679) (xy 113.172299 -225.937975) (xy 113.188009 -225.887045)
			(xy 113.211135 -225.839024) (xy 113.241159 -225.794987) (xy 113.277411 -225.755916) (xy 113.319082 -225.722685)
			(xy 113.36524 -225.696036) (xy 113.414854 -225.676564) (xy 113.466816 -225.664704) (xy 113.519966 -225.660721)
			(xy 113.573116 -225.664704) (xy 113.625078 -225.676564) (xy 113.674692 -225.696036) (xy 113.72085 -225.722685)
			(xy 113.762521 -225.755916) (xy 113.798773 -225.794987) (xy 113.828797 -225.839024) (xy 113.851923 -225.887045)
			(xy 113.867633 -225.937975) (xy 113.875576 -225.990679) (xy 113.876074 -226.017328) (xy 113.875576 -226.043977)
			(xy 114.104156 -226.043977) (xy 114.104156 -225.990679) (xy 114.112099 -225.937975) (xy 114.127809 -225.887045)
			(xy 114.150935 -225.839024) (xy 114.180959 -225.794987) (xy 114.217211 -225.755916) (xy 114.258882 -225.722685)
			(xy 114.30504 -225.696036) (xy 114.354654 -225.676564) (xy 114.406616 -225.664704) (xy 114.459766 -225.660721)
			(xy 114.512916 -225.664704) (xy 114.564878 -225.676564) (xy 114.614492 -225.696036) (xy 114.66065 -225.722685)
			(xy 114.702321 -225.755916) (xy 114.738573 -225.794987) (xy 114.768597 -225.839024) (xy 114.791723 -225.887045)
			(xy 114.807433 -225.937975) (xy 114.815376 -225.990679) (xy 114.815874 -226.017328) (xy 114.815376 -226.043977)
			(xy 115.043956 -226.043977) (xy 115.043956 -225.990679) (xy 115.051899 -225.937975) (xy 115.067609 -225.887045)
			(xy 115.090735 -225.839024) (xy 115.120759 -225.794987) (xy 115.157011 -225.755916) (xy 115.198682 -225.722685)
			(xy 115.24484 -225.696036) (xy 115.294454 -225.676564) (xy 115.346416 -225.664704) (xy 115.399566 -225.660721)
			(xy 115.452716 -225.664704) (xy 115.504678 -225.676564) (xy 115.554292 -225.696036) (xy 115.60045 -225.722685)
			(xy 115.642121 -225.755916) (xy 115.678373 -225.794987) (xy 115.708397 -225.839024) (xy 115.731523 -225.887045)
			(xy 115.747233 -225.937975) (xy 115.755176 -225.990679) (xy 115.755674 -226.017328) (xy 115.755176 -226.043977)
			(xy 115.983756 -226.043977) (xy 115.983756 -225.990679) (xy 115.991699 -225.937975) (xy 116.007409 -225.887045)
			(xy 116.030535 -225.839024) (xy 116.060559 -225.794987) (xy 116.096811 -225.755916) (xy 116.138482 -225.722685)
			(xy 116.18464 -225.696036) (xy 116.234254 -225.676564) (xy 116.286216 -225.664704) (xy 116.339366 -225.660721)
			(xy 116.392516 -225.664704) (xy 116.444478 -225.676564) (xy 116.494092 -225.696036) (xy 116.54025 -225.722685)
			(xy 116.581921 -225.755916) (xy 116.618173 -225.794987) (xy 116.648197 -225.839024) (xy 116.671323 -225.887045)
			(xy 116.687033 -225.937975) (xy 116.694976 -225.990679) (xy 116.695474 -226.017328) (xy 116.694976 -226.043977)
			(xy 116.923556 -226.043977) (xy 116.923556 -225.990679) (xy 116.931499 -225.937975) (xy 116.947209 -225.887045)
			(xy 116.970335 -225.839024) (xy 117.000359 -225.794987) (xy 117.036611 -225.755916) (xy 117.078282 -225.722685)
			(xy 117.12444 -225.696036) (xy 117.174054 -225.676564) (xy 117.226016 -225.664704) (xy 117.279166 -225.660721)
			(xy 117.332316 -225.664704) (xy 117.384278 -225.676564) (xy 117.433892 -225.696036) (xy 117.48005 -225.722685)
			(xy 117.521721 -225.755916) (xy 117.557973 -225.794987) (xy 117.587997 -225.839024) (xy 117.611123 -225.887045)
			(xy 117.626833 -225.937975) (xy 117.634776 -225.990679) (xy 117.635274 -226.017328) (xy 117.634776 -226.043977)
			(xy 117.863356 -226.043977) (xy 117.863356 -225.990679) (xy 117.871299 -225.937975) (xy 117.887009 -225.887045)
			(xy 117.910135 -225.839024) (xy 117.940159 -225.794987) (xy 117.976411 -225.755916) (xy 118.018082 -225.722685)
			(xy 118.06424 -225.696036) (xy 118.113854 -225.676564) (xy 118.165816 -225.664704) (xy 118.218966 -225.660721)
			(xy 118.272116 -225.664704) (xy 118.324078 -225.676564) (xy 118.373692 -225.696036) (xy 118.41985 -225.722685)
			(xy 118.461521 -225.755916) (xy 118.497773 -225.794987) (xy 118.527797 -225.839024) (xy 118.550923 -225.887045)
			(xy 118.566633 -225.937975) (xy 118.574576 -225.990679) (xy 118.575074 -226.017328) (xy 118.574576 -226.043977)
			(xy 118.803156 -226.043977) (xy 118.803156 -225.990679) (xy 118.811099 -225.937975) (xy 118.826809 -225.887045)
			(xy 118.849935 -225.839024) (xy 118.879959 -225.794987) (xy 118.916211 -225.755916) (xy 118.957882 -225.722685)
			(xy 119.00404 -225.696036) (xy 119.053654 -225.676564) (xy 119.105616 -225.664704) (xy 119.158766 -225.660721)
			(xy 119.211916 -225.664704) (xy 119.263878 -225.676564) (xy 119.313492 -225.696036) (xy 119.35965 -225.722685)
			(xy 119.401321 -225.755916) (xy 119.437573 -225.794987) (xy 119.467597 -225.839024) (xy 119.490723 -225.887045)
			(xy 119.506433 -225.937975) (xy 119.514376 -225.990679) (xy 119.514874 -226.017328) (xy 119.514376 -226.043977)
			(xy 119.742956 -226.043977) (xy 119.742956 -225.990679) (xy 119.750899 -225.937975) (xy 119.766609 -225.887045)
			(xy 119.789735 -225.839024) (xy 119.819759 -225.794987) (xy 119.856011 -225.755916) (xy 119.897682 -225.722685)
			(xy 119.94384 -225.696036) (xy 119.993454 -225.676564) (xy 120.045416 -225.664704) (xy 120.098566 -225.660721)
			(xy 120.151716 -225.664704) (xy 120.203678 -225.676564) (xy 120.253292 -225.696036) (xy 120.29945 -225.722685)
			(xy 120.341121 -225.755916) (xy 120.377373 -225.794987) (xy 120.407397 -225.839024) (xy 120.430523 -225.887045)
			(xy 120.446233 -225.937975) (xy 120.454176 -225.990679) (xy 120.454674 -226.017328) (xy 120.454176 -226.043977)
			(xy 120.682756 -226.043977) (xy 120.682756 -225.990679) (xy 120.690699 -225.937975) (xy 120.706409 -225.887045)
			(xy 120.729535 -225.839024) (xy 120.759559 -225.794987) (xy 120.795811 -225.755916) (xy 120.837482 -225.722685)
			(xy 120.88364 -225.696036) (xy 120.933254 -225.676564) (xy 120.985216 -225.664704) (xy 121.038366 -225.660721)
			(xy 121.091516 -225.664704) (xy 121.143478 -225.676564) (xy 121.193092 -225.696036) (xy 121.23925 -225.722685)
			(xy 121.280921 -225.755916) (xy 121.317173 -225.794987) (xy 121.347197 -225.839024) (xy 121.370323 -225.887045)
			(xy 121.386033 -225.937975) (xy 121.393976 -225.990679) (xy 121.394474 -226.017328) (xy 121.393976 -226.043977)
			(xy 121.622556 -226.043977) (xy 121.622556 -225.990679) (xy 121.630499 -225.937975) (xy 121.646209 -225.887045)
			(xy 121.669335 -225.839024) (xy 121.699359 -225.794987) (xy 121.735611 -225.755916) (xy 121.777282 -225.722685)
			(xy 121.82344 -225.696036) (xy 121.873054 -225.676564) (xy 121.925016 -225.664704) (xy 121.978166 -225.660721)
			(xy 122.031316 -225.664704) (xy 122.083278 -225.676564) (xy 122.132892 -225.696036) (xy 122.17905 -225.722685)
			(xy 122.220721 -225.755916) (xy 122.256973 -225.794987) (xy 122.286997 -225.839024) (xy 122.310123 -225.887045)
			(xy 122.325833 -225.937975) (xy 122.333776 -225.990679) (xy 122.334274 -226.017328) (xy 122.333776 -226.043977)
			(xy 122.562356 -226.043977) (xy 122.562356 -225.990679) (xy 122.570299 -225.937975) (xy 122.586009 -225.887045)
			(xy 122.609135 -225.839024) (xy 122.639159 -225.794987) (xy 122.675411 -225.755916) (xy 122.717082 -225.722685)
			(xy 122.76324 -225.696036) (xy 122.812854 -225.676564) (xy 122.864816 -225.664704) (xy 122.917966 -225.660721)
			(xy 122.971116 -225.664704) (xy 123.023078 -225.676564) (xy 123.072692 -225.696036) (xy 123.11885 -225.722685)
			(xy 123.160521 -225.755916) (xy 123.196773 -225.794987) (xy 123.226797 -225.839024) (xy 123.249923 -225.887045)
			(xy 123.265633 -225.937975) (xy 123.273576 -225.990679) (xy 123.274074 -226.017328) (xy 123.273576 -226.043977)
			(xy 123.502156 -226.043977) (xy 123.502156 -225.990679) (xy 123.510099 -225.937975) (xy 123.525809 -225.887045)
			(xy 123.548935 -225.839024) (xy 123.578959 -225.794987) (xy 123.615211 -225.755916) (xy 123.656882 -225.722685)
			(xy 123.70304 -225.696036) (xy 123.752654 -225.676564) (xy 123.804616 -225.664704) (xy 123.857766 -225.660721)
			(xy 123.910916 -225.664704) (xy 123.962878 -225.676564) (xy 124.012492 -225.696036) (xy 124.05865 -225.722685)
			(xy 124.100321 -225.755916) (xy 124.136573 -225.794987) (xy 124.166597 -225.839024) (xy 124.189723 -225.887045)
			(xy 124.205433 -225.937975) (xy 124.213376 -225.990679) (xy 124.213874 -226.017328) (xy 124.213376 -226.043977)
			(xy 124.441956 -226.043977) (xy 124.441956 -225.990679) (xy 124.449899 -225.937975) (xy 124.465609 -225.887045)
			(xy 124.488735 -225.839024) (xy 124.518759 -225.794987) (xy 124.555011 -225.755916) (xy 124.596682 -225.722685)
			(xy 124.64284 -225.696036) (xy 124.692454 -225.676564) (xy 124.744416 -225.664704) (xy 124.797566 -225.660721)
			(xy 124.850716 -225.664704) (xy 124.902678 -225.676564) (xy 124.952292 -225.696036) (xy 124.99845 -225.722685)
			(xy 125.040121 -225.755916) (xy 125.076373 -225.794987) (xy 125.106397 -225.839024) (xy 125.129523 -225.887045)
			(xy 125.145233 -225.937975) (xy 125.153176 -225.990679) (xy 125.153674 -226.017328) (xy 125.153176 -226.043977)
			(xy 125.381756 -226.043977) (xy 125.381756 -225.990679) (xy 125.389699 -225.937975) (xy 125.405409 -225.887045)
			(xy 125.428535 -225.839024) (xy 125.458559 -225.794987) (xy 125.494811 -225.755916) (xy 125.536482 -225.722685)
			(xy 125.58264 -225.696036) (xy 125.632254 -225.676564) (xy 125.684216 -225.664704) (xy 125.737366 -225.660721)
			(xy 125.790516 -225.664704) (xy 125.842478 -225.676564) (xy 125.892092 -225.696036) (xy 125.93825 -225.722685)
			(xy 125.979921 -225.755916) (xy 126.016173 -225.794987) (xy 126.046197 -225.839024) (xy 126.069323 -225.887045)
			(xy 126.085033 -225.937975) (xy 126.092976 -225.990679) (xy 126.093474 -226.017328) (xy 126.092976 -226.043977)
			(xy 126.321556 -226.043977) (xy 126.321556 -225.990679) (xy 126.329499 -225.937975) (xy 126.345209 -225.887045)
			(xy 126.368335 -225.839024) (xy 126.398359 -225.794987) (xy 126.434611 -225.755916) (xy 126.476282 -225.722685)
			(xy 126.52244 -225.696036) (xy 126.572054 -225.676564) (xy 126.624016 -225.664704) (xy 126.677166 -225.660721)
			(xy 126.730316 -225.664704) (xy 126.782278 -225.676564) (xy 126.831892 -225.696036) (xy 126.87805 -225.722685)
			(xy 126.919721 -225.755916) (xy 126.955973 -225.794987) (xy 126.985997 -225.839024) (xy 127.009123 -225.887045)
			(xy 127.024833 -225.937975) (xy 127.032776 -225.990679) (xy 127.033274 -226.017328) (xy 127.032776 -226.043977)
			(xy 127.261356 -226.043977) (xy 127.261356 -225.990679) (xy 127.269299 -225.937975) (xy 127.285009 -225.887045)
			(xy 127.308135 -225.839024) (xy 127.338159 -225.794987) (xy 127.374411 -225.755916) (xy 127.416082 -225.722685)
			(xy 127.46224 -225.696036) (xy 127.511854 -225.676564) (xy 127.563816 -225.664704) (xy 127.616966 -225.660721)
			(xy 127.670116 -225.664704) (xy 127.722078 -225.676564) (xy 127.771692 -225.696036) (xy 127.81785 -225.722685)
			(xy 127.859521 -225.755916) (xy 127.895773 -225.794987) (xy 127.925797 -225.839024) (xy 127.948923 -225.887045)
			(xy 127.964633 -225.937975) (xy 127.972576 -225.990679) (xy 127.973074 -226.017328) (xy 127.972576 -226.043977)
			(xy 128.201156 -226.043977) (xy 128.201156 -225.990679) (xy 128.209099 -225.937975) (xy 128.224809 -225.887045)
			(xy 128.247935 -225.839024) (xy 128.277959 -225.794987) (xy 128.314211 -225.755916) (xy 128.355882 -225.722685)
			(xy 128.40204 -225.696036) (xy 128.451654 -225.676564) (xy 128.503616 -225.664704) (xy 128.556766 -225.660721)
			(xy 128.609916 -225.664704) (xy 128.661878 -225.676564) (xy 128.711492 -225.696036) (xy 128.75765 -225.722685)
			(xy 128.799321 -225.755916) (xy 128.835573 -225.794987) (xy 128.865597 -225.839024) (xy 128.888723 -225.887045)
			(xy 128.904433 -225.937975) (xy 128.912376 -225.990679) (xy 128.912874 -226.017328) (xy 128.912376 -226.043977)
			(xy 129.140956 -226.043977) (xy 129.140956 -225.990679) (xy 129.148899 -225.937975) (xy 129.164609 -225.887045)
			(xy 129.187735 -225.839024) (xy 129.217759 -225.794987) (xy 129.254011 -225.755916) (xy 129.295682 -225.722685)
			(xy 129.34184 -225.696036) (xy 129.391454 -225.676564) (xy 129.443416 -225.664704) (xy 129.496566 -225.660721)
			(xy 129.549716 -225.664704) (xy 129.601678 -225.676564) (xy 129.651292 -225.696036) (xy 129.69745 -225.722685)
			(xy 129.739121 -225.755916) (xy 129.775373 -225.794987) (xy 129.805397 -225.839024) (xy 129.828523 -225.887045)
			(xy 129.844233 -225.937975) (xy 129.852176 -225.990679) (xy 129.852674 -226.017328) (xy 129.852176 -226.043977)
			(xy 130.080756 -226.043977) (xy 130.080756 -225.990679) (xy 130.088699 -225.937975) (xy 130.104409 -225.887045)
			(xy 130.127535 -225.839024) (xy 130.157559 -225.794987) (xy 130.193811 -225.755916) (xy 130.235482 -225.722685)
			(xy 130.28164 -225.696036) (xy 130.331254 -225.676564) (xy 130.383216 -225.664704) (xy 130.436366 -225.660721)
			(xy 130.489516 -225.664704) (xy 130.541478 -225.676564) (xy 130.591092 -225.696036) (xy 130.63725 -225.722685)
			(xy 130.678921 -225.755916) (xy 130.715173 -225.794987) (xy 130.745197 -225.839024) (xy 130.768323 -225.887045)
			(xy 130.784033 -225.937975) (xy 130.791976 -225.990679) (xy 130.792474 -226.017328) (xy 130.791976 -226.043977)
			(xy 131.020556 -226.043977) (xy 131.020556 -225.990679) (xy 131.028499 -225.937975) (xy 131.044209 -225.887045)
			(xy 131.067335 -225.839024) (xy 131.097359 -225.794987) (xy 131.133611 -225.755916) (xy 131.175282 -225.722685)
			(xy 131.22144 -225.696036) (xy 131.271054 -225.676564) (xy 131.323016 -225.664704) (xy 131.376166 -225.660721)
			(xy 131.429316 -225.664704) (xy 131.481278 -225.676564) (xy 131.530892 -225.696036) (xy 131.57705 -225.722685)
			(xy 131.618721 -225.755916) (xy 131.654973 -225.794987) (xy 131.684997 -225.839024) (xy 131.708123 -225.887045)
			(xy 131.723833 -225.937975) (xy 131.731776 -225.990679) (xy 131.732274 -226.017328) (xy 131.731776 -226.043977)
			(xy 131.960356 -226.043977) (xy 131.960356 -225.990679) (xy 131.968299 -225.937975) (xy 131.984009 -225.887045)
			(xy 132.007135 -225.839024) (xy 132.037159 -225.794987) (xy 132.073411 -225.755916) (xy 132.115082 -225.722685)
			(xy 132.16124 -225.696036) (xy 132.210854 -225.676564) (xy 132.262816 -225.664704) (xy 132.315966 -225.660721)
			(xy 132.369116 -225.664704) (xy 132.421078 -225.676564) (xy 132.470692 -225.696036) (xy 132.51685 -225.722685)
			(xy 132.558521 -225.755916) (xy 132.594773 -225.794987) (xy 132.624797 -225.839024) (xy 132.647923 -225.887045)
			(xy 132.663633 -225.937975) (xy 132.671576 -225.990679) (xy 132.672074 -226.017328) (xy 132.671576 -226.043977)
			(xy 132.900156 -226.043977) (xy 132.900156 -225.990679) (xy 132.908099 -225.937975) (xy 132.923809 -225.887045)
			(xy 132.946935 -225.839024) (xy 132.976959 -225.794987) (xy 133.013211 -225.755916) (xy 133.054882 -225.722685)
			(xy 133.10104 -225.696036) (xy 133.150654 -225.676564) (xy 133.202616 -225.664704) (xy 133.255766 -225.660721)
			(xy 133.308916 -225.664704) (xy 133.360878 -225.676564) (xy 133.410492 -225.696036) (xy 133.45665 -225.722685)
			(xy 133.498321 -225.755916) (xy 133.534573 -225.794987) (xy 133.564597 -225.839024) (xy 133.587723 -225.887045)
			(xy 133.603433 -225.937975) (xy 133.611376 -225.990679) (xy 133.611874 -226.017328) (xy 133.611376 -226.043977)
			(xy 133.839956 -226.043977) (xy 133.839956 -225.990679) (xy 133.847899 -225.937975) (xy 133.863609 -225.887045)
			(xy 133.886735 -225.839024) (xy 133.916759 -225.794987) (xy 133.953011 -225.755916) (xy 133.994682 -225.722685)
			(xy 134.04084 -225.696036) (xy 134.090454 -225.676564) (xy 134.142416 -225.664704) (xy 134.195566 -225.660721)
			(xy 134.248716 -225.664704) (xy 134.300678 -225.676564) (xy 134.350292 -225.696036) (xy 134.39645 -225.722685)
			(xy 134.438121 -225.755916) (xy 134.474373 -225.794987) (xy 134.504397 -225.839024) (xy 134.527523 -225.887045)
			(xy 134.543233 -225.937975) (xy 134.551176 -225.990679) (xy 134.551674 -226.017328) (xy 134.551176 -226.043977)
			(xy 134.543233 -226.096681) (xy 134.527523 -226.147611) (xy 134.504397 -226.195632) (xy 134.474373 -226.239669)
			(xy 134.438121 -226.27874) (xy 134.39645 -226.311971) (xy 134.350292 -226.33862) (xy 134.300678 -226.358092)
			(xy 134.248716 -226.369952) (xy 134.195566 -226.373936) (xy 134.142416 -226.369952) (xy 134.090454 -226.358092)
			(xy 134.04084 -226.33862) (xy 133.994682 -226.311971) (xy 133.953011 -226.27874) (xy 133.916759 -226.239669)
			(xy 133.886735 -226.195632) (xy 133.863609 -226.147611) (xy 133.847899 -226.096681) (xy 133.839956 -226.043977)
			(xy 133.611376 -226.043977) (xy 133.603433 -226.096681) (xy 133.587723 -226.147611) (xy 133.564597 -226.195632)
			(xy 133.534573 -226.239669) (xy 133.498321 -226.27874) (xy 133.45665 -226.311971) (xy 133.410492 -226.33862)
			(xy 133.360878 -226.358092) (xy 133.308916 -226.369952) (xy 133.255766 -226.373936) (xy 133.202616 -226.369952)
			(xy 133.150654 -226.358092) (xy 133.10104 -226.33862) (xy 133.054882 -226.311971) (xy 133.013211 -226.27874)
			(xy 132.976959 -226.239669) (xy 132.946935 -226.195632) (xy 132.923809 -226.147611) (xy 132.908099 -226.096681)
			(xy 132.900156 -226.043977) (xy 132.671576 -226.043977) (xy 132.663633 -226.096681) (xy 132.647923 -226.147611)
			(xy 132.624797 -226.195632) (xy 132.594773 -226.239669) (xy 132.558521 -226.27874) (xy 132.51685 -226.311971)
			(xy 132.470692 -226.33862) (xy 132.421078 -226.358092) (xy 132.369116 -226.369952) (xy 132.315966 -226.373936)
			(xy 132.262816 -226.369952) (xy 132.210854 -226.358092) (xy 132.16124 -226.33862) (xy 132.115082 -226.311971)
			(xy 132.073411 -226.27874) (xy 132.037159 -226.239669) (xy 132.007135 -226.195632) (xy 131.984009 -226.147611)
			(xy 131.968299 -226.096681) (xy 131.960356 -226.043977) (xy 131.731776 -226.043977) (xy 131.723833 -226.096681)
			(xy 131.708123 -226.147611) (xy 131.684997 -226.195632) (xy 131.654973 -226.239669) (xy 131.618721 -226.27874)
			(xy 131.57705 -226.311971) (xy 131.530892 -226.33862) (xy 131.481278 -226.358092) (xy 131.429316 -226.369952)
			(xy 131.376166 -226.373936) (xy 131.323016 -226.369952) (xy 131.271054 -226.358092) (xy 131.22144 -226.33862)
			(xy 131.175282 -226.311971) (xy 131.133611 -226.27874) (xy 131.097359 -226.239669) (xy 131.067335 -226.195632)
			(xy 131.044209 -226.147611) (xy 131.028499 -226.096681) (xy 131.020556 -226.043977) (xy 130.791976 -226.043977)
			(xy 130.784033 -226.096681) (xy 130.768323 -226.147611) (xy 130.745197 -226.195632) (xy 130.715173 -226.239669)
			(xy 130.678921 -226.27874) (xy 130.63725 -226.311971) (xy 130.591092 -226.33862) (xy 130.541478 -226.358092)
			(xy 130.489516 -226.369952) (xy 130.436366 -226.373936) (xy 130.383216 -226.369952) (xy 130.331254 -226.358092)
			(xy 130.28164 -226.33862) (xy 130.235482 -226.311971) (xy 130.193811 -226.27874) (xy 130.157559 -226.239669)
			(xy 130.127535 -226.195632) (xy 130.104409 -226.147611) (xy 130.088699 -226.096681) (xy 130.080756 -226.043977)
			(xy 129.852176 -226.043977) (xy 129.844233 -226.096681) (xy 129.828523 -226.147611) (xy 129.805397 -226.195632)
			(xy 129.775373 -226.239669) (xy 129.739121 -226.27874) (xy 129.69745 -226.311971) (xy 129.651292 -226.33862)
			(xy 129.601678 -226.358092) (xy 129.549716 -226.369952) (xy 129.496566 -226.373936) (xy 129.443416 -226.369952)
			(xy 129.391454 -226.358092) (xy 129.34184 -226.33862) (xy 129.295682 -226.311971) (xy 129.254011 -226.27874)
			(xy 129.217759 -226.239669) (xy 129.187735 -226.195632) (xy 129.164609 -226.147611) (xy 129.148899 -226.096681)
			(xy 129.140956 -226.043977) (xy 128.912376 -226.043977) (xy 128.904433 -226.096681) (xy 128.888723 -226.147611)
			(xy 128.865597 -226.195632) (xy 128.835573 -226.239669) (xy 128.799321 -226.27874) (xy 128.75765 -226.311971)
			(xy 128.711492 -226.33862) (xy 128.661878 -226.358092) (xy 128.609916 -226.369952) (xy 128.556766 -226.373936)
			(xy 128.503616 -226.369952) (xy 128.451654 -226.358092) (xy 128.40204 -226.33862) (xy 128.355882 -226.311971)
			(xy 128.314211 -226.27874) (xy 128.277959 -226.239669) (xy 128.247935 -226.195632) (xy 128.224809 -226.147611)
			(xy 128.209099 -226.096681) (xy 128.201156 -226.043977) (xy 127.972576 -226.043977) (xy 127.964633 -226.096681)
			(xy 127.948923 -226.147611) (xy 127.925797 -226.195632) (xy 127.895773 -226.239669) (xy 127.859521 -226.27874)
			(xy 127.81785 -226.311971) (xy 127.771692 -226.33862) (xy 127.722078 -226.358092) (xy 127.670116 -226.369952)
			(xy 127.616966 -226.373936) (xy 127.563816 -226.369952) (xy 127.511854 -226.358092) (xy 127.46224 -226.33862)
			(xy 127.416082 -226.311971) (xy 127.374411 -226.27874) (xy 127.338159 -226.239669) (xy 127.308135 -226.195632)
			(xy 127.285009 -226.147611) (xy 127.269299 -226.096681) (xy 127.261356 -226.043977) (xy 127.032776 -226.043977)
			(xy 127.024833 -226.096681) (xy 127.009123 -226.147611) (xy 126.985997 -226.195632) (xy 126.955973 -226.239669)
			(xy 126.919721 -226.27874) (xy 126.87805 -226.311971) (xy 126.831892 -226.33862) (xy 126.782278 -226.358092)
			(xy 126.730316 -226.369952) (xy 126.677166 -226.373936) (xy 126.624016 -226.369952) (xy 126.572054 -226.358092)
			(xy 126.52244 -226.33862) (xy 126.476282 -226.311971) (xy 126.434611 -226.27874) (xy 126.398359 -226.239669)
			(xy 126.368335 -226.195632) (xy 126.345209 -226.147611) (xy 126.329499 -226.096681) (xy 126.321556 -226.043977)
			(xy 126.092976 -226.043977) (xy 126.085033 -226.096681) (xy 126.069323 -226.147611) (xy 126.046197 -226.195632)
			(xy 126.016173 -226.239669) (xy 125.979921 -226.27874) (xy 125.93825 -226.311971) (xy 125.892092 -226.33862)
			(xy 125.842478 -226.358092) (xy 125.790516 -226.369952) (xy 125.737366 -226.373936) (xy 125.684216 -226.369952)
			(xy 125.632254 -226.358092) (xy 125.58264 -226.33862) (xy 125.536482 -226.311971) (xy 125.494811 -226.27874)
			(xy 125.458559 -226.239669) (xy 125.428535 -226.195632) (xy 125.405409 -226.147611) (xy 125.389699 -226.096681)
			(xy 125.381756 -226.043977) (xy 125.153176 -226.043977) (xy 125.145233 -226.096681) (xy 125.129523 -226.147611)
			(xy 125.106397 -226.195632) (xy 125.076373 -226.239669) (xy 125.040121 -226.27874) (xy 124.99845 -226.311971)
			(xy 124.952292 -226.33862) (xy 124.902678 -226.358092) (xy 124.850716 -226.369952) (xy 124.797566 -226.373936)
			(xy 124.744416 -226.369952) (xy 124.692454 -226.358092) (xy 124.64284 -226.33862) (xy 124.596682 -226.311971)
			(xy 124.555011 -226.27874) (xy 124.518759 -226.239669) (xy 124.488735 -226.195632) (xy 124.465609 -226.147611)
			(xy 124.449899 -226.096681) (xy 124.441956 -226.043977) (xy 124.213376 -226.043977) (xy 124.205433 -226.096681)
			(xy 124.189723 -226.147611) (xy 124.166597 -226.195632) (xy 124.136573 -226.239669) (xy 124.100321 -226.27874)
			(xy 124.05865 -226.311971) (xy 124.012492 -226.33862) (xy 123.962878 -226.358092) (xy 123.910916 -226.369952)
			(xy 123.857766 -226.373936) (xy 123.804616 -226.369952) (xy 123.752654 -226.358092) (xy 123.70304 -226.33862)
			(xy 123.656882 -226.311971) (xy 123.615211 -226.27874) (xy 123.578959 -226.239669) (xy 123.548935 -226.195632)
			(xy 123.525809 -226.147611) (xy 123.510099 -226.096681) (xy 123.502156 -226.043977) (xy 123.273576 -226.043977)
			(xy 123.265633 -226.096681) (xy 123.249923 -226.147611) (xy 123.226797 -226.195632) (xy 123.196773 -226.239669)
			(xy 123.160521 -226.27874) (xy 123.11885 -226.311971) (xy 123.072692 -226.33862) (xy 123.023078 -226.358092)
			(xy 122.971116 -226.369952) (xy 122.917966 -226.373936) (xy 122.864816 -226.369952) (xy 122.812854 -226.358092)
			(xy 122.76324 -226.33862) (xy 122.717082 -226.311971) (xy 122.675411 -226.27874) (xy 122.639159 -226.239669)
			(xy 122.609135 -226.195632) (xy 122.586009 -226.147611) (xy 122.570299 -226.096681) (xy 122.562356 -226.043977)
			(xy 122.333776 -226.043977) (xy 122.325833 -226.096681) (xy 122.310123 -226.147611) (xy 122.286997 -226.195632)
			(xy 122.256973 -226.239669) (xy 122.220721 -226.27874) (xy 122.17905 -226.311971) (xy 122.132892 -226.33862)
			(xy 122.083278 -226.358092) (xy 122.031316 -226.369952) (xy 121.978166 -226.373936) (xy 121.925016 -226.369952)
			(xy 121.873054 -226.358092) (xy 121.82344 -226.33862) (xy 121.777282 -226.311971) (xy 121.735611 -226.27874)
			(xy 121.699359 -226.239669) (xy 121.669335 -226.195632) (xy 121.646209 -226.147611) (xy 121.630499 -226.096681)
			(xy 121.622556 -226.043977) (xy 121.393976 -226.043977) (xy 121.386033 -226.096681) (xy 121.370323 -226.147611)
			(xy 121.347197 -226.195632) (xy 121.317173 -226.239669) (xy 121.280921 -226.27874) (xy 121.23925 -226.311971)
			(xy 121.193092 -226.33862) (xy 121.143478 -226.358092) (xy 121.091516 -226.369952) (xy 121.038366 -226.373936)
			(xy 120.985216 -226.369952) (xy 120.933254 -226.358092) (xy 120.88364 -226.33862) (xy 120.837482 -226.311971)
			(xy 120.795811 -226.27874) (xy 120.759559 -226.239669) (xy 120.729535 -226.195632) (xy 120.706409 -226.147611)
			(xy 120.690699 -226.096681) (xy 120.682756 -226.043977) (xy 120.454176 -226.043977) (xy 120.446233 -226.096681)
			(xy 120.430523 -226.147611) (xy 120.407397 -226.195632) (xy 120.377373 -226.239669) (xy 120.341121 -226.27874)
			(xy 120.29945 -226.311971) (xy 120.253292 -226.33862) (xy 120.203678 -226.358092) (xy 120.151716 -226.369952)
			(xy 120.098566 -226.373936) (xy 120.045416 -226.369952) (xy 119.993454 -226.358092) (xy 119.94384 -226.33862)
			(xy 119.897682 -226.311971) (xy 119.856011 -226.27874) (xy 119.819759 -226.239669) (xy 119.789735 -226.195632)
			(xy 119.766609 -226.147611) (xy 119.750899 -226.096681) (xy 119.742956 -226.043977) (xy 119.514376 -226.043977)
			(xy 119.506433 -226.096681) (xy 119.490723 -226.147611) (xy 119.467597 -226.195632) (xy 119.437573 -226.239669)
			(xy 119.401321 -226.27874) (xy 119.35965 -226.311971) (xy 119.313492 -226.33862) (xy 119.263878 -226.358092)
			(xy 119.211916 -226.369952) (xy 119.158766 -226.373936) (xy 119.105616 -226.369952) (xy 119.053654 -226.358092)
			(xy 119.00404 -226.33862) (xy 118.957882 -226.311971) (xy 118.916211 -226.27874) (xy 118.879959 -226.239669)
			(xy 118.849935 -226.195632) (xy 118.826809 -226.147611) (xy 118.811099 -226.096681) (xy 118.803156 -226.043977)
			(xy 118.574576 -226.043977) (xy 118.566633 -226.096681) (xy 118.550923 -226.147611) (xy 118.527797 -226.195632)
			(xy 118.497773 -226.239669) (xy 118.461521 -226.27874) (xy 118.41985 -226.311971) (xy 118.373692 -226.33862)
			(xy 118.324078 -226.358092) (xy 118.272116 -226.369952) (xy 118.218966 -226.373936) (xy 118.165816 -226.369952)
			(xy 118.113854 -226.358092) (xy 118.06424 -226.33862) (xy 118.018082 -226.311971) (xy 117.976411 -226.27874)
			(xy 117.940159 -226.239669) (xy 117.910135 -226.195632) (xy 117.887009 -226.147611) (xy 117.871299 -226.096681)
			(xy 117.863356 -226.043977) (xy 117.634776 -226.043977) (xy 117.626833 -226.096681) (xy 117.611123 -226.147611)
			(xy 117.587997 -226.195632) (xy 117.557973 -226.239669) (xy 117.521721 -226.27874) (xy 117.48005 -226.311971)
			(xy 117.433892 -226.33862) (xy 117.384278 -226.358092) (xy 117.332316 -226.369952) (xy 117.279166 -226.373936)
			(xy 117.226016 -226.369952) (xy 117.174054 -226.358092) (xy 117.12444 -226.33862) (xy 117.078282 -226.311971)
			(xy 117.036611 -226.27874) (xy 117.000359 -226.239669) (xy 116.970335 -226.195632) (xy 116.947209 -226.147611)
			(xy 116.931499 -226.096681) (xy 116.923556 -226.043977) (xy 116.694976 -226.043977) (xy 116.687033 -226.096681)
			(xy 116.671323 -226.147611) (xy 116.648197 -226.195632) (xy 116.618173 -226.239669) (xy 116.581921 -226.27874)
			(xy 116.54025 -226.311971) (xy 116.494092 -226.33862) (xy 116.444478 -226.358092) (xy 116.392516 -226.369952)
			(xy 116.339366 -226.373936) (xy 116.286216 -226.369952) (xy 116.234254 -226.358092) (xy 116.18464 -226.33862)
			(xy 116.138482 -226.311971) (xy 116.096811 -226.27874) (xy 116.060559 -226.239669) (xy 116.030535 -226.195632)
			(xy 116.007409 -226.147611) (xy 115.991699 -226.096681) (xy 115.983756 -226.043977) (xy 115.755176 -226.043977)
			(xy 115.747233 -226.096681) (xy 115.731523 -226.147611) (xy 115.708397 -226.195632) (xy 115.678373 -226.239669)
			(xy 115.642121 -226.27874) (xy 115.60045 -226.311971) (xy 115.554292 -226.33862) (xy 115.504678 -226.358092)
			(xy 115.452716 -226.369952) (xy 115.399566 -226.373936) (xy 115.346416 -226.369952) (xy 115.294454 -226.358092)
			(xy 115.24484 -226.33862) (xy 115.198682 -226.311971) (xy 115.157011 -226.27874) (xy 115.120759 -226.239669)
			(xy 115.090735 -226.195632) (xy 115.067609 -226.147611) (xy 115.051899 -226.096681) (xy 115.043956 -226.043977)
			(xy 114.815376 -226.043977) (xy 114.807433 -226.096681) (xy 114.791723 -226.147611) (xy 114.768597 -226.195632)
			(xy 114.738573 -226.239669) (xy 114.702321 -226.27874) (xy 114.66065 -226.311971) (xy 114.614492 -226.33862)
			(xy 114.564878 -226.358092) (xy 114.512916 -226.369952) (xy 114.459766 -226.373936) (xy 114.406616 -226.369952)
			(xy 114.354654 -226.358092) (xy 114.30504 -226.33862) (xy 114.258882 -226.311971) (xy 114.217211 -226.27874)
			(xy 114.180959 -226.239669) (xy 114.150935 -226.195632) (xy 114.127809 -226.147611) (xy 114.112099 -226.096681)
			(xy 114.104156 -226.043977) (xy 113.875576 -226.043977) (xy 113.867633 -226.096681) (xy 113.851923 -226.147611)
			(xy 113.828797 -226.195632) (xy 113.798773 -226.239669) (xy 113.762521 -226.27874) (xy 113.72085 -226.311971)
			(xy 113.674692 -226.33862) (xy 113.625078 -226.358092) (xy 113.573116 -226.369952) (xy 113.519966 -226.373936)
			(xy 113.466816 -226.369952) (xy 113.414854 -226.358092) (xy 113.36524 -226.33862) (xy 113.319082 -226.311971)
			(xy 113.277411 -226.27874) (xy 113.241159 -226.239669) (xy 113.211135 -226.195632) (xy 113.188009 -226.147611)
			(xy 113.172299 -226.096681) (xy 113.164356 -226.043977) (xy 112.935776 -226.043977) (xy 112.927833 -226.096681)
			(xy 112.912123 -226.147611) (xy 112.888997 -226.195632) (xy 112.858973 -226.239669) (xy 112.822721 -226.27874)
			(xy 112.78105 -226.311971) (xy 112.734892 -226.33862) (xy 112.685278 -226.358092) (xy 112.633316 -226.369952)
			(xy 112.580166 -226.373936) (xy 112.527016 -226.369952) (xy 112.475054 -226.358092) (xy 112.42544 -226.33862)
			(xy 112.379282 -226.311971) (xy 112.337611 -226.27874) (xy 112.301359 -226.239669) (xy 112.271335 -226.195632)
			(xy 112.248209 -226.147611) (xy 112.232499 -226.096681) (xy 112.224556 -226.043977) (xy 111.994986 -226.043977)
			(xy 111.993197 -226.068681) (xy 111.982124 -226.118971) (xy 111.963928 -226.167145) (xy 111.938986 -226.212197)
			(xy 111.90782 -226.25319) (xy 111.889794 -226.271582) (xy 111.889794 -226.389184) (xy 111.89019 -226.402513)
			(xy 111.897095 -226.428262) (xy 111.910437 -226.451342) (xy 111.929304 -226.470176) (xy 111.952408 -226.483476)
			(xy 111.978169 -226.490334) (xy 112.004828 -226.490282) (xy 112.01781 -226.487228) (xy 112.040494 -226.481508)
			(xy 112.086875 -226.475386) (xy 112.110266 -226.475036) (xy 112.136916 -226.475507) (xy 112.18962 -226.483446)
			(xy 112.240552 -226.499152) (xy 112.288574 -226.522274) (xy 112.332614 -226.552296) (xy 112.371686 -226.588547)
			(xy 112.40492 -226.630216) (xy 112.43157 -226.676373) (xy 112.451044 -226.725988) (xy 112.462905 -226.77795)
			(xy 112.466888 -226.8311) (xy 112.464888 -226.857793) (xy 112.694202 -226.857793) (xy 112.694202 -226.804495)
			(xy 112.702145 -226.751791) (xy 112.717855 -226.700861) (xy 112.740981 -226.65284) (xy 112.771005 -226.608803)
			(xy 112.807257 -226.569732) (xy 112.848928 -226.536501) (xy 112.895086 -226.509852) (xy 112.9447 -226.49038)
			(xy 112.996662 -226.47852) (xy 113.049812 -226.474537) (xy 113.102962 -226.47852) (xy 113.154924 -226.49038)
			(xy 113.204538 -226.509852) (xy 113.250696 -226.536501) (xy 113.292367 -226.569732) (xy 113.328619 -226.608803)
			(xy 113.358643 -226.65284) (xy 113.381769 -226.700861) (xy 113.397479 -226.751791) (xy 113.405422 -226.804495)
			(xy 113.40592 -226.831144) (xy 113.405422 -226.857793) (xy 113.634256 -226.857793) (xy 113.634256 -226.804495)
			(xy 113.642199 -226.751791) (xy 113.657909 -226.700861) (xy 113.681035 -226.65284) (xy 113.711059 -226.608803)
			(xy 113.747311 -226.569732) (xy 113.788982 -226.536501) (xy 113.83514 -226.509852) (xy 113.884754 -226.49038)
			(xy 113.936716 -226.47852) (xy 113.989866 -226.474537) (xy 114.043016 -226.47852) (xy 114.094978 -226.49038)
			(xy 114.144592 -226.509852) (xy 114.19075 -226.536501) (xy 114.232421 -226.569732) (xy 114.268673 -226.608803)
			(xy 114.298697 -226.65284) (xy 114.321823 -226.700861) (xy 114.337533 -226.751791) (xy 114.345476 -226.804495)
			(xy 114.345974 -226.831144) (xy 114.345476 -226.857793) (xy 114.574056 -226.857793) (xy 114.574056 -226.804495)
			(xy 114.581999 -226.751791) (xy 114.597709 -226.700861) (xy 114.620835 -226.65284) (xy 114.650859 -226.608803)
			(xy 114.687111 -226.569732) (xy 114.728782 -226.536501) (xy 114.77494 -226.509852) (xy 114.824554 -226.49038)
			(xy 114.876516 -226.47852) (xy 114.929666 -226.474537) (xy 114.982816 -226.47852) (xy 115.034778 -226.49038)
			(xy 115.084392 -226.509852) (xy 115.13055 -226.536501) (xy 115.172221 -226.569732) (xy 115.208473 -226.608803)
			(xy 115.238497 -226.65284) (xy 115.261623 -226.700861) (xy 115.277333 -226.751791) (xy 115.285276 -226.804495)
			(xy 115.285774 -226.831144) (xy 115.285276 -226.857793) (xy 115.513856 -226.857793) (xy 115.513856 -226.804495)
			(xy 115.521799 -226.751791) (xy 115.537509 -226.700861) (xy 115.560635 -226.65284) (xy 115.590659 -226.608803)
			(xy 115.626911 -226.569732) (xy 115.668582 -226.536501) (xy 115.71474 -226.509852) (xy 115.764354 -226.49038)
			(xy 115.816316 -226.47852) (xy 115.869466 -226.474537) (xy 115.922616 -226.47852) (xy 115.974578 -226.49038)
			(xy 116.024192 -226.509852) (xy 116.07035 -226.536501) (xy 116.112021 -226.569732) (xy 116.148273 -226.608803)
			(xy 116.178297 -226.65284) (xy 116.201423 -226.700861) (xy 116.217133 -226.751791) (xy 116.225076 -226.804495)
			(xy 116.225574 -226.831144) (xy 116.225076 -226.857793) (xy 116.453402 -226.857793) (xy 116.453402 -226.804495)
			(xy 116.461345 -226.751791) (xy 116.477055 -226.700861) (xy 116.500181 -226.65284) (xy 116.530205 -226.608803)
			(xy 116.566457 -226.569732) (xy 116.608128 -226.536501) (xy 116.654286 -226.509852) (xy 116.7039 -226.49038)
			(xy 116.755862 -226.47852) (xy 116.809012 -226.474537) (xy 116.862162 -226.47852) (xy 116.914124 -226.49038)
			(xy 116.963738 -226.509852) (xy 117.009896 -226.536501) (xy 117.051567 -226.569732) (xy 117.087819 -226.608803)
			(xy 117.117843 -226.65284) (xy 117.140969 -226.700861) (xy 117.156679 -226.751791) (xy 117.164622 -226.804495)
			(xy 117.16512 -226.831144) (xy 117.164622 -226.857793) (xy 117.393456 -226.857793) (xy 117.393456 -226.804495)
			(xy 117.401399 -226.751791) (xy 117.417109 -226.700861) (xy 117.440235 -226.65284) (xy 117.470259 -226.608803)
			(xy 117.506511 -226.569732) (xy 117.548182 -226.536501) (xy 117.59434 -226.509852) (xy 117.643954 -226.49038)
			(xy 117.695916 -226.47852) (xy 117.749066 -226.474537) (xy 117.802216 -226.47852) (xy 117.854178 -226.49038)
			(xy 117.903792 -226.509852) (xy 117.94995 -226.536501) (xy 117.991621 -226.569732) (xy 118.027873 -226.608803)
			(xy 118.057897 -226.65284) (xy 118.081023 -226.700861) (xy 118.096733 -226.751791) (xy 118.104676 -226.804495)
			(xy 118.105174 -226.831144) (xy 118.104676 -226.857793) (xy 118.333002 -226.857793) (xy 118.333002 -226.804495)
			(xy 118.340945 -226.751791) (xy 118.356655 -226.700861) (xy 118.379781 -226.65284) (xy 118.409805 -226.608803)
			(xy 118.446057 -226.569732) (xy 118.487728 -226.536501) (xy 118.533886 -226.509852) (xy 118.5835 -226.49038)
			(xy 118.635462 -226.47852) (xy 118.688612 -226.474537) (xy 118.741762 -226.47852) (xy 118.793724 -226.49038)
			(xy 118.843338 -226.509852) (xy 118.889496 -226.536501) (xy 118.931167 -226.569732) (xy 118.967419 -226.608803)
			(xy 118.997443 -226.65284) (xy 119.020569 -226.700861) (xy 119.036279 -226.751791) (xy 119.044222 -226.804495)
			(xy 119.04472 -226.831144) (xy 119.044222 -226.857793) (xy 119.273056 -226.857793) (xy 119.273056 -226.804495)
			(xy 119.280999 -226.751791) (xy 119.296709 -226.700861) (xy 119.319835 -226.65284) (xy 119.349859 -226.608803)
			(xy 119.386111 -226.569732) (xy 119.427782 -226.536501) (xy 119.47394 -226.509852) (xy 119.523554 -226.49038)
			(xy 119.575516 -226.47852) (xy 119.628666 -226.474537) (xy 119.681816 -226.47852) (xy 119.733778 -226.49038)
			(xy 119.783392 -226.509852) (xy 119.82955 -226.536501) (xy 119.871221 -226.569732) (xy 119.907473 -226.608803)
			(xy 119.937497 -226.65284) (xy 119.960623 -226.700861) (xy 119.976333 -226.751791) (xy 119.984276 -226.804495)
			(xy 119.984774 -226.831144) (xy 119.984276 -226.857793) (xy 120.212602 -226.857793) (xy 120.212602 -226.804495)
			(xy 120.220545 -226.751791) (xy 120.236255 -226.700861) (xy 120.259381 -226.65284) (xy 120.289405 -226.608803)
			(xy 120.325657 -226.569732) (xy 120.367328 -226.536501) (xy 120.413486 -226.509852) (xy 120.4631 -226.49038)
			(xy 120.515062 -226.47852) (xy 120.568212 -226.474537) (xy 120.621362 -226.47852) (xy 120.673324 -226.49038)
			(xy 120.722938 -226.509852) (xy 120.769096 -226.536501) (xy 120.810767 -226.569732) (xy 120.847019 -226.608803)
			(xy 120.877043 -226.65284) (xy 120.900169 -226.700861) (xy 120.915879 -226.751791) (xy 120.923822 -226.804495)
			(xy 120.92432 -226.831144) (xy 120.923822 -226.857793) (xy 121.152656 -226.857793) (xy 121.152656 -226.804495)
			(xy 121.160599 -226.751791) (xy 121.176309 -226.700861) (xy 121.199435 -226.65284) (xy 121.229459 -226.608803)
			(xy 121.265711 -226.569732) (xy 121.307382 -226.536501) (xy 121.35354 -226.509852) (xy 121.403154 -226.49038)
			(xy 121.455116 -226.47852) (xy 121.508266 -226.474537) (xy 121.561416 -226.47852) (xy 121.613378 -226.49038)
			(xy 121.662992 -226.509852) (xy 121.70915 -226.536501) (xy 121.750821 -226.569732) (xy 121.787073 -226.608803)
			(xy 121.817097 -226.65284) (xy 121.840223 -226.700861) (xy 121.855933 -226.751791) (xy 121.863876 -226.804495)
			(xy 121.864374 -226.831144) (xy 121.863876 -226.857793) (xy 122.092202 -226.857793) (xy 122.092202 -226.804495)
			(xy 122.100145 -226.751791) (xy 122.115855 -226.700861) (xy 122.138981 -226.65284) (xy 122.169005 -226.608803)
			(xy 122.205257 -226.569732) (xy 122.246928 -226.536501) (xy 122.293086 -226.509852) (xy 122.3427 -226.49038)
			(xy 122.394662 -226.47852) (xy 122.447812 -226.474537) (xy 122.500962 -226.47852) (xy 122.552924 -226.49038)
			(xy 122.602538 -226.509852) (xy 122.648696 -226.536501) (xy 122.690367 -226.569732) (xy 122.726619 -226.608803)
			(xy 122.756643 -226.65284) (xy 122.779769 -226.700861) (xy 122.795479 -226.751791) (xy 122.803422 -226.804495)
			(xy 122.80392 -226.831144) (xy 122.803422 -226.857793) (xy 123.032002 -226.857793) (xy 123.032002 -226.804495)
			(xy 123.039945 -226.751791) (xy 123.055655 -226.700861) (xy 123.078781 -226.65284) (xy 123.108805 -226.608803)
			(xy 123.145057 -226.569732) (xy 123.186728 -226.536501) (xy 123.232886 -226.509852) (xy 123.2825 -226.49038)
			(xy 123.334462 -226.47852) (xy 123.387612 -226.474537) (xy 123.440762 -226.47852) (xy 123.492724 -226.49038)
			(xy 123.542338 -226.509852) (xy 123.588496 -226.536501) (xy 123.630167 -226.569732) (xy 123.666419 -226.608803)
			(xy 123.696443 -226.65284) (xy 123.719569 -226.700861) (xy 123.735279 -226.751791) (xy 123.743222 -226.804495)
			(xy 123.74372 -226.831144) (xy 123.743222 -226.857793) (xy 123.972056 -226.857793) (xy 123.972056 -226.804495)
			(xy 123.979999 -226.751791) (xy 123.995709 -226.700861) (xy 124.018835 -226.65284) (xy 124.048859 -226.608803)
			(xy 124.085111 -226.569732) (xy 124.126782 -226.536501) (xy 124.17294 -226.509852) (xy 124.222554 -226.49038)
			(xy 124.274516 -226.47852) (xy 124.327666 -226.474537) (xy 124.380816 -226.47852) (xy 124.432778 -226.49038)
			(xy 124.482392 -226.509852) (xy 124.52855 -226.536501) (xy 124.570221 -226.569732) (xy 124.606473 -226.608803)
			(xy 124.636497 -226.65284) (xy 124.659623 -226.700861) (xy 124.675333 -226.751791) (xy 124.683276 -226.804495)
			(xy 124.683774 -226.831144) (xy 124.683276 -226.857793) (xy 124.911602 -226.857793) (xy 124.911602 -226.804495)
			(xy 124.919545 -226.751791) (xy 124.935255 -226.700861) (xy 124.958381 -226.65284) (xy 124.988405 -226.608803)
			(xy 125.024657 -226.569732) (xy 125.066328 -226.536501) (xy 125.112486 -226.509852) (xy 125.1621 -226.49038)
			(xy 125.214062 -226.47852) (xy 125.267212 -226.474537) (xy 125.320362 -226.47852) (xy 125.372324 -226.49038)
			(xy 125.421938 -226.509852) (xy 125.468096 -226.536501) (xy 125.509767 -226.569732) (xy 125.546019 -226.608803)
			(xy 125.576043 -226.65284) (xy 125.599169 -226.700861) (xy 125.614879 -226.751791) (xy 125.622822 -226.804495)
			(xy 125.62332 -226.831144) (xy 125.622822 -226.857793) (xy 125.851402 -226.857793) (xy 125.851402 -226.804495)
			(xy 125.859345 -226.751791) (xy 125.875055 -226.700861) (xy 125.898181 -226.65284) (xy 125.928205 -226.608803)
			(xy 125.964457 -226.569732) (xy 126.006128 -226.536501) (xy 126.052286 -226.509852) (xy 126.1019 -226.49038)
			(xy 126.153862 -226.47852) (xy 126.207012 -226.474537) (xy 126.260162 -226.47852) (xy 126.312124 -226.49038)
			(xy 126.361738 -226.509852) (xy 126.407896 -226.536501) (xy 126.449567 -226.569732) (xy 126.485819 -226.608803)
			(xy 126.515843 -226.65284) (xy 126.538969 -226.700861) (xy 126.554679 -226.751791) (xy 126.562622 -226.804495)
			(xy 126.56312 -226.831144) (xy 126.562622 -226.857793) (xy 126.791456 -226.857793) (xy 126.791456 -226.804495)
			(xy 126.799399 -226.751791) (xy 126.815109 -226.700861) (xy 126.838235 -226.65284) (xy 126.868259 -226.608803)
			(xy 126.904511 -226.569732) (xy 126.946182 -226.536501) (xy 126.99234 -226.509852) (xy 127.041954 -226.49038)
			(xy 127.093916 -226.47852) (xy 127.147066 -226.474537) (xy 127.200216 -226.47852) (xy 127.252178 -226.49038)
			(xy 127.301792 -226.509852) (xy 127.34795 -226.536501) (xy 127.389621 -226.569732) (xy 127.425873 -226.608803)
			(xy 127.455897 -226.65284) (xy 127.479023 -226.700861) (xy 127.494733 -226.751791) (xy 127.502676 -226.804495)
			(xy 127.503174 -226.831144) (xy 127.502676 -226.857793) (xy 127.731256 -226.857793) (xy 127.731256 -226.804495)
			(xy 127.739199 -226.751791) (xy 127.754909 -226.700861) (xy 127.778035 -226.65284) (xy 127.808059 -226.608803)
			(xy 127.844311 -226.569732) (xy 127.885982 -226.536501) (xy 127.93214 -226.509852) (xy 127.981754 -226.49038)
			(xy 128.033716 -226.47852) (xy 128.086866 -226.474537) (xy 128.140016 -226.47852) (xy 128.191978 -226.49038)
			(xy 128.241592 -226.509852) (xy 128.28775 -226.536501) (xy 128.329421 -226.569732) (xy 128.365673 -226.608803)
			(xy 128.395697 -226.65284) (xy 128.418823 -226.700861) (xy 128.434533 -226.751791) (xy 128.442476 -226.804495)
			(xy 128.442974 -226.831144) (xy 128.442476 -226.857793) (xy 128.670802 -226.857793) (xy 128.670802 -226.804495)
			(xy 128.678745 -226.751791) (xy 128.694455 -226.700861) (xy 128.717581 -226.65284) (xy 128.747605 -226.608803)
			(xy 128.783857 -226.569732) (xy 128.825528 -226.536501) (xy 128.871686 -226.509852) (xy 128.9213 -226.49038)
			(xy 128.973262 -226.47852) (xy 129.026412 -226.474537) (xy 129.079562 -226.47852) (xy 129.131524 -226.49038)
			(xy 129.181138 -226.509852) (xy 129.227296 -226.536501) (xy 129.268967 -226.569732) (xy 129.305219 -226.608803)
			(xy 129.335243 -226.65284) (xy 129.358369 -226.700861) (xy 129.374079 -226.751791) (xy 129.382022 -226.804495)
			(xy 129.38252 -226.831144) (xy 129.382022 -226.857793) (xy 129.610602 -226.857793) (xy 129.610602 -226.804495)
			(xy 129.618545 -226.751791) (xy 129.634255 -226.700861) (xy 129.657381 -226.65284) (xy 129.687405 -226.608803)
			(xy 129.723657 -226.569732) (xy 129.765328 -226.536501) (xy 129.811486 -226.509852) (xy 129.8611 -226.49038)
			(xy 129.913062 -226.47852) (xy 129.966212 -226.474537) (xy 130.019362 -226.47852) (xy 130.071324 -226.49038)
			(xy 130.120938 -226.509852) (xy 130.167096 -226.536501) (xy 130.208767 -226.569732) (xy 130.245019 -226.608803)
			(xy 130.275043 -226.65284) (xy 130.298169 -226.700861) (xy 130.313879 -226.751791) (xy 130.321822 -226.804495)
			(xy 130.32232 -226.831144) (xy 130.321822 -226.857793) (xy 130.550656 -226.857793) (xy 130.550656 -226.804495)
			(xy 130.558599 -226.751791) (xy 130.574309 -226.700861) (xy 130.597435 -226.65284) (xy 130.627459 -226.608803)
			(xy 130.663711 -226.569732) (xy 130.705382 -226.536501) (xy 130.75154 -226.509852) (xy 130.801154 -226.49038)
			(xy 130.853116 -226.47852) (xy 130.906266 -226.474537) (xy 130.959416 -226.47852) (xy 131.011378 -226.49038)
			(xy 131.060992 -226.509852) (xy 131.10715 -226.536501) (xy 131.148821 -226.569732) (xy 131.185073 -226.608803)
			(xy 131.215097 -226.65284) (xy 131.238223 -226.700861) (xy 131.253933 -226.751791) (xy 131.261876 -226.804495)
			(xy 131.262374 -226.831144) (xy 131.261876 -226.857793) (xy 131.490202 -226.857793) (xy 131.490202 -226.804495)
			(xy 131.498145 -226.751791) (xy 131.513855 -226.700861) (xy 131.536981 -226.65284) (xy 131.567005 -226.608803)
			(xy 131.603257 -226.569732) (xy 131.644928 -226.536501) (xy 131.691086 -226.509852) (xy 131.7407 -226.49038)
			(xy 131.792662 -226.47852) (xy 131.845812 -226.474537) (xy 131.898962 -226.47852) (xy 131.950924 -226.49038)
			(xy 132.000538 -226.509852) (xy 132.046696 -226.536501) (xy 132.088367 -226.569732) (xy 132.124619 -226.608803)
			(xy 132.154643 -226.65284) (xy 132.177769 -226.700861) (xy 132.193479 -226.751791) (xy 132.201422 -226.804495)
			(xy 132.20192 -226.831144) (xy 132.201422 -226.857793) (xy 132.430002 -226.857793) (xy 132.430002 -226.804495)
			(xy 132.437945 -226.751791) (xy 132.453655 -226.700861) (xy 132.476781 -226.65284) (xy 132.506805 -226.608803)
			(xy 132.543057 -226.569732) (xy 132.584728 -226.536501) (xy 132.630886 -226.509852) (xy 132.6805 -226.49038)
			(xy 132.732462 -226.47852) (xy 132.785612 -226.474537) (xy 132.838762 -226.47852) (xy 132.890724 -226.49038)
			(xy 132.940338 -226.509852) (xy 132.986496 -226.536501) (xy 133.028167 -226.569732) (xy 133.064419 -226.608803)
			(xy 133.094443 -226.65284) (xy 133.117569 -226.700861) (xy 133.133279 -226.751791) (xy 133.141222 -226.804495)
			(xy 133.14172 -226.831144) (xy 133.141222 -226.857793) (xy 133.370056 -226.857793) (xy 133.370056 -226.804495)
			(xy 133.377999 -226.751791) (xy 133.393709 -226.700861) (xy 133.416835 -226.65284) (xy 133.446859 -226.608803)
			(xy 133.483111 -226.569732) (xy 133.524782 -226.536501) (xy 133.57094 -226.509852) (xy 133.620554 -226.49038)
			(xy 133.672516 -226.47852) (xy 133.725666 -226.474537) (xy 133.778816 -226.47852) (xy 133.830778 -226.49038)
			(xy 133.880392 -226.509852) (xy 133.92655 -226.536501) (xy 133.968221 -226.569732) (xy 134.004473 -226.608803)
			(xy 134.034497 -226.65284) (xy 134.057623 -226.700861) (xy 134.073333 -226.751791) (xy 134.081276 -226.804495)
			(xy 134.081774 -226.831144) (xy 134.081276 -226.857793) (xy 134.309602 -226.857793) (xy 134.309602 -226.804495)
			(xy 134.317545 -226.751791) (xy 134.333255 -226.700861) (xy 134.356381 -226.65284) (xy 134.386405 -226.608803)
			(xy 134.422657 -226.569732) (xy 134.464328 -226.536501) (xy 134.510486 -226.509852) (xy 134.5601 -226.49038)
			(xy 134.612062 -226.47852) (xy 134.665212 -226.474537) (xy 134.718362 -226.47852) (xy 134.770324 -226.49038)
			(xy 134.819938 -226.509852) (xy 134.866096 -226.536501) (xy 134.907767 -226.569732) (xy 134.944019 -226.608803)
			(xy 134.974043 -226.65284) (xy 134.997169 -226.700861) (xy 135.012879 -226.751791) (xy 135.020822 -226.804495)
			(xy 135.02132 -226.831144) (xy 135.020822 -226.857793) (xy 135.012879 -226.910497) (xy 134.997169 -226.961427)
			(xy 134.974043 -227.009448) (xy 134.944019 -227.053485) (xy 134.907767 -227.092556) (xy 134.866096 -227.125787)
			(xy 134.819938 -227.152436) (xy 134.770324 -227.171908) (xy 134.718362 -227.183768) (xy 134.665212 -227.187752)
			(xy 134.612062 -227.183768) (xy 134.5601 -227.171908) (xy 134.510486 -227.152436) (xy 134.464328 -227.125787)
			(xy 134.422657 -227.092556) (xy 134.386405 -227.053485) (xy 134.356381 -227.009448) (xy 134.333255 -226.961427)
			(xy 134.317545 -226.910497) (xy 134.309602 -226.857793) (xy 134.081276 -226.857793) (xy 134.073333 -226.910497)
			(xy 134.057623 -226.961427) (xy 134.034497 -227.009448) (xy 134.004473 -227.053485) (xy 133.968221 -227.092556)
			(xy 133.92655 -227.125787) (xy 133.880392 -227.152436) (xy 133.830778 -227.171908) (xy 133.778816 -227.183768)
			(xy 133.725666 -227.187752) (xy 133.672516 -227.183768) (xy 133.620554 -227.171908) (xy 133.57094 -227.152436)
			(xy 133.524782 -227.125787) (xy 133.483111 -227.092556) (xy 133.446859 -227.053485) (xy 133.416835 -227.009448)
			(xy 133.393709 -226.961427) (xy 133.377999 -226.910497) (xy 133.370056 -226.857793) (xy 133.141222 -226.857793)
			(xy 133.133279 -226.910497) (xy 133.117569 -226.961427) (xy 133.094443 -227.009448) (xy 133.064419 -227.053485)
			(xy 133.028167 -227.092556) (xy 132.986496 -227.125787) (xy 132.940338 -227.152436) (xy 132.890724 -227.171908)
			(xy 132.838762 -227.183768) (xy 132.785612 -227.187752) (xy 132.732462 -227.183768) (xy 132.6805 -227.171908)
			(xy 132.630886 -227.152436) (xy 132.584728 -227.125787) (xy 132.543057 -227.092556) (xy 132.506805 -227.053485)
			(xy 132.476781 -227.009448) (xy 132.453655 -226.961427) (xy 132.437945 -226.910497) (xy 132.430002 -226.857793)
			(xy 132.201422 -226.857793) (xy 132.193479 -226.910497) (xy 132.177769 -226.961427) (xy 132.154643 -227.009448)
			(xy 132.124619 -227.053485) (xy 132.088367 -227.092556) (xy 132.046696 -227.125787) (xy 132.000538 -227.152436)
			(xy 131.950924 -227.171908) (xy 131.898962 -227.183768) (xy 131.845812 -227.187752) (xy 131.792662 -227.183768)
			(xy 131.7407 -227.171908) (xy 131.691086 -227.152436) (xy 131.644928 -227.125787) (xy 131.603257 -227.092556)
			(xy 131.567005 -227.053485) (xy 131.536981 -227.009448) (xy 131.513855 -226.961427) (xy 131.498145 -226.910497)
			(xy 131.490202 -226.857793) (xy 131.261876 -226.857793) (xy 131.253933 -226.910497) (xy 131.238223 -226.961427)
			(xy 131.215097 -227.009448) (xy 131.185073 -227.053485) (xy 131.148821 -227.092556) (xy 131.10715 -227.125787)
			(xy 131.060992 -227.152436) (xy 131.011378 -227.171908) (xy 130.959416 -227.183768) (xy 130.906266 -227.187752)
			(xy 130.853116 -227.183768) (xy 130.801154 -227.171908) (xy 130.75154 -227.152436) (xy 130.705382 -227.125787)
			(xy 130.663711 -227.092556) (xy 130.627459 -227.053485) (xy 130.597435 -227.009448) (xy 130.574309 -226.961427)
			(xy 130.558599 -226.910497) (xy 130.550656 -226.857793) (xy 130.321822 -226.857793) (xy 130.313879 -226.910497)
			(xy 130.298169 -226.961427) (xy 130.275043 -227.009448) (xy 130.245019 -227.053485) (xy 130.208767 -227.092556)
			(xy 130.167096 -227.125787) (xy 130.120938 -227.152436) (xy 130.071324 -227.171908) (xy 130.019362 -227.183768)
			(xy 129.966212 -227.187752) (xy 129.913062 -227.183768) (xy 129.8611 -227.171908) (xy 129.811486 -227.152436)
			(xy 129.765328 -227.125787) (xy 129.723657 -227.092556) (xy 129.687405 -227.053485) (xy 129.657381 -227.009448)
			(xy 129.634255 -226.961427) (xy 129.618545 -226.910497) (xy 129.610602 -226.857793) (xy 129.382022 -226.857793)
			(xy 129.374079 -226.910497) (xy 129.358369 -226.961427) (xy 129.335243 -227.009448) (xy 129.305219 -227.053485)
			(xy 129.268967 -227.092556) (xy 129.227296 -227.125787) (xy 129.181138 -227.152436) (xy 129.131524 -227.171908)
			(xy 129.079562 -227.183768) (xy 129.026412 -227.187752) (xy 128.973262 -227.183768) (xy 128.9213 -227.171908)
			(xy 128.871686 -227.152436) (xy 128.825528 -227.125787) (xy 128.783857 -227.092556) (xy 128.747605 -227.053485)
			(xy 128.717581 -227.009448) (xy 128.694455 -226.961427) (xy 128.678745 -226.910497) (xy 128.670802 -226.857793)
			(xy 128.442476 -226.857793) (xy 128.434533 -226.910497) (xy 128.418823 -226.961427) (xy 128.395697 -227.009448)
			(xy 128.365673 -227.053485) (xy 128.329421 -227.092556) (xy 128.28775 -227.125787) (xy 128.241592 -227.152436)
			(xy 128.191978 -227.171908) (xy 128.140016 -227.183768) (xy 128.086866 -227.187752) (xy 128.033716 -227.183768)
			(xy 127.981754 -227.171908) (xy 127.93214 -227.152436) (xy 127.885982 -227.125787) (xy 127.844311 -227.092556)
			(xy 127.808059 -227.053485) (xy 127.778035 -227.009448) (xy 127.754909 -226.961427) (xy 127.739199 -226.910497)
			(xy 127.731256 -226.857793) (xy 127.502676 -226.857793) (xy 127.494733 -226.910497) (xy 127.479023 -226.961427)
			(xy 127.455897 -227.009448) (xy 127.425873 -227.053485) (xy 127.389621 -227.092556) (xy 127.34795 -227.125787)
			(xy 127.301792 -227.152436) (xy 127.252178 -227.171908) (xy 127.200216 -227.183768) (xy 127.147066 -227.187752)
			(xy 127.093916 -227.183768) (xy 127.041954 -227.171908) (xy 126.99234 -227.152436) (xy 126.946182 -227.125787)
			(xy 126.904511 -227.092556) (xy 126.868259 -227.053485) (xy 126.838235 -227.009448) (xy 126.815109 -226.961427)
			(xy 126.799399 -226.910497) (xy 126.791456 -226.857793) (xy 126.562622 -226.857793) (xy 126.554679 -226.910497)
			(xy 126.538969 -226.961427) (xy 126.515843 -227.009448) (xy 126.485819 -227.053485) (xy 126.449567 -227.092556)
			(xy 126.407896 -227.125787) (xy 126.361738 -227.152436) (xy 126.312124 -227.171908) (xy 126.260162 -227.183768)
			(xy 126.207012 -227.187752) (xy 126.153862 -227.183768) (xy 126.1019 -227.171908) (xy 126.052286 -227.152436)
			(xy 126.006128 -227.125787) (xy 125.964457 -227.092556) (xy 125.928205 -227.053485) (xy 125.898181 -227.009448)
			(xy 125.875055 -226.961427) (xy 125.859345 -226.910497) (xy 125.851402 -226.857793) (xy 125.622822 -226.857793)
			(xy 125.614879 -226.910497) (xy 125.599169 -226.961427) (xy 125.576043 -227.009448) (xy 125.546019 -227.053485)
			(xy 125.509767 -227.092556) (xy 125.468096 -227.125787) (xy 125.421938 -227.152436) (xy 125.372324 -227.171908)
			(xy 125.320362 -227.183768) (xy 125.267212 -227.187752) (xy 125.214062 -227.183768) (xy 125.1621 -227.171908)
			(xy 125.112486 -227.152436) (xy 125.066328 -227.125787) (xy 125.024657 -227.092556) (xy 124.988405 -227.053485)
			(xy 124.958381 -227.009448) (xy 124.935255 -226.961427) (xy 124.919545 -226.910497) (xy 124.911602 -226.857793)
			(xy 124.683276 -226.857793) (xy 124.675333 -226.910497) (xy 124.659623 -226.961427) (xy 124.636497 -227.009448)
			(xy 124.606473 -227.053485) (xy 124.570221 -227.092556) (xy 124.52855 -227.125787) (xy 124.482392 -227.152436)
			(xy 124.432778 -227.171908) (xy 124.380816 -227.183768) (xy 124.327666 -227.187752) (xy 124.274516 -227.183768)
			(xy 124.222554 -227.171908) (xy 124.17294 -227.152436) (xy 124.126782 -227.125787) (xy 124.085111 -227.092556)
			(xy 124.048859 -227.053485) (xy 124.018835 -227.009448) (xy 123.995709 -226.961427) (xy 123.979999 -226.910497)
			(xy 123.972056 -226.857793) (xy 123.743222 -226.857793) (xy 123.735279 -226.910497) (xy 123.719569 -226.961427)
			(xy 123.696443 -227.009448) (xy 123.666419 -227.053485) (xy 123.630167 -227.092556) (xy 123.588496 -227.125787)
			(xy 123.542338 -227.152436) (xy 123.492724 -227.171908) (xy 123.440762 -227.183768) (xy 123.387612 -227.187752)
			(xy 123.334462 -227.183768) (xy 123.2825 -227.171908) (xy 123.232886 -227.152436) (xy 123.186728 -227.125787)
			(xy 123.145057 -227.092556) (xy 123.108805 -227.053485) (xy 123.078781 -227.009448) (xy 123.055655 -226.961427)
			(xy 123.039945 -226.910497) (xy 123.032002 -226.857793) (xy 122.803422 -226.857793) (xy 122.795479 -226.910497)
			(xy 122.779769 -226.961427) (xy 122.756643 -227.009448) (xy 122.726619 -227.053485) (xy 122.690367 -227.092556)
			(xy 122.648696 -227.125787) (xy 122.602538 -227.152436) (xy 122.552924 -227.171908) (xy 122.500962 -227.183768)
			(xy 122.447812 -227.187752) (xy 122.394662 -227.183768) (xy 122.3427 -227.171908) (xy 122.293086 -227.152436)
			(xy 122.246928 -227.125787) (xy 122.205257 -227.092556) (xy 122.169005 -227.053485) (xy 122.138981 -227.009448)
			(xy 122.115855 -226.961427) (xy 122.100145 -226.910497) (xy 122.092202 -226.857793) (xy 121.863876 -226.857793)
			(xy 121.855933 -226.910497) (xy 121.840223 -226.961427) (xy 121.817097 -227.009448) (xy 121.787073 -227.053485)
			(xy 121.750821 -227.092556) (xy 121.70915 -227.125787) (xy 121.662992 -227.152436) (xy 121.613378 -227.171908)
			(xy 121.561416 -227.183768) (xy 121.508266 -227.187752) (xy 121.455116 -227.183768) (xy 121.403154 -227.171908)
			(xy 121.35354 -227.152436) (xy 121.307382 -227.125787) (xy 121.265711 -227.092556) (xy 121.229459 -227.053485)
			(xy 121.199435 -227.009448) (xy 121.176309 -226.961427) (xy 121.160599 -226.910497) (xy 121.152656 -226.857793)
			(xy 120.923822 -226.857793) (xy 120.915879 -226.910497) (xy 120.900169 -226.961427) (xy 120.877043 -227.009448)
			(xy 120.847019 -227.053485) (xy 120.810767 -227.092556) (xy 120.769096 -227.125787) (xy 120.722938 -227.152436)
			(xy 120.673324 -227.171908) (xy 120.621362 -227.183768) (xy 120.568212 -227.187752) (xy 120.515062 -227.183768)
			(xy 120.4631 -227.171908) (xy 120.413486 -227.152436) (xy 120.367328 -227.125787) (xy 120.325657 -227.092556)
			(xy 120.289405 -227.053485) (xy 120.259381 -227.009448) (xy 120.236255 -226.961427) (xy 120.220545 -226.910497)
			(xy 120.212602 -226.857793) (xy 119.984276 -226.857793) (xy 119.976333 -226.910497) (xy 119.960623 -226.961427)
			(xy 119.937497 -227.009448) (xy 119.907473 -227.053485) (xy 119.871221 -227.092556) (xy 119.82955 -227.125787)
			(xy 119.783392 -227.152436) (xy 119.733778 -227.171908) (xy 119.681816 -227.183768) (xy 119.628666 -227.187752)
			(xy 119.575516 -227.183768) (xy 119.523554 -227.171908) (xy 119.47394 -227.152436) (xy 119.427782 -227.125787)
			(xy 119.386111 -227.092556) (xy 119.349859 -227.053485) (xy 119.319835 -227.009448) (xy 119.296709 -226.961427)
			(xy 119.280999 -226.910497) (xy 119.273056 -226.857793) (xy 119.044222 -226.857793) (xy 119.036279 -226.910497)
			(xy 119.020569 -226.961427) (xy 118.997443 -227.009448) (xy 118.967419 -227.053485) (xy 118.931167 -227.092556)
			(xy 118.889496 -227.125787) (xy 118.843338 -227.152436) (xy 118.793724 -227.171908) (xy 118.741762 -227.183768)
			(xy 118.688612 -227.187752) (xy 118.635462 -227.183768) (xy 118.5835 -227.171908) (xy 118.533886 -227.152436)
			(xy 118.487728 -227.125787) (xy 118.446057 -227.092556) (xy 118.409805 -227.053485) (xy 118.379781 -227.009448)
			(xy 118.356655 -226.961427) (xy 118.340945 -226.910497) (xy 118.333002 -226.857793) (xy 118.104676 -226.857793)
			(xy 118.096733 -226.910497) (xy 118.081023 -226.961427) (xy 118.057897 -227.009448) (xy 118.027873 -227.053485)
			(xy 117.991621 -227.092556) (xy 117.94995 -227.125787) (xy 117.903792 -227.152436) (xy 117.854178 -227.171908)
			(xy 117.802216 -227.183768) (xy 117.749066 -227.187752) (xy 117.695916 -227.183768) (xy 117.643954 -227.171908)
			(xy 117.59434 -227.152436) (xy 117.548182 -227.125787) (xy 117.506511 -227.092556) (xy 117.470259 -227.053485)
			(xy 117.440235 -227.009448) (xy 117.417109 -226.961427) (xy 117.401399 -226.910497) (xy 117.393456 -226.857793)
			(xy 117.164622 -226.857793) (xy 117.156679 -226.910497) (xy 117.140969 -226.961427) (xy 117.117843 -227.009448)
			(xy 117.087819 -227.053485) (xy 117.051567 -227.092556) (xy 117.009896 -227.125787) (xy 116.963738 -227.152436)
			(xy 116.914124 -227.171908) (xy 116.862162 -227.183768) (xy 116.809012 -227.187752) (xy 116.755862 -227.183768)
			(xy 116.7039 -227.171908) (xy 116.654286 -227.152436) (xy 116.608128 -227.125787) (xy 116.566457 -227.092556)
			(xy 116.530205 -227.053485) (xy 116.500181 -227.009448) (xy 116.477055 -226.961427) (xy 116.461345 -226.910497)
			(xy 116.453402 -226.857793) (xy 116.225076 -226.857793) (xy 116.217133 -226.910497) (xy 116.201423 -226.961427)
			(xy 116.178297 -227.009448) (xy 116.148273 -227.053485) (xy 116.112021 -227.092556) (xy 116.07035 -227.125787)
			(xy 116.024192 -227.152436) (xy 115.974578 -227.171908) (xy 115.922616 -227.183768) (xy 115.869466 -227.187752)
			(xy 115.816316 -227.183768) (xy 115.764354 -227.171908) (xy 115.71474 -227.152436) (xy 115.668582 -227.125787)
			(xy 115.626911 -227.092556) (xy 115.590659 -227.053485) (xy 115.560635 -227.009448) (xy 115.537509 -226.961427)
			(xy 115.521799 -226.910497) (xy 115.513856 -226.857793) (xy 115.285276 -226.857793) (xy 115.277333 -226.910497)
			(xy 115.261623 -226.961427) (xy 115.238497 -227.009448) (xy 115.208473 -227.053485) (xy 115.172221 -227.092556)
			(xy 115.13055 -227.125787) (xy 115.084392 -227.152436) (xy 115.034778 -227.171908) (xy 114.982816 -227.183768)
			(xy 114.929666 -227.187752) (xy 114.876516 -227.183768) (xy 114.824554 -227.171908) (xy 114.77494 -227.152436)
			(xy 114.728782 -227.125787) (xy 114.687111 -227.092556) (xy 114.650859 -227.053485) (xy 114.620835 -227.009448)
			(xy 114.597709 -226.961427) (xy 114.581999 -226.910497) (xy 114.574056 -226.857793) (xy 114.345476 -226.857793)
			(xy 114.337533 -226.910497) (xy 114.321823 -226.961427) (xy 114.298697 -227.009448) (xy 114.268673 -227.053485)
			(xy 114.232421 -227.092556) (xy 114.19075 -227.125787) (xy 114.144592 -227.152436) (xy 114.094978 -227.171908)
			(xy 114.043016 -227.183768) (xy 113.989866 -227.187752) (xy 113.936716 -227.183768) (xy 113.884754 -227.171908)
			(xy 113.83514 -227.152436) (xy 113.788982 -227.125787) (xy 113.747311 -227.092556) (xy 113.711059 -227.053485)
			(xy 113.681035 -227.009448) (xy 113.657909 -226.961427) (xy 113.642199 -226.910497) (xy 113.634256 -226.857793)
			(xy 113.405422 -226.857793) (xy 113.397479 -226.910497) (xy 113.381769 -226.961427) (xy 113.358643 -227.009448)
			(xy 113.328619 -227.053485) (xy 113.292367 -227.092556) (xy 113.250696 -227.125787) (xy 113.204538 -227.152436)
			(xy 113.154924 -227.171908) (xy 113.102962 -227.183768) (xy 113.049812 -227.187752) (xy 112.996662 -227.183768)
			(xy 112.9447 -227.171908) (xy 112.895086 -227.152436) (xy 112.848928 -227.125787) (xy 112.807257 -227.092556)
			(xy 112.771005 -227.053485) (xy 112.740981 -227.009448) (xy 112.717855 -226.961427) (xy 112.702145 -226.910497)
			(xy 112.694202 -226.857793) (xy 112.464888 -226.857793) (xy 112.462905 -226.88425) (xy 112.451044 -226.936212)
			(xy 112.43157 -226.985826) (xy 112.40492 -227.031984) (xy 112.371686 -227.073653) (xy 112.332614 -227.109904)
			(xy 112.288574 -227.139926) (xy 112.240552 -227.163048) (xy 112.18962 -227.178754) (xy 112.136916 -227.186693)
			(xy 112.110266 -227.187252) (xy 112.086876 -227.186868) (xy 112.040498 -227.180758) (xy 112.01781 -227.17506)
			(xy 112.004836 -227.171979) (xy 111.978178 -227.171951) (xy 111.952422 -227.178823) (xy 111.929322 -227.192129)
			(xy 111.910453 -227.21096) (xy 111.897102 -227.234033) (xy 111.890177 -227.259776) (xy 111.889794 -227.273104)
			(xy 111.889794 -227.390706) (xy 111.90785 -227.409072) (xy 111.939022 -227.450069) (xy 111.963968 -227.495127)
			(xy 111.982168 -227.543307) (xy 111.993244 -227.593604) (xy 111.996965 -227.644972) (xy 111.99504 -227.671609)
			(xy 112.224556 -227.671609) (xy 112.224556 -227.618311) (xy 112.232499 -227.565607) (xy 112.248209 -227.514677)
			(xy 112.271335 -227.466656) (xy 112.301359 -227.422619) (xy 112.337611 -227.383548) (xy 112.379282 -227.350317)
			(xy 112.42544 -227.323668) (xy 112.475054 -227.304196) (xy 112.527016 -227.292336) (xy 112.580166 -227.288353)
			(xy 112.633316 -227.292336) (xy 112.685278 -227.304196) (xy 112.734892 -227.323668) (xy 112.78105 -227.350317)
			(xy 112.822721 -227.383548) (xy 112.858973 -227.422619) (xy 112.888997 -227.466656) (xy 112.912123 -227.514677)
			(xy 112.927833 -227.565607) (xy 112.935776 -227.618311) (xy 112.936274 -227.64496) (xy 112.935776 -227.671609)
			(xy 113.164356 -227.671609) (xy 113.164356 -227.618311) (xy 113.172299 -227.565607) (xy 113.188009 -227.514677)
			(xy 113.211135 -227.466656) (xy 113.241159 -227.422619) (xy 113.277411 -227.383548) (xy 113.319082 -227.350317)
			(xy 113.36524 -227.323668) (xy 113.414854 -227.304196) (xy 113.466816 -227.292336) (xy 113.519966 -227.288353)
			(xy 113.573116 -227.292336) (xy 113.625078 -227.304196) (xy 113.674692 -227.323668) (xy 113.72085 -227.350317)
			(xy 113.762521 -227.383548) (xy 113.798773 -227.422619) (xy 113.828797 -227.466656) (xy 113.851923 -227.514677)
			(xy 113.867633 -227.565607) (xy 113.875576 -227.618311) (xy 113.876074 -227.64496) (xy 113.875576 -227.671609)
			(xy 114.10441 -227.671609) (xy 114.10441 -227.618311) (xy 114.112353 -227.565607) (xy 114.128063 -227.514677)
			(xy 114.151189 -227.466656) (xy 114.181213 -227.422619) (xy 114.217465 -227.383548) (xy 114.259136 -227.350317)
			(xy 114.305294 -227.323668) (xy 114.354908 -227.304196) (xy 114.40687 -227.292336) (xy 114.46002 -227.288353)
			(xy 114.51317 -227.292336) (xy 114.565132 -227.304196) (xy 114.614746 -227.323668) (xy 114.660904 -227.350317)
			(xy 114.702575 -227.383548) (xy 114.738827 -227.422619) (xy 114.768851 -227.466656) (xy 114.791977 -227.514677)
			(xy 114.807687 -227.565607) (xy 114.81563 -227.618311) (xy 114.816128 -227.64496) (xy 114.81563 -227.671609)
			(xy 115.043956 -227.671609) (xy 115.043956 -227.618311) (xy 115.051899 -227.565607) (xy 115.067609 -227.514677)
			(xy 115.090735 -227.466656) (xy 115.120759 -227.422619) (xy 115.157011 -227.383548) (xy 115.198682 -227.350317)
			(xy 115.24484 -227.323668) (xy 115.294454 -227.304196) (xy 115.346416 -227.292336) (xy 115.399566 -227.288353)
			(xy 115.452716 -227.292336) (xy 115.504678 -227.304196) (xy 115.554292 -227.323668) (xy 115.60045 -227.350317)
			(xy 115.642121 -227.383548) (xy 115.678373 -227.422619) (xy 115.708397 -227.466656) (xy 115.731523 -227.514677)
			(xy 115.747233 -227.565607) (xy 115.755176 -227.618311) (xy 115.755674 -227.64496) (xy 115.755176 -227.671609)
			(xy 115.983756 -227.671609) (xy 115.983756 -227.618311) (xy 115.991699 -227.565607) (xy 116.007409 -227.514677)
			(xy 116.030535 -227.466656) (xy 116.060559 -227.422619) (xy 116.096811 -227.383548) (xy 116.138482 -227.350317)
			(xy 116.18464 -227.323668) (xy 116.234254 -227.304196) (xy 116.286216 -227.292336) (xy 116.339366 -227.288353)
			(xy 116.392516 -227.292336) (xy 116.444478 -227.304196) (xy 116.494092 -227.323668) (xy 116.54025 -227.350317)
			(xy 116.581921 -227.383548) (xy 116.618173 -227.422619) (xy 116.648197 -227.466656) (xy 116.671323 -227.514677)
			(xy 116.687033 -227.565607) (xy 116.694976 -227.618311) (xy 116.695474 -227.64496) (xy 116.694976 -227.671609)
			(xy 116.923556 -227.671609) (xy 116.923556 -227.618311) (xy 116.931499 -227.565607) (xy 116.947209 -227.514677)
			(xy 116.970335 -227.466656) (xy 117.000359 -227.422619) (xy 117.036611 -227.383548) (xy 117.078282 -227.350317)
			(xy 117.12444 -227.323668) (xy 117.174054 -227.304196) (xy 117.226016 -227.292336) (xy 117.279166 -227.288353)
			(xy 117.332316 -227.292336) (xy 117.384278 -227.304196) (xy 117.433892 -227.323668) (xy 117.48005 -227.350317)
			(xy 117.521721 -227.383548) (xy 117.557973 -227.422619) (xy 117.587997 -227.466656) (xy 117.611123 -227.514677)
			(xy 117.626833 -227.565607) (xy 117.634776 -227.618311) (xy 117.635274 -227.64496) (xy 117.634776 -227.671609)
			(xy 117.863356 -227.671609) (xy 117.863356 -227.618311) (xy 117.871299 -227.565607) (xy 117.887009 -227.514677)
			(xy 117.910135 -227.466656) (xy 117.940159 -227.422619) (xy 117.976411 -227.383548) (xy 118.018082 -227.350317)
			(xy 118.06424 -227.323668) (xy 118.113854 -227.304196) (xy 118.165816 -227.292336) (xy 118.218966 -227.288353)
			(xy 118.272116 -227.292336) (xy 118.324078 -227.304196) (xy 118.373692 -227.323668) (xy 118.41985 -227.350317)
			(xy 118.461521 -227.383548) (xy 118.497773 -227.422619) (xy 118.527797 -227.466656) (xy 118.550923 -227.514677)
			(xy 118.566633 -227.565607) (xy 118.574576 -227.618311) (xy 118.575074 -227.64496) (xy 118.574576 -227.671609)
			(xy 118.803156 -227.671609) (xy 118.803156 -227.618311) (xy 118.811099 -227.565607) (xy 118.826809 -227.514677)
			(xy 118.849935 -227.466656) (xy 118.879959 -227.422619) (xy 118.916211 -227.383548) (xy 118.957882 -227.350317)
			(xy 119.00404 -227.323668) (xy 119.053654 -227.304196) (xy 119.105616 -227.292336) (xy 119.158766 -227.288353)
			(xy 119.211916 -227.292336) (xy 119.263878 -227.304196) (xy 119.313492 -227.323668) (xy 119.35965 -227.350317)
			(xy 119.401321 -227.383548) (xy 119.437573 -227.422619) (xy 119.467597 -227.466656) (xy 119.490723 -227.514677)
			(xy 119.506433 -227.565607) (xy 119.514376 -227.618311) (xy 119.514874 -227.64496) (xy 119.514376 -227.671609)
			(xy 119.742956 -227.671609) (xy 119.742956 -227.618311) (xy 119.750899 -227.565607) (xy 119.766609 -227.514677)
			(xy 119.789735 -227.466656) (xy 119.819759 -227.422619) (xy 119.856011 -227.383548) (xy 119.897682 -227.350317)
			(xy 119.94384 -227.323668) (xy 119.993454 -227.304196) (xy 120.045416 -227.292336) (xy 120.098566 -227.288353)
			(xy 120.151716 -227.292336) (xy 120.203678 -227.304196) (xy 120.253292 -227.323668) (xy 120.29945 -227.350317)
			(xy 120.341121 -227.383548) (xy 120.377373 -227.422619) (xy 120.407397 -227.466656) (xy 120.430523 -227.514677)
			(xy 120.446233 -227.565607) (xy 120.454176 -227.618311) (xy 120.454674 -227.64496) (xy 120.454176 -227.671609)
			(xy 120.682756 -227.671609) (xy 120.682756 -227.618311) (xy 120.690699 -227.565607) (xy 120.706409 -227.514677)
			(xy 120.729535 -227.466656) (xy 120.759559 -227.422619) (xy 120.795811 -227.383548) (xy 120.837482 -227.350317)
			(xy 120.88364 -227.323668) (xy 120.933254 -227.304196) (xy 120.985216 -227.292336) (xy 121.038366 -227.288353)
			(xy 121.091516 -227.292336) (xy 121.143478 -227.304196) (xy 121.193092 -227.323668) (xy 121.23925 -227.350317)
			(xy 121.280921 -227.383548) (xy 121.317173 -227.422619) (xy 121.347197 -227.466656) (xy 121.370323 -227.514677)
			(xy 121.386033 -227.565607) (xy 121.393976 -227.618311) (xy 121.394474 -227.64496) (xy 121.393976 -227.671609)
			(xy 121.622302 -227.671609) (xy 121.622302 -227.618311) (xy 121.630245 -227.565607) (xy 121.645955 -227.514677)
			(xy 121.669081 -227.466656) (xy 121.699105 -227.422619) (xy 121.735357 -227.383548) (xy 121.777028 -227.350317)
			(xy 121.823186 -227.323668) (xy 121.8728 -227.304196) (xy 121.924762 -227.292336) (xy 121.977912 -227.288353)
			(xy 122.031062 -227.292336) (xy 122.083024 -227.304196) (xy 122.132638 -227.323668) (xy 122.178796 -227.350317)
			(xy 122.220467 -227.383548) (xy 122.256719 -227.422619) (xy 122.286743 -227.466656) (xy 122.309869 -227.514677)
			(xy 122.325579 -227.565607) (xy 122.333522 -227.618311) (xy 122.33402 -227.64496) (xy 122.333522 -227.671609)
			(xy 122.562356 -227.671609) (xy 122.562356 -227.618311) (xy 122.570299 -227.565607) (xy 122.586009 -227.514677)
			(xy 122.609135 -227.466656) (xy 122.639159 -227.422619) (xy 122.675411 -227.383548) (xy 122.717082 -227.350317)
			(xy 122.76324 -227.323668) (xy 122.812854 -227.304196) (xy 122.864816 -227.292336) (xy 122.917966 -227.288353)
			(xy 122.971116 -227.292336) (xy 123.023078 -227.304196) (xy 123.072692 -227.323668) (xy 123.11885 -227.350317)
			(xy 123.160521 -227.383548) (xy 123.196773 -227.422619) (xy 123.226797 -227.466656) (xy 123.249923 -227.514677)
			(xy 123.265633 -227.565607) (xy 123.273576 -227.618311) (xy 123.274074 -227.64496) (xy 123.273576 -227.671609)
			(xy 123.502156 -227.671609) (xy 123.502156 -227.618311) (xy 123.510099 -227.565607) (xy 123.525809 -227.514677)
			(xy 123.548935 -227.466656) (xy 123.578959 -227.422619) (xy 123.615211 -227.383548) (xy 123.656882 -227.350317)
			(xy 123.70304 -227.323668) (xy 123.752654 -227.304196) (xy 123.804616 -227.292336) (xy 123.857766 -227.288353)
			(xy 123.910916 -227.292336) (xy 123.962878 -227.304196) (xy 124.012492 -227.323668) (xy 124.05865 -227.350317)
			(xy 124.100321 -227.383548) (xy 124.136573 -227.422619) (xy 124.166597 -227.466656) (xy 124.189723 -227.514677)
			(xy 124.205433 -227.565607) (xy 124.213376 -227.618311) (xy 124.213874 -227.64496) (xy 124.213376 -227.671609)
			(xy 124.441956 -227.671609) (xy 124.441956 -227.618311) (xy 124.449899 -227.565607) (xy 124.465609 -227.514677)
			(xy 124.488735 -227.466656) (xy 124.518759 -227.422619) (xy 124.555011 -227.383548) (xy 124.596682 -227.350317)
			(xy 124.64284 -227.323668) (xy 124.692454 -227.304196) (xy 124.744416 -227.292336) (xy 124.797566 -227.288353)
			(xy 124.850716 -227.292336) (xy 124.902678 -227.304196) (xy 124.952292 -227.323668) (xy 124.99845 -227.350317)
			(xy 125.040121 -227.383548) (xy 125.076373 -227.422619) (xy 125.106397 -227.466656) (xy 125.129523 -227.514677)
			(xy 125.145233 -227.565607) (xy 125.153176 -227.618311) (xy 125.153674 -227.64496) (xy 125.153176 -227.671609)
			(xy 125.381756 -227.671609) (xy 125.381756 -227.618311) (xy 125.389699 -227.565607) (xy 125.405409 -227.514677)
			(xy 125.428535 -227.466656) (xy 125.458559 -227.422619) (xy 125.494811 -227.383548) (xy 125.536482 -227.350317)
			(xy 125.58264 -227.323668) (xy 125.632254 -227.304196) (xy 125.684216 -227.292336) (xy 125.737366 -227.288353)
			(xy 125.790516 -227.292336) (xy 125.842478 -227.304196) (xy 125.892092 -227.323668) (xy 125.93825 -227.350317)
			(xy 125.979921 -227.383548) (xy 126.016173 -227.422619) (xy 126.046197 -227.466656) (xy 126.069323 -227.514677)
			(xy 126.085033 -227.565607) (xy 126.092976 -227.618311) (xy 126.093474 -227.64496) (xy 126.092976 -227.671609)
			(xy 126.321556 -227.671609) (xy 126.321556 -227.618311) (xy 126.329499 -227.565607) (xy 126.345209 -227.514677)
			(xy 126.368335 -227.466656) (xy 126.398359 -227.422619) (xy 126.434611 -227.383548) (xy 126.476282 -227.350317)
			(xy 126.52244 -227.323668) (xy 126.572054 -227.304196) (xy 126.624016 -227.292336) (xy 126.677166 -227.288353)
			(xy 126.730316 -227.292336) (xy 126.782278 -227.304196) (xy 126.831892 -227.323668) (xy 126.87805 -227.350317)
			(xy 126.919721 -227.383548) (xy 126.955973 -227.422619) (xy 126.985997 -227.466656) (xy 127.009123 -227.514677)
			(xy 127.024833 -227.565607) (xy 127.032776 -227.618311) (xy 127.033274 -227.64496) (xy 127.032776 -227.671609)
			(xy 127.261102 -227.671609) (xy 127.261102 -227.618311) (xy 127.269045 -227.565607) (xy 127.284755 -227.514677)
			(xy 127.307881 -227.466656) (xy 127.337905 -227.422619) (xy 127.374157 -227.383548) (xy 127.415828 -227.350317)
			(xy 127.461986 -227.323668) (xy 127.5116 -227.304196) (xy 127.563562 -227.292336) (xy 127.616712 -227.288353)
			(xy 127.669862 -227.292336) (xy 127.721824 -227.304196) (xy 127.771438 -227.323668) (xy 127.817596 -227.350317)
			(xy 127.859267 -227.383548) (xy 127.895519 -227.422619) (xy 127.925543 -227.466656) (xy 127.948669 -227.514677)
			(xy 127.964379 -227.565607) (xy 127.972322 -227.618311) (xy 127.97282 -227.64496) (xy 127.972322 -227.671609)
			(xy 128.200902 -227.671609) (xy 128.200902 -227.618311) (xy 128.208845 -227.565607) (xy 128.224555 -227.514677)
			(xy 128.247681 -227.466656) (xy 128.277705 -227.422619) (xy 128.313957 -227.383548) (xy 128.355628 -227.350317)
			(xy 128.401786 -227.323668) (xy 128.4514 -227.304196) (xy 128.503362 -227.292336) (xy 128.556512 -227.288353)
			(xy 128.609662 -227.292336) (xy 128.661624 -227.304196) (xy 128.711238 -227.323668) (xy 128.757396 -227.350317)
			(xy 128.799067 -227.383548) (xy 128.835319 -227.422619) (xy 128.865343 -227.466656) (xy 128.888469 -227.514677)
			(xy 128.904179 -227.565607) (xy 128.912122 -227.618311) (xy 128.91262 -227.64496) (xy 128.912122 -227.671609)
			(xy 129.140956 -227.671609) (xy 129.140956 -227.618311) (xy 129.148899 -227.565607) (xy 129.164609 -227.514677)
			(xy 129.187735 -227.466656) (xy 129.217759 -227.422619) (xy 129.254011 -227.383548) (xy 129.295682 -227.350317)
			(xy 129.34184 -227.323668) (xy 129.391454 -227.304196) (xy 129.443416 -227.292336) (xy 129.496566 -227.288353)
			(xy 129.549716 -227.292336) (xy 129.601678 -227.304196) (xy 129.651292 -227.323668) (xy 129.69745 -227.350317)
			(xy 129.739121 -227.383548) (xy 129.775373 -227.422619) (xy 129.805397 -227.466656) (xy 129.828523 -227.514677)
			(xy 129.844233 -227.565607) (xy 129.852176 -227.618311) (xy 129.852674 -227.64496) (xy 129.852176 -227.671609)
			(xy 130.080756 -227.671609) (xy 130.080756 -227.618311) (xy 130.088699 -227.565607) (xy 130.104409 -227.514677)
			(xy 130.127535 -227.466656) (xy 130.157559 -227.422619) (xy 130.193811 -227.383548) (xy 130.235482 -227.350317)
			(xy 130.28164 -227.323668) (xy 130.331254 -227.304196) (xy 130.383216 -227.292336) (xy 130.436366 -227.288353)
			(xy 130.489516 -227.292336) (xy 130.541478 -227.304196) (xy 130.591092 -227.323668) (xy 130.63725 -227.350317)
			(xy 130.678921 -227.383548) (xy 130.715173 -227.422619) (xy 130.745197 -227.466656) (xy 130.768323 -227.514677)
			(xy 130.784033 -227.565607) (xy 130.791976 -227.618311) (xy 130.792474 -227.64496) (xy 130.791976 -227.671609)
			(xy 131.020556 -227.671609) (xy 131.020556 -227.618311) (xy 131.028499 -227.565607) (xy 131.044209 -227.514677)
			(xy 131.067335 -227.466656) (xy 131.097359 -227.422619) (xy 131.133611 -227.383548) (xy 131.175282 -227.350317)
			(xy 131.22144 -227.323668) (xy 131.271054 -227.304196) (xy 131.323016 -227.292336) (xy 131.376166 -227.288353)
			(xy 131.429316 -227.292336) (xy 131.481278 -227.304196) (xy 131.530892 -227.323668) (xy 131.57705 -227.350317)
			(xy 131.618721 -227.383548) (xy 131.654973 -227.422619) (xy 131.684997 -227.466656) (xy 131.708123 -227.514677)
			(xy 131.723833 -227.565607) (xy 131.731776 -227.618311) (xy 131.732274 -227.64496) (xy 131.731776 -227.671609)
			(xy 131.960356 -227.671609) (xy 131.960356 -227.618311) (xy 131.968299 -227.565607) (xy 131.984009 -227.514677)
			(xy 132.007135 -227.466656) (xy 132.037159 -227.422619) (xy 132.073411 -227.383548) (xy 132.115082 -227.350317)
			(xy 132.16124 -227.323668) (xy 132.210854 -227.304196) (xy 132.262816 -227.292336) (xy 132.315966 -227.288353)
			(xy 132.369116 -227.292336) (xy 132.421078 -227.304196) (xy 132.470692 -227.323668) (xy 132.51685 -227.350317)
			(xy 132.558521 -227.383548) (xy 132.594773 -227.422619) (xy 132.624797 -227.466656) (xy 132.647923 -227.514677)
			(xy 132.663633 -227.565607) (xy 132.671576 -227.618311) (xy 132.672074 -227.64496) (xy 132.671576 -227.671609)
			(xy 132.900156 -227.671609) (xy 132.900156 -227.618311) (xy 132.908099 -227.565607) (xy 132.923809 -227.514677)
			(xy 132.946935 -227.466656) (xy 132.976959 -227.422619) (xy 133.013211 -227.383548) (xy 133.054882 -227.350317)
			(xy 133.10104 -227.323668) (xy 133.150654 -227.304196) (xy 133.202616 -227.292336) (xy 133.255766 -227.288353)
			(xy 133.308916 -227.292336) (xy 133.360878 -227.304196) (xy 133.410492 -227.323668) (xy 133.45665 -227.350317)
			(xy 133.498321 -227.383548) (xy 133.534573 -227.422619) (xy 133.564597 -227.466656) (xy 133.587723 -227.514677)
			(xy 133.603433 -227.565607) (xy 133.611376 -227.618311) (xy 133.611874 -227.64496) (xy 133.611376 -227.671609)
			(xy 133.839956 -227.671609) (xy 133.839956 -227.618311) (xy 133.847899 -227.565607) (xy 133.863609 -227.514677)
			(xy 133.886735 -227.466656) (xy 133.916759 -227.422619) (xy 133.953011 -227.383548) (xy 133.994682 -227.350317)
			(xy 134.04084 -227.323668) (xy 134.090454 -227.304196) (xy 134.142416 -227.292336) (xy 134.195566 -227.288353)
			(xy 134.248716 -227.292336) (xy 134.300678 -227.304196) (xy 134.350292 -227.323668) (xy 134.39645 -227.350317)
			(xy 134.438121 -227.383548) (xy 134.474373 -227.422619) (xy 134.504397 -227.466656) (xy 134.527523 -227.514677)
			(xy 134.543233 -227.565607) (xy 134.551176 -227.618311) (xy 134.551674 -227.64496) (xy 134.551176 -227.671609)
			(xy 134.543233 -227.724313) (xy 134.527523 -227.775243) (xy 134.504397 -227.823264) (xy 134.474373 -227.867301)
			(xy 134.438121 -227.906372) (xy 134.39645 -227.939603) (xy 134.350292 -227.966252) (xy 134.300678 -227.985724)
			(xy 134.248716 -227.997584) (xy 134.195566 -228.001568) (xy 134.142416 -227.997584) (xy 134.090454 -227.985724)
			(xy 134.04084 -227.966252) (xy 133.994682 -227.939603) (xy 133.953011 -227.906372) (xy 133.916759 -227.867301)
			(xy 133.886735 -227.823264) (xy 133.863609 -227.775243) (xy 133.847899 -227.724313) (xy 133.839956 -227.671609)
			(xy 133.611376 -227.671609) (xy 133.603433 -227.724313) (xy 133.587723 -227.775243) (xy 133.564597 -227.823264)
			(xy 133.534573 -227.867301) (xy 133.498321 -227.906372) (xy 133.45665 -227.939603) (xy 133.410492 -227.966252)
			(xy 133.360878 -227.985724) (xy 133.308916 -227.997584) (xy 133.255766 -228.001568) (xy 133.202616 -227.997584)
			(xy 133.150654 -227.985724) (xy 133.10104 -227.966252) (xy 133.054882 -227.939603) (xy 133.013211 -227.906372)
			(xy 132.976959 -227.867301) (xy 132.946935 -227.823264) (xy 132.923809 -227.775243) (xy 132.908099 -227.724313)
			(xy 132.900156 -227.671609) (xy 132.671576 -227.671609) (xy 132.663633 -227.724313) (xy 132.647923 -227.775243)
			(xy 132.624797 -227.823264) (xy 132.594773 -227.867301) (xy 132.558521 -227.906372) (xy 132.51685 -227.939603)
			(xy 132.470692 -227.966252) (xy 132.421078 -227.985724) (xy 132.369116 -227.997584) (xy 132.315966 -228.001568)
			(xy 132.262816 -227.997584) (xy 132.210854 -227.985724) (xy 132.16124 -227.966252) (xy 132.115082 -227.939603)
			(xy 132.073411 -227.906372) (xy 132.037159 -227.867301) (xy 132.007135 -227.823264) (xy 131.984009 -227.775243)
			(xy 131.968299 -227.724313) (xy 131.960356 -227.671609) (xy 131.731776 -227.671609) (xy 131.723833 -227.724313)
			(xy 131.708123 -227.775243) (xy 131.684997 -227.823264) (xy 131.654973 -227.867301) (xy 131.618721 -227.906372)
			(xy 131.57705 -227.939603) (xy 131.530892 -227.966252) (xy 131.481278 -227.985724) (xy 131.429316 -227.997584)
			(xy 131.376166 -228.001568) (xy 131.323016 -227.997584) (xy 131.271054 -227.985724) (xy 131.22144 -227.966252)
			(xy 131.175282 -227.939603) (xy 131.133611 -227.906372) (xy 131.097359 -227.867301) (xy 131.067335 -227.823264)
			(xy 131.044209 -227.775243) (xy 131.028499 -227.724313) (xy 131.020556 -227.671609) (xy 130.791976 -227.671609)
			(xy 130.784033 -227.724313) (xy 130.768323 -227.775243) (xy 130.745197 -227.823264) (xy 130.715173 -227.867301)
			(xy 130.678921 -227.906372) (xy 130.63725 -227.939603) (xy 130.591092 -227.966252) (xy 130.541478 -227.985724)
			(xy 130.489516 -227.997584) (xy 130.436366 -228.001568) (xy 130.383216 -227.997584) (xy 130.331254 -227.985724)
			(xy 130.28164 -227.966252) (xy 130.235482 -227.939603) (xy 130.193811 -227.906372) (xy 130.157559 -227.867301)
			(xy 130.127535 -227.823264) (xy 130.104409 -227.775243) (xy 130.088699 -227.724313) (xy 130.080756 -227.671609)
			(xy 129.852176 -227.671609) (xy 129.844233 -227.724313) (xy 129.828523 -227.775243) (xy 129.805397 -227.823264)
			(xy 129.775373 -227.867301) (xy 129.739121 -227.906372) (xy 129.69745 -227.939603) (xy 129.651292 -227.966252)
			(xy 129.601678 -227.985724) (xy 129.549716 -227.997584) (xy 129.496566 -228.001568) (xy 129.443416 -227.997584)
			(xy 129.391454 -227.985724) (xy 129.34184 -227.966252) (xy 129.295682 -227.939603) (xy 129.254011 -227.906372)
			(xy 129.217759 -227.867301) (xy 129.187735 -227.823264) (xy 129.164609 -227.775243) (xy 129.148899 -227.724313)
			(xy 129.140956 -227.671609) (xy 128.912122 -227.671609) (xy 128.904179 -227.724313) (xy 128.888469 -227.775243)
			(xy 128.865343 -227.823264) (xy 128.835319 -227.867301) (xy 128.799067 -227.906372) (xy 128.757396 -227.939603)
			(xy 128.711238 -227.966252) (xy 128.661624 -227.985724) (xy 128.609662 -227.997584) (xy 128.556512 -228.001568)
			(xy 128.503362 -227.997584) (xy 128.4514 -227.985724) (xy 128.401786 -227.966252) (xy 128.355628 -227.939603)
			(xy 128.313957 -227.906372) (xy 128.277705 -227.867301) (xy 128.247681 -227.823264) (xy 128.224555 -227.775243)
			(xy 128.208845 -227.724313) (xy 128.200902 -227.671609) (xy 127.972322 -227.671609) (xy 127.964379 -227.724313)
			(xy 127.948669 -227.775243) (xy 127.925543 -227.823264) (xy 127.895519 -227.867301) (xy 127.859267 -227.906372)
			(xy 127.817596 -227.939603) (xy 127.771438 -227.966252) (xy 127.721824 -227.985724) (xy 127.669862 -227.997584)
			(xy 127.616712 -228.001568) (xy 127.563562 -227.997584) (xy 127.5116 -227.985724) (xy 127.461986 -227.966252)
			(xy 127.415828 -227.939603) (xy 127.374157 -227.906372) (xy 127.337905 -227.867301) (xy 127.307881 -227.823264)
			(xy 127.284755 -227.775243) (xy 127.269045 -227.724313) (xy 127.261102 -227.671609) (xy 127.032776 -227.671609)
			(xy 127.024833 -227.724313) (xy 127.009123 -227.775243) (xy 126.985997 -227.823264) (xy 126.955973 -227.867301)
			(xy 126.919721 -227.906372) (xy 126.87805 -227.939603) (xy 126.831892 -227.966252) (xy 126.782278 -227.985724)
			(xy 126.730316 -227.997584) (xy 126.677166 -228.001568) (xy 126.624016 -227.997584) (xy 126.572054 -227.985724)
			(xy 126.52244 -227.966252) (xy 126.476282 -227.939603) (xy 126.434611 -227.906372) (xy 126.398359 -227.867301)
			(xy 126.368335 -227.823264) (xy 126.345209 -227.775243) (xy 126.329499 -227.724313) (xy 126.321556 -227.671609)
			(xy 126.092976 -227.671609) (xy 126.085033 -227.724313) (xy 126.069323 -227.775243) (xy 126.046197 -227.823264)
			(xy 126.016173 -227.867301) (xy 125.979921 -227.906372) (xy 125.93825 -227.939603) (xy 125.892092 -227.966252)
			(xy 125.842478 -227.985724) (xy 125.790516 -227.997584) (xy 125.737366 -228.001568) (xy 125.684216 -227.997584)
			(xy 125.632254 -227.985724) (xy 125.58264 -227.966252) (xy 125.536482 -227.939603) (xy 125.494811 -227.906372)
			(xy 125.458559 -227.867301) (xy 125.428535 -227.823264) (xy 125.405409 -227.775243) (xy 125.389699 -227.724313)
			(xy 125.381756 -227.671609) (xy 125.153176 -227.671609) (xy 125.145233 -227.724313) (xy 125.129523 -227.775243)
			(xy 125.106397 -227.823264) (xy 125.076373 -227.867301) (xy 125.040121 -227.906372) (xy 124.99845 -227.939603)
			(xy 124.952292 -227.966252) (xy 124.902678 -227.985724) (xy 124.850716 -227.997584) (xy 124.797566 -228.001568)
			(xy 124.744416 -227.997584) (xy 124.692454 -227.985724) (xy 124.64284 -227.966252) (xy 124.596682 -227.939603)
			(xy 124.555011 -227.906372) (xy 124.518759 -227.867301) (xy 124.488735 -227.823264) (xy 124.465609 -227.775243)
			(xy 124.449899 -227.724313) (xy 124.441956 -227.671609) (xy 124.213376 -227.671609) (xy 124.205433 -227.724313)
			(xy 124.189723 -227.775243) (xy 124.166597 -227.823264) (xy 124.136573 -227.867301) (xy 124.100321 -227.906372)
			(xy 124.05865 -227.939603) (xy 124.012492 -227.966252) (xy 123.962878 -227.985724) (xy 123.910916 -227.997584)
			(xy 123.857766 -228.001568) (xy 123.804616 -227.997584) (xy 123.752654 -227.985724) (xy 123.70304 -227.966252)
			(xy 123.656882 -227.939603) (xy 123.615211 -227.906372) (xy 123.578959 -227.867301) (xy 123.548935 -227.823264)
			(xy 123.525809 -227.775243) (xy 123.510099 -227.724313) (xy 123.502156 -227.671609) (xy 123.273576 -227.671609)
			(xy 123.265633 -227.724313) (xy 123.249923 -227.775243) (xy 123.226797 -227.823264) (xy 123.196773 -227.867301)
			(xy 123.160521 -227.906372) (xy 123.11885 -227.939603) (xy 123.072692 -227.966252) (xy 123.023078 -227.985724)
			(xy 122.971116 -227.997584) (xy 122.917966 -228.001568) (xy 122.864816 -227.997584) (xy 122.812854 -227.985724)
			(xy 122.76324 -227.966252) (xy 122.717082 -227.939603) (xy 122.675411 -227.906372) (xy 122.639159 -227.867301)
			(xy 122.609135 -227.823264) (xy 122.586009 -227.775243) (xy 122.570299 -227.724313) (xy 122.562356 -227.671609)
			(xy 122.333522 -227.671609) (xy 122.325579 -227.724313) (xy 122.309869 -227.775243) (xy 122.286743 -227.823264)
			(xy 122.256719 -227.867301) (xy 122.220467 -227.906372) (xy 122.178796 -227.939603) (xy 122.132638 -227.966252)
			(xy 122.083024 -227.985724) (xy 122.031062 -227.997584) (xy 121.977912 -228.001568) (xy 121.924762 -227.997584)
			(xy 121.8728 -227.985724) (xy 121.823186 -227.966252) (xy 121.777028 -227.939603) (xy 121.735357 -227.906372)
			(xy 121.699105 -227.867301) (xy 121.669081 -227.823264) (xy 121.645955 -227.775243) (xy 121.630245 -227.724313)
			(xy 121.622302 -227.671609) (xy 121.393976 -227.671609) (xy 121.386033 -227.724313) (xy 121.370323 -227.775243)
			(xy 121.347197 -227.823264) (xy 121.317173 -227.867301) (xy 121.280921 -227.906372) (xy 121.23925 -227.939603)
			(xy 121.193092 -227.966252) (xy 121.143478 -227.985724) (xy 121.091516 -227.997584) (xy 121.038366 -228.001568)
			(xy 120.985216 -227.997584) (xy 120.933254 -227.985724) (xy 120.88364 -227.966252) (xy 120.837482 -227.939603)
			(xy 120.795811 -227.906372) (xy 120.759559 -227.867301) (xy 120.729535 -227.823264) (xy 120.706409 -227.775243)
			(xy 120.690699 -227.724313) (xy 120.682756 -227.671609) (xy 120.454176 -227.671609) (xy 120.446233 -227.724313)
			(xy 120.430523 -227.775243) (xy 120.407397 -227.823264) (xy 120.377373 -227.867301) (xy 120.341121 -227.906372)
			(xy 120.29945 -227.939603) (xy 120.253292 -227.966252) (xy 120.203678 -227.985724) (xy 120.151716 -227.997584)
			(xy 120.098566 -228.001568) (xy 120.045416 -227.997584) (xy 119.993454 -227.985724) (xy 119.94384 -227.966252)
			(xy 119.897682 -227.939603) (xy 119.856011 -227.906372) (xy 119.819759 -227.867301) (xy 119.789735 -227.823264)
			(xy 119.766609 -227.775243) (xy 119.750899 -227.724313) (xy 119.742956 -227.671609) (xy 119.514376 -227.671609)
			(xy 119.506433 -227.724313) (xy 119.490723 -227.775243) (xy 119.467597 -227.823264) (xy 119.437573 -227.867301)
			(xy 119.401321 -227.906372) (xy 119.35965 -227.939603) (xy 119.313492 -227.966252) (xy 119.263878 -227.985724)
			(xy 119.211916 -227.997584) (xy 119.158766 -228.001568) (xy 119.105616 -227.997584) (xy 119.053654 -227.985724)
			(xy 119.00404 -227.966252) (xy 118.957882 -227.939603) (xy 118.916211 -227.906372) (xy 118.879959 -227.867301)
			(xy 118.849935 -227.823264) (xy 118.826809 -227.775243) (xy 118.811099 -227.724313) (xy 118.803156 -227.671609)
			(xy 118.574576 -227.671609) (xy 118.566633 -227.724313) (xy 118.550923 -227.775243) (xy 118.527797 -227.823264)
			(xy 118.497773 -227.867301) (xy 118.461521 -227.906372) (xy 118.41985 -227.939603) (xy 118.373692 -227.966252)
			(xy 118.324078 -227.985724) (xy 118.272116 -227.997584) (xy 118.218966 -228.001568) (xy 118.165816 -227.997584)
			(xy 118.113854 -227.985724) (xy 118.06424 -227.966252) (xy 118.018082 -227.939603) (xy 117.976411 -227.906372)
			(xy 117.940159 -227.867301) (xy 117.910135 -227.823264) (xy 117.887009 -227.775243) (xy 117.871299 -227.724313)
			(xy 117.863356 -227.671609) (xy 117.634776 -227.671609) (xy 117.626833 -227.724313) (xy 117.611123 -227.775243)
			(xy 117.587997 -227.823264) (xy 117.557973 -227.867301) (xy 117.521721 -227.906372) (xy 117.48005 -227.939603)
			(xy 117.433892 -227.966252) (xy 117.384278 -227.985724) (xy 117.332316 -227.997584) (xy 117.279166 -228.001568)
			(xy 117.226016 -227.997584) (xy 117.174054 -227.985724) (xy 117.12444 -227.966252) (xy 117.078282 -227.939603)
			(xy 117.036611 -227.906372) (xy 117.000359 -227.867301) (xy 116.970335 -227.823264) (xy 116.947209 -227.775243)
			(xy 116.931499 -227.724313) (xy 116.923556 -227.671609) (xy 116.694976 -227.671609) (xy 116.687033 -227.724313)
			(xy 116.671323 -227.775243) (xy 116.648197 -227.823264) (xy 116.618173 -227.867301) (xy 116.581921 -227.906372)
			(xy 116.54025 -227.939603) (xy 116.494092 -227.966252) (xy 116.444478 -227.985724) (xy 116.392516 -227.997584)
			(xy 116.339366 -228.001568) (xy 116.286216 -227.997584) (xy 116.234254 -227.985724) (xy 116.18464 -227.966252)
			(xy 116.138482 -227.939603) (xy 116.096811 -227.906372) (xy 116.060559 -227.867301) (xy 116.030535 -227.823264)
			(xy 116.007409 -227.775243) (xy 115.991699 -227.724313) (xy 115.983756 -227.671609) (xy 115.755176 -227.671609)
			(xy 115.747233 -227.724313) (xy 115.731523 -227.775243) (xy 115.708397 -227.823264) (xy 115.678373 -227.867301)
			(xy 115.642121 -227.906372) (xy 115.60045 -227.939603) (xy 115.554292 -227.966252) (xy 115.504678 -227.985724)
			(xy 115.452716 -227.997584) (xy 115.399566 -228.001568) (xy 115.346416 -227.997584) (xy 115.294454 -227.985724)
			(xy 115.24484 -227.966252) (xy 115.198682 -227.939603) (xy 115.157011 -227.906372) (xy 115.120759 -227.867301)
			(xy 115.090735 -227.823264) (xy 115.067609 -227.775243) (xy 115.051899 -227.724313) (xy 115.043956 -227.671609)
			(xy 114.81563 -227.671609) (xy 114.807687 -227.724313) (xy 114.791977 -227.775243) (xy 114.768851 -227.823264)
			(xy 114.738827 -227.867301) (xy 114.702575 -227.906372) (xy 114.660904 -227.939603) (xy 114.614746 -227.966252)
			(xy 114.565132 -227.985724) (xy 114.51317 -227.997584) (xy 114.46002 -228.001568) (xy 114.40687 -227.997584)
			(xy 114.354908 -227.985724) (xy 114.305294 -227.966252) (xy 114.259136 -227.939603) (xy 114.217465 -227.906372)
			(xy 114.181213 -227.867301) (xy 114.151189 -227.823264) (xy 114.128063 -227.775243) (xy 114.112353 -227.724313)
			(xy 114.10441 -227.671609) (xy 113.875576 -227.671609) (xy 113.867633 -227.724313) (xy 113.851923 -227.775243)
			(xy 113.828797 -227.823264) (xy 113.798773 -227.867301) (xy 113.762521 -227.906372) (xy 113.72085 -227.939603)
			(xy 113.674692 -227.966252) (xy 113.625078 -227.985724) (xy 113.573116 -227.997584) (xy 113.519966 -228.001568)
			(xy 113.466816 -227.997584) (xy 113.414854 -227.985724) (xy 113.36524 -227.966252) (xy 113.319082 -227.939603)
			(xy 113.277411 -227.906372) (xy 113.241159 -227.867301) (xy 113.211135 -227.823264) (xy 113.188009 -227.775243)
			(xy 113.172299 -227.724313) (xy 113.164356 -227.671609) (xy 112.935776 -227.671609) (xy 112.927833 -227.724313)
			(xy 112.912123 -227.775243) (xy 112.888997 -227.823264) (xy 112.858973 -227.867301) (xy 112.822721 -227.906372)
			(xy 112.78105 -227.939603) (xy 112.734892 -227.966252) (xy 112.685278 -227.985724) (xy 112.633316 -227.997584)
			(xy 112.580166 -228.001568) (xy 112.527016 -227.997584) (xy 112.475054 -227.985724) (xy 112.42544 -227.966252)
			(xy 112.379282 -227.939603) (xy 112.337611 -227.906372) (xy 112.301359 -227.867301) (xy 112.271335 -227.823264)
			(xy 112.248209 -227.775243) (xy 112.232499 -227.724313) (xy 112.224556 -227.671609) (xy 111.99504 -227.671609)
			(xy 111.993252 -227.69634) (xy 111.982184 -227.74664) (xy 111.963992 -227.794822) (xy 111.939053 -227.839883)
			(xy 111.907887 -227.880886) (xy 111.889794 -227.899214) (xy 111.889794 -228.01707) (xy 111.890188 -228.030401)
			(xy 111.897091 -228.056153) (xy 111.910432 -228.079236) (xy 111.9293 -228.098072) (xy 111.952405 -228.111375)
			(xy 111.978169 -228.118234) (xy 112.00483 -228.118181) (xy 112.01781 -228.115114) (xy 112.040432 -228.109407)
			(xy 112.086684 -228.103285) (xy 112.110012 -228.102922) (xy 112.136658 -228.103421) (xy 112.189356 -228.111365)
			(xy 112.240281 -228.127075) (xy 112.288295 -228.150199) (xy 112.332327 -228.180221) (xy 112.371393 -228.21647)
			(xy 112.40462 -228.258137) (xy 112.431266 -228.30429) (xy 112.450736 -228.353899) (xy 112.462595 -228.405856)
			(xy 112.466577 -228.459) (xy 112.464578 -228.485679) (xy 112.694202 -228.485679) (xy 112.694202 -228.432381)
			(xy 112.702145 -228.379677) (xy 112.717855 -228.328747) (xy 112.740981 -228.280726) (xy 112.771005 -228.236689)
			(xy 112.807257 -228.197618) (xy 112.848928 -228.164387) (xy 112.895086 -228.137738) (xy 112.9447 -228.118266)
			(xy 112.996662 -228.106406) (xy 113.049812 -228.102423) (xy 113.102962 -228.106406) (xy 113.154924 -228.118266)
			(xy 113.204538 -228.137738) (xy 113.250696 -228.164387) (xy 113.292367 -228.197618) (xy 113.328619 -228.236689)
			(xy 113.358643 -228.280726) (xy 113.381769 -228.328747) (xy 113.397479 -228.379677) (xy 113.405422 -228.432381)
			(xy 113.40592 -228.45903) (xy 113.405422 -228.485679) (xy 113.634002 -228.485679) (xy 113.634002 -228.432381)
			(xy 113.641945 -228.379677) (xy 113.657655 -228.328747) (xy 113.680781 -228.280726) (xy 113.710805 -228.236689)
			(xy 113.747057 -228.197618) (xy 113.788728 -228.164387) (xy 113.834886 -228.137738) (xy 113.8845 -228.118266)
			(xy 113.936462 -228.106406) (xy 113.989612 -228.102423) (xy 114.042762 -228.106406) (xy 114.094724 -228.118266)
			(xy 114.144338 -228.137738) (xy 114.190496 -228.164387) (xy 114.232167 -228.197618) (xy 114.268419 -228.236689)
			(xy 114.298443 -228.280726) (xy 114.321569 -228.328747) (xy 114.337279 -228.379677) (xy 114.345222 -228.432381)
			(xy 114.34572 -228.45903) (xy 114.345222 -228.485679) (xy 114.573802 -228.485679) (xy 114.573802 -228.432381)
			(xy 114.581745 -228.379677) (xy 114.597455 -228.328747) (xy 114.620581 -228.280726) (xy 114.650605 -228.236689)
			(xy 114.686857 -228.197618) (xy 114.728528 -228.164387) (xy 114.774686 -228.137738) (xy 114.8243 -228.118266)
			(xy 114.876262 -228.106406) (xy 114.929412 -228.102423) (xy 114.982562 -228.106406) (xy 115.034524 -228.118266)
			(xy 115.084138 -228.137738) (xy 115.130296 -228.164387) (xy 115.171967 -228.197618) (xy 115.208219 -228.236689)
			(xy 115.238243 -228.280726) (xy 115.261369 -228.328747) (xy 115.277079 -228.379677) (xy 115.285022 -228.432381)
			(xy 115.28552 -228.45903) (xy 115.285022 -228.485679) (xy 115.513602 -228.485679) (xy 115.513602 -228.432381)
			(xy 115.521545 -228.379677) (xy 115.537255 -228.328747) (xy 115.560381 -228.280726) (xy 115.590405 -228.236689)
			(xy 115.626657 -228.197618) (xy 115.668328 -228.164387) (xy 115.714486 -228.137738) (xy 115.7641 -228.118266)
			(xy 115.816062 -228.106406) (xy 115.869212 -228.102423) (xy 115.922362 -228.106406) (xy 115.974324 -228.118266)
			(xy 116.023938 -228.137738) (xy 116.070096 -228.164387) (xy 116.111767 -228.197618) (xy 116.148019 -228.236689)
			(xy 116.178043 -228.280726) (xy 116.201169 -228.328747) (xy 116.216879 -228.379677) (xy 116.224822 -228.432381)
			(xy 116.22532 -228.45903) (xy 116.224822 -228.485679) (xy 116.453402 -228.485679) (xy 116.453402 -228.432381)
			(xy 116.461345 -228.379677) (xy 116.477055 -228.328747) (xy 116.500181 -228.280726) (xy 116.530205 -228.236689)
			(xy 116.566457 -228.197618) (xy 116.608128 -228.164387) (xy 116.654286 -228.137738) (xy 116.7039 -228.118266)
			(xy 116.755862 -228.106406) (xy 116.809012 -228.102423) (xy 116.862162 -228.106406) (xy 116.914124 -228.118266)
			(xy 116.963738 -228.137738) (xy 117.009896 -228.164387) (xy 117.051567 -228.197618) (xy 117.087819 -228.236689)
			(xy 117.117843 -228.280726) (xy 117.140969 -228.328747) (xy 117.156679 -228.379677) (xy 117.164622 -228.432381)
			(xy 117.16512 -228.45903) (xy 117.164622 -228.485679) (xy 117.393202 -228.485679) (xy 117.393202 -228.432381)
			(xy 117.401145 -228.379677) (xy 117.416855 -228.328747) (xy 117.439981 -228.280726) (xy 117.470005 -228.236689)
			(xy 117.506257 -228.197618) (xy 117.547928 -228.164387) (xy 117.594086 -228.137738) (xy 117.6437 -228.118266)
			(xy 117.695662 -228.106406) (xy 117.748812 -228.102423) (xy 117.801962 -228.106406) (xy 117.853924 -228.118266)
			(xy 117.903538 -228.137738) (xy 117.949696 -228.164387) (xy 117.991367 -228.197618) (xy 118.027619 -228.236689)
			(xy 118.057643 -228.280726) (xy 118.080769 -228.328747) (xy 118.096479 -228.379677) (xy 118.104422 -228.432381)
			(xy 118.10492 -228.45903) (xy 118.104422 -228.485679) (xy 118.333002 -228.485679) (xy 118.333002 -228.432381)
			(xy 118.340945 -228.379677) (xy 118.356655 -228.328747) (xy 118.379781 -228.280726) (xy 118.409805 -228.236689)
			(xy 118.446057 -228.197618) (xy 118.487728 -228.164387) (xy 118.533886 -228.137738) (xy 118.5835 -228.118266)
			(xy 118.635462 -228.106406) (xy 118.688612 -228.102423) (xy 118.741762 -228.106406) (xy 118.793724 -228.118266)
			(xy 118.843338 -228.137738) (xy 118.889496 -228.164387) (xy 118.931167 -228.197618) (xy 118.967419 -228.236689)
			(xy 118.997443 -228.280726) (xy 119.020569 -228.328747) (xy 119.036279 -228.379677) (xy 119.044222 -228.432381)
			(xy 119.04472 -228.45903) (xy 119.044222 -228.485679) (xy 119.272802 -228.485679) (xy 119.272802 -228.432381)
			(xy 119.280745 -228.379677) (xy 119.296455 -228.328747) (xy 119.319581 -228.280726) (xy 119.349605 -228.236689)
			(xy 119.385857 -228.197618) (xy 119.427528 -228.164387) (xy 119.473686 -228.137738) (xy 119.5233 -228.118266)
			(xy 119.575262 -228.106406) (xy 119.628412 -228.102423) (xy 119.681562 -228.106406) (xy 119.733524 -228.118266)
			(xy 119.783138 -228.137738) (xy 119.829296 -228.164387) (xy 119.870967 -228.197618) (xy 119.907219 -228.236689)
			(xy 119.937243 -228.280726) (xy 119.960369 -228.328747) (xy 119.976079 -228.379677) (xy 119.984022 -228.432381)
			(xy 119.98452 -228.45903) (xy 119.984022 -228.485679) (xy 120.212602 -228.485679) (xy 120.212602 -228.432381)
			(xy 120.220545 -228.379677) (xy 120.236255 -228.328747) (xy 120.259381 -228.280726) (xy 120.289405 -228.236689)
			(xy 120.325657 -228.197618) (xy 120.367328 -228.164387) (xy 120.413486 -228.137738) (xy 120.4631 -228.118266)
			(xy 120.515062 -228.106406) (xy 120.568212 -228.102423) (xy 120.621362 -228.106406) (xy 120.673324 -228.118266)
			(xy 120.722938 -228.137738) (xy 120.769096 -228.164387) (xy 120.810767 -228.197618) (xy 120.847019 -228.236689)
			(xy 120.877043 -228.280726) (xy 120.900169 -228.328747) (xy 120.915879 -228.379677) (xy 120.923822 -228.432381)
			(xy 120.92432 -228.45903) (xy 120.923822 -228.485679) (xy 121.152402 -228.485679) (xy 121.152402 -228.432381)
			(xy 121.160345 -228.379677) (xy 121.176055 -228.328747) (xy 121.199181 -228.280726) (xy 121.229205 -228.236689)
			(xy 121.265457 -228.197618) (xy 121.307128 -228.164387) (xy 121.353286 -228.137738) (xy 121.4029 -228.118266)
			(xy 121.454862 -228.106406) (xy 121.508012 -228.102423) (xy 121.561162 -228.106406) (xy 121.613124 -228.118266)
			(xy 121.662738 -228.137738) (xy 121.708896 -228.164387) (xy 121.750567 -228.197618) (xy 121.786819 -228.236689)
			(xy 121.816843 -228.280726) (xy 121.839969 -228.328747) (xy 121.855679 -228.379677) (xy 121.863622 -228.432381)
			(xy 121.86412 -228.45903) (xy 121.863622 -228.485679) (xy 122.092202 -228.485679) (xy 122.092202 -228.432381)
			(xy 122.100145 -228.379677) (xy 122.115855 -228.328747) (xy 122.138981 -228.280726) (xy 122.169005 -228.236689)
			(xy 122.205257 -228.197618) (xy 122.246928 -228.164387) (xy 122.293086 -228.137738) (xy 122.3427 -228.118266)
			(xy 122.394662 -228.106406) (xy 122.447812 -228.102423) (xy 122.500962 -228.106406) (xy 122.552924 -228.118266)
			(xy 122.602538 -228.137738) (xy 122.648696 -228.164387) (xy 122.690367 -228.197618) (xy 122.726619 -228.236689)
			(xy 122.756643 -228.280726) (xy 122.779769 -228.328747) (xy 122.795479 -228.379677) (xy 122.803422 -228.432381)
			(xy 122.80392 -228.45903) (xy 122.803422 -228.485679) (xy 123.032002 -228.485679) (xy 123.032002 -228.432381)
			(xy 123.039945 -228.379677) (xy 123.055655 -228.328747) (xy 123.078781 -228.280726) (xy 123.108805 -228.236689)
			(xy 123.145057 -228.197618) (xy 123.186728 -228.164387) (xy 123.232886 -228.137738) (xy 123.2825 -228.118266)
			(xy 123.334462 -228.106406) (xy 123.387612 -228.102423) (xy 123.440762 -228.106406) (xy 123.492724 -228.118266)
			(xy 123.542338 -228.137738) (xy 123.588496 -228.164387) (xy 123.630167 -228.197618) (xy 123.666419 -228.236689)
			(xy 123.696443 -228.280726) (xy 123.719569 -228.328747) (xy 123.735279 -228.379677) (xy 123.743222 -228.432381)
			(xy 123.74372 -228.45903) (xy 123.743222 -228.485679) (xy 123.971802 -228.485679) (xy 123.971802 -228.432381)
			(xy 123.979745 -228.379677) (xy 123.995455 -228.328747) (xy 124.018581 -228.280726) (xy 124.048605 -228.236689)
			(xy 124.084857 -228.197618) (xy 124.126528 -228.164387) (xy 124.172686 -228.137738) (xy 124.2223 -228.118266)
			(xy 124.274262 -228.106406) (xy 124.327412 -228.102423) (xy 124.380562 -228.106406) (xy 124.432524 -228.118266)
			(xy 124.482138 -228.137738) (xy 124.528296 -228.164387) (xy 124.569967 -228.197618) (xy 124.606219 -228.236689)
			(xy 124.636243 -228.280726) (xy 124.659369 -228.328747) (xy 124.675079 -228.379677) (xy 124.683022 -228.432381)
			(xy 124.68352 -228.45903) (xy 124.683022 -228.485679) (xy 124.911602 -228.485679) (xy 124.911602 -228.432381)
			(xy 124.919545 -228.379677) (xy 124.935255 -228.328747) (xy 124.958381 -228.280726) (xy 124.988405 -228.236689)
			(xy 125.024657 -228.197618) (xy 125.066328 -228.164387) (xy 125.112486 -228.137738) (xy 125.1621 -228.118266)
			(xy 125.214062 -228.106406) (xy 125.267212 -228.102423) (xy 125.320362 -228.106406) (xy 125.372324 -228.118266)
			(xy 125.421938 -228.137738) (xy 125.468096 -228.164387) (xy 125.509767 -228.197618) (xy 125.546019 -228.236689)
			(xy 125.576043 -228.280726) (xy 125.599169 -228.328747) (xy 125.614879 -228.379677) (xy 125.622822 -228.432381)
			(xy 125.62332 -228.45903) (xy 125.622822 -228.485679) (xy 125.851656 -228.485679) (xy 125.851656 -228.432381)
			(xy 125.859599 -228.379677) (xy 125.875309 -228.328747) (xy 125.898435 -228.280726) (xy 125.928459 -228.236689)
			(xy 125.964711 -228.197618) (xy 126.006382 -228.164387) (xy 126.05254 -228.137738) (xy 126.102154 -228.118266)
			(xy 126.154116 -228.106406) (xy 126.207266 -228.102423) (xy 126.260416 -228.106406) (xy 126.312378 -228.118266)
			(xy 126.361992 -228.137738) (xy 126.40815 -228.164387) (xy 126.449821 -228.197618) (xy 126.486073 -228.236689)
			(xy 126.516097 -228.280726) (xy 126.539223 -228.328747) (xy 126.554933 -228.379677) (xy 126.562876 -228.432381)
			(xy 126.563374 -228.45903) (xy 126.562876 -228.485679) (xy 126.791202 -228.485679) (xy 126.791202 -228.432381)
			(xy 126.799145 -228.379677) (xy 126.814855 -228.328747) (xy 126.837981 -228.280726) (xy 126.868005 -228.236689)
			(xy 126.904257 -228.197618) (xy 126.945928 -228.164387) (xy 126.992086 -228.137738) (xy 127.0417 -228.118266)
			(xy 127.093662 -228.106406) (xy 127.146812 -228.102423) (xy 127.199962 -228.106406) (xy 127.251924 -228.118266)
			(xy 127.301538 -228.137738) (xy 127.347696 -228.164387) (xy 127.389367 -228.197618) (xy 127.425619 -228.236689)
			(xy 127.455643 -228.280726) (xy 127.478769 -228.328747) (xy 127.494479 -228.379677) (xy 127.502422 -228.432381)
			(xy 127.50292 -228.45903) (xy 127.502422 -228.485679) (xy 127.731002 -228.485679) (xy 127.731002 -228.432381)
			(xy 127.738945 -228.379677) (xy 127.754655 -228.328747) (xy 127.777781 -228.280726) (xy 127.807805 -228.236689)
			(xy 127.844057 -228.197618) (xy 127.885728 -228.164387) (xy 127.931886 -228.137738) (xy 127.9815 -228.118266)
			(xy 128.033462 -228.106406) (xy 128.086612 -228.102423) (xy 128.139762 -228.106406) (xy 128.191724 -228.118266)
			(xy 128.241338 -228.137738) (xy 128.287496 -228.164387) (xy 128.329167 -228.197618) (xy 128.365419 -228.236689)
			(xy 128.395443 -228.280726) (xy 128.418569 -228.328747) (xy 128.434279 -228.379677) (xy 128.442222 -228.432381)
			(xy 128.44272 -228.45903) (xy 128.442222 -228.485679) (xy 128.670802 -228.485679) (xy 128.670802 -228.432381)
			(xy 128.678745 -228.379677) (xy 128.694455 -228.328747) (xy 128.717581 -228.280726) (xy 128.747605 -228.236689)
			(xy 128.783857 -228.197618) (xy 128.825528 -228.164387) (xy 128.871686 -228.137738) (xy 128.9213 -228.118266)
			(xy 128.973262 -228.106406) (xy 129.026412 -228.102423) (xy 129.079562 -228.106406) (xy 129.131524 -228.118266)
			(xy 129.181138 -228.137738) (xy 129.227296 -228.164387) (xy 129.268967 -228.197618) (xy 129.305219 -228.236689)
			(xy 129.335243 -228.280726) (xy 129.358369 -228.328747) (xy 129.374079 -228.379677) (xy 129.382022 -228.432381)
			(xy 129.38252 -228.45903) (xy 129.382022 -228.485679) (xy 129.610602 -228.485679) (xy 129.610602 -228.432381)
			(xy 129.618545 -228.379677) (xy 129.634255 -228.328747) (xy 129.657381 -228.280726) (xy 129.687405 -228.236689)
			(xy 129.723657 -228.197618) (xy 129.765328 -228.164387) (xy 129.811486 -228.137738) (xy 129.8611 -228.118266)
			(xy 129.913062 -228.106406) (xy 129.966212 -228.102423) (xy 130.019362 -228.106406) (xy 130.071324 -228.118266)
			(xy 130.120938 -228.137738) (xy 130.167096 -228.164387) (xy 130.208767 -228.197618) (xy 130.245019 -228.236689)
			(xy 130.275043 -228.280726) (xy 130.298169 -228.328747) (xy 130.313879 -228.379677) (xy 130.321822 -228.432381)
			(xy 130.32232 -228.45903) (xy 130.321822 -228.485679) (xy 130.550402 -228.485679) (xy 130.550402 -228.432381)
			(xy 130.558345 -228.379677) (xy 130.574055 -228.328747) (xy 130.597181 -228.280726) (xy 130.627205 -228.236689)
			(xy 130.663457 -228.197618) (xy 130.705128 -228.164387) (xy 130.751286 -228.137738) (xy 130.8009 -228.118266)
			(xy 130.852862 -228.106406) (xy 130.906012 -228.102423) (xy 130.959162 -228.106406) (xy 131.011124 -228.118266)
			(xy 131.060738 -228.137738) (xy 131.106896 -228.164387) (xy 131.148567 -228.197618) (xy 131.184819 -228.236689)
			(xy 131.214843 -228.280726) (xy 131.237969 -228.328747) (xy 131.253679 -228.379677) (xy 131.261622 -228.432381)
			(xy 131.26212 -228.45903) (xy 131.261622 -228.485679) (xy 131.490202 -228.485679) (xy 131.490202 -228.432381)
			(xy 131.498145 -228.379677) (xy 131.513855 -228.328747) (xy 131.536981 -228.280726) (xy 131.567005 -228.236689)
			(xy 131.603257 -228.197618) (xy 131.644928 -228.164387) (xy 131.691086 -228.137738) (xy 131.7407 -228.118266)
			(xy 131.792662 -228.106406) (xy 131.845812 -228.102423) (xy 131.898962 -228.106406) (xy 131.950924 -228.118266)
			(xy 132.000538 -228.137738) (xy 132.046696 -228.164387) (xy 132.088367 -228.197618) (xy 132.124619 -228.236689)
			(xy 132.154643 -228.280726) (xy 132.177769 -228.328747) (xy 132.193479 -228.379677) (xy 132.201422 -228.432381)
			(xy 132.20192 -228.45903) (xy 132.201422 -228.485679) (xy 132.430256 -228.485679) (xy 132.430256 -228.432381)
			(xy 132.438199 -228.379677) (xy 132.453909 -228.328747) (xy 132.477035 -228.280726) (xy 132.507059 -228.236689)
			(xy 132.543311 -228.197618) (xy 132.584982 -228.164387) (xy 132.63114 -228.137738) (xy 132.680754 -228.118266)
			(xy 132.732716 -228.106406) (xy 132.785866 -228.102423) (xy 132.839016 -228.106406) (xy 132.890978 -228.118266)
			(xy 132.940592 -228.137738) (xy 132.98675 -228.164387) (xy 133.028421 -228.197618) (xy 133.064673 -228.236689)
			(xy 133.094697 -228.280726) (xy 133.117823 -228.328747) (xy 133.133533 -228.379677) (xy 133.141476 -228.432381)
			(xy 133.141974 -228.45903) (xy 133.141476 -228.485679) (xy 133.370056 -228.485679) (xy 133.370056 -228.432381)
			(xy 133.377999 -228.379677) (xy 133.393709 -228.328747) (xy 133.416835 -228.280726) (xy 133.446859 -228.236689)
			(xy 133.483111 -228.197618) (xy 133.524782 -228.164387) (xy 133.57094 -228.137738) (xy 133.620554 -228.118266)
			(xy 133.672516 -228.106406) (xy 133.725666 -228.102423) (xy 133.778816 -228.106406) (xy 133.830778 -228.118266)
			(xy 133.880392 -228.137738) (xy 133.92655 -228.164387) (xy 133.968221 -228.197618) (xy 134.004473 -228.236689)
			(xy 134.034497 -228.280726) (xy 134.057623 -228.328747) (xy 134.073333 -228.379677) (xy 134.081276 -228.432381)
			(xy 134.081774 -228.45903) (xy 134.081276 -228.485679) (xy 134.309602 -228.485679) (xy 134.309602 -228.432381)
			(xy 134.317545 -228.379677) (xy 134.333255 -228.328747) (xy 134.356381 -228.280726) (xy 134.386405 -228.236689)
			(xy 134.422657 -228.197618) (xy 134.464328 -228.164387) (xy 134.510486 -228.137738) (xy 134.5601 -228.118266)
			(xy 134.612062 -228.106406) (xy 134.665212 -228.102423) (xy 134.718362 -228.106406) (xy 134.770324 -228.118266)
			(xy 134.819938 -228.137738) (xy 134.866096 -228.164387) (xy 134.907767 -228.197618) (xy 134.944019 -228.236689)
			(xy 134.974043 -228.280726) (xy 134.997169 -228.328747) (xy 135.012879 -228.379677) (xy 135.020822 -228.432381)
			(xy 135.02132 -228.45903) (xy 135.020822 -228.485679) (xy 135.012879 -228.538383) (xy 134.997169 -228.589313)
			(xy 134.974043 -228.637334) (xy 134.944019 -228.681371) (xy 134.907767 -228.720442) (xy 134.866096 -228.753673)
			(xy 134.819938 -228.780322) (xy 134.770324 -228.799794) (xy 134.718362 -228.811654) (xy 134.665212 -228.815638)
			(xy 134.612062 -228.811654) (xy 134.5601 -228.799794) (xy 134.510486 -228.780322) (xy 134.464328 -228.753673)
			(xy 134.422657 -228.720442) (xy 134.386405 -228.681371) (xy 134.356381 -228.637334) (xy 134.333255 -228.589313)
			(xy 134.317545 -228.538383) (xy 134.309602 -228.485679) (xy 134.081276 -228.485679) (xy 134.073333 -228.538383)
			(xy 134.057623 -228.589313) (xy 134.034497 -228.637334) (xy 134.004473 -228.681371) (xy 133.968221 -228.720442)
			(xy 133.92655 -228.753673) (xy 133.880392 -228.780322) (xy 133.830778 -228.799794) (xy 133.778816 -228.811654)
			(xy 133.725666 -228.815638) (xy 133.672516 -228.811654) (xy 133.620554 -228.799794) (xy 133.57094 -228.780322)
			(xy 133.524782 -228.753673) (xy 133.483111 -228.720442) (xy 133.446859 -228.681371) (xy 133.416835 -228.637334)
			(xy 133.393709 -228.589313) (xy 133.377999 -228.538383) (xy 133.370056 -228.485679) (xy 133.141476 -228.485679)
			(xy 133.133533 -228.538383) (xy 133.117823 -228.589313) (xy 133.094697 -228.637334) (xy 133.064673 -228.681371)
			(xy 133.028421 -228.720442) (xy 132.98675 -228.753673) (xy 132.940592 -228.780322) (xy 132.890978 -228.799794)
			(xy 132.839016 -228.811654) (xy 132.785866 -228.815638) (xy 132.732716 -228.811654) (xy 132.680754 -228.799794)
			(xy 132.63114 -228.780322) (xy 132.584982 -228.753673) (xy 132.543311 -228.720442) (xy 132.507059 -228.681371)
			(xy 132.477035 -228.637334) (xy 132.453909 -228.589313) (xy 132.438199 -228.538383) (xy 132.430256 -228.485679)
			(xy 132.201422 -228.485679) (xy 132.193479 -228.538383) (xy 132.177769 -228.589313) (xy 132.154643 -228.637334)
			(xy 132.124619 -228.681371) (xy 132.088367 -228.720442) (xy 132.046696 -228.753673) (xy 132.000538 -228.780322)
			(xy 131.950924 -228.799794) (xy 131.898962 -228.811654) (xy 131.845812 -228.815638) (xy 131.792662 -228.811654)
			(xy 131.7407 -228.799794) (xy 131.691086 -228.780322) (xy 131.644928 -228.753673) (xy 131.603257 -228.720442)
			(xy 131.567005 -228.681371) (xy 131.536981 -228.637334) (xy 131.513855 -228.589313) (xy 131.498145 -228.538383)
			(xy 131.490202 -228.485679) (xy 131.261622 -228.485679) (xy 131.253679 -228.538383) (xy 131.237969 -228.589313)
			(xy 131.214843 -228.637334) (xy 131.184819 -228.681371) (xy 131.148567 -228.720442) (xy 131.106896 -228.753673)
			(xy 131.060738 -228.780322) (xy 131.011124 -228.799794) (xy 130.959162 -228.811654) (xy 130.906012 -228.815638)
			(xy 130.852862 -228.811654) (xy 130.8009 -228.799794) (xy 130.751286 -228.780322) (xy 130.705128 -228.753673)
			(xy 130.663457 -228.720442) (xy 130.627205 -228.681371) (xy 130.597181 -228.637334) (xy 130.574055 -228.589313)
			(xy 130.558345 -228.538383) (xy 130.550402 -228.485679) (xy 130.321822 -228.485679) (xy 130.313879 -228.538383)
			(xy 130.298169 -228.589313) (xy 130.275043 -228.637334) (xy 130.245019 -228.681371) (xy 130.208767 -228.720442)
			(xy 130.167096 -228.753673) (xy 130.120938 -228.780322) (xy 130.071324 -228.799794) (xy 130.019362 -228.811654)
			(xy 129.966212 -228.815638) (xy 129.913062 -228.811654) (xy 129.8611 -228.799794) (xy 129.811486 -228.780322)
			(xy 129.765328 -228.753673) (xy 129.723657 -228.720442) (xy 129.687405 -228.681371) (xy 129.657381 -228.637334)
			(xy 129.634255 -228.589313) (xy 129.618545 -228.538383) (xy 129.610602 -228.485679) (xy 129.382022 -228.485679)
			(xy 129.374079 -228.538383) (xy 129.358369 -228.589313) (xy 129.335243 -228.637334) (xy 129.305219 -228.681371)
			(xy 129.268967 -228.720442) (xy 129.227296 -228.753673) (xy 129.181138 -228.780322) (xy 129.131524 -228.799794)
			(xy 129.079562 -228.811654) (xy 129.026412 -228.815638) (xy 128.973262 -228.811654) (xy 128.9213 -228.799794)
			(xy 128.871686 -228.780322) (xy 128.825528 -228.753673) (xy 128.783857 -228.720442) (xy 128.747605 -228.681371)
			(xy 128.717581 -228.637334) (xy 128.694455 -228.589313) (xy 128.678745 -228.538383) (xy 128.670802 -228.485679)
			(xy 128.442222 -228.485679) (xy 128.434279 -228.538383) (xy 128.418569 -228.589313) (xy 128.395443 -228.637334)
			(xy 128.365419 -228.681371) (xy 128.329167 -228.720442) (xy 128.287496 -228.753673) (xy 128.241338 -228.780322)
			(xy 128.191724 -228.799794) (xy 128.139762 -228.811654) (xy 128.086612 -228.815638) (xy 128.033462 -228.811654)
			(xy 127.9815 -228.799794) (xy 127.931886 -228.780322) (xy 127.885728 -228.753673) (xy 127.844057 -228.720442)
			(xy 127.807805 -228.681371) (xy 127.777781 -228.637334) (xy 127.754655 -228.589313) (xy 127.738945 -228.538383)
			(xy 127.731002 -228.485679) (xy 127.502422 -228.485679) (xy 127.494479 -228.538383) (xy 127.478769 -228.589313)
			(xy 127.455643 -228.637334) (xy 127.425619 -228.681371) (xy 127.389367 -228.720442) (xy 127.347696 -228.753673)
			(xy 127.301538 -228.780322) (xy 127.251924 -228.799794) (xy 127.199962 -228.811654) (xy 127.146812 -228.815638)
			(xy 127.093662 -228.811654) (xy 127.0417 -228.799794) (xy 126.992086 -228.780322) (xy 126.945928 -228.753673)
			(xy 126.904257 -228.720442) (xy 126.868005 -228.681371) (xy 126.837981 -228.637334) (xy 126.814855 -228.589313)
			(xy 126.799145 -228.538383) (xy 126.791202 -228.485679) (xy 126.562876 -228.485679) (xy 126.554933 -228.538383)
			(xy 126.539223 -228.589313) (xy 126.516097 -228.637334) (xy 126.486073 -228.681371) (xy 126.449821 -228.720442)
			(xy 126.40815 -228.753673) (xy 126.361992 -228.780322) (xy 126.312378 -228.799794) (xy 126.260416 -228.811654)
			(xy 126.207266 -228.815638) (xy 126.154116 -228.811654) (xy 126.102154 -228.799794) (xy 126.05254 -228.780322)
			(xy 126.006382 -228.753673) (xy 125.964711 -228.720442) (xy 125.928459 -228.681371) (xy 125.898435 -228.637334)
			(xy 125.875309 -228.589313) (xy 125.859599 -228.538383) (xy 125.851656 -228.485679) (xy 125.622822 -228.485679)
			(xy 125.614879 -228.538383) (xy 125.599169 -228.589313) (xy 125.576043 -228.637334) (xy 125.546019 -228.681371)
			(xy 125.509767 -228.720442) (xy 125.468096 -228.753673) (xy 125.421938 -228.780322) (xy 125.372324 -228.799794)
			(xy 125.320362 -228.811654) (xy 125.267212 -228.815638) (xy 125.214062 -228.811654) (xy 125.1621 -228.799794)
			(xy 125.112486 -228.780322) (xy 125.066328 -228.753673) (xy 125.024657 -228.720442) (xy 124.988405 -228.681371)
			(xy 124.958381 -228.637334) (xy 124.935255 -228.589313) (xy 124.919545 -228.538383) (xy 124.911602 -228.485679)
			(xy 124.683022 -228.485679) (xy 124.675079 -228.538383) (xy 124.659369 -228.589313) (xy 124.636243 -228.637334)
			(xy 124.606219 -228.681371) (xy 124.569967 -228.720442) (xy 124.528296 -228.753673) (xy 124.482138 -228.780322)
			(xy 124.432524 -228.799794) (xy 124.380562 -228.811654) (xy 124.327412 -228.815638) (xy 124.274262 -228.811654)
			(xy 124.2223 -228.799794) (xy 124.172686 -228.780322) (xy 124.126528 -228.753673) (xy 124.084857 -228.720442)
			(xy 124.048605 -228.681371) (xy 124.018581 -228.637334) (xy 123.995455 -228.589313) (xy 123.979745 -228.538383)
			(xy 123.971802 -228.485679) (xy 123.743222 -228.485679) (xy 123.735279 -228.538383) (xy 123.719569 -228.589313)
			(xy 123.696443 -228.637334) (xy 123.666419 -228.681371) (xy 123.630167 -228.720442) (xy 123.588496 -228.753673)
			(xy 123.542338 -228.780322) (xy 123.492724 -228.799794) (xy 123.440762 -228.811654) (xy 123.387612 -228.815638)
			(xy 123.334462 -228.811654) (xy 123.2825 -228.799794) (xy 123.232886 -228.780322) (xy 123.186728 -228.753673)
			(xy 123.145057 -228.720442) (xy 123.108805 -228.681371) (xy 123.078781 -228.637334) (xy 123.055655 -228.589313)
			(xy 123.039945 -228.538383) (xy 123.032002 -228.485679) (xy 122.803422 -228.485679) (xy 122.795479 -228.538383)
			(xy 122.779769 -228.589313) (xy 122.756643 -228.637334) (xy 122.726619 -228.681371) (xy 122.690367 -228.720442)
			(xy 122.648696 -228.753673) (xy 122.602538 -228.780322) (xy 122.552924 -228.799794) (xy 122.500962 -228.811654)
			(xy 122.447812 -228.815638) (xy 122.394662 -228.811654) (xy 122.3427 -228.799794) (xy 122.293086 -228.780322)
			(xy 122.246928 -228.753673) (xy 122.205257 -228.720442) (xy 122.169005 -228.681371) (xy 122.138981 -228.637334)
			(xy 122.115855 -228.589313) (xy 122.100145 -228.538383) (xy 122.092202 -228.485679) (xy 121.863622 -228.485679)
			(xy 121.855679 -228.538383) (xy 121.839969 -228.589313) (xy 121.816843 -228.637334) (xy 121.786819 -228.681371)
			(xy 121.750567 -228.720442) (xy 121.708896 -228.753673) (xy 121.662738 -228.780322) (xy 121.613124 -228.799794)
			(xy 121.561162 -228.811654) (xy 121.508012 -228.815638) (xy 121.454862 -228.811654) (xy 121.4029 -228.799794)
			(xy 121.353286 -228.780322) (xy 121.307128 -228.753673) (xy 121.265457 -228.720442) (xy 121.229205 -228.681371)
			(xy 121.199181 -228.637334) (xy 121.176055 -228.589313) (xy 121.160345 -228.538383) (xy 121.152402 -228.485679)
			(xy 120.923822 -228.485679) (xy 120.915879 -228.538383) (xy 120.900169 -228.589313) (xy 120.877043 -228.637334)
			(xy 120.847019 -228.681371) (xy 120.810767 -228.720442) (xy 120.769096 -228.753673) (xy 120.722938 -228.780322)
			(xy 120.673324 -228.799794) (xy 120.621362 -228.811654) (xy 120.568212 -228.815638) (xy 120.515062 -228.811654)
			(xy 120.4631 -228.799794) (xy 120.413486 -228.780322) (xy 120.367328 -228.753673) (xy 120.325657 -228.720442)
			(xy 120.289405 -228.681371) (xy 120.259381 -228.637334) (xy 120.236255 -228.589313) (xy 120.220545 -228.538383)
			(xy 120.212602 -228.485679) (xy 119.984022 -228.485679) (xy 119.976079 -228.538383) (xy 119.960369 -228.589313)
			(xy 119.937243 -228.637334) (xy 119.907219 -228.681371) (xy 119.870967 -228.720442) (xy 119.829296 -228.753673)
			(xy 119.783138 -228.780322) (xy 119.733524 -228.799794) (xy 119.681562 -228.811654) (xy 119.628412 -228.815638)
			(xy 119.575262 -228.811654) (xy 119.5233 -228.799794) (xy 119.473686 -228.780322) (xy 119.427528 -228.753673)
			(xy 119.385857 -228.720442) (xy 119.349605 -228.681371) (xy 119.319581 -228.637334) (xy 119.296455 -228.589313)
			(xy 119.280745 -228.538383) (xy 119.272802 -228.485679) (xy 119.044222 -228.485679) (xy 119.036279 -228.538383)
			(xy 119.020569 -228.589313) (xy 118.997443 -228.637334) (xy 118.967419 -228.681371) (xy 118.931167 -228.720442)
			(xy 118.889496 -228.753673) (xy 118.843338 -228.780322) (xy 118.793724 -228.799794) (xy 118.741762 -228.811654)
			(xy 118.688612 -228.815638) (xy 118.635462 -228.811654) (xy 118.5835 -228.799794) (xy 118.533886 -228.780322)
			(xy 118.487728 -228.753673) (xy 118.446057 -228.720442) (xy 118.409805 -228.681371) (xy 118.379781 -228.637334)
			(xy 118.356655 -228.589313) (xy 118.340945 -228.538383) (xy 118.333002 -228.485679) (xy 118.104422 -228.485679)
			(xy 118.096479 -228.538383) (xy 118.080769 -228.589313) (xy 118.057643 -228.637334) (xy 118.027619 -228.681371)
			(xy 117.991367 -228.720442) (xy 117.949696 -228.753673) (xy 117.903538 -228.780322) (xy 117.853924 -228.799794)
			(xy 117.801962 -228.811654) (xy 117.748812 -228.815638) (xy 117.695662 -228.811654) (xy 117.6437 -228.799794)
			(xy 117.594086 -228.780322) (xy 117.547928 -228.753673) (xy 117.506257 -228.720442) (xy 117.470005 -228.681371)
			(xy 117.439981 -228.637334) (xy 117.416855 -228.589313) (xy 117.401145 -228.538383) (xy 117.393202 -228.485679)
			(xy 117.164622 -228.485679) (xy 117.156679 -228.538383) (xy 117.140969 -228.589313) (xy 117.117843 -228.637334)
			(xy 117.087819 -228.681371) (xy 117.051567 -228.720442) (xy 117.009896 -228.753673) (xy 116.963738 -228.780322)
			(xy 116.914124 -228.799794) (xy 116.862162 -228.811654) (xy 116.809012 -228.815638) (xy 116.755862 -228.811654)
			(xy 116.7039 -228.799794) (xy 116.654286 -228.780322) (xy 116.608128 -228.753673) (xy 116.566457 -228.720442)
			(xy 116.530205 -228.681371) (xy 116.500181 -228.637334) (xy 116.477055 -228.589313) (xy 116.461345 -228.538383)
			(xy 116.453402 -228.485679) (xy 116.224822 -228.485679) (xy 116.216879 -228.538383) (xy 116.201169 -228.589313)
			(xy 116.178043 -228.637334) (xy 116.148019 -228.681371) (xy 116.111767 -228.720442) (xy 116.070096 -228.753673)
			(xy 116.023938 -228.780322) (xy 115.974324 -228.799794) (xy 115.922362 -228.811654) (xy 115.869212 -228.815638)
			(xy 115.816062 -228.811654) (xy 115.7641 -228.799794) (xy 115.714486 -228.780322) (xy 115.668328 -228.753673)
			(xy 115.626657 -228.720442) (xy 115.590405 -228.681371) (xy 115.560381 -228.637334) (xy 115.537255 -228.589313)
			(xy 115.521545 -228.538383) (xy 115.513602 -228.485679) (xy 115.285022 -228.485679) (xy 115.277079 -228.538383)
			(xy 115.261369 -228.589313) (xy 115.238243 -228.637334) (xy 115.208219 -228.681371) (xy 115.171967 -228.720442)
			(xy 115.130296 -228.753673) (xy 115.084138 -228.780322) (xy 115.034524 -228.799794) (xy 114.982562 -228.811654)
			(xy 114.929412 -228.815638) (xy 114.876262 -228.811654) (xy 114.8243 -228.799794) (xy 114.774686 -228.780322)
			(xy 114.728528 -228.753673) (xy 114.686857 -228.720442) (xy 114.650605 -228.681371) (xy 114.620581 -228.637334)
			(xy 114.597455 -228.589313) (xy 114.581745 -228.538383) (xy 114.573802 -228.485679) (xy 114.345222 -228.485679)
			(xy 114.337279 -228.538383) (xy 114.321569 -228.589313) (xy 114.298443 -228.637334) (xy 114.268419 -228.681371)
			(xy 114.232167 -228.720442) (xy 114.190496 -228.753673) (xy 114.144338 -228.780322) (xy 114.094724 -228.799794)
			(xy 114.042762 -228.811654) (xy 113.989612 -228.815638) (xy 113.936462 -228.811654) (xy 113.8845 -228.799794)
			(xy 113.834886 -228.780322) (xy 113.788728 -228.753673) (xy 113.747057 -228.720442) (xy 113.710805 -228.681371)
			(xy 113.680781 -228.637334) (xy 113.657655 -228.589313) (xy 113.641945 -228.538383) (xy 113.634002 -228.485679)
			(xy 113.405422 -228.485679) (xy 113.397479 -228.538383) (xy 113.381769 -228.589313) (xy 113.358643 -228.637334)
			(xy 113.328619 -228.681371) (xy 113.292367 -228.720442) (xy 113.250696 -228.753673) (xy 113.204538 -228.780322)
			(xy 113.154924 -228.799794) (xy 113.102962 -228.811654) (xy 113.049812 -228.815638) (xy 112.996662 -228.811654)
			(xy 112.9447 -228.799794) (xy 112.895086 -228.780322) (xy 112.848928 -228.753673) (xy 112.807257 -228.720442)
			(xy 112.771005 -228.681371) (xy 112.740981 -228.637334) (xy 112.717855 -228.589313) (xy 112.702145 -228.538383)
			(xy 112.694202 -228.485679) (xy 112.464578 -228.485679) (xy 112.462595 -228.512144) (xy 112.450736 -228.564101)
			(xy 112.431266 -228.61371) (xy 112.40462 -228.659863) (xy 112.371393 -228.70153) (xy 112.332327 -228.737779)
			(xy 112.288295 -228.767801) (xy 112.240281 -228.790925) (xy 112.189356 -228.806635) (xy 112.136658 -228.814579)
			(xy 112.110012 -228.815138) (xy 112.086686 -228.81474) (xy 112.040436 -228.808629) (xy 112.01781 -228.802946)
			(xy 112.00483 -228.799904) (xy 111.978182 -228.799876) (xy 111.952434 -228.806746) (xy 111.929342 -228.820046)
			(xy 111.910478 -228.838869) (xy 111.897129 -228.861933) (xy 111.890204 -228.887666) (xy 111.889794 -228.90099)
			(xy 111.889794 -229.018846) (xy 111.907806 -229.037204) (xy 111.938897 -229.078172) (xy 111.963774 -229.123184)
			(xy 111.981921 -229.171306) (xy 111.99296 -229.221536) (xy 111.996662 -229.272832) (xy 111.994733 -229.299495)
			(xy 112.224556 -229.299495) (xy 112.224556 -229.246197) (xy 112.232499 -229.193493) (xy 112.248209 -229.142563)
			(xy 112.271335 -229.094542) (xy 112.301359 -229.050505) (xy 112.337611 -229.011434) (xy 112.379282 -228.978203)
			(xy 112.42544 -228.951554) (xy 112.475054 -228.932082) (xy 112.527016 -228.920222) (xy 112.580166 -228.916239)
			(xy 112.633316 -228.920222) (xy 112.685278 -228.932082) (xy 112.734892 -228.951554) (xy 112.78105 -228.978203)
			(xy 112.822721 -229.011434) (xy 112.858973 -229.050505) (xy 112.888997 -229.094542) (xy 112.912123 -229.142563)
			(xy 112.927833 -229.193493) (xy 112.935776 -229.246197) (xy 112.936274 -229.272846) (xy 112.935776 -229.299495)
			(xy 113.164356 -229.299495) (xy 113.164356 -229.246197) (xy 113.172299 -229.193493) (xy 113.188009 -229.142563)
			(xy 113.211135 -229.094542) (xy 113.241159 -229.050505) (xy 113.277411 -229.011434) (xy 113.319082 -228.978203)
			(xy 113.36524 -228.951554) (xy 113.414854 -228.932082) (xy 113.466816 -228.920222) (xy 113.519966 -228.916239)
			(xy 113.573116 -228.920222) (xy 113.625078 -228.932082) (xy 113.674692 -228.951554) (xy 113.72085 -228.978203)
			(xy 113.762521 -229.011434) (xy 113.798773 -229.050505) (xy 113.828797 -229.094542) (xy 113.851923 -229.142563)
			(xy 113.867633 -229.193493) (xy 113.875576 -229.246197) (xy 113.876074 -229.272846) (xy 113.875576 -229.299495)
			(xy 114.104156 -229.299495) (xy 114.104156 -229.246197) (xy 114.112099 -229.193493) (xy 114.127809 -229.142563)
			(xy 114.150935 -229.094542) (xy 114.180959 -229.050505) (xy 114.217211 -229.011434) (xy 114.258882 -228.978203)
			(xy 114.30504 -228.951554) (xy 114.354654 -228.932082) (xy 114.406616 -228.920222) (xy 114.459766 -228.916239)
			(xy 114.512916 -228.920222) (xy 114.564878 -228.932082) (xy 114.614492 -228.951554) (xy 114.66065 -228.978203)
			(xy 114.702321 -229.011434) (xy 114.738573 -229.050505) (xy 114.768597 -229.094542) (xy 114.791723 -229.142563)
			(xy 114.807433 -229.193493) (xy 114.815376 -229.246197) (xy 114.815874 -229.272846) (xy 114.815376 -229.299495)
			(xy 115.043956 -229.299495) (xy 115.043956 -229.246197) (xy 115.051899 -229.193493) (xy 115.067609 -229.142563)
			(xy 115.090735 -229.094542) (xy 115.120759 -229.050505) (xy 115.157011 -229.011434) (xy 115.198682 -228.978203)
			(xy 115.24484 -228.951554) (xy 115.294454 -228.932082) (xy 115.346416 -228.920222) (xy 115.399566 -228.916239)
			(xy 115.452716 -228.920222) (xy 115.504678 -228.932082) (xy 115.554292 -228.951554) (xy 115.60045 -228.978203)
			(xy 115.642121 -229.011434) (xy 115.678373 -229.050505) (xy 115.708397 -229.094542) (xy 115.731523 -229.142563)
			(xy 115.747233 -229.193493) (xy 115.755176 -229.246197) (xy 115.755674 -229.272846) (xy 115.755176 -229.299495)
			(xy 115.983756 -229.299495) (xy 115.983756 -229.246197) (xy 115.991699 -229.193493) (xy 116.007409 -229.142563)
			(xy 116.030535 -229.094542) (xy 116.060559 -229.050505) (xy 116.096811 -229.011434) (xy 116.138482 -228.978203)
			(xy 116.18464 -228.951554) (xy 116.234254 -228.932082) (xy 116.286216 -228.920222) (xy 116.339366 -228.916239)
			(xy 116.392516 -228.920222) (xy 116.444478 -228.932082) (xy 116.494092 -228.951554) (xy 116.54025 -228.978203)
			(xy 116.581921 -229.011434) (xy 116.618173 -229.050505) (xy 116.648197 -229.094542) (xy 116.671323 -229.142563)
			(xy 116.687033 -229.193493) (xy 116.694976 -229.246197) (xy 116.695474 -229.272846) (xy 116.694976 -229.299495)
			(xy 116.923556 -229.299495) (xy 116.923556 -229.246197) (xy 116.931499 -229.193493) (xy 116.947209 -229.142563)
			(xy 116.970335 -229.094542) (xy 117.000359 -229.050505) (xy 117.036611 -229.011434) (xy 117.078282 -228.978203)
			(xy 117.12444 -228.951554) (xy 117.174054 -228.932082) (xy 117.226016 -228.920222) (xy 117.279166 -228.916239)
			(xy 117.332316 -228.920222) (xy 117.384278 -228.932082) (xy 117.433892 -228.951554) (xy 117.48005 -228.978203)
			(xy 117.521721 -229.011434) (xy 117.557973 -229.050505) (xy 117.587997 -229.094542) (xy 117.611123 -229.142563)
			(xy 117.626833 -229.193493) (xy 117.634776 -229.246197) (xy 117.635274 -229.272846) (xy 117.634776 -229.299495)
			(xy 117.863356 -229.299495) (xy 117.863356 -229.246197) (xy 117.871299 -229.193493) (xy 117.887009 -229.142563)
			(xy 117.910135 -229.094542) (xy 117.940159 -229.050505) (xy 117.976411 -229.011434) (xy 118.018082 -228.978203)
			(xy 118.06424 -228.951554) (xy 118.113854 -228.932082) (xy 118.165816 -228.920222) (xy 118.218966 -228.916239)
			(xy 118.272116 -228.920222) (xy 118.324078 -228.932082) (xy 118.373692 -228.951554) (xy 118.41985 -228.978203)
			(xy 118.461521 -229.011434) (xy 118.497773 -229.050505) (xy 118.527797 -229.094542) (xy 118.550923 -229.142563)
			(xy 118.566633 -229.193493) (xy 118.574576 -229.246197) (xy 118.575074 -229.272846) (xy 118.574576 -229.299495)
			(xy 118.803156 -229.299495) (xy 118.803156 -229.246197) (xy 118.811099 -229.193493) (xy 118.826809 -229.142563)
			(xy 118.849935 -229.094542) (xy 118.879959 -229.050505) (xy 118.916211 -229.011434) (xy 118.957882 -228.978203)
			(xy 119.00404 -228.951554) (xy 119.053654 -228.932082) (xy 119.105616 -228.920222) (xy 119.158766 -228.916239)
			(xy 119.211916 -228.920222) (xy 119.263878 -228.932082) (xy 119.313492 -228.951554) (xy 119.35965 -228.978203)
			(xy 119.401321 -229.011434) (xy 119.437573 -229.050505) (xy 119.467597 -229.094542) (xy 119.490723 -229.142563)
			(xy 119.506433 -229.193493) (xy 119.514376 -229.246197) (xy 119.514874 -229.272846) (xy 119.514376 -229.299495)
			(xy 119.742956 -229.299495) (xy 119.742956 -229.246197) (xy 119.750899 -229.193493) (xy 119.766609 -229.142563)
			(xy 119.789735 -229.094542) (xy 119.819759 -229.050505) (xy 119.856011 -229.011434) (xy 119.897682 -228.978203)
			(xy 119.94384 -228.951554) (xy 119.993454 -228.932082) (xy 120.045416 -228.920222) (xy 120.098566 -228.916239)
			(xy 120.151716 -228.920222) (xy 120.203678 -228.932082) (xy 120.253292 -228.951554) (xy 120.29945 -228.978203)
			(xy 120.341121 -229.011434) (xy 120.377373 -229.050505) (xy 120.407397 -229.094542) (xy 120.430523 -229.142563)
			(xy 120.446233 -229.193493) (xy 120.454176 -229.246197) (xy 120.454674 -229.272846) (xy 120.454176 -229.299495)
			(xy 120.682756 -229.299495) (xy 120.682756 -229.246197) (xy 120.690699 -229.193493) (xy 120.706409 -229.142563)
			(xy 120.729535 -229.094542) (xy 120.759559 -229.050505) (xy 120.795811 -229.011434) (xy 120.837482 -228.978203)
			(xy 120.88364 -228.951554) (xy 120.933254 -228.932082) (xy 120.985216 -228.920222) (xy 121.038366 -228.916239)
			(xy 121.091516 -228.920222) (xy 121.143478 -228.932082) (xy 121.193092 -228.951554) (xy 121.23925 -228.978203)
			(xy 121.280921 -229.011434) (xy 121.317173 -229.050505) (xy 121.347197 -229.094542) (xy 121.370323 -229.142563)
			(xy 121.386033 -229.193493) (xy 121.393976 -229.246197) (xy 121.394474 -229.272846) (xy 121.393976 -229.299495)
			(xy 121.622556 -229.299495) (xy 121.622556 -229.246197) (xy 121.630499 -229.193493) (xy 121.646209 -229.142563)
			(xy 121.669335 -229.094542) (xy 121.699359 -229.050505) (xy 121.735611 -229.011434) (xy 121.777282 -228.978203)
			(xy 121.82344 -228.951554) (xy 121.873054 -228.932082) (xy 121.925016 -228.920222) (xy 121.978166 -228.916239)
			(xy 122.031316 -228.920222) (xy 122.083278 -228.932082) (xy 122.132892 -228.951554) (xy 122.17905 -228.978203)
			(xy 122.220721 -229.011434) (xy 122.256973 -229.050505) (xy 122.286997 -229.094542) (xy 122.310123 -229.142563)
			(xy 122.325833 -229.193493) (xy 122.333776 -229.246197) (xy 122.334274 -229.272846) (xy 122.333776 -229.299495)
			(xy 122.562102 -229.299495) (xy 122.562102 -229.246197) (xy 122.570045 -229.193493) (xy 122.585755 -229.142563)
			(xy 122.608881 -229.094542) (xy 122.638905 -229.050505) (xy 122.675157 -229.011434) (xy 122.716828 -228.978203)
			(xy 122.762986 -228.951554) (xy 122.8126 -228.932082) (xy 122.864562 -228.920222) (xy 122.917712 -228.916239)
			(xy 122.970862 -228.920222) (xy 123.022824 -228.932082) (xy 123.072438 -228.951554) (xy 123.118596 -228.978203)
			(xy 123.160267 -229.011434) (xy 123.196519 -229.050505) (xy 123.226543 -229.094542) (xy 123.249669 -229.142563)
			(xy 123.265379 -229.193493) (xy 123.273322 -229.246197) (xy 123.27382 -229.272846) (xy 123.273322 -229.299495)
			(xy 123.502156 -229.299495) (xy 123.502156 -229.246197) (xy 123.510099 -229.193493) (xy 123.525809 -229.142563)
			(xy 123.548935 -229.094542) (xy 123.578959 -229.050505) (xy 123.615211 -229.011434) (xy 123.656882 -228.978203)
			(xy 123.70304 -228.951554) (xy 123.752654 -228.932082) (xy 123.804616 -228.920222) (xy 123.857766 -228.916239)
			(xy 123.910916 -228.920222) (xy 123.962878 -228.932082) (xy 124.012492 -228.951554) (xy 124.05865 -228.978203)
			(xy 124.100321 -229.011434) (xy 124.136573 -229.050505) (xy 124.166597 -229.094542) (xy 124.189723 -229.142563)
			(xy 124.205433 -229.193493) (xy 124.213376 -229.246197) (xy 124.213874 -229.272846) (xy 124.213376 -229.299495)
			(xy 124.441956 -229.299495) (xy 124.441956 -229.246197) (xy 124.449899 -229.193493) (xy 124.465609 -229.142563)
			(xy 124.488735 -229.094542) (xy 124.518759 -229.050505) (xy 124.555011 -229.011434) (xy 124.596682 -228.978203)
			(xy 124.64284 -228.951554) (xy 124.692454 -228.932082) (xy 124.744416 -228.920222) (xy 124.797566 -228.916239)
			(xy 124.850716 -228.920222) (xy 124.902678 -228.932082) (xy 124.952292 -228.951554) (xy 124.99845 -228.978203)
			(xy 125.040121 -229.011434) (xy 125.076373 -229.050505) (xy 125.106397 -229.094542) (xy 125.129523 -229.142563)
			(xy 125.145233 -229.193493) (xy 125.153176 -229.246197) (xy 125.153674 -229.272846) (xy 125.153176 -229.299495)
			(xy 125.381756 -229.299495) (xy 125.381756 -229.246197) (xy 125.389699 -229.193493) (xy 125.405409 -229.142563)
			(xy 125.428535 -229.094542) (xy 125.458559 -229.050505) (xy 125.494811 -229.011434) (xy 125.536482 -228.978203)
			(xy 125.58264 -228.951554) (xy 125.632254 -228.932082) (xy 125.684216 -228.920222) (xy 125.737366 -228.916239)
			(xy 125.790516 -228.920222) (xy 125.842478 -228.932082) (xy 125.892092 -228.951554) (xy 125.93825 -228.978203)
			(xy 125.979921 -229.011434) (xy 126.016173 -229.050505) (xy 126.046197 -229.094542) (xy 126.069323 -229.142563)
			(xy 126.085033 -229.193493) (xy 126.092976 -229.246197) (xy 126.093474 -229.272846) (xy 126.092976 -229.299495)
			(xy 126.321556 -229.299495) (xy 126.321556 -229.246197) (xy 126.329499 -229.193493) (xy 126.345209 -229.142563)
			(xy 126.368335 -229.094542) (xy 126.398359 -229.050505) (xy 126.434611 -229.011434) (xy 126.476282 -228.978203)
			(xy 126.52244 -228.951554) (xy 126.572054 -228.932082) (xy 126.624016 -228.920222) (xy 126.677166 -228.916239)
			(xy 126.730316 -228.920222) (xy 126.782278 -228.932082) (xy 126.831892 -228.951554) (xy 126.87805 -228.978203)
			(xy 126.919721 -229.011434) (xy 126.955973 -229.050505) (xy 126.985997 -229.094542) (xy 127.009123 -229.142563)
			(xy 127.024833 -229.193493) (xy 127.032776 -229.246197) (xy 127.033274 -229.272846) (xy 127.032776 -229.299495)
			(xy 127.261356 -229.299495) (xy 127.261356 -229.246197) (xy 127.269299 -229.193493) (xy 127.285009 -229.142563)
			(xy 127.308135 -229.094542) (xy 127.338159 -229.050505) (xy 127.374411 -229.011434) (xy 127.416082 -228.978203)
			(xy 127.46224 -228.951554) (xy 127.511854 -228.932082) (xy 127.563816 -228.920222) (xy 127.616966 -228.916239)
			(xy 127.670116 -228.920222) (xy 127.722078 -228.932082) (xy 127.771692 -228.951554) (xy 127.81785 -228.978203)
			(xy 127.859521 -229.011434) (xy 127.895773 -229.050505) (xy 127.925797 -229.094542) (xy 127.948923 -229.142563)
			(xy 127.964633 -229.193493) (xy 127.972576 -229.246197) (xy 127.973074 -229.272846) (xy 127.972576 -229.299495)
			(xy 128.201156 -229.299495) (xy 128.201156 -229.246197) (xy 128.209099 -229.193493) (xy 128.224809 -229.142563)
			(xy 128.247935 -229.094542) (xy 128.277959 -229.050505) (xy 128.314211 -229.011434) (xy 128.355882 -228.978203)
			(xy 128.40204 -228.951554) (xy 128.451654 -228.932082) (xy 128.503616 -228.920222) (xy 128.556766 -228.916239)
			(xy 128.609916 -228.920222) (xy 128.661878 -228.932082) (xy 128.711492 -228.951554) (xy 128.75765 -228.978203)
			(xy 128.799321 -229.011434) (xy 128.835573 -229.050505) (xy 128.865597 -229.094542) (xy 128.888723 -229.142563)
			(xy 128.904433 -229.193493) (xy 128.912376 -229.246197) (xy 128.912874 -229.272846) (xy 128.912376 -229.299495)
			(xy 129.140702 -229.299495) (xy 129.140702 -229.246197) (xy 129.148645 -229.193493) (xy 129.164355 -229.142563)
			(xy 129.187481 -229.094542) (xy 129.217505 -229.050505) (xy 129.253757 -229.011434) (xy 129.295428 -228.978203)
			(xy 129.341586 -228.951554) (xy 129.3912 -228.932082) (xy 129.443162 -228.920222) (xy 129.496312 -228.916239)
			(xy 129.549462 -228.920222) (xy 129.601424 -228.932082) (xy 129.651038 -228.951554) (xy 129.697196 -228.978203)
			(xy 129.738867 -229.011434) (xy 129.775119 -229.050505) (xy 129.805143 -229.094542) (xy 129.828269 -229.142563)
			(xy 129.843979 -229.193493) (xy 129.851922 -229.246197) (xy 129.85242 -229.272846) (xy 129.851922 -229.299495)
			(xy 130.080756 -229.299495) (xy 130.080756 -229.246197) (xy 130.088699 -229.193493) (xy 130.104409 -229.142563)
			(xy 130.127535 -229.094542) (xy 130.157559 -229.050505) (xy 130.193811 -229.011434) (xy 130.235482 -228.978203)
			(xy 130.28164 -228.951554) (xy 130.331254 -228.932082) (xy 130.383216 -228.920222) (xy 130.436366 -228.916239)
			(xy 130.489516 -228.920222) (xy 130.541478 -228.932082) (xy 130.591092 -228.951554) (xy 130.63725 -228.978203)
			(xy 130.678921 -229.011434) (xy 130.715173 -229.050505) (xy 130.745197 -229.094542) (xy 130.768323 -229.142563)
			(xy 130.784033 -229.193493) (xy 130.791976 -229.246197) (xy 130.792474 -229.272846) (xy 130.791976 -229.299495)
			(xy 131.020556 -229.299495) (xy 131.020556 -229.246197) (xy 131.028499 -229.193493) (xy 131.044209 -229.142563)
			(xy 131.067335 -229.094542) (xy 131.097359 -229.050505) (xy 131.133611 -229.011434) (xy 131.175282 -228.978203)
			(xy 131.22144 -228.951554) (xy 131.271054 -228.932082) (xy 131.323016 -228.920222) (xy 131.376166 -228.916239)
			(xy 131.429316 -228.920222) (xy 131.481278 -228.932082) (xy 131.530892 -228.951554) (xy 131.57705 -228.978203)
			(xy 131.618721 -229.011434) (xy 131.654973 -229.050505) (xy 131.684997 -229.094542) (xy 131.708123 -229.142563)
			(xy 131.723833 -229.193493) (xy 131.731776 -229.246197) (xy 131.732274 -229.272846) (xy 131.731776 -229.299495)
			(xy 131.960356 -229.299495) (xy 131.960356 -229.246197) (xy 131.968299 -229.193493) (xy 131.984009 -229.142563)
			(xy 132.007135 -229.094542) (xy 132.037159 -229.050505) (xy 132.073411 -229.011434) (xy 132.115082 -228.978203)
			(xy 132.16124 -228.951554) (xy 132.210854 -228.932082) (xy 132.262816 -228.920222) (xy 132.315966 -228.916239)
			(xy 132.369116 -228.920222) (xy 132.421078 -228.932082) (xy 132.470692 -228.951554) (xy 132.51685 -228.978203)
			(xy 132.558521 -229.011434) (xy 132.594773 -229.050505) (xy 132.624797 -229.094542) (xy 132.647923 -229.142563)
			(xy 132.663633 -229.193493) (xy 132.671576 -229.246197) (xy 132.672074 -229.272846) (xy 132.671576 -229.299495)
			(xy 132.900156 -229.299495) (xy 132.900156 -229.246197) (xy 132.908099 -229.193493) (xy 132.923809 -229.142563)
			(xy 132.946935 -229.094542) (xy 132.976959 -229.050505) (xy 133.013211 -229.011434) (xy 133.054882 -228.978203)
			(xy 133.10104 -228.951554) (xy 133.150654 -228.932082) (xy 133.202616 -228.920222) (xy 133.255766 -228.916239)
			(xy 133.308916 -228.920222) (xy 133.360878 -228.932082) (xy 133.410492 -228.951554) (xy 133.45665 -228.978203)
			(xy 133.498321 -229.011434) (xy 133.534573 -229.050505) (xy 133.564597 -229.094542) (xy 133.587723 -229.142563)
			(xy 133.603433 -229.193493) (xy 133.611376 -229.246197) (xy 133.611874 -229.272846) (xy 133.611376 -229.299495)
			(xy 133.839956 -229.299495) (xy 133.839956 -229.246197) (xy 133.847899 -229.193493) (xy 133.863609 -229.142563)
			(xy 133.886735 -229.094542) (xy 133.916759 -229.050505) (xy 133.953011 -229.011434) (xy 133.994682 -228.978203)
			(xy 134.04084 -228.951554) (xy 134.090454 -228.932082) (xy 134.142416 -228.920222) (xy 134.195566 -228.916239)
			(xy 134.248716 -228.920222) (xy 134.300678 -228.932082) (xy 134.350292 -228.951554) (xy 134.39645 -228.978203)
			(xy 134.438121 -229.011434) (xy 134.474373 -229.050505) (xy 134.504397 -229.094542) (xy 134.527523 -229.142563)
			(xy 134.543233 -229.193493) (xy 134.551176 -229.246197) (xy 134.551674 -229.272846) (xy 134.551176 -229.299495)
			(xy 134.543233 -229.352199) (xy 134.527523 -229.403129) (xy 134.504397 -229.45115) (xy 134.474373 -229.495187)
			(xy 134.438121 -229.534258) (xy 134.39645 -229.567489) (xy 134.350292 -229.594138) (xy 134.300678 -229.61361)
			(xy 134.248716 -229.62547) (xy 134.195566 -229.629454) (xy 134.142416 -229.62547) (xy 134.090454 -229.61361)
			(xy 134.04084 -229.594138) (xy 133.994682 -229.567489) (xy 133.953011 -229.534258) (xy 133.916759 -229.495187)
			(xy 133.886735 -229.45115) (xy 133.863609 -229.403129) (xy 133.847899 -229.352199) (xy 133.839956 -229.299495)
			(xy 133.611376 -229.299495) (xy 133.603433 -229.352199) (xy 133.587723 -229.403129) (xy 133.564597 -229.45115)
			(xy 133.534573 -229.495187) (xy 133.498321 -229.534258) (xy 133.45665 -229.567489) (xy 133.410492 -229.594138)
			(xy 133.360878 -229.61361) (xy 133.308916 -229.62547) (xy 133.255766 -229.629454) (xy 133.202616 -229.62547)
			(xy 133.150654 -229.61361) (xy 133.10104 -229.594138) (xy 133.054882 -229.567489) (xy 133.013211 -229.534258)
			(xy 132.976959 -229.495187) (xy 132.946935 -229.45115) (xy 132.923809 -229.403129) (xy 132.908099 -229.352199)
			(xy 132.900156 -229.299495) (xy 132.671576 -229.299495) (xy 132.663633 -229.352199) (xy 132.647923 -229.403129)
			(xy 132.624797 -229.45115) (xy 132.594773 -229.495187) (xy 132.558521 -229.534258) (xy 132.51685 -229.567489)
			(xy 132.470692 -229.594138) (xy 132.421078 -229.61361) (xy 132.369116 -229.62547) (xy 132.315966 -229.629454)
			(xy 132.262816 -229.62547) (xy 132.210854 -229.61361) (xy 132.16124 -229.594138) (xy 132.115082 -229.567489)
			(xy 132.073411 -229.534258) (xy 132.037159 -229.495187) (xy 132.007135 -229.45115) (xy 131.984009 -229.403129)
			(xy 131.968299 -229.352199) (xy 131.960356 -229.299495) (xy 131.731776 -229.299495) (xy 131.723833 -229.352199)
			(xy 131.708123 -229.403129) (xy 131.684997 -229.45115) (xy 131.654973 -229.495187) (xy 131.618721 -229.534258)
			(xy 131.57705 -229.567489) (xy 131.530892 -229.594138) (xy 131.481278 -229.61361) (xy 131.429316 -229.62547)
			(xy 131.376166 -229.629454) (xy 131.323016 -229.62547) (xy 131.271054 -229.61361) (xy 131.22144 -229.594138)
			(xy 131.175282 -229.567489) (xy 131.133611 -229.534258) (xy 131.097359 -229.495187) (xy 131.067335 -229.45115)
			(xy 131.044209 -229.403129) (xy 131.028499 -229.352199) (xy 131.020556 -229.299495) (xy 130.791976 -229.299495)
			(xy 130.784033 -229.352199) (xy 130.768323 -229.403129) (xy 130.745197 -229.45115) (xy 130.715173 -229.495187)
			(xy 130.678921 -229.534258) (xy 130.63725 -229.567489) (xy 130.591092 -229.594138) (xy 130.541478 -229.61361)
			(xy 130.489516 -229.62547) (xy 130.436366 -229.629454) (xy 130.383216 -229.62547) (xy 130.331254 -229.61361)
			(xy 130.28164 -229.594138) (xy 130.235482 -229.567489) (xy 130.193811 -229.534258) (xy 130.157559 -229.495187)
			(xy 130.127535 -229.45115) (xy 130.104409 -229.403129) (xy 130.088699 -229.352199) (xy 130.080756 -229.299495)
			(xy 129.851922 -229.299495) (xy 129.843979 -229.352199) (xy 129.828269 -229.403129) (xy 129.805143 -229.45115)
			(xy 129.775119 -229.495187) (xy 129.738867 -229.534258) (xy 129.697196 -229.567489) (xy 129.651038 -229.594138)
			(xy 129.601424 -229.61361) (xy 129.549462 -229.62547) (xy 129.496312 -229.629454) (xy 129.443162 -229.62547)
			(xy 129.3912 -229.61361) (xy 129.341586 -229.594138) (xy 129.295428 -229.567489) (xy 129.253757 -229.534258)
			(xy 129.217505 -229.495187) (xy 129.187481 -229.45115) (xy 129.164355 -229.403129) (xy 129.148645 -229.352199)
			(xy 129.140702 -229.299495) (xy 128.912376 -229.299495) (xy 128.904433 -229.352199) (xy 128.888723 -229.403129)
			(xy 128.865597 -229.45115) (xy 128.835573 -229.495187) (xy 128.799321 -229.534258) (xy 128.75765 -229.567489)
			(xy 128.711492 -229.594138) (xy 128.661878 -229.61361) (xy 128.609916 -229.62547) (xy 128.556766 -229.629454)
			(xy 128.503616 -229.62547) (xy 128.451654 -229.61361) (xy 128.40204 -229.594138) (xy 128.355882 -229.567489)
			(xy 128.314211 -229.534258) (xy 128.277959 -229.495187) (xy 128.247935 -229.45115) (xy 128.224809 -229.403129)
			(xy 128.209099 -229.352199) (xy 128.201156 -229.299495) (xy 127.972576 -229.299495) (xy 127.964633 -229.352199)
			(xy 127.948923 -229.403129) (xy 127.925797 -229.45115) (xy 127.895773 -229.495187) (xy 127.859521 -229.534258)
			(xy 127.81785 -229.567489) (xy 127.771692 -229.594138) (xy 127.722078 -229.61361) (xy 127.670116 -229.62547)
			(xy 127.616966 -229.629454) (xy 127.563816 -229.62547) (xy 127.511854 -229.61361) (xy 127.46224 -229.594138)
			(xy 127.416082 -229.567489) (xy 127.374411 -229.534258) (xy 127.338159 -229.495187) (xy 127.308135 -229.45115)
			(xy 127.285009 -229.403129) (xy 127.269299 -229.352199) (xy 127.261356 -229.299495) (xy 127.032776 -229.299495)
			(xy 127.024833 -229.352199) (xy 127.009123 -229.403129) (xy 126.985997 -229.45115) (xy 126.955973 -229.495187)
			(xy 126.919721 -229.534258) (xy 126.87805 -229.567489) (xy 126.831892 -229.594138) (xy 126.782278 -229.61361)
			(xy 126.730316 -229.62547) (xy 126.677166 -229.629454) (xy 126.624016 -229.62547) (xy 126.572054 -229.61361)
			(xy 126.52244 -229.594138) (xy 126.476282 -229.567489) (xy 126.434611 -229.534258) (xy 126.398359 -229.495187)
			(xy 126.368335 -229.45115) (xy 126.345209 -229.403129) (xy 126.329499 -229.352199) (xy 126.321556 -229.299495)
			(xy 126.092976 -229.299495) (xy 126.085033 -229.352199) (xy 126.069323 -229.403129) (xy 126.046197 -229.45115)
			(xy 126.016173 -229.495187) (xy 125.979921 -229.534258) (xy 125.93825 -229.567489) (xy 125.892092 -229.594138)
			(xy 125.842478 -229.61361) (xy 125.790516 -229.62547) (xy 125.737366 -229.629454) (xy 125.684216 -229.62547)
			(xy 125.632254 -229.61361) (xy 125.58264 -229.594138) (xy 125.536482 -229.567489) (xy 125.494811 -229.534258)
			(xy 125.458559 -229.495187) (xy 125.428535 -229.45115) (xy 125.405409 -229.403129) (xy 125.389699 -229.352199)
			(xy 125.381756 -229.299495) (xy 125.153176 -229.299495) (xy 125.145233 -229.352199) (xy 125.129523 -229.403129)
			(xy 125.106397 -229.45115) (xy 125.076373 -229.495187) (xy 125.040121 -229.534258) (xy 124.99845 -229.567489)
			(xy 124.952292 -229.594138) (xy 124.902678 -229.61361) (xy 124.850716 -229.62547) (xy 124.797566 -229.629454)
			(xy 124.744416 -229.62547) (xy 124.692454 -229.61361) (xy 124.64284 -229.594138) (xy 124.596682 -229.567489)
			(xy 124.555011 -229.534258) (xy 124.518759 -229.495187) (xy 124.488735 -229.45115) (xy 124.465609 -229.403129)
			(xy 124.449899 -229.352199) (xy 124.441956 -229.299495) (xy 124.213376 -229.299495) (xy 124.205433 -229.352199)
			(xy 124.189723 -229.403129) (xy 124.166597 -229.45115) (xy 124.136573 -229.495187) (xy 124.100321 -229.534258)
			(xy 124.05865 -229.567489) (xy 124.012492 -229.594138) (xy 123.962878 -229.61361) (xy 123.910916 -229.62547)
			(xy 123.857766 -229.629454) (xy 123.804616 -229.62547) (xy 123.752654 -229.61361) (xy 123.70304 -229.594138)
			(xy 123.656882 -229.567489) (xy 123.615211 -229.534258) (xy 123.578959 -229.495187) (xy 123.548935 -229.45115)
			(xy 123.525809 -229.403129) (xy 123.510099 -229.352199) (xy 123.502156 -229.299495) (xy 123.273322 -229.299495)
			(xy 123.265379 -229.352199) (xy 123.249669 -229.403129) (xy 123.226543 -229.45115) (xy 123.196519 -229.495187)
			(xy 123.160267 -229.534258) (xy 123.118596 -229.567489) (xy 123.072438 -229.594138) (xy 123.022824 -229.61361)
			(xy 122.970862 -229.62547) (xy 122.917712 -229.629454) (xy 122.864562 -229.62547) (xy 122.8126 -229.61361)
			(xy 122.762986 -229.594138) (xy 122.716828 -229.567489) (xy 122.675157 -229.534258) (xy 122.638905 -229.495187)
			(xy 122.608881 -229.45115) (xy 122.585755 -229.403129) (xy 122.570045 -229.352199) (xy 122.562102 -229.299495)
			(xy 122.333776 -229.299495) (xy 122.325833 -229.352199) (xy 122.310123 -229.403129) (xy 122.286997 -229.45115)
			(xy 122.256973 -229.495187) (xy 122.220721 -229.534258) (xy 122.17905 -229.567489) (xy 122.132892 -229.594138)
			(xy 122.083278 -229.61361) (xy 122.031316 -229.62547) (xy 121.978166 -229.629454) (xy 121.925016 -229.62547)
			(xy 121.873054 -229.61361) (xy 121.82344 -229.594138) (xy 121.777282 -229.567489) (xy 121.735611 -229.534258)
			(xy 121.699359 -229.495187) (xy 121.669335 -229.45115) (xy 121.646209 -229.403129) (xy 121.630499 -229.352199)
			(xy 121.622556 -229.299495) (xy 121.393976 -229.299495) (xy 121.386033 -229.352199) (xy 121.370323 -229.403129)
			(xy 121.347197 -229.45115) (xy 121.317173 -229.495187) (xy 121.280921 -229.534258) (xy 121.23925 -229.567489)
			(xy 121.193092 -229.594138) (xy 121.143478 -229.61361) (xy 121.091516 -229.62547) (xy 121.038366 -229.629454)
			(xy 120.985216 -229.62547) (xy 120.933254 -229.61361) (xy 120.88364 -229.594138) (xy 120.837482 -229.567489)
			(xy 120.795811 -229.534258) (xy 120.759559 -229.495187) (xy 120.729535 -229.45115) (xy 120.706409 -229.403129)
			(xy 120.690699 -229.352199) (xy 120.682756 -229.299495) (xy 120.454176 -229.299495) (xy 120.446233 -229.352199)
			(xy 120.430523 -229.403129) (xy 120.407397 -229.45115) (xy 120.377373 -229.495187) (xy 120.341121 -229.534258)
			(xy 120.29945 -229.567489) (xy 120.253292 -229.594138) (xy 120.203678 -229.61361) (xy 120.151716 -229.62547)
			(xy 120.098566 -229.629454) (xy 120.045416 -229.62547) (xy 119.993454 -229.61361) (xy 119.94384 -229.594138)
			(xy 119.897682 -229.567489) (xy 119.856011 -229.534258) (xy 119.819759 -229.495187) (xy 119.789735 -229.45115)
			(xy 119.766609 -229.403129) (xy 119.750899 -229.352199) (xy 119.742956 -229.299495) (xy 119.514376 -229.299495)
			(xy 119.506433 -229.352199) (xy 119.490723 -229.403129) (xy 119.467597 -229.45115) (xy 119.437573 -229.495187)
			(xy 119.401321 -229.534258) (xy 119.35965 -229.567489) (xy 119.313492 -229.594138) (xy 119.263878 -229.61361)
			(xy 119.211916 -229.62547) (xy 119.158766 -229.629454) (xy 119.105616 -229.62547) (xy 119.053654 -229.61361)
			(xy 119.00404 -229.594138) (xy 118.957882 -229.567489) (xy 118.916211 -229.534258) (xy 118.879959 -229.495187)
			(xy 118.849935 -229.45115) (xy 118.826809 -229.403129) (xy 118.811099 -229.352199) (xy 118.803156 -229.299495)
			(xy 118.574576 -229.299495) (xy 118.566633 -229.352199) (xy 118.550923 -229.403129) (xy 118.527797 -229.45115)
			(xy 118.497773 -229.495187) (xy 118.461521 -229.534258) (xy 118.41985 -229.567489) (xy 118.373692 -229.594138)
			(xy 118.324078 -229.61361) (xy 118.272116 -229.62547) (xy 118.218966 -229.629454) (xy 118.165816 -229.62547)
			(xy 118.113854 -229.61361) (xy 118.06424 -229.594138) (xy 118.018082 -229.567489) (xy 117.976411 -229.534258)
			(xy 117.940159 -229.495187) (xy 117.910135 -229.45115) (xy 117.887009 -229.403129) (xy 117.871299 -229.352199)
			(xy 117.863356 -229.299495) (xy 117.634776 -229.299495) (xy 117.626833 -229.352199) (xy 117.611123 -229.403129)
			(xy 117.587997 -229.45115) (xy 117.557973 -229.495187) (xy 117.521721 -229.534258) (xy 117.48005 -229.567489)
			(xy 117.433892 -229.594138) (xy 117.384278 -229.61361) (xy 117.332316 -229.62547) (xy 117.279166 -229.629454)
			(xy 117.226016 -229.62547) (xy 117.174054 -229.61361) (xy 117.12444 -229.594138) (xy 117.078282 -229.567489)
			(xy 117.036611 -229.534258) (xy 117.000359 -229.495187) (xy 116.970335 -229.45115) (xy 116.947209 -229.403129)
			(xy 116.931499 -229.352199) (xy 116.923556 -229.299495) (xy 116.694976 -229.299495) (xy 116.687033 -229.352199)
			(xy 116.671323 -229.403129) (xy 116.648197 -229.45115) (xy 116.618173 -229.495187) (xy 116.581921 -229.534258)
			(xy 116.54025 -229.567489) (xy 116.494092 -229.594138) (xy 116.444478 -229.61361) (xy 116.392516 -229.62547)
			(xy 116.339366 -229.629454) (xy 116.286216 -229.62547) (xy 116.234254 -229.61361) (xy 116.18464 -229.594138)
			(xy 116.138482 -229.567489) (xy 116.096811 -229.534258) (xy 116.060559 -229.495187) (xy 116.030535 -229.45115)
			(xy 116.007409 -229.403129) (xy 115.991699 -229.352199) (xy 115.983756 -229.299495) (xy 115.755176 -229.299495)
			(xy 115.747233 -229.352199) (xy 115.731523 -229.403129) (xy 115.708397 -229.45115) (xy 115.678373 -229.495187)
			(xy 115.642121 -229.534258) (xy 115.60045 -229.567489) (xy 115.554292 -229.594138) (xy 115.504678 -229.61361)
			(xy 115.452716 -229.62547) (xy 115.399566 -229.629454) (xy 115.346416 -229.62547) (xy 115.294454 -229.61361)
			(xy 115.24484 -229.594138) (xy 115.198682 -229.567489) (xy 115.157011 -229.534258) (xy 115.120759 -229.495187)
			(xy 115.090735 -229.45115) (xy 115.067609 -229.403129) (xy 115.051899 -229.352199) (xy 115.043956 -229.299495)
			(xy 114.815376 -229.299495) (xy 114.807433 -229.352199) (xy 114.791723 -229.403129) (xy 114.768597 -229.45115)
			(xy 114.738573 -229.495187) (xy 114.702321 -229.534258) (xy 114.66065 -229.567489) (xy 114.614492 -229.594138)
			(xy 114.564878 -229.61361) (xy 114.512916 -229.62547) (xy 114.459766 -229.629454) (xy 114.406616 -229.62547)
			(xy 114.354654 -229.61361) (xy 114.30504 -229.594138) (xy 114.258882 -229.567489) (xy 114.217211 -229.534258)
			(xy 114.180959 -229.495187) (xy 114.150935 -229.45115) (xy 114.127809 -229.403129) (xy 114.112099 -229.352199)
			(xy 114.104156 -229.299495) (xy 113.875576 -229.299495) (xy 113.867633 -229.352199) (xy 113.851923 -229.403129)
			(xy 113.828797 -229.45115) (xy 113.798773 -229.495187) (xy 113.762521 -229.534258) (xy 113.72085 -229.567489)
			(xy 113.674692 -229.594138) (xy 113.625078 -229.61361) (xy 113.573116 -229.62547) (xy 113.519966 -229.629454)
			(xy 113.466816 -229.62547) (xy 113.414854 -229.61361) (xy 113.36524 -229.594138) (xy 113.319082 -229.567489)
			(xy 113.277411 -229.534258) (xy 113.241159 -229.495187) (xy 113.211135 -229.45115) (xy 113.188009 -229.403129)
			(xy 113.172299 -229.352199) (xy 113.164356 -229.299495) (xy 112.935776 -229.299495) (xy 112.927833 -229.352199)
			(xy 112.912123 -229.403129) (xy 112.888997 -229.45115) (xy 112.858973 -229.495187) (xy 112.822721 -229.534258)
			(xy 112.78105 -229.567489) (xy 112.734892 -229.594138) (xy 112.685278 -229.61361) (xy 112.633316 -229.62547)
			(xy 112.580166 -229.629454) (xy 112.527016 -229.62547) (xy 112.475054 -229.61361) (xy 112.42544 -229.594138)
			(xy 112.379282 -229.567489) (xy 112.337611 -229.534258) (xy 112.301359 -229.495187) (xy 112.271335 -229.45115)
			(xy 112.248209 -229.403129) (xy 112.232499 -229.352199) (xy 112.224556 -229.299495) (xy 111.994733 -229.299495)
			(xy 111.992951 -229.324128) (xy 111.981903 -229.374356) (xy 111.963747 -229.422475) (xy 111.938862 -229.467483)
			(xy 111.907764 -229.508445) (xy 111.889794 -229.526846) (xy 111.889794 -229.644702) (xy 111.890192 -229.65803)
			(xy 111.8971 -229.683774) (xy 111.910443 -229.70685) (xy 111.929309 -229.72568) (xy 111.952411 -229.738977)
			(xy 111.978169 -229.745834) (xy 112.004825 -229.745782) (xy 112.01781 -229.742746) (xy 112.040494 -229.737026)
			(xy 112.086875 -229.730904) (xy 112.110266 -229.730554) (xy 112.136922 -229.731025) (xy 112.189638 -229.738966)
			(xy 112.240582 -229.754676) (xy 112.288615 -229.777803) (xy 112.332665 -229.807832) (xy 112.371747 -229.844091)
			(xy 112.404987 -229.88577) (xy 112.431644 -229.931938) (xy 112.451122 -229.981563) (xy 112.462986 -230.033538)
			(xy 112.46697 -230.0867) (xy 112.464976 -230.113311) (xy 112.694456 -230.113311) (xy 112.694456 -230.060013)
			(xy 112.702399 -230.007309) (xy 112.718109 -229.956379) (xy 112.741235 -229.908358) (xy 112.771259 -229.864321)
			(xy 112.807511 -229.82525) (xy 112.849182 -229.792019) (xy 112.89534 -229.76537) (xy 112.944954 -229.745898)
			(xy 112.996916 -229.734038) (xy 113.050066 -229.730055) (xy 113.103216 -229.734038) (xy 113.155178 -229.745898)
			(xy 113.204792 -229.76537) (xy 113.25095 -229.792019) (xy 113.292621 -229.82525) (xy 113.328873 -229.864321)
			(xy 113.358897 -229.908358) (xy 113.382023 -229.956379) (xy 113.397733 -230.007309) (xy 113.405676 -230.060013)
			(xy 113.406174 -230.086662) (xy 113.405676 -230.113311) (xy 113.634256 -230.113311) (xy 113.634256 -230.060013)
			(xy 113.642199 -230.007309) (xy 113.657909 -229.956379) (xy 113.681035 -229.908358) (xy 113.711059 -229.864321)
			(xy 113.747311 -229.82525) (xy 113.788982 -229.792019) (xy 113.83514 -229.76537) (xy 113.884754 -229.745898)
			(xy 113.936716 -229.734038) (xy 113.989866 -229.730055) (xy 114.043016 -229.734038) (xy 114.094978 -229.745898)
			(xy 114.144592 -229.76537) (xy 114.19075 -229.792019) (xy 114.232421 -229.82525) (xy 114.268673 -229.864321)
			(xy 114.298697 -229.908358) (xy 114.321823 -229.956379) (xy 114.337533 -230.007309) (xy 114.345476 -230.060013)
			(xy 114.345974 -230.086662) (xy 114.345476 -230.113311) (xy 114.574056 -230.113311) (xy 114.574056 -230.060013)
			(xy 114.581999 -230.007309) (xy 114.597709 -229.956379) (xy 114.620835 -229.908358) (xy 114.650859 -229.864321)
			(xy 114.687111 -229.82525) (xy 114.728782 -229.792019) (xy 114.77494 -229.76537) (xy 114.824554 -229.745898)
			(xy 114.876516 -229.734038) (xy 114.929666 -229.730055) (xy 114.982816 -229.734038) (xy 115.034778 -229.745898)
			(xy 115.084392 -229.76537) (xy 115.13055 -229.792019) (xy 115.172221 -229.82525) (xy 115.208473 -229.864321)
			(xy 115.238497 -229.908358) (xy 115.261623 -229.956379) (xy 115.277333 -230.007309) (xy 115.285276 -230.060013)
			(xy 115.285774 -230.086662) (xy 115.285276 -230.113311) (xy 115.513602 -230.113311) (xy 115.513602 -230.060013)
			(xy 115.521545 -230.007309) (xy 115.537255 -229.956379) (xy 115.560381 -229.908358) (xy 115.590405 -229.864321)
			(xy 115.626657 -229.82525) (xy 115.668328 -229.792019) (xy 115.714486 -229.76537) (xy 115.7641 -229.745898)
			(xy 115.816062 -229.734038) (xy 115.869212 -229.730055) (xy 115.922362 -229.734038) (xy 115.974324 -229.745898)
			(xy 116.023938 -229.76537) (xy 116.070096 -229.792019) (xy 116.111767 -229.82525) (xy 116.148019 -229.864321)
			(xy 116.178043 -229.908358) (xy 116.201169 -229.956379) (xy 116.216879 -230.007309) (xy 116.224822 -230.060013)
			(xy 116.22532 -230.086662) (xy 116.224822 -230.113311) (xy 116.453402 -230.113311) (xy 116.453402 -230.060013)
			(xy 116.461345 -230.007309) (xy 116.477055 -229.956379) (xy 116.500181 -229.908358) (xy 116.530205 -229.864321)
			(xy 116.566457 -229.82525) (xy 116.608128 -229.792019) (xy 116.654286 -229.76537) (xy 116.7039 -229.745898)
			(xy 116.755862 -229.734038) (xy 116.809012 -229.730055) (xy 116.862162 -229.734038) (xy 116.914124 -229.745898)
			(xy 116.963738 -229.76537) (xy 117.009896 -229.792019) (xy 117.051567 -229.82525) (xy 117.087819 -229.864321)
			(xy 117.117843 -229.908358) (xy 117.140969 -229.956379) (xy 117.156679 -230.007309) (xy 117.164622 -230.060013)
			(xy 117.16512 -230.086662) (xy 117.164622 -230.113311) (xy 117.393202 -230.113311) (xy 117.393202 -230.060013)
			(xy 117.401145 -230.007309) (xy 117.416855 -229.956379) (xy 117.439981 -229.908358) (xy 117.470005 -229.864321)
			(xy 117.506257 -229.82525) (xy 117.547928 -229.792019) (xy 117.594086 -229.76537) (xy 117.6437 -229.745898)
			(xy 117.695662 -229.734038) (xy 117.748812 -229.730055) (xy 117.801962 -229.734038) (xy 117.853924 -229.745898)
			(xy 117.903538 -229.76537) (xy 117.949696 -229.792019) (xy 117.991367 -229.82525) (xy 118.027619 -229.864321)
			(xy 118.057643 -229.908358) (xy 118.080769 -229.956379) (xy 118.096479 -230.007309) (xy 118.104422 -230.060013)
			(xy 118.10492 -230.086662) (xy 118.104422 -230.113311) (xy 118.333002 -230.113311) (xy 118.333002 -230.060013)
			(xy 118.340945 -230.007309) (xy 118.356655 -229.956379) (xy 118.379781 -229.908358) (xy 118.409805 -229.864321)
			(xy 118.446057 -229.82525) (xy 118.487728 -229.792019) (xy 118.533886 -229.76537) (xy 118.5835 -229.745898)
			(xy 118.635462 -229.734038) (xy 118.688612 -229.730055) (xy 118.741762 -229.734038) (xy 118.793724 -229.745898)
			(xy 118.843338 -229.76537) (xy 118.889496 -229.792019) (xy 118.931167 -229.82525) (xy 118.967419 -229.864321)
			(xy 118.997443 -229.908358) (xy 119.020569 -229.956379) (xy 119.036279 -230.007309) (xy 119.044222 -230.060013)
			(xy 119.04472 -230.086662) (xy 119.044222 -230.113311) (xy 119.272802 -230.113311) (xy 119.272802 -230.060013)
			(xy 119.280745 -230.007309) (xy 119.296455 -229.956379) (xy 119.319581 -229.908358) (xy 119.349605 -229.864321)
			(xy 119.385857 -229.82525) (xy 119.427528 -229.792019) (xy 119.473686 -229.76537) (xy 119.5233 -229.745898)
			(xy 119.575262 -229.734038) (xy 119.628412 -229.730055) (xy 119.681562 -229.734038) (xy 119.733524 -229.745898)
			(xy 119.783138 -229.76537) (xy 119.829296 -229.792019) (xy 119.870967 -229.82525) (xy 119.907219 -229.864321)
			(xy 119.937243 -229.908358) (xy 119.960369 -229.956379) (xy 119.976079 -230.007309) (xy 119.984022 -230.060013)
			(xy 119.98452 -230.086662) (xy 119.984022 -230.113311) (xy 120.212602 -230.113311) (xy 120.212602 -230.060013)
			(xy 120.220545 -230.007309) (xy 120.236255 -229.956379) (xy 120.259381 -229.908358) (xy 120.289405 -229.864321)
			(xy 120.325657 -229.82525) (xy 120.367328 -229.792019) (xy 120.413486 -229.76537) (xy 120.4631 -229.745898)
			(xy 120.515062 -229.734038) (xy 120.568212 -229.730055) (xy 120.621362 -229.734038) (xy 120.673324 -229.745898)
			(xy 120.722938 -229.76537) (xy 120.769096 -229.792019) (xy 120.810767 -229.82525) (xy 120.847019 -229.864321)
			(xy 120.877043 -229.908358) (xy 120.900169 -229.956379) (xy 120.915879 -230.007309) (xy 120.923822 -230.060013)
			(xy 120.92432 -230.086662) (xy 120.923822 -230.113311) (xy 121.152402 -230.113311) (xy 121.152402 -230.060013)
			(xy 121.160345 -230.007309) (xy 121.176055 -229.956379) (xy 121.199181 -229.908358) (xy 121.229205 -229.864321)
			(xy 121.265457 -229.82525) (xy 121.307128 -229.792019) (xy 121.353286 -229.76537) (xy 121.4029 -229.745898)
			(xy 121.454862 -229.734038) (xy 121.508012 -229.730055) (xy 121.561162 -229.734038) (xy 121.613124 -229.745898)
			(xy 121.662738 -229.76537) (xy 121.708896 -229.792019) (xy 121.750567 -229.82525) (xy 121.786819 -229.864321)
			(xy 121.816843 -229.908358) (xy 121.839969 -229.956379) (xy 121.855679 -230.007309) (xy 121.863622 -230.060013)
			(xy 121.86412 -230.086662) (xy 121.863622 -230.113311) (xy 122.092202 -230.113311) (xy 122.092202 -230.060013)
			(xy 122.100145 -230.007309) (xy 122.115855 -229.956379) (xy 122.138981 -229.908358) (xy 122.169005 -229.864321)
			(xy 122.205257 -229.82525) (xy 122.246928 -229.792019) (xy 122.293086 -229.76537) (xy 122.3427 -229.745898)
			(xy 122.394662 -229.734038) (xy 122.447812 -229.730055) (xy 122.500962 -229.734038) (xy 122.552924 -229.745898)
			(xy 122.602538 -229.76537) (xy 122.648696 -229.792019) (xy 122.690367 -229.82525) (xy 122.726619 -229.864321)
			(xy 122.756643 -229.908358) (xy 122.779769 -229.956379) (xy 122.795479 -230.007309) (xy 122.803422 -230.060013)
			(xy 122.80392 -230.086662) (xy 122.803422 -230.113311) (xy 123.032002 -230.113311) (xy 123.032002 -230.060013)
			(xy 123.039945 -230.007309) (xy 123.055655 -229.956379) (xy 123.078781 -229.908358) (xy 123.108805 -229.864321)
			(xy 123.145057 -229.82525) (xy 123.186728 -229.792019) (xy 123.232886 -229.76537) (xy 123.2825 -229.745898)
			(xy 123.334462 -229.734038) (xy 123.387612 -229.730055) (xy 123.440762 -229.734038) (xy 123.492724 -229.745898)
			(xy 123.542338 -229.76537) (xy 123.588496 -229.792019) (xy 123.630167 -229.82525) (xy 123.666419 -229.864321)
			(xy 123.696443 -229.908358) (xy 123.719569 -229.956379) (xy 123.735279 -230.007309) (xy 123.743222 -230.060013)
			(xy 123.74372 -230.086662) (xy 123.743222 -230.113311) (xy 123.971802 -230.113311) (xy 123.971802 -230.060013)
			(xy 123.979745 -230.007309) (xy 123.995455 -229.956379) (xy 124.018581 -229.908358) (xy 124.048605 -229.864321)
			(xy 124.084857 -229.82525) (xy 124.126528 -229.792019) (xy 124.172686 -229.76537) (xy 124.2223 -229.745898)
			(xy 124.274262 -229.734038) (xy 124.327412 -229.730055) (xy 124.380562 -229.734038) (xy 124.432524 -229.745898)
			(xy 124.482138 -229.76537) (xy 124.528296 -229.792019) (xy 124.569967 -229.82525) (xy 124.606219 -229.864321)
			(xy 124.636243 -229.908358) (xy 124.659369 -229.956379) (xy 124.675079 -230.007309) (xy 124.683022 -230.060013)
			(xy 124.68352 -230.086662) (xy 124.683022 -230.113311) (xy 124.911856 -230.113311) (xy 124.911856 -230.060013)
			(xy 124.919799 -230.007309) (xy 124.935509 -229.956379) (xy 124.958635 -229.908358) (xy 124.988659 -229.864321)
			(xy 125.024911 -229.82525) (xy 125.066582 -229.792019) (xy 125.11274 -229.76537) (xy 125.162354 -229.745898)
			(xy 125.214316 -229.734038) (xy 125.267466 -229.730055) (xy 125.320616 -229.734038) (xy 125.372578 -229.745898)
			(xy 125.422192 -229.76537) (xy 125.46835 -229.792019) (xy 125.510021 -229.82525) (xy 125.546273 -229.864321)
			(xy 125.576297 -229.908358) (xy 125.599423 -229.956379) (xy 125.615133 -230.007309) (xy 125.623076 -230.060013)
			(xy 125.623574 -230.086662) (xy 125.623076 -230.113311) (xy 125.851402 -230.113311) (xy 125.851402 -230.060013)
			(xy 125.859345 -230.007309) (xy 125.875055 -229.956379) (xy 125.898181 -229.908358) (xy 125.928205 -229.864321)
			(xy 125.964457 -229.82525) (xy 126.006128 -229.792019) (xy 126.052286 -229.76537) (xy 126.1019 -229.745898)
			(xy 126.153862 -229.734038) (xy 126.207012 -229.730055) (xy 126.260162 -229.734038) (xy 126.312124 -229.745898)
			(xy 126.361738 -229.76537) (xy 126.407896 -229.792019) (xy 126.449567 -229.82525) (xy 126.485819 -229.864321)
			(xy 126.515843 -229.908358) (xy 126.538969 -229.956379) (xy 126.554679 -230.007309) (xy 126.562622 -230.060013)
			(xy 126.56312 -230.086662) (xy 126.562622 -230.113311) (xy 126.791202 -230.113311) (xy 126.791202 -230.060013)
			(xy 126.799145 -230.007309) (xy 126.814855 -229.956379) (xy 126.837981 -229.908358) (xy 126.868005 -229.864321)
			(xy 126.904257 -229.82525) (xy 126.945928 -229.792019) (xy 126.992086 -229.76537) (xy 127.0417 -229.745898)
			(xy 127.093662 -229.734038) (xy 127.146812 -229.730055) (xy 127.199962 -229.734038) (xy 127.251924 -229.745898)
			(xy 127.301538 -229.76537) (xy 127.347696 -229.792019) (xy 127.389367 -229.82525) (xy 127.425619 -229.864321)
			(xy 127.455643 -229.908358) (xy 127.478769 -229.956379) (xy 127.494479 -230.007309) (xy 127.502422 -230.060013)
			(xy 127.50292 -230.086662) (xy 127.502422 -230.113311) (xy 127.731002 -230.113311) (xy 127.731002 -230.060013)
			(xy 127.738945 -230.007309) (xy 127.754655 -229.956379) (xy 127.777781 -229.908358) (xy 127.807805 -229.864321)
			(xy 127.844057 -229.82525) (xy 127.885728 -229.792019) (xy 127.931886 -229.76537) (xy 127.9815 -229.745898)
			(xy 128.033462 -229.734038) (xy 128.086612 -229.730055) (xy 128.139762 -229.734038) (xy 128.191724 -229.745898)
			(xy 128.241338 -229.76537) (xy 128.287496 -229.792019) (xy 128.329167 -229.82525) (xy 128.365419 -229.864321)
			(xy 128.395443 -229.908358) (xy 128.418569 -229.956379) (xy 128.434279 -230.007309) (xy 128.442222 -230.060013)
			(xy 128.44272 -230.086662) (xy 128.442222 -230.113311) (xy 128.670802 -230.113311) (xy 128.670802 -230.060013)
			(xy 128.678745 -230.007309) (xy 128.694455 -229.956379) (xy 128.717581 -229.908358) (xy 128.747605 -229.864321)
			(xy 128.783857 -229.82525) (xy 128.825528 -229.792019) (xy 128.871686 -229.76537) (xy 128.9213 -229.745898)
			(xy 128.973262 -229.734038) (xy 129.026412 -229.730055) (xy 129.079562 -229.734038) (xy 129.131524 -229.745898)
			(xy 129.181138 -229.76537) (xy 129.227296 -229.792019) (xy 129.268967 -229.82525) (xy 129.305219 -229.864321)
			(xy 129.335243 -229.908358) (xy 129.358369 -229.956379) (xy 129.374079 -230.007309) (xy 129.382022 -230.060013)
			(xy 129.38252 -230.086662) (xy 129.382022 -230.113311) (xy 129.610602 -230.113311) (xy 129.610602 -230.060013)
			(xy 129.618545 -230.007309) (xy 129.634255 -229.956379) (xy 129.657381 -229.908358) (xy 129.687405 -229.864321)
			(xy 129.723657 -229.82525) (xy 129.765328 -229.792019) (xy 129.811486 -229.76537) (xy 129.8611 -229.745898)
			(xy 129.913062 -229.734038) (xy 129.966212 -229.730055) (xy 130.019362 -229.734038) (xy 130.071324 -229.745898)
			(xy 130.120938 -229.76537) (xy 130.167096 -229.792019) (xy 130.208767 -229.82525) (xy 130.245019 -229.864321)
			(xy 130.275043 -229.908358) (xy 130.298169 -229.956379) (xy 130.313879 -230.007309) (xy 130.321822 -230.060013)
			(xy 130.32232 -230.086662) (xy 130.321822 -230.113311) (xy 130.550402 -230.113311) (xy 130.550402 -230.060013)
			(xy 130.558345 -230.007309) (xy 130.574055 -229.956379) (xy 130.597181 -229.908358) (xy 130.627205 -229.864321)
			(xy 130.663457 -229.82525) (xy 130.705128 -229.792019) (xy 130.751286 -229.76537) (xy 130.8009 -229.745898)
			(xy 130.852862 -229.734038) (xy 130.906012 -229.730055) (xy 130.959162 -229.734038) (xy 131.011124 -229.745898)
			(xy 131.060738 -229.76537) (xy 131.106896 -229.792019) (xy 131.148567 -229.82525) (xy 131.184819 -229.864321)
			(xy 131.214843 -229.908358) (xy 131.237969 -229.956379) (xy 131.253679 -230.007309) (xy 131.261622 -230.060013)
			(xy 131.26212 -230.086662) (xy 131.261622 -230.113311) (xy 131.490456 -230.113311) (xy 131.490456 -230.060013)
			(xy 131.498399 -230.007309) (xy 131.514109 -229.956379) (xy 131.537235 -229.908358) (xy 131.567259 -229.864321)
			(xy 131.603511 -229.82525) (xy 131.645182 -229.792019) (xy 131.69134 -229.76537) (xy 131.740954 -229.745898)
			(xy 131.792916 -229.734038) (xy 131.846066 -229.730055) (xy 131.899216 -229.734038) (xy 131.951178 -229.745898)
			(xy 132.000792 -229.76537) (xy 132.04695 -229.792019) (xy 132.088621 -229.82525) (xy 132.124873 -229.864321)
			(xy 132.154897 -229.908358) (xy 132.178023 -229.956379) (xy 132.193733 -230.007309) (xy 132.201676 -230.060013)
			(xy 132.202174 -230.086662) (xy 132.201676 -230.113311) (xy 132.430002 -230.113311) (xy 132.430002 -230.060013)
			(xy 132.437945 -230.007309) (xy 132.453655 -229.956379) (xy 132.476781 -229.908358) (xy 132.506805 -229.864321)
			(xy 132.543057 -229.82525) (xy 132.584728 -229.792019) (xy 132.630886 -229.76537) (xy 132.6805 -229.745898)
			(xy 132.732462 -229.734038) (xy 132.785612 -229.730055) (xy 132.838762 -229.734038) (xy 132.890724 -229.745898)
			(xy 132.940338 -229.76537) (xy 132.986496 -229.792019) (xy 133.028167 -229.82525) (xy 133.064419 -229.864321)
			(xy 133.094443 -229.908358) (xy 133.117569 -229.956379) (xy 133.133279 -230.007309) (xy 133.141222 -230.060013)
			(xy 133.14172 -230.086662) (xy 133.141222 -230.113311) (xy 133.370056 -230.113311) (xy 133.370056 -230.060013)
			(xy 133.377999 -230.007309) (xy 133.393709 -229.956379) (xy 133.416835 -229.908358) (xy 133.446859 -229.864321)
			(xy 133.483111 -229.82525) (xy 133.524782 -229.792019) (xy 133.57094 -229.76537) (xy 133.620554 -229.745898)
			(xy 133.672516 -229.734038) (xy 133.725666 -229.730055) (xy 133.778816 -229.734038) (xy 133.830778 -229.745898)
			(xy 133.880392 -229.76537) (xy 133.92655 -229.792019) (xy 133.968221 -229.82525) (xy 134.004473 -229.864321)
			(xy 134.034497 -229.908358) (xy 134.057623 -229.956379) (xy 134.073333 -230.007309) (xy 134.081276 -230.060013)
			(xy 134.081774 -230.086662) (xy 134.081276 -230.113311) (xy 134.309856 -230.113311) (xy 134.309856 -230.060013)
			(xy 134.317799 -230.007309) (xy 134.333509 -229.956379) (xy 134.356635 -229.908358) (xy 134.386659 -229.864321)
			(xy 134.422911 -229.82525) (xy 134.464582 -229.792019) (xy 134.51074 -229.76537) (xy 134.560354 -229.745898)
			(xy 134.612316 -229.734038) (xy 134.665466 -229.730055) (xy 134.718616 -229.734038) (xy 134.770578 -229.745898)
			(xy 134.820192 -229.76537) (xy 134.86635 -229.792019) (xy 134.908021 -229.82525) (xy 134.944273 -229.864321)
			(xy 134.974297 -229.908358) (xy 134.997423 -229.956379) (xy 135.013133 -230.007309) (xy 135.021076 -230.060013)
			(xy 135.021574 -230.086662) (xy 135.021076 -230.113311) (xy 135.013133 -230.166015) (xy 134.997423 -230.216945)
			(xy 134.974297 -230.264966) (xy 134.944273 -230.309003) (xy 134.908021 -230.348074) (xy 134.86635 -230.381305)
			(xy 134.820192 -230.407954) (xy 134.770578 -230.427426) (xy 134.718616 -230.439286) (xy 134.665466 -230.44327)
			(xy 134.612316 -230.439286) (xy 134.560354 -230.427426) (xy 134.51074 -230.407954) (xy 134.464582 -230.381305)
			(xy 134.422911 -230.348074) (xy 134.386659 -230.309003) (xy 134.356635 -230.264966) (xy 134.333509 -230.216945)
			(xy 134.317799 -230.166015) (xy 134.309856 -230.113311) (xy 134.081276 -230.113311) (xy 134.073333 -230.166015)
			(xy 134.057623 -230.216945) (xy 134.034497 -230.264966) (xy 134.004473 -230.309003) (xy 133.968221 -230.348074)
			(xy 133.92655 -230.381305) (xy 133.880392 -230.407954) (xy 133.830778 -230.427426) (xy 133.778816 -230.439286)
			(xy 133.725666 -230.44327) (xy 133.672516 -230.439286) (xy 133.620554 -230.427426) (xy 133.57094 -230.407954)
			(xy 133.524782 -230.381305) (xy 133.483111 -230.348074) (xy 133.446859 -230.309003) (xy 133.416835 -230.264966)
			(xy 133.393709 -230.216945) (xy 133.377999 -230.166015) (xy 133.370056 -230.113311) (xy 133.141222 -230.113311)
			(xy 133.133279 -230.166015) (xy 133.117569 -230.216945) (xy 133.094443 -230.264966) (xy 133.064419 -230.309003)
			(xy 133.028167 -230.348074) (xy 132.986496 -230.381305) (xy 132.940338 -230.407954) (xy 132.890724 -230.427426)
			(xy 132.838762 -230.439286) (xy 132.785612 -230.44327) (xy 132.732462 -230.439286) (xy 132.6805 -230.427426)
			(xy 132.630886 -230.407954) (xy 132.584728 -230.381305) (xy 132.543057 -230.348074) (xy 132.506805 -230.309003)
			(xy 132.476781 -230.264966) (xy 132.453655 -230.216945) (xy 132.437945 -230.166015) (xy 132.430002 -230.113311)
			(xy 132.201676 -230.113311) (xy 132.193733 -230.166015) (xy 132.178023 -230.216945) (xy 132.154897 -230.264966)
			(xy 132.124873 -230.309003) (xy 132.088621 -230.348074) (xy 132.04695 -230.381305) (xy 132.000792 -230.407954)
			(xy 131.951178 -230.427426) (xy 131.899216 -230.439286) (xy 131.846066 -230.44327) (xy 131.792916 -230.439286)
			(xy 131.740954 -230.427426) (xy 131.69134 -230.407954) (xy 131.645182 -230.381305) (xy 131.603511 -230.348074)
			(xy 131.567259 -230.309003) (xy 131.537235 -230.264966) (xy 131.514109 -230.216945) (xy 131.498399 -230.166015)
			(xy 131.490456 -230.113311) (xy 131.261622 -230.113311) (xy 131.253679 -230.166015) (xy 131.237969 -230.216945)
			(xy 131.214843 -230.264966) (xy 131.184819 -230.309003) (xy 131.148567 -230.348074) (xy 131.106896 -230.381305)
			(xy 131.060738 -230.407954) (xy 131.011124 -230.427426) (xy 130.959162 -230.439286) (xy 130.906012 -230.44327)
			(xy 130.852862 -230.439286) (xy 130.8009 -230.427426) (xy 130.751286 -230.407954) (xy 130.705128 -230.381305)
			(xy 130.663457 -230.348074) (xy 130.627205 -230.309003) (xy 130.597181 -230.264966) (xy 130.574055 -230.216945)
			(xy 130.558345 -230.166015) (xy 130.550402 -230.113311) (xy 130.321822 -230.113311) (xy 130.313879 -230.166015)
			(xy 130.298169 -230.216945) (xy 130.275043 -230.264966) (xy 130.245019 -230.309003) (xy 130.208767 -230.348074)
			(xy 130.167096 -230.381305) (xy 130.120938 -230.407954) (xy 130.071324 -230.427426) (xy 130.019362 -230.439286)
			(xy 129.966212 -230.44327) (xy 129.913062 -230.439286) (xy 129.8611 -230.427426) (xy 129.811486 -230.407954)
			(xy 129.765328 -230.381305) (xy 129.723657 -230.348074) (xy 129.687405 -230.309003) (xy 129.657381 -230.264966)
			(xy 129.634255 -230.216945) (xy 129.618545 -230.166015) (xy 129.610602 -230.113311) (xy 129.382022 -230.113311)
			(xy 129.374079 -230.166015) (xy 129.358369 -230.216945) (xy 129.335243 -230.264966) (xy 129.305219 -230.309003)
			(xy 129.268967 -230.348074) (xy 129.227296 -230.381305) (xy 129.181138 -230.407954) (xy 129.131524 -230.427426)
			(xy 129.079562 -230.439286) (xy 129.026412 -230.44327) (xy 128.973262 -230.439286) (xy 128.9213 -230.427426)
			(xy 128.871686 -230.407954) (xy 128.825528 -230.381305) (xy 128.783857 -230.348074) (xy 128.747605 -230.309003)
			(xy 128.717581 -230.264966) (xy 128.694455 -230.216945) (xy 128.678745 -230.166015) (xy 128.670802 -230.113311)
			(xy 128.442222 -230.113311) (xy 128.434279 -230.166015) (xy 128.418569 -230.216945) (xy 128.395443 -230.264966)
			(xy 128.365419 -230.309003) (xy 128.329167 -230.348074) (xy 128.287496 -230.381305) (xy 128.241338 -230.407954)
			(xy 128.191724 -230.427426) (xy 128.139762 -230.439286) (xy 128.086612 -230.44327) (xy 128.033462 -230.439286)
			(xy 127.9815 -230.427426) (xy 127.931886 -230.407954) (xy 127.885728 -230.381305) (xy 127.844057 -230.348074)
			(xy 127.807805 -230.309003) (xy 127.777781 -230.264966) (xy 127.754655 -230.216945) (xy 127.738945 -230.166015)
			(xy 127.731002 -230.113311) (xy 127.502422 -230.113311) (xy 127.494479 -230.166015) (xy 127.478769 -230.216945)
			(xy 127.455643 -230.264966) (xy 127.425619 -230.309003) (xy 127.389367 -230.348074) (xy 127.347696 -230.381305)
			(xy 127.301538 -230.407954) (xy 127.251924 -230.427426) (xy 127.199962 -230.439286) (xy 127.146812 -230.44327)
			(xy 127.093662 -230.439286) (xy 127.0417 -230.427426) (xy 126.992086 -230.407954) (xy 126.945928 -230.381305)
			(xy 126.904257 -230.348074) (xy 126.868005 -230.309003) (xy 126.837981 -230.264966) (xy 126.814855 -230.216945)
			(xy 126.799145 -230.166015) (xy 126.791202 -230.113311) (xy 126.562622 -230.113311) (xy 126.554679 -230.166015)
			(xy 126.538969 -230.216945) (xy 126.515843 -230.264966) (xy 126.485819 -230.309003) (xy 126.449567 -230.348074)
			(xy 126.407896 -230.381305) (xy 126.361738 -230.407954) (xy 126.312124 -230.427426) (xy 126.260162 -230.439286)
			(xy 126.207012 -230.44327) (xy 126.153862 -230.439286) (xy 126.1019 -230.427426) (xy 126.052286 -230.407954)
			(xy 126.006128 -230.381305) (xy 125.964457 -230.348074) (xy 125.928205 -230.309003) (xy 125.898181 -230.264966)
			(xy 125.875055 -230.216945) (xy 125.859345 -230.166015) (xy 125.851402 -230.113311) (xy 125.623076 -230.113311)
			(xy 125.615133 -230.166015) (xy 125.599423 -230.216945) (xy 125.576297 -230.264966) (xy 125.546273 -230.309003)
			(xy 125.510021 -230.348074) (xy 125.46835 -230.381305) (xy 125.422192 -230.407954) (xy 125.372578 -230.427426)
			(xy 125.320616 -230.439286) (xy 125.267466 -230.44327) (xy 125.214316 -230.439286) (xy 125.162354 -230.427426)
			(xy 125.11274 -230.407954) (xy 125.066582 -230.381305) (xy 125.024911 -230.348074) (xy 124.988659 -230.309003)
			(xy 124.958635 -230.264966) (xy 124.935509 -230.216945) (xy 124.919799 -230.166015) (xy 124.911856 -230.113311)
			(xy 124.683022 -230.113311) (xy 124.675079 -230.166015) (xy 124.659369 -230.216945) (xy 124.636243 -230.264966)
			(xy 124.606219 -230.309003) (xy 124.569967 -230.348074) (xy 124.528296 -230.381305) (xy 124.482138 -230.407954)
			(xy 124.432524 -230.427426) (xy 124.380562 -230.439286) (xy 124.327412 -230.44327) (xy 124.274262 -230.439286)
			(xy 124.2223 -230.427426) (xy 124.172686 -230.407954) (xy 124.126528 -230.381305) (xy 124.084857 -230.348074)
			(xy 124.048605 -230.309003) (xy 124.018581 -230.264966) (xy 123.995455 -230.216945) (xy 123.979745 -230.166015)
			(xy 123.971802 -230.113311) (xy 123.743222 -230.113311) (xy 123.735279 -230.166015) (xy 123.719569 -230.216945)
			(xy 123.696443 -230.264966) (xy 123.666419 -230.309003) (xy 123.630167 -230.348074) (xy 123.588496 -230.381305)
			(xy 123.542338 -230.407954) (xy 123.492724 -230.427426) (xy 123.440762 -230.439286) (xy 123.387612 -230.44327)
			(xy 123.334462 -230.439286) (xy 123.2825 -230.427426) (xy 123.232886 -230.407954) (xy 123.186728 -230.381305)
			(xy 123.145057 -230.348074) (xy 123.108805 -230.309003) (xy 123.078781 -230.264966) (xy 123.055655 -230.216945)
			(xy 123.039945 -230.166015) (xy 123.032002 -230.113311) (xy 122.803422 -230.113311) (xy 122.795479 -230.166015)
			(xy 122.779769 -230.216945) (xy 122.756643 -230.264966) (xy 122.726619 -230.309003) (xy 122.690367 -230.348074)
			(xy 122.648696 -230.381305) (xy 122.602538 -230.407954) (xy 122.552924 -230.427426) (xy 122.500962 -230.439286)
			(xy 122.447812 -230.44327) (xy 122.394662 -230.439286) (xy 122.3427 -230.427426) (xy 122.293086 -230.407954)
			(xy 122.246928 -230.381305) (xy 122.205257 -230.348074) (xy 122.169005 -230.309003) (xy 122.138981 -230.264966)
			(xy 122.115855 -230.216945) (xy 122.100145 -230.166015) (xy 122.092202 -230.113311) (xy 121.863622 -230.113311)
			(xy 121.855679 -230.166015) (xy 121.839969 -230.216945) (xy 121.816843 -230.264966) (xy 121.786819 -230.309003)
			(xy 121.750567 -230.348074) (xy 121.708896 -230.381305) (xy 121.662738 -230.407954) (xy 121.613124 -230.427426)
			(xy 121.561162 -230.439286) (xy 121.508012 -230.44327) (xy 121.454862 -230.439286) (xy 121.4029 -230.427426)
			(xy 121.353286 -230.407954) (xy 121.307128 -230.381305) (xy 121.265457 -230.348074) (xy 121.229205 -230.309003)
			(xy 121.199181 -230.264966) (xy 121.176055 -230.216945) (xy 121.160345 -230.166015) (xy 121.152402 -230.113311)
			(xy 120.923822 -230.113311) (xy 120.915879 -230.166015) (xy 120.900169 -230.216945) (xy 120.877043 -230.264966)
			(xy 120.847019 -230.309003) (xy 120.810767 -230.348074) (xy 120.769096 -230.381305) (xy 120.722938 -230.407954)
			(xy 120.673324 -230.427426) (xy 120.621362 -230.439286) (xy 120.568212 -230.44327) (xy 120.515062 -230.439286)
			(xy 120.4631 -230.427426) (xy 120.413486 -230.407954) (xy 120.367328 -230.381305) (xy 120.325657 -230.348074)
			(xy 120.289405 -230.309003) (xy 120.259381 -230.264966) (xy 120.236255 -230.216945) (xy 120.220545 -230.166015)
			(xy 120.212602 -230.113311) (xy 119.984022 -230.113311) (xy 119.976079 -230.166015) (xy 119.960369 -230.216945)
			(xy 119.937243 -230.264966) (xy 119.907219 -230.309003) (xy 119.870967 -230.348074) (xy 119.829296 -230.381305)
			(xy 119.783138 -230.407954) (xy 119.733524 -230.427426) (xy 119.681562 -230.439286) (xy 119.628412 -230.44327)
			(xy 119.575262 -230.439286) (xy 119.5233 -230.427426) (xy 119.473686 -230.407954) (xy 119.427528 -230.381305)
			(xy 119.385857 -230.348074) (xy 119.349605 -230.309003) (xy 119.319581 -230.264966) (xy 119.296455 -230.216945)
			(xy 119.280745 -230.166015) (xy 119.272802 -230.113311) (xy 119.044222 -230.113311) (xy 119.036279 -230.166015)
			(xy 119.020569 -230.216945) (xy 118.997443 -230.264966) (xy 118.967419 -230.309003) (xy 118.931167 -230.348074)
			(xy 118.889496 -230.381305) (xy 118.843338 -230.407954) (xy 118.793724 -230.427426) (xy 118.741762 -230.439286)
			(xy 118.688612 -230.44327) (xy 118.635462 -230.439286) (xy 118.5835 -230.427426) (xy 118.533886 -230.407954)
			(xy 118.487728 -230.381305) (xy 118.446057 -230.348074) (xy 118.409805 -230.309003) (xy 118.379781 -230.264966)
			(xy 118.356655 -230.216945) (xy 118.340945 -230.166015) (xy 118.333002 -230.113311) (xy 118.104422 -230.113311)
			(xy 118.096479 -230.166015) (xy 118.080769 -230.216945) (xy 118.057643 -230.264966) (xy 118.027619 -230.309003)
			(xy 117.991367 -230.348074) (xy 117.949696 -230.381305) (xy 117.903538 -230.407954) (xy 117.853924 -230.427426)
			(xy 117.801962 -230.439286) (xy 117.748812 -230.44327) (xy 117.695662 -230.439286) (xy 117.6437 -230.427426)
			(xy 117.594086 -230.407954) (xy 117.547928 -230.381305) (xy 117.506257 -230.348074) (xy 117.470005 -230.309003)
			(xy 117.439981 -230.264966) (xy 117.416855 -230.216945) (xy 117.401145 -230.166015) (xy 117.393202 -230.113311)
			(xy 117.164622 -230.113311) (xy 117.156679 -230.166015) (xy 117.140969 -230.216945) (xy 117.117843 -230.264966)
			(xy 117.087819 -230.309003) (xy 117.051567 -230.348074) (xy 117.009896 -230.381305) (xy 116.963738 -230.407954)
			(xy 116.914124 -230.427426) (xy 116.862162 -230.439286) (xy 116.809012 -230.44327) (xy 116.755862 -230.439286)
			(xy 116.7039 -230.427426) (xy 116.654286 -230.407954) (xy 116.608128 -230.381305) (xy 116.566457 -230.348074)
			(xy 116.530205 -230.309003) (xy 116.500181 -230.264966) (xy 116.477055 -230.216945) (xy 116.461345 -230.166015)
			(xy 116.453402 -230.113311) (xy 116.224822 -230.113311) (xy 116.216879 -230.166015) (xy 116.201169 -230.216945)
			(xy 116.178043 -230.264966) (xy 116.148019 -230.309003) (xy 116.111767 -230.348074) (xy 116.070096 -230.381305)
			(xy 116.023938 -230.407954) (xy 115.974324 -230.427426) (xy 115.922362 -230.439286) (xy 115.869212 -230.44327)
			(xy 115.816062 -230.439286) (xy 115.7641 -230.427426) (xy 115.714486 -230.407954) (xy 115.668328 -230.381305)
			(xy 115.626657 -230.348074) (xy 115.590405 -230.309003) (xy 115.560381 -230.264966) (xy 115.537255 -230.216945)
			(xy 115.521545 -230.166015) (xy 115.513602 -230.113311) (xy 115.285276 -230.113311) (xy 115.277333 -230.166015)
			(xy 115.261623 -230.216945) (xy 115.238497 -230.264966) (xy 115.208473 -230.309003) (xy 115.172221 -230.348074)
			(xy 115.13055 -230.381305) (xy 115.084392 -230.407954) (xy 115.034778 -230.427426) (xy 114.982816 -230.439286)
			(xy 114.929666 -230.44327) (xy 114.876516 -230.439286) (xy 114.824554 -230.427426) (xy 114.77494 -230.407954)
			(xy 114.728782 -230.381305) (xy 114.687111 -230.348074) (xy 114.650859 -230.309003) (xy 114.620835 -230.264966)
			(xy 114.597709 -230.216945) (xy 114.581999 -230.166015) (xy 114.574056 -230.113311) (xy 114.345476 -230.113311)
			(xy 114.337533 -230.166015) (xy 114.321823 -230.216945) (xy 114.298697 -230.264966) (xy 114.268673 -230.309003)
			(xy 114.232421 -230.348074) (xy 114.19075 -230.381305) (xy 114.144592 -230.407954) (xy 114.094978 -230.427426)
			(xy 114.043016 -230.439286) (xy 113.989866 -230.44327) (xy 113.936716 -230.439286) (xy 113.884754 -230.427426)
			(xy 113.83514 -230.407954) (xy 113.788982 -230.381305) (xy 113.747311 -230.348074) (xy 113.711059 -230.309003)
			(xy 113.681035 -230.264966) (xy 113.657909 -230.216945) (xy 113.642199 -230.166015) (xy 113.634256 -230.113311)
			(xy 113.405676 -230.113311) (xy 113.397733 -230.166015) (xy 113.382023 -230.216945) (xy 113.358897 -230.264966)
			(xy 113.328873 -230.309003) (xy 113.292621 -230.348074) (xy 113.25095 -230.381305) (xy 113.204792 -230.407954)
			(xy 113.155178 -230.427426) (xy 113.103216 -230.439286) (xy 113.050066 -230.44327) (xy 112.996916 -230.439286)
			(xy 112.944954 -230.427426) (xy 112.89534 -230.407954) (xy 112.849182 -230.381305) (xy 112.807511 -230.348074)
			(xy 112.771259 -230.309003) (xy 112.741235 -230.264966) (xy 112.718109 -230.216945) (xy 112.702399 -230.166015)
			(xy 112.694456 -230.113311) (xy 112.464976 -230.113311) (xy 112.462986 -230.139862) (xy 112.451122 -230.191837)
			(xy 112.431644 -230.241462) (xy 112.404987 -230.28763) (xy 112.371747 -230.329309) (xy 112.332665 -230.365568)
			(xy 112.288615 -230.395597) (xy 112.240582 -230.418724) (xy 112.189638 -230.434434) (xy 112.136922 -230.442375)
			(xy 112.110266 -230.44277) (xy 112.086876 -230.442386) (xy 112.040498 -230.436276) (xy 112.01781 -230.430578)
			(xy 112.004837 -230.427497) (xy 111.97818 -230.427468) (xy 111.952425 -230.434341) (xy 111.929327 -230.447647)
			(xy 111.910461 -230.466478) (xy 111.897113 -230.489552) (xy 111.890192 -230.515294) (xy 111.889794 -230.528622)
			(xy 111.889794 -230.646224) (xy 111.909623 -230.666462) (xy 111.943257 -230.712053) (xy 111.969255 -230.762391)
			(xy 111.98696 -230.816209) (xy 111.995927 -230.87215) (xy 111.996474 -230.900478) (xy 111.995976 -230.926872)
			(xy 111.995938 -230.927127) (xy 112.224556 -230.927127) (xy 112.224556 -230.873829) (xy 112.232499 -230.821125)
			(xy 112.248209 -230.770195) (xy 112.271335 -230.722174) (xy 112.301359 -230.678137) (xy 112.337611 -230.639066)
			(xy 112.379282 -230.605835) (xy 112.42544 -230.579186) (xy 112.475054 -230.559714) (xy 112.527016 -230.547854)
			(xy 112.580166 -230.543871) (xy 112.633316 -230.547854) (xy 112.685278 -230.559714) (xy 112.734892 -230.579186)
			(xy 112.78105 -230.605835) (xy 112.822721 -230.639066) (xy 112.858973 -230.678137) (xy 112.888997 -230.722174)
			(xy 112.912123 -230.770195) (xy 112.927833 -230.821125) (xy 112.935776 -230.873829) (xy 112.936274 -230.900478)
			(xy 112.935776 -230.927127) (xy 113.164356 -230.927127) (xy 113.164356 -230.873829) (xy 113.172299 -230.821125)
			(xy 113.188009 -230.770195) (xy 113.211135 -230.722174) (xy 113.241159 -230.678137) (xy 113.277411 -230.639066)
			(xy 113.319082 -230.605835) (xy 113.36524 -230.579186) (xy 113.414854 -230.559714) (xy 113.466816 -230.547854)
			(xy 113.519966 -230.543871) (xy 113.573116 -230.547854) (xy 113.625078 -230.559714) (xy 113.674692 -230.579186)
			(xy 113.72085 -230.605835) (xy 113.762521 -230.639066) (xy 113.798773 -230.678137) (xy 113.828797 -230.722174)
			(xy 113.851923 -230.770195) (xy 113.867633 -230.821125) (xy 113.875576 -230.873829) (xy 113.876074 -230.900478)
			(xy 113.875576 -230.927127) (xy 114.10441 -230.927127) (xy 114.10441 -230.873829) (xy 114.112353 -230.821125)
			(xy 114.128063 -230.770195) (xy 114.151189 -230.722174) (xy 114.181213 -230.678137) (xy 114.217465 -230.639066)
			(xy 114.259136 -230.605835) (xy 114.305294 -230.579186) (xy 114.354908 -230.559714) (xy 114.40687 -230.547854)
			(xy 114.46002 -230.543871) (xy 114.51317 -230.547854) (xy 114.565132 -230.559714) (xy 114.614746 -230.579186)
			(xy 114.660904 -230.605835) (xy 114.702575 -230.639066) (xy 114.738827 -230.678137) (xy 114.768851 -230.722174)
			(xy 114.791977 -230.770195) (xy 114.807687 -230.821125) (xy 114.81563 -230.873829) (xy 114.816128 -230.900478)
			(xy 114.81563 -230.927127) (xy 115.043956 -230.927127) (xy 115.043956 -230.873829) (xy 115.051899 -230.821125)
			(xy 115.067609 -230.770195) (xy 115.090735 -230.722174) (xy 115.120759 -230.678137) (xy 115.157011 -230.639066)
			(xy 115.198682 -230.605835) (xy 115.24484 -230.579186) (xy 115.294454 -230.559714) (xy 115.346416 -230.547854)
			(xy 115.399566 -230.543871) (xy 115.452716 -230.547854) (xy 115.504678 -230.559714) (xy 115.554292 -230.579186)
			(xy 115.60045 -230.605835) (xy 115.642121 -230.639066) (xy 115.678373 -230.678137) (xy 115.708397 -230.722174)
			(xy 115.731523 -230.770195) (xy 115.747233 -230.821125) (xy 115.755176 -230.873829) (xy 115.755674 -230.900478)
			(xy 115.755176 -230.927127) (xy 115.983756 -230.927127) (xy 115.983756 -230.873829) (xy 115.991699 -230.821125)
			(xy 116.007409 -230.770195) (xy 116.030535 -230.722174) (xy 116.060559 -230.678137) (xy 116.096811 -230.639066)
			(xy 116.138482 -230.605835) (xy 116.18464 -230.579186) (xy 116.234254 -230.559714) (xy 116.286216 -230.547854)
			(xy 116.339366 -230.543871) (xy 116.392516 -230.547854) (xy 116.444478 -230.559714) (xy 116.494092 -230.579186)
			(xy 116.54025 -230.605835) (xy 116.581921 -230.639066) (xy 116.618173 -230.678137) (xy 116.648197 -230.722174)
			(xy 116.671323 -230.770195) (xy 116.687033 -230.821125) (xy 116.694976 -230.873829) (xy 116.695474 -230.900478)
			(xy 116.694976 -230.927127) (xy 116.923556 -230.927127) (xy 116.923556 -230.873829) (xy 116.931499 -230.821125)
			(xy 116.947209 -230.770195) (xy 116.970335 -230.722174) (xy 117.000359 -230.678137) (xy 117.036611 -230.639066)
			(xy 117.078282 -230.605835) (xy 117.12444 -230.579186) (xy 117.174054 -230.559714) (xy 117.226016 -230.547854)
			(xy 117.279166 -230.543871) (xy 117.332316 -230.547854) (xy 117.384278 -230.559714) (xy 117.433892 -230.579186)
			(xy 117.48005 -230.605835) (xy 117.521721 -230.639066) (xy 117.557973 -230.678137) (xy 117.587997 -230.722174)
			(xy 117.611123 -230.770195) (xy 117.626833 -230.821125) (xy 117.634776 -230.873829) (xy 117.635274 -230.900478)
			(xy 117.634776 -230.927127) (xy 117.863356 -230.927127) (xy 117.863356 -230.873829) (xy 117.871299 -230.821125)
			(xy 117.887009 -230.770195) (xy 117.910135 -230.722174) (xy 117.940159 -230.678137) (xy 117.976411 -230.639066)
			(xy 118.018082 -230.605835) (xy 118.06424 -230.579186) (xy 118.113854 -230.559714) (xy 118.165816 -230.547854)
			(xy 118.218966 -230.543871) (xy 118.272116 -230.547854) (xy 118.324078 -230.559714) (xy 118.373692 -230.579186)
			(xy 118.41985 -230.605835) (xy 118.461521 -230.639066) (xy 118.497773 -230.678137) (xy 118.527797 -230.722174)
			(xy 118.550923 -230.770195) (xy 118.566633 -230.821125) (xy 118.574576 -230.873829) (xy 118.575074 -230.900478)
			(xy 118.574576 -230.927127) (xy 118.803156 -230.927127) (xy 118.803156 -230.873829) (xy 118.811099 -230.821125)
			(xy 118.826809 -230.770195) (xy 118.849935 -230.722174) (xy 118.879959 -230.678137) (xy 118.916211 -230.639066)
			(xy 118.957882 -230.605835) (xy 119.00404 -230.579186) (xy 119.053654 -230.559714) (xy 119.105616 -230.547854)
			(xy 119.158766 -230.543871) (xy 119.211916 -230.547854) (xy 119.263878 -230.559714) (xy 119.313492 -230.579186)
			(xy 119.35965 -230.605835) (xy 119.401321 -230.639066) (xy 119.437573 -230.678137) (xy 119.467597 -230.722174)
			(xy 119.490723 -230.770195) (xy 119.506433 -230.821125) (xy 119.514376 -230.873829) (xy 119.514874 -230.900478)
			(xy 119.514376 -230.927127) (xy 119.742956 -230.927127) (xy 119.742956 -230.873829) (xy 119.750899 -230.821125)
			(xy 119.766609 -230.770195) (xy 119.789735 -230.722174) (xy 119.819759 -230.678137) (xy 119.856011 -230.639066)
			(xy 119.897682 -230.605835) (xy 119.94384 -230.579186) (xy 119.993454 -230.559714) (xy 120.045416 -230.547854)
			(xy 120.098566 -230.543871) (xy 120.151716 -230.547854) (xy 120.203678 -230.559714) (xy 120.253292 -230.579186)
			(xy 120.29945 -230.605835) (xy 120.341121 -230.639066) (xy 120.377373 -230.678137) (xy 120.407397 -230.722174)
			(xy 120.430523 -230.770195) (xy 120.446233 -230.821125) (xy 120.454176 -230.873829) (xy 120.454674 -230.900478)
			(xy 120.454176 -230.927127) (xy 120.682756 -230.927127) (xy 120.682756 -230.873829) (xy 120.690699 -230.821125)
			(xy 120.706409 -230.770195) (xy 120.729535 -230.722174) (xy 120.759559 -230.678137) (xy 120.795811 -230.639066)
			(xy 120.837482 -230.605835) (xy 120.88364 -230.579186) (xy 120.933254 -230.559714) (xy 120.985216 -230.547854)
			(xy 121.038366 -230.543871) (xy 121.091516 -230.547854) (xy 121.143478 -230.559714) (xy 121.193092 -230.579186)
			(xy 121.23925 -230.605835) (xy 121.280921 -230.639066) (xy 121.317173 -230.678137) (xy 121.347197 -230.722174)
			(xy 121.370323 -230.770195) (xy 121.386033 -230.821125) (xy 121.393976 -230.873829) (xy 121.394474 -230.900478)
			(xy 121.393976 -230.927127) (xy 121.622302 -230.927127) (xy 121.622302 -230.873829) (xy 121.630245 -230.821125)
			(xy 121.645955 -230.770195) (xy 121.669081 -230.722174) (xy 121.699105 -230.678137) (xy 121.735357 -230.639066)
			(xy 121.777028 -230.605835) (xy 121.823186 -230.579186) (xy 121.8728 -230.559714) (xy 121.924762 -230.547854)
			(xy 121.977912 -230.543871) (xy 122.031062 -230.547854) (xy 122.083024 -230.559714) (xy 122.132638 -230.579186)
			(xy 122.178796 -230.605835) (xy 122.220467 -230.639066) (xy 122.256719 -230.678137) (xy 122.286743 -230.722174)
			(xy 122.309869 -230.770195) (xy 122.325579 -230.821125) (xy 122.333522 -230.873829) (xy 122.33402 -230.900478)
			(xy 122.333522 -230.927127) (xy 122.562356 -230.927127) (xy 122.562356 -230.873829) (xy 122.570299 -230.821125)
			(xy 122.586009 -230.770195) (xy 122.609135 -230.722174) (xy 122.639159 -230.678137) (xy 122.675411 -230.639066)
			(xy 122.717082 -230.605835) (xy 122.76324 -230.579186) (xy 122.812854 -230.559714) (xy 122.864816 -230.547854)
			(xy 122.917966 -230.543871) (xy 122.971116 -230.547854) (xy 123.023078 -230.559714) (xy 123.072692 -230.579186)
			(xy 123.11885 -230.605835) (xy 123.160521 -230.639066) (xy 123.196773 -230.678137) (xy 123.226797 -230.722174)
			(xy 123.249923 -230.770195) (xy 123.265633 -230.821125) (xy 123.273576 -230.873829) (xy 123.274074 -230.900478)
			(xy 123.273576 -230.927127) (xy 123.502156 -230.927127) (xy 123.502156 -230.873829) (xy 123.510099 -230.821125)
			(xy 123.525809 -230.770195) (xy 123.548935 -230.722174) (xy 123.578959 -230.678137) (xy 123.615211 -230.639066)
			(xy 123.656882 -230.605835) (xy 123.70304 -230.579186) (xy 123.752654 -230.559714) (xy 123.804616 -230.547854)
			(xy 123.857766 -230.543871) (xy 123.910916 -230.547854) (xy 123.962878 -230.559714) (xy 124.012492 -230.579186)
			(xy 124.05865 -230.605835) (xy 124.100321 -230.639066) (xy 124.136573 -230.678137) (xy 124.166597 -230.722174)
			(xy 124.189723 -230.770195) (xy 124.205433 -230.821125) (xy 124.213376 -230.873829) (xy 124.213874 -230.900478)
			(xy 124.213376 -230.927127) (xy 124.441956 -230.927127) (xy 124.441956 -230.873829) (xy 124.449899 -230.821125)
			(xy 124.465609 -230.770195) (xy 124.488735 -230.722174) (xy 124.518759 -230.678137) (xy 124.555011 -230.639066)
			(xy 124.596682 -230.605835) (xy 124.64284 -230.579186) (xy 124.692454 -230.559714) (xy 124.744416 -230.547854)
			(xy 124.797566 -230.543871) (xy 124.850716 -230.547854) (xy 124.902678 -230.559714) (xy 124.952292 -230.579186)
			(xy 124.99845 -230.605835) (xy 125.040121 -230.639066) (xy 125.076373 -230.678137) (xy 125.106397 -230.722174)
			(xy 125.129523 -230.770195) (xy 125.145233 -230.821125) (xy 125.153176 -230.873829) (xy 125.153674 -230.900478)
			(xy 125.153176 -230.927127) (xy 125.381756 -230.927127) (xy 125.381756 -230.873829) (xy 125.389699 -230.821125)
			(xy 125.405409 -230.770195) (xy 125.428535 -230.722174) (xy 125.458559 -230.678137) (xy 125.494811 -230.639066)
			(xy 125.536482 -230.605835) (xy 125.58264 -230.579186) (xy 125.632254 -230.559714) (xy 125.684216 -230.547854)
			(xy 125.737366 -230.543871) (xy 125.790516 -230.547854) (xy 125.842478 -230.559714) (xy 125.892092 -230.579186)
			(xy 125.93825 -230.605835) (xy 125.979921 -230.639066) (xy 126.016173 -230.678137) (xy 126.046197 -230.722174)
			(xy 126.069323 -230.770195) (xy 126.085033 -230.821125) (xy 126.092976 -230.873829) (xy 126.093474 -230.900478)
			(xy 126.092976 -230.927127) (xy 126.321556 -230.927127) (xy 126.321556 -230.873829) (xy 126.329499 -230.821125)
			(xy 126.345209 -230.770195) (xy 126.368335 -230.722174) (xy 126.398359 -230.678137) (xy 126.434611 -230.639066)
			(xy 126.476282 -230.605835) (xy 126.52244 -230.579186) (xy 126.572054 -230.559714) (xy 126.624016 -230.547854)
			(xy 126.677166 -230.543871) (xy 126.730316 -230.547854) (xy 126.782278 -230.559714) (xy 126.831892 -230.579186)
			(xy 126.87805 -230.605835) (xy 126.919721 -230.639066) (xy 126.955973 -230.678137) (xy 126.985997 -230.722174)
			(xy 127.009123 -230.770195) (xy 127.024833 -230.821125) (xy 127.032776 -230.873829) (xy 127.033274 -230.900478)
			(xy 127.032776 -230.927127) (xy 127.261356 -230.927127) (xy 127.261356 -230.873829) (xy 127.269299 -230.821125)
			(xy 127.285009 -230.770195) (xy 127.308135 -230.722174) (xy 127.338159 -230.678137) (xy 127.374411 -230.639066)
			(xy 127.416082 -230.605835) (xy 127.46224 -230.579186) (xy 127.511854 -230.559714) (xy 127.563816 -230.547854)
			(xy 127.616966 -230.543871) (xy 127.670116 -230.547854) (xy 127.722078 -230.559714) (xy 127.771692 -230.579186)
			(xy 127.81785 -230.605835) (xy 127.859521 -230.639066) (xy 127.895773 -230.678137) (xy 127.925797 -230.722174)
			(xy 127.948923 -230.770195) (xy 127.964633 -230.821125) (xy 127.972576 -230.873829) (xy 127.973074 -230.900478)
			(xy 127.972576 -230.927127) (xy 128.201156 -230.927127) (xy 128.201156 -230.873829) (xy 128.209099 -230.821125)
			(xy 128.224809 -230.770195) (xy 128.247935 -230.722174) (xy 128.277959 -230.678137) (xy 128.314211 -230.639066)
			(xy 128.355882 -230.605835) (xy 128.40204 -230.579186) (xy 128.451654 -230.559714) (xy 128.503616 -230.547854)
			(xy 128.556766 -230.543871) (xy 128.609916 -230.547854) (xy 128.661878 -230.559714) (xy 128.711492 -230.579186)
			(xy 128.75765 -230.605835) (xy 128.799321 -230.639066) (xy 128.835573 -230.678137) (xy 128.865597 -230.722174)
			(xy 128.888723 -230.770195) (xy 128.904433 -230.821125) (xy 128.912376 -230.873829) (xy 128.912874 -230.900478)
			(xy 128.912376 -230.927127) (xy 129.140956 -230.927127) (xy 129.140956 -230.873829) (xy 129.148899 -230.821125)
			(xy 129.164609 -230.770195) (xy 129.187735 -230.722174) (xy 129.217759 -230.678137) (xy 129.254011 -230.639066)
			(xy 129.295682 -230.605835) (xy 129.34184 -230.579186) (xy 129.391454 -230.559714) (xy 129.443416 -230.547854)
			(xy 129.496566 -230.543871) (xy 129.549716 -230.547854) (xy 129.601678 -230.559714) (xy 129.651292 -230.579186)
			(xy 129.69745 -230.605835) (xy 129.739121 -230.639066) (xy 129.775373 -230.678137) (xy 129.805397 -230.722174)
			(xy 129.828523 -230.770195) (xy 129.844233 -230.821125) (xy 129.852176 -230.873829) (xy 129.852674 -230.900478)
			(xy 129.852176 -230.927127) (xy 130.080756 -230.927127) (xy 130.080756 -230.873829) (xy 130.088699 -230.821125)
			(xy 130.104409 -230.770195) (xy 130.127535 -230.722174) (xy 130.157559 -230.678137) (xy 130.193811 -230.639066)
			(xy 130.235482 -230.605835) (xy 130.28164 -230.579186) (xy 130.331254 -230.559714) (xy 130.383216 -230.547854)
			(xy 130.436366 -230.543871) (xy 130.489516 -230.547854) (xy 130.541478 -230.559714) (xy 130.591092 -230.579186)
			(xy 130.63725 -230.605835) (xy 130.678921 -230.639066) (xy 130.715173 -230.678137) (xy 130.745197 -230.722174)
			(xy 130.768323 -230.770195) (xy 130.784033 -230.821125) (xy 130.791976 -230.873829) (xy 130.792474 -230.900478)
			(xy 130.791976 -230.927127) (xy 131.020556 -230.927127) (xy 131.020556 -230.873829) (xy 131.028499 -230.821125)
			(xy 131.044209 -230.770195) (xy 131.067335 -230.722174) (xy 131.097359 -230.678137) (xy 131.133611 -230.639066)
			(xy 131.175282 -230.605835) (xy 131.22144 -230.579186) (xy 131.271054 -230.559714) (xy 131.323016 -230.547854)
			(xy 131.376166 -230.543871) (xy 131.429316 -230.547854) (xy 131.481278 -230.559714) (xy 131.530892 -230.579186)
			(xy 131.57705 -230.605835) (xy 131.618721 -230.639066) (xy 131.654973 -230.678137) (xy 131.684997 -230.722174)
			(xy 131.708123 -230.770195) (xy 131.723833 -230.821125) (xy 131.731776 -230.873829) (xy 131.732274 -230.900478)
			(xy 131.731776 -230.927127) (xy 131.960102 -230.927127) (xy 131.960102 -230.873829) (xy 131.968045 -230.821125)
			(xy 131.983755 -230.770195) (xy 132.006881 -230.722174) (xy 132.036905 -230.678137) (xy 132.073157 -230.639066)
			(xy 132.114828 -230.605835) (xy 132.160986 -230.579186) (xy 132.2106 -230.559714) (xy 132.262562 -230.547854)
			(xy 132.315712 -230.543871) (xy 132.368862 -230.547854) (xy 132.420824 -230.559714) (xy 132.470438 -230.579186)
			(xy 132.516596 -230.605835) (xy 132.558267 -230.639066) (xy 132.594519 -230.678137) (xy 132.624543 -230.722174)
			(xy 132.647669 -230.770195) (xy 132.663379 -230.821125) (xy 132.671322 -230.873829) (xy 132.67182 -230.900478)
			(xy 132.671322 -230.927127) (xy 132.900156 -230.927127) (xy 132.900156 -230.873829) (xy 132.908099 -230.821125)
			(xy 132.923809 -230.770195) (xy 132.946935 -230.722174) (xy 132.976959 -230.678137) (xy 133.013211 -230.639066)
			(xy 133.054882 -230.605835) (xy 133.10104 -230.579186) (xy 133.150654 -230.559714) (xy 133.202616 -230.547854)
			(xy 133.255766 -230.543871) (xy 133.308916 -230.547854) (xy 133.360878 -230.559714) (xy 133.410492 -230.579186)
			(xy 133.45665 -230.605835) (xy 133.498321 -230.639066) (xy 133.534573 -230.678137) (xy 133.564597 -230.722174)
			(xy 133.587723 -230.770195) (xy 133.603433 -230.821125) (xy 133.611376 -230.873829) (xy 133.611874 -230.900478)
			(xy 133.611376 -230.927127) (xy 133.839956 -230.927127) (xy 133.839956 -230.873829) (xy 133.847899 -230.821125)
			(xy 133.863609 -230.770195) (xy 133.886735 -230.722174) (xy 133.916759 -230.678137) (xy 133.953011 -230.639066)
			(xy 133.994682 -230.605835) (xy 134.04084 -230.579186) (xy 134.090454 -230.559714) (xy 134.142416 -230.547854)
			(xy 134.195566 -230.543871) (xy 134.248716 -230.547854) (xy 134.300678 -230.559714) (xy 134.350292 -230.579186)
			(xy 134.39645 -230.605835) (xy 134.438121 -230.639066) (xy 134.474373 -230.678137) (xy 134.504397 -230.722174)
			(xy 134.527523 -230.770195) (xy 134.543233 -230.821125) (xy 134.551176 -230.873829) (xy 134.551674 -230.900478)
			(xy 134.551176 -230.927127) (xy 134.543233 -230.979831) (xy 134.527523 -231.030761) (xy 134.504397 -231.078782)
			(xy 134.474373 -231.122819) (xy 134.438121 -231.16189) (xy 134.39645 -231.195121) (xy 134.350292 -231.22177)
			(xy 134.300678 -231.241242) (xy 134.248716 -231.253102) (xy 134.195566 -231.257086) (xy 134.142416 -231.253102)
			(xy 134.090454 -231.241242) (xy 134.04084 -231.22177) (xy 133.994682 -231.195121) (xy 133.953011 -231.16189)
			(xy 133.916759 -231.122819) (xy 133.886735 -231.078782) (xy 133.863609 -231.030761) (xy 133.847899 -230.979831)
			(xy 133.839956 -230.927127) (xy 133.611376 -230.927127) (xy 133.603433 -230.979831) (xy 133.587723 -231.030761)
			(xy 133.564597 -231.078782) (xy 133.534573 -231.122819) (xy 133.498321 -231.16189) (xy 133.45665 -231.195121)
			(xy 133.410492 -231.22177) (xy 133.360878 -231.241242) (xy 133.308916 -231.253102) (xy 133.255766 -231.257086)
			(xy 133.202616 -231.253102) (xy 133.150654 -231.241242) (xy 133.10104 -231.22177) (xy 133.054882 -231.195121)
			(xy 133.013211 -231.16189) (xy 132.976959 -231.122819) (xy 132.946935 -231.078782) (xy 132.923809 -231.030761)
			(xy 132.908099 -230.979831) (xy 132.900156 -230.927127) (xy 132.671322 -230.927127) (xy 132.663379 -230.979831)
			(xy 132.647669 -231.030761) (xy 132.624543 -231.078782) (xy 132.594519 -231.122819) (xy 132.558267 -231.16189)
			(xy 132.516596 -231.195121) (xy 132.470438 -231.22177) (xy 132.420824 -231.241242) (xy 132.368862 -231.253102)
			(xy 132.315712 -231.257086) (xy 132.262562 -231.253102) (xy 132.2106 -231.241242) (xy 132.160986 -231.22177)
			(xy 132.114828 -231.195121) (xy 132.073157 -231.16189) (xy 132.036905 -231.122819) (xy 132.006881 -231.078782)
			(xy 131.983755 -231.030761) (xy 131.968045 -230.979831) (xy 131.960102 -230.927127) (xy 131.731776 -230.927127)
			(xy 131.723833 -230.979831) (xy 131.708123 -231.030761) (xy 131.684997 -231.078782) (xy 131.654973 -231.122819)
			(xy 131.618721 -231.16189) (xy 131.57705 -231.195121) (xy 131.530892 -231.22177) (xy 131.481278 -231.241242)
			(xy 131.429316 -231.253102) (xy 131.376166 -231.257086) (xy 131.323016 -231.253102) (xy 131.271054 -231.241242)
			(xy 131.22144 -231.22177) (xy 131.175282 -231.195121) (xy 131.133611 -231.16189) (xy 131.097359 -231.122819)
			(xy 131.067335 -231.078782) (xy 131.044209 -231.030761) (xy 131.028499 -230.979831) (xy 131.020556 -230.927127)
			(xy 130.791976 -230.927127) (xy 130.784033 -230.979831) (xy 130.768323 -231.030761) (xy 130.745197 -231.078782)
			(xy 130.715173 -231.122819) (xy 130.678921 -231.16189) (xy 130.63725 -231.195121) (xy 130.591092 -231.22177)
			(xy 130.541478 -231.241242) (xy 130.489516 -231.253102) (xy 130.436366 -231.257086) (xy 130.383216 -231.253102)
			(xy 130.331254 -231.241242) (xy 130.28164 -231.22177) (xy 130.235482 -231.195121) (xy 130.193811 -231.16189)
			(xy 130.157559 -231.122819) (xy 130.127535 -231.078782) (xy 130.104409 -231.030761) (xy 130.088699 -230.979831)
			(xy 130.080756 -230.927127) (xy 129.852176 -230.927127) (xy 129.844233 -230.979831) (xy 129.828523 -231.030761)
			(xy 129.805397 -231.078782) (xy 129.775373 -231.122819) (xy 129.739121 -231.16189) (xy 129.69745 -231.195121)
			(xy 129.651292 -231.22177) (xy 129.601678 -231.241242) (xy 129.549716 -231.253102) (xy 129.496566 -231.257086)
			(xy 129.443416 -231.253102) (xy 129.391454 -231.241242) (xy 129.34184 -231.22177) (xy 129.295682 -231.195121)
			(xy 129.254011 -231.16189) (xy 129.217759 -231.122819) (xy 129.187735 -231.078782) (xy 129.164609 -231.030761)
			(xy 129.148899 -230.979831) (xy 129.140956 -230.927127) (xy 128.912376 -230.927127) (xy 128.904433 -230.979831)
			(xy 128.888723 -231.030761) (xy 128.865597 -231.078782) (xy 128.835573 -231.122819) (xy 128.799321 -231.16189)
			(xy 128.75765 -231.195121) (xy 128.711492 -231.22177) (xy 128.661878 -231.241242) (xy 128.609916 -231.253102)
			(xy 128.556766 -231.257086) (xy 128.503616 -231.253102) (xy 128.451654 -231.241242) (xy 128.40204 -231.22177)
			(xy 128.355882 -231.195121) (xy 128.314211 -231.16189) (xy 128.277959 -231.122819) (xy 128.247935 -231.078782)
			(xy 128.224809 -231.030761) (xy 128.209099 -230.979831) (xy 128.201156 -230.927127) (xy 127.972576 -230.927127)
			(xy 127.964633 -230.979831) (xy 127.948923 -231.030761) (xy 127.925797 -231.078782) (xy 127.895773 -231.122819)
			(xy 127.859521 -231.16189) (xy 127.81785 -231.195121) (xy 127.771692 -231.22177) (xy 127.722078 -231.241242)
			(xy 127.670116 -231.253102) (xy 127.616966 -231.257086) (xy 127.563816 -231.253102) (xy 127.511854 -231.241242)
			(xy 127.46224 -231.22177) (xy 127.416082 -231.195121) (xy 127.374411 -231.16189) (xy 127.338159 -231.122819)
			(xy 127.308135 -231.078782) (xy 127.285009 -231.030761) (xy 127.269299 -230.979831) (xy 127.261356 -230.927127)
			(xy 127.032776 -230.927127) (xy 127.024833 -230.979831) (xy 127.009123 -231.030761) (xy 126.985997 -231.078782)
			(xy 126.955973 -231.122819) (xy 126.919721 -231.16189) (xy 126.87805 -231.195121) (xy 126.831892 -231.22177)
			(xy 126.782278 -231.241242) (xy 126.730316 -231.253102) (xy 126.677166 -231.257086) (xy 126.624016 -231.253102)
			(xy 126.572054 -231.241242) (xy 126.52244 -231.22177) (xy 126.476282 -231.195121) (xy 126.434611 -231.16189)
			(xy 126.398359 -231.122819) (xy 126.368335 -231.078782) (xy 126.345209 -231.030761) (xy 126.329499 -230.979831)
			(xy 126.321556 -230.927127) (xy 126.092976 -230.927127) (xy 126.085033 -230.979831) (xy 126.069323 -231.030761)
			(xy 126.046197 -231.078782) (xy 126.016173 -231.122819) (xy 125.979921 -231.16189) (xy 125.93825 -231.195121)
			(xy 125.892092 -231.22177) (xy 125.842478 -231.241242) (xy 125.790516 -231.253102) (xy 125.737366 -231.257086)
			(xy 125.684216 -231.253102) (xy 125.632254 -231.241242) (xy 125.58264 -231.22177) (xy 125.536482 -231.195121)
			(xy 125.494811 -231.16189) (xy 125.458559 -231.122819) (xy 125.428535 -231.078782) (xy 125.405409 -231.030761)
			(xy 125.389699 -230.979831) (xy 125.381756 -230.927127) (xy 125.153176 -230.927127) (xy 125.145233 -230.979831)
			(xy 125.129523 -231.030761) (xy 125.106397 -231.078782) (xy 125.076373 -231.122819) (xy 125.040121 -231.16189)
			(xy 124.99845 -231.195121) (xy 124.952292 -231.22177) (xy 124.902678 -231.241242) (xy 124.850716 -231.253102)
			(xy 124.797566 -231.257086) (xy 124.744416 -231.253102) (xy 124.692454 -231.241242) (xy 124.64284 -231.22177)
			(xy 124.596682 -231.195121) (xy 124.555011 -231.16189) (xy 124.518759 -231.122819) (xy 124.488735 -231.078782)
			(xy 124.465609 -231.030761) (xy 124.449899 -230.979831) (xy 124.441956 -230.927127) (xy 124.213376 -230.927127)
			(xy 124.205433 -230.979831) (xy 124.189723 -231.030761) (xy 124.166597 -231.078782) (xy 124.136573 -231.122819)
			(xy 124.100321 -231.16189) (xy 124.05865 -231.195121) (xy 124.012492 -231.22177) (xy 123.962878 -231.241242)
			(xy 123.910916 -231.253102) (xy 123.857766 -231.257086) (xy 123.804616 -231.253102) (xy 123.752654 -231.241242)
			(xy 123.70304 -231.22177) (xy 123.656882 -231.195121) (xy 123.615211 -231.16189) (xy 123.578959 -231.122819)
			(xy 123.548935 -231.078782) (xy 123.525809 -231.030761) (xy 123.510099 -230.979831) (xy 123.502156 -230.927127)
			(xy 123.273576 -230.927127) (xy 123.265633 -230.979831) (xy 123.249923 -231.030761) (xy 123.226797 -231.078782)
			(xy 123.196773 -231.122819) (xy 123.160521 -231.16189) (xy 123.11885 -231.195121) (xy 123.072692 -231.22177)
			(xy 123.023078 -231.241242) (xy 122.971116 -231.253102) (xy 122.917966 -231.257086) (xy 122.864816 -231.253102)
			(xy 122.812854 -231.241242) (xy 122.76324 -231.22177) (xy 122.717082 -231.195121) (xy 122.675411 -231.16189)
			(xy 122.639159 -231.122819) (xy 122.609135 -231.078782) (xy 122.586009 -231.030761) (xy 122.570299 -230.979831)
			(xy 122.562356 -230.927127) (xy 122.333522 -230.927127) (xy 122.325579 -230.979831) (xy 122.309869 -231.030761)
			(xy 122.286743 -231.078782) (xy 122.256719 -231.122819) (xy 122.220467 -231.16189) (xy 122.178796 -231.195121)
			(xy 122.132638 -231.22177) (xy 122.083024 -231.241242) (xy 122.031062 -231.253102) (xy 121.977912 -231.257086)
			(xy 121.924762 -231.253102) (xy 121.8728 -231.241242) (xy 121.823186 -231.22177) (xy 121.777028 -231.195121)
			(xy 121.735357 -231.16189) (xy 121.699105 -231.122819) (xy 121.669081 -231.078782) (xy 121.645955 -231.030761)
			(xy 121.630245 -230.979831) (xy 121.622302 -230.927127) (xy 121.393976 -230.927127) (xy 121.386033 -230.979831)
			(xy 121.370323 -231.030761) (xy 121.347197 -231.078782) (xy 121.317173 -231.122819) (xy 121.280921 -231.16189)
			(xy 121.23925 -231.195121) (xy 121.193092 -231.22177) (xy 121.143478 -231.241242) (xy 121.091516 -231.253102)
			(xy 121.038366 -231.257086) (xy 120.985216 -231.253102) (xy 120.933254 -231.241242) (xy 120.88364 -231.22177)
			(xy 120.837482 -231.195121) (xy 120.795811 -231.16189) (xy 120.759559 -231.122819) (xy 120.729535 -231.078782)
			(xy 120.706409 -231.030761) (xy 120.690699 -230.979831) (xy 120.682756 -230.927127) (xy 120.454176 -230.927127)
			(xy 120.446233 -230.979831) (xy 120.430523 -231.030761) (xy 120.407397 -231.078782) (xy 120.377373 -231.122819)
			(xy 120.341121 -231.16189) (xy 120.29945 -231.195121) (xy 120.253292 -231.22177) (xy 120.203678 -231.241242)
			(xy 120.151716 -231.253102) (xy 120.098566 -231.257086) (xy 120.045416 -231.253102) (xy 119.993454 -231.241242)
			(xy 119.94384 -231.22177) (xy 119.897682 -231.195121) (xy 119.856011 -231.16189) (xy 119.819759 -231.122819)
			(xy 119.789735 -231.078782) (xy 119.766609 -231.030761) (xy 119.750899 -230.979831) (xy 119.742956 -230.927127)
			(xy 119.514376 -230.927127) (xy 119.506433 -230.979831) (xy 119.490723 -231.030761) (xy 119.467597 -231.078782)
			(xy 119.437573 -231.122819) (xy 119.401321 -231.16189) (xy 119.35965 -231.195121) (xy 119.313492 -231.22177)
			(xy 119.263878 -231.241242) (xy 119.211916 -231.253102) (xy 119.158766 -231.257086) (xy 119.105616 -231.253102)
			(xy 119.053654 -231.241242) (xy 119.00404 -231.22177) (xy 118.957882 -231.195121) (xy 118.916211 -231.16189)
			(xy 118.879959 -231.122819) (xy 118.849935 -231.078782) (xy 118.826809 -231.030761) (xy 118.811099 -230.979831)
			(xy 118.803156 -230.927127) (xy 118.574576 -230.927127) (xy 118.566633 -230.979831) (xy 118.550923 -231.030761)
			(xy 118.527797 -231.078782) (xy 118.497773 -231.122819) (xy 118.461521 -231.16189) (xy 118.41985 -231.195121)
			(xy 118.373692 -231.22177) (xy 118.324078 -231.241242) (xy 118.272116 -231.253102) (xy 118.218966 -231.257086)
			(xy 118.165816 -231.253102) (xy 118.113854 -231.241242) (xy 118.06424 -231.22177) (xy 118.018082 -231.195121)
			(xy 117.976411 -231.16189) (xy 117.940159 -231.122819) (xy 117.910135 -231.078782) (xy 117.887009 -231.030761)
			(xy 117.871299 -230.979831) (xy 117.863356 -230.927127) (xy 117.634776 -230.927127) (xy 117.626833 -230.979831)
			(xy 117.611123 -231.030761) (xy 117.587997 -231.078782) (xy 117.557973 -231.122819) (xy 117.521721 -231.16189)
			(xy 117.48005 -231.195121) (xy 117.433892 -231.22177) (xy 117.384278 -231.241242) (xy 117.332316 -231.253102)
			(xy 117.279166 -231.257086) (xy 117.226016 -231.253102) (xy 117.174054 -231.241242) (xy 117.12444 -231.22177)
			(xy 117.078282 -231.195121) (xy 117.036611 -231.16189) (xy 117.000359 -231.122819) (xy 116.970335 -231.078782)
			(xy 116.947209 -231.030761) (xy 116.931499 -230.979831) (xy 116.923556 -230.927127) (xy 116.694976 -230.927127)
			(xy 116.687033 -230.979831) (xy 116.671323 -231.030761) (xy 116.648197 -231.078782) (xy 116.618173 -231.122819)
			(xy 116.581921 -231.16189) (xy 116.54025 -231.195121) (xy 116.494092 -231.22177) (xy 116.444478 -231.241242)
			(xy 116.392516 -231.253102) (xy 116.339366 -231.257086) (xy 116.286216 -231.253102) (xy 116.234254 -231.241242)
			(xy 116.18464 -231.22177) (xy 116.138482 -231.195121) (xy 116.096811 -231.16189) (xy 116.060559 -231.122819)
			(xy 116.030535 -231.078782) (xy 116.007409 -231.030761) (xy 115.991699 -230.979831) (xy 115.983756 -230.927127)
			(xy 115.755176 -230.927127) (xy 115.747233 -230.979831) (xy 115.731523 -231.030761) (xy 115.708397 -231.078782)
			(xy 115.678373 -231.122819) (xy 115.642121 -231.16189) (xy 115.60045 -231.195121) (xy 115.554292 -231.22177)
			(xy 115.504678 -231.241242) (xy 115.452716 -231.253102) (xy 115.399566 -231.257086) (xy 115.346416 -231.253102)
			(xy 115.294454 -231.241242) (xy 115.24484 -231.22177) (xy 115.198682 -231.195121) (xy 115.157011 -231.16189)
			(xy 115.120759 -231.122819) (xy 115.090735 -231.078782) (xy 115.067609 -231.030761) (xy 115.051899 -230.979831)
			(xy 115.043956 -230.927127) (xy 114.81563 -230.927127) (xy 114.807687 -230.979831) (xy 114.791977 -231.030761)
			(xy 114.768851 -231.078782) (xy 114.738827 -231.122819) (xy 114.702575 -231.16189) (xy 114.660904 -231.195121)
			(xy 114.614746 -231.22177) (xy 114.565132 -231.241242) (xy 114.51317 -231.253102) (xy 114.46002 -231.257086)
			(xy 114.40687 -231.253102) (xy 114.354908 -231.241242) (xy 114.305294 -231.22177) (xy 114.259136 -231.195121)
			(xy 114.217465 -231.16189) (xy 114.181213 -231.122819) (xy 114.151189 -231.078782) (xy 114.128063 -231.030761)
			(xy 114.112353 -230.979831) (xy 114.10441 -230.927127) (xy 113.875576 -230.927127) (xy 113.867633 -230.979831)
			(xy 113.851923 -231.030761) (xy 113.828797 -231.078782) (xy 113.798773 -231.122819) (xy 113.762521 -231.16189)
			(xy 113.72085 -231.195121) (xy 113.674692 -231.22177) (xy 113.625078 -231.241242) (xy 113.573116 -231.253102)
			(xy 113.519966 -231.257086) (xy 113.466816 -231.253102) (xy 113.414854 -231.241242) (xy 113.36524 -231.22177)
			(xy 113.319082 -231.195121) (xy 113.277411 -231.16189) (xy 113.241159 -231.122819) (xy 113.211135 -231.078782)
			(xy 113.188009 -231.030761) (xy 113.172299 -230.979831) (xy 113.164356 -230.927127) (xy 112.935776 -230.927127)
			(xy 112.927833 -230.979831) (xy 112.912123 -231.030761) (xy 112.888997 -231.078782) (xy 112.858973 -231.122819)
			(xy 112.822721 -231.16189) (xy 112.78105 -231.195121) (xy 112.734892 -231.22177) (xy 112.685278 -231.241242)
			(xy 112.633316 -231.253102) (xy 112.580166 -231.257086) (xy 112.527016 -231.253102) (xy 112.475054 -231.241242)
			(xy 112.42544 -231.22177) (xy 112.379282 -231.195121) (xy 112.337611 -231.16189) (xy 112.301359 -231.122819)
			(xy 112.271335 -231.078782) (xy 112.248209 -231.030761) (xy 112.232499 -230.979831) (xy 112.224556 -230.927127)
			(xy 111.995938 -230.927127) (xy 111.988148 -230.979077) (xy 111.972704 -231.029556) (xy 111.949984 -231.077205)
			(xy 111.920483 -231.120981) (xy 111.903002 -231.140762) (xy 111.889794 -231.155494) (xy 111.889794 -231.224074)
			(xy 111.50981 -231.604058) (xy 111.516414 -231.63149) (xy 111.521023 -231.651945) (xy 111.52599 -231.693582)
			(xy 111.52632 -231.714548) (xy 111.525793 -231.741197) (xy 111.75491 -231.741197) (xy 111.75491 -231.687899)
			(xy 111.762853 -231.635195) (xy 111.778563 -231.584265) (xy 111.801689 -231.536244) (xy 111.831713 -231.492207)
			(xy 111.867965 -231.453136) (xy 111.909636 -231.419905) (xy 111.955794 -231.393256) (xy 112.005408 -231.373784)
			(xy 112.05737 -231.361924) (xy 112.11052 -231.357941) (xy 112.16367 -231.361924) (xy 112.215632 -231.373784)
			(xy 112.265246 -231.393256) (xy 112.311404 -231.419905) (xy 112.353075 -231.453136) (xy 112.389327 -231.492207)
			(xy 112.419351 -231.536244) (xy 112.442477 -231.584265) (xy 112.458187 -231.635195) (xy 112.46613 -231.687899)
			(xy 112.466628 -231.714548) (xy 112.46613 -231.741197) (xy 112.69471 -231.741197) (xy 112.69471 -231.687899)
			(xy 112.702653 -231.635195) (xy 112.718363 -231.584265) (xy 112.741489 -231.536244) (xy 112.771513 -231.492207)
			(xy 112.807765 -231.453136) (xy 112.849436 -231.419905) (xy 112.895594 -231.393256) (xy 112.945208 -231.373784)
			(xy 112.99717 -231.361924) (xy 113.05032 -231.357941) (xy 113.10347 -231.361924) (xy 113.155432 -231.373784)
			(xy 113.205046 -231.393256) (xy 113.251204 -231.419905) (xy 113.292875 -231.453136) (xy 113.329127 -231.492207)
			(xy 113.359151 -231.536244) (xy 113.382277 -231.584265) (xy 113.397987 -231.635195) (xy 113.40593 -231.687899)
			(xy 113.406428 -231.714548) (xy 113.40593 -231.741197) (xy 113.63451 -231.741197) (xy 113.63451 -231.687899)
			(xy 113.642453 -231.635195) (xy 113.658163 -231.584265) (xy 113.681289 -231.536244) (xy 113.711313 -231.492207)
			(xy 113.747565 -231.453136) (xy 113.789236 -231.419905) (xy 113.835394 -231.393256) (xy 113.885008 -231.373784)
			(xy 113.93697 -231.361924) (xy 113.99012 -231.357941) (xy 114.04327 -231.361924) (xy 114.095232 -231.373784)
			(xy 114.144846 -231.393256) (xy 114.191004 -231.419905) (xy 114.232675 -231.453136) (xy 114.268927 -231.492207)
			(xy 114.298951 -231.536244) (xy 114.322077 -231.584265) (xy 114.337787 -231.635195) (xy 114.34573 -231.687899)
			(xy 114.346228 -231.714548) (xy 114.34573 -231.741197) (xy 114.573802 -231.741197) (xy 114.573802 -231.687899)
			(xy 114.581745 -231.635195) (xy 114.597455 -231.584265) (xy 114.620581 -231.536244) (xy 114.650605 -231.492207)
			(xy 114.686857 -231.453136) (xy 114.728528 -231.419905) (xy 114.774686 -231.393256) (xy 114.8243 -231.373784)
			(xy 114.876262 -231.361924) (xy 114.929412 -231.357941) (xy 114.982562 -231.361924) (xy 115.034524 -231.373784)
			(xy 115.084138 -231.393256) (xy 115.130296 -231.419905) (xy 115.171967 -231.453136) (xy 115.208219 -231.492207)
			(xy 115.238243 -231.536244) (xy 115.261369 -231.584265) (xy 115.277079 -231.635195) (xy 115.285022 -231.687899)
			(xy 115.28552 -231.714548) (xy 115.285022 -231.741197) (xy 115.513602 -231.741197) (xy 115.513602 -231.687899)
			(xy 115.521545 -231.635195) (xy 115.537255 -231.584265) (xy 115.560381 -231.536244) (xy 115.590405 -231.492207)
			(xy 115.626657 -231.453136) (xy 115.668328 -231.419905) (xy 115.714486 -231.393256) (xy 115.7641 -231.373784)
			(xy 115.816062 -231.361924) (xy 115.869212 -231.357941) (xy 115.922362 -231.361924) (xy 115.974324 -231.373784)
			(xy 116.023938 -231.393256) (xy 116.070096 -231.419905) (xy 116.111767 -231.453136) (xy 116.148019 -231.492207)
			(xy 116.178043 -231.536244) (xy 116.201169 -231.584265) (xy 116.216879 -231.635195) (xy 116.224822 -231.687899)
			(xy 116.22532 -231.714548) (xy 116.224822 -231.741197) (xy 116.453402 -231.741197) (xy 116.453402 -231.687899)
			(xy 116.461345 -231.635195) (xy 116.477055 -231.584265) (xy 116.500181 -231.536244) (xy 116.530205 -231.492207)
			(xy 116.566457 -231.453136) (xy 116.608128 -231.419905) (xy 116.654286 -231.393256) (xy 116.7039 -231.373784)
			(xy 116.755862 -231.361924) (xy 116.809012 -231.357941) (xy 116.862162 -231.361924) (xy 116.914124 -231.373784)
			(xy 116.963738 -231.393256) (xy 117.009896 -231.419905) (xy 117.051567 -231.453136) (xy 117.087819 -231.492207)
			(xy 117.117843 -231.536244) (xy 117.140969 -231.584265) (xy 117.156679 -231.635195) (xy 117.164622 -231.687899)
			(xy 117.16512 -231.714548) (xy 117.164622 -231.741197) (xy 117.393202 -231.741197) (xy 117.393202 -231.687899)
			(xy 117.401145 -231.635195) (xy 117.416855 -231.584265) (xy 117.439981 -231.536244) (xy 117.470005 -231.492207)
			(xy 117.506257 -231.453136) (xy 117.547928 -231.419905) (xy 117.594086 -231.393256) (xy 117.6437 -231.373784)
			(xy 117.695662 -231.361924) (xy 117.748812 -231.357941) (xy 117.801962 -231.361924) (xy 117.853924 -231.373784)
			(xy 117.903538 -231.393256) (xy 117.949696 -231.419905) (xy 117.991367 -231.453136) (xy 118.027619 -231.492207)
			(xy 118.057643 -231.536244) (xy 118.080769 -231.584265) (xy 118.096479 -231.635195) (xy 118.104422 -231.687899)
			(xy 118.10492 -231.714548) (xy 118.104422 -231.741197) (xy 118.333002 -231.741197) (xy 118.333002 -231.687899)
			(xy 118.340945 -231.635195) (xy 118.356655 -231.584265) (xy 118.379781 -231.536244) (xy 118.409805 -231.492207)
			(xy 118.446057 -231.453136) (xy 118.487728 -231.419905) (xy 118.533886 -231.393256) (xy 118.5835 -231.373784)
			(xy 118.635462 -231.361924) (xy 118.688612 -231.357941) (xy 118.741762 -231.361924) (xy 118.793724 -231.373784)
			(xy 118.843338 -231.393256) (xy 118.889496 -231.419905) (xy 118.931167 -231.453136) (xy 118.967419 -231.492207)
			(xy 118.997443 -231.536244) (xy 119.020569 -231.584265) (xy 119.036279 -231.635195) (xy 119.044222 -231.687899)
			(xy 119.04472 -231.714548) (xy 119.044222 -231.741197) (xy 119.27331 -231.741197) (xy 119.27331 -231.687899)
			(xy 119.281253 -231.635195) (xy 119.296963 -231.584265) (xy 119.320089 -231.536244) (xy 119.350113 -231.492207)
			(xy 119.386365 -231.453136) (xy 119.428036 -231.419905) (xy 119.474194 -231.393256) (xy 119.523808 -231.373784)
			(xy 119.57577 -231.361924) (xy 119.62892 -231.357941) (xy 119.68207 -231.361924) (xy 119.734032 -231.373784)
			(xy 119.783646 -231.393256) (xy 119.829804 -231.419905) (xy 119.871475 -231.453136) (xy 119.907727 -231.492207)
			(xy 119.937751 -231.536244) (xy 119.960877 -231.584265) (xy 119.976587 -231.635195) (xy 119.98453 -231.687899)
			(xy 119.985028 -231.714548) (xy 119.98453 -231.741197) (xy 120.212602 -231.741197) (xy 120.212602 -231.687899)
			(xy 120.220545 -231.635195) (xy 120.236255 -231.584265) (xy 120.259381 -231.536244) (xy 120.289405 -231.492207)
			(xy 120.325657 -231.453136) (xy 120.367328 -231.419905) (xy 120.413486 -231.393256) (xy 120.4631 -231.373784)
			(xy 120.515062 -231.361924) (xy 120.568212 -231.357941) (xy 120.621362 -231.361924) (xy 120.673324 -231.373784)
			(xy 120.722938 -231.393256) (xy 120.769096 -231.419905) (xy 120.810767 -231.453136) (xy 120.847019 -231.492207)
			(xy 120.877043 -231.536244) (xy 120.900169 -231.584265) (xy 120.915879 -231.635195) (xy 120.923822 -231.687899)
			(xy 120.92432 -231.714548) (xy 120.923822 -231.741197) (xy 121.15291 -231.741197) (xy 121.15291 -231.687899)
			(xy 121.160853 -231.635195) (xy 121.176563 -231.584265) (xy 121.199689 -231.536244) (xy 121.229713 -231.492207)
			(xy 121.265965 -231.453136) (xy 121.307636 -231.419905) (xy 121.353794 -231.393256) (xy 121.403408 -231.373784)
			(xy 121.45537 -231.361924) (xy 121.50852 -231.357941) (xy 121.56167 -231.361924) (xy 121.613632 -231.373784)
			(xy 121.663246 -231.393256) (xy 121.709404 -231.419905) (xy 121.751075 -231.453136) (xy 121.787327 -231.492207)
			(xy 121.817351 -231.536244) (xy 121.840477 -231.584265) (xy 121.856187 -231.635195) (xy 121.86413 -231.687899)
			(xy 121.864628 -231.714548) (xy 121.86413 -231.741197) (xy 122.092456 -231.741197) (xy 122.092456 -231.687899)
			(xy 122.100399 -231.635195) (xy 122.116109 -231.584265) (xy 122.139235 -231.536244) (xy 122.169259 -231.492207)
			(xy 122.205511 -231.453136) (xy 122.247182 -231.419905) (xy 122.29334 -231.393256) (xy 122.342954 -231.373784)
			(xy 122.394916 -231.361924) (xy 122.448066 -231.357941) (xy 122.501216 -231.361924) (xy 122.553178 -231.373784)
			(xy 122.602792 -231.393256) (xy 122.64895 -231.419905) (xy 122.690621 -231.453136) (xy 122.726873 -231.492207)
			(xy 122.756897 -231.536244) (xy 122.780023 -231.584265) (xy 122.795733 -231.635195) (xy 122.803676 -231.687899)
			(xy 122.804174 -231.714548) (xy 122.803676 -231.741197) (xy 123.032002 -231.741197) (xy 123.032002 -231.687899)
			(xy 123.039945 -231.635195) (xy 123.055655 -231.584265) (xy 123.078781 -231.536244) (xy 123.108805 -231.492207)
			(xy 123.145057 -231.453136) (xy 123.186728 -231.419905) (xy 123.232886 -231.393256) (xy 123.2825 -231.373784)
			(xy 123.334462 -231.361924) (xy 123.387612 -231.357941) (xy 123.440762 -231.361924) (xy 123.492724 -231.373784)
			(xy 123.542338 -231.393256) (xy 123.588496 -231.419905) (xy 123.630167 -231.453136) (xy 123.666419 -231.492207)
			(xy 123.696443 -231.536244) (xy 123.719569 -231.584265) (xy 123.735279 -231.635195) (xy 123.743222 -231.687899)
			(xy 123.74372 -231.714548) (xy 123.743222 -231.741197) (xy 123.971802 -231.741197) (xy 123.971802 -231.687899)
			(xy 123.979745 -231.635195) (xy 123.995455 -231.584265) (xy 124.018581 -231.536244) (xy 124.048605 -231.492207)
			(xy 124.084857 -231.453136) (xy 124.126528 -231.419905) (xy 124.172686 -231.393256) (xy 124.2223 -231.373784)
			(xy 124.274262 -231.361924) (xy 124.327412 -231.357941) (xy 124.380562 -231.361924) (xy 124.432524 -231.373784)
			(xy 124.482138 -231.393256) (xy 124.528296 -231.419905) (xy 124.569967 -231.453136) (xy 124.606219 -231.492207)
			(xy 124.636243 -231.536244) (xy 124.659369 -231.584265) (xy 124.675079 -231.635195) (xy 124.683022 -231.687899)
			(xy 124.68352 -231.714548) (xy 124.683022 -231.741197) (xy 124.911602 -231.741197) (xy 124.911602 -231.687899)
			(xy 124.919545 -231.635195) (xy 124.935255 -231.584265) (xy 124.958381 -231.536244) (xy 124.988405 -231.492207)
			(xy 125.024657 -231.453136) (xy 125.066328 -231.419905) (xy 125.112486 -231.393256) (xy 125.1621 -231.373784)
			(xy 125.214062 -231.361924) (xy 125.267212 -231.357941) (xy 125.320362 -231.361924) (xy 125.372324 -231.373784)
			(xy 125.421938 -231.393256) (xy 125.468096 -231.419905) (xy 125.509767 -231.453136) (xy 125.546019 -231.492207)
			(xy 125.576043 -231.536244) (xy 125.599169 -231.584265) (xy 125.614879 -231.635195) (xy 125.622822 -231.687899)
			(xy 125.62332 -231.714548) (xy 125.622822 -231.741197) (xy 125.851402 -231.741197) (xy 125.851402 -231.687899)
			(xy 125.859345 -231.635195) (xy 125.875055 -231.584265) (xy 125.898181 -231.536244) (xy 125.928205 -231.492207)
			(xy 125.964457 -231.453136) (xy 126.006128 -231.419905) (xy 126.052286 -231.393256) (xy 126.1019 -231.373784)
			(xy 126.153862 -231.361924) (xy 126.207012 -231.357941) (xy 126.260162 -231.361924) (xy 126.312124 -231.373784)
			(xy 126.361738 -231.393256) (xy 126.407896 -231.419905) (xy 126.449567 -231.453136) (xy 126.485819 -231.492207)
			(xy 126.515843 -231.536244) (xy 126.538969 -231.584265) (xy 126.554679 -231.635195) (xy 126.562622 -231.687899)
			(xy 126.56312 -231.714548) (xy 126.562622 -231.741197) (xy 126.791202 -231.741197) (xy 126.791202 -231.687899)
			(xy 126.799145 -231.635195) (xy 126.814855 -231.584265) (xy 126.837981 -231.536244) (xy 126.868005 -231.492207)
			(xy 126.904257 -231.453136) (xy 126.945928 -231.419905) (xy 126.992086 -231.393256) (xy 127.0417 -231.373784)
			(xy 127.093662 -231.361924) (xy 127.146812 -231.357941) (xy 127.199962 -231.361924) (xy 127.251924 -231.373784)
			(xy 127.301538 -231.393256) (xy 127.347696 -231.419905) (xy 127.389367 -231.453136) (xy 127.425619 -231.492207)
			(xy 127.455643 -231.536244) (xy 127.478769 -231.584265) (xy 127.494479 -231.635195) (xy 127.502422 -231.687899)
			(xy 127.50292 -231.714548) (xy 127.502422 -231.741197) (xy 127.731002 -231.741197) (xy 127.731002 -231.687899)
			(xy 127.738945 -231.635195) (xy 127.754655 -231.584265) (xy 127.777781 -231.536244) (xy 127.807805 -231.492207)
			(xy 127.844057 -231.453136) (xy 127.885728 -231.419905) (xy 127.931886 -231.393256) (xy 127.9815 -231.373784)
			(xy 128.033462 -231.361924) (xy 128.086612 -231.357941) (xy 128.139762 -231.361924) (xy 128.191724 -231.373784)
			(xy 128.241338 -231.393256) (xy 128.287496 -231.419905) (xy 128.329167 -231.453136) (xy 128.365419 -231.492207)
			(xy 128.395443 -231.536244) (xy 128.418569 -231.584265) (xy 128.434279 -231.635195) (xy 128.442222 -231.687899)
			(xy 128.44272 -231.714548) (xy 128.442222 -231.741197) (xy 128.671056 -231.741197) (xy 128.671056 -231.687899)
			(xy 128.678999 -231.635195) (xy 128.694709 -231.584265) (xy 128.717835 -231.536244) (xy 128.747859 -231.492207)
			(xy 128.784111 -231.453136) (xy 128.825782 -231.419905) (xy 128.87194 -231.393256) (xy 128.921554 -231.373784)
			(xy 128.973516 -231.361924) (xy 129.026666 -231.357941) (xy 129.079816 -231.361924) (xy 129.131778 -231.373784)
			(xy 129.181392 -231.393256) (xy 129.22755 -231.419905) (xy 129.269221 -231.453136) (xy 129.305473 -231.492207)
			(xy 129.335497 -231.536244) (xy 129.358623 -231.584265) (xy 129.374333 -231.635195) (xy 129.382276 -231.687899)
			(xy 129.382774 -231.714548) (xy 129.382276 -231.741197) (xy 129.610602 -231.741197) (xy 129.610602 -231.687899)
			(xy 129.618545 -231.635195) (xy 129.634255 -231.584265) (xy 129.657381 -231.536244) (xy 129.687405 -231.492207)
			(xy 129.723657 -231.453136) (xy 129.765328 -231.419905) (xy 129.811486 -231.393256) (xy 129.8611 -231.373784)
			(xy 129.913062 -231.361924) (xy 129.966212 -231.357941) (xy 130.019362 -231.361924) (xy 130.071324 -231.373784)
			(xy 130.120938 -231.393256) (xy 130.167096 -231.419905) (xy 130.208767 -231.453136) (xy 130.245019 -231.492207)
			(xy 130.275043 -231.536244) (xy 130.298169 -231.584265) (xy 130.313879 -231.635195) (xy 130.321822 -231.687899)
			(xy 130.32232 -231.714548) (xy 130.321822 -231.741197) (xy 130.550402 -231.741197) (xy 130.550402 -231.687899)
			(xy 130.558345 -231.635195) (xy 130.574055 -231.584265) (xy 130.597181 -231.536244) (xy 130.627205 -231.492207)
			(xy 130.663457 -231.453136) (xy 130.705128 -231.419905) (xy 130.751286 -231.393256) (xy 130.8009 -231.373784)
			(xy 130.852862 -231.361924) (xy 130.906012 -231.357941) (xy 130.959162 -231.361924) (xy 131.011124 -231.373784)
			(xy 131.060738 -231.393256) (xy 131.106896 -231.419905) (xy 131.148567 -231.453136) (xy 131.184819 -231.492207)
			(xy 131.214843 -231.536244) (xy 131.237969 -231.584265) (xy 131.253679 -231.635195) (xy 131.261622 -231.687899)
			(xy 131.26212 -231.714548) (xy 131.261622 -231.741197) (xy 131.490202 -231.741197) (xy 131.490202 -231.687899)
			(xy 131.498145 -231.635195) (xy 131.513855 -231.584265) (xy 131.536981 -231.536244) (xy 131.567005 -231.492207)
			(xy 131.603257 -231.453136) (xy 131.644928 -231.419905) (xy 131.691086 -231.393256) (xy 131.7407 -231.373784)
			(xy 131.792662 -231.361924) (xy 131.845812 -231.357941) (xy 131.898962 -231.361924) (xy 131.950924 -231.373784)
			(xy 132.000538 -231.393256) (xy 132.046696 -231.419905) (xy 132.088367 -231.453136) (xy 132.124619 -231.492207)
			(xy 132.154643 -231.536244) (xy 132.177769 -231.584265) (xy 132.193479 -231.635195) (xy 132.201422 -231.687899)
			(xy 132.20192 -231.714548) (xy 132.201422 -231.741197) (xy 132.430002 -231.741197) (xy 132.430002 -231.687899)
			(xy 132.437945 -231.635195) (xy 132.453655 -231.584265) (xy 132.476781 -231.536244) (xy 132.506805 -231.492207)
			(xy 132.543057 -231.453136) (xy 132.584728 -231.419905) (xy 132.630886 -231.393256) (xy 132.6805 -231.373784)
			(xy 132.732462 -231.361924) (xy 132.785612 -231.357941) (xy 132.838762 -231.361924) (xy 132.890724 -231.373784)
			(xy 132.940338 -231.393256) (xy 132.986496 -231.419905) (xy 133.028167 -231.453136) (xy 133.064419 -231.492207)
			(xy 133.094443 -231.536244) (xy 133.117569 -231.584265) (xy 133.133279 -231.635195) (xy 133.141222 -231.687899)
			(xy 133.14172 -231.714548) (xy 133.141222 -231.741197) (xy 133.370056 -231.741197) (xy 133.370056 -231.687899)
			(xy 133.377999 -231.635195) (xy 133.393709 -231.584265) (xy 133.416835 -231.536244) (xy 133.446859 -231.492207)
			(xy 133.483111 -231.453136) (xy 133.524782 -231.419905) (xy 133.57094 -231.393256) (xy 133.620554 -231.373784)
			(xy 133.672516 -231.361924) (xy 133.725666 -231.357941) (xy 133.778816 -231.361924) (xy 133.830778 -231.373784)
			(xy 133.880392 -231.393256) (xy 133.92655 -231.419905) (xy 133.968221 -231.453136) (xy 134.004473 -231.492207)
			(xy 134.034497 -231.536244) (xy 134.057623 -231.584265) (xy 134.073333 -231.635195) (xy 134.081276 -231.687899)
			(xy 134.081774 -231.714548) (xy 134.081276 -231.741197) (xy 134.309856 -231.741197) (xy 134.309856 -231.687899)
			(xy 134.317799 -231.635195) (xy 134.333509 -231.584265) (xy 134.356635 -231.536244) (xy 134.386659 -231.492207)
			(xy 134.422911 -231.453136) (xy 134.464582 -231.419905) (xy 134.51074 -231.393256) (xy 134.560354 -231.373784)
			(xy 134.612316 -231.361924) (xy 134.665466 -231.357941) (xy 134.718616 -231.361924) (xy 134.770578 -231.373784)
			(xy 134.820192 -231.393256) (xy 134.86635 -231.419905) (xy 134.908021 -231.453136) (xy 134.944273 -231.492207)
			(xy 134.974297 -231.536244) (xy 134.997423 -231.584265) (xy 135.013133 -231.635195) (xy 135.021076 -231.687899)
			(xy 135.021574 -231.714548) (xy 135.021076 -231.741197) (xy 135.013133 -231.793901) (xy 134.997423 -231.844831)
			(xy 134.974297 -231.892852) (xy 134.944273 -231.936889) (xy 134.908021 -231.97596) (xy 134.86635 -232.009191)
			(xy 134.820192 -232.03584) (xy 134.770578 -232.055312) (xy 134.718616 -232.067172) (xy 134.665466 -232.071156)
			(xy 134.612316 -232.067172) (xy 134.560354 -232.055312) (xy 134.51074 -232.03584) (xy 134.464582 -232.009191)
			(xy 134.422911 -231.97596) (xy 134.386659 -231.936889) (xy 134.356635 -231.892852) (xy 134.333509 -231.844831)
			(xy 134.317799 -231.793901) (xy 134.309856 -231.741197) (xy 134.081276 -231.741197) (xy 134.073333 -231.793901)
			(xy 134.057623 -231.844831) (xy 134.034497 -231.892852) (xy 134.004473 -231.936889) (xy 133.968221 -231.97596)
			(xy 133.92655 -232.009191) (xy 133.880392 -232.03584) (xy 133.830778 -232.055312) (xy 133.778816 -232.067172)
			(xy 133.725666 -232.071156) (xy 133.672516 -232.067172) (xy 133.620554 -232.055312) (xy 133.57094 -232.03584)
			(xy 133.524782 -232.009191) (xy 133.483111 -231.97596) (xy 133.446859 -231.936889) (xy 133.416835 -231.892852)
			(xy 133.393709 -231.844831) (xy 133.377999 -231.793901) (xy 133.370056 -231.741197) (xy 133.141222 -231.741197)
			(xy 133.133279 -231.793901) (xy 133.117569 -231.844831) (xy 133.094443 -231.892852) (xy 133.064419 -231.936889)
			(xy 133.028167 -231.97596) (xy 132.986496 -232.009191) (xy 132.940338 -232.03584) (xy 132.890724 -232.055312)
			(xy 132.838762 -232.067172) (xy 132.785612 -232.071156) (xy 132.732462 -232.067172) (xy 132.6805 -232.055312)
			(xy 132.630886 -232.03584) (xy 132.584728 -232.009191) (xy 132.543057 -231.97596) (xy 132.506805 -231.936889)
			(xy 132.476781 -231.892852) (xy 132.453655 -231.844831) (xy 132.437945 -231.793901) (xy 132.430002 -231.741197)
			(xy 132.201422 -231.741197) (xy 132.193479 -231.793901) (xy 132.177769 -231.844831) (xy 132.154643 -231.892852)
			(xy 132.124619 -231.936889) (xy 132.088367 -231.97596) (xy 132.046696 -232.009191) (xy 132.000538 -232.03584)
			(xy 131.950924 -232.055312) (xy 131.898962 -232.067172) (xy 131.845812 -232.071156) (xy 131.792662 -232.067172)
			(xy 131.7407 -232.055312) (xy 131.691086 -232.03584) (xy 131.644928 -232.009191) (xy 131.603257 -231.97596)
			(xy 131.567005 -231.936889) (xy 131.536981 -231.892852) (xy 131.513855 -231.844831) (xy 131.498145 -231.793901)
			(xy 131.490202 -231.741197) (xy 131.261622 -231.741197) (xy 131.253679 -231.793901) (xy 131.237969 -231.844831)
			(xy 131.214843 -231.892852) (xy 131.184819 -231.936889) (xy 131.148567 -231.97596) (xy 131.106896 -232.009191)
			(xy 131.060738 -232.03584) (xy 131.011124 -232.055312) (xy 130.959162 -232.067172) (xy 130.906012 -232.071156)
			(xy 130.852862 -232.067172) (xy 130.8009 -232.055312) (xy 130.751286 -232.03584) (xy 130.705128 -232.009191)
			(xy 130.663457 -231.97596) (xy 130.627205 -231.936889) (xy 130.597181 -231.892852) (xy 130.574055 -231.844831)
			(xy 130.558345 -231.793901) (xy 130.550402 -231.741197) (xy 130.321822 -231.741197) (xy 130.313879 -231.793901)
			(xy 130.298169 -231.844831) (xy 130.275043 -231.892852) (xy 130.245019 -231.936889) (xy 130.208767 -231.97596)
			(xy 130.167096 -232.009191) (xy 130.120938 -232.03584) (xy 130.071324 -232.055312) (xy 130.019362 -232.067172)
			(xy 129.966212 -232.071156) (xy 129.913062 -232.067172) (xy 129.8611 -232.055312) (xy 129.811486 -232.03584)
			(xy 129.765328 -232.009191) (xy 129.723657 -231.97596) (xy 129.687405 -231.936889) (xy 129.657381 -231.892852)
			(xy 129.634255 -231.844831) (xy 129.618545 -231.793901) (xy 129.610602 -231.741197) (xy 129.382276 -231.741197)
			(xy 129.374333 -231.793901) (xy 129.358623 -231.844831) (xy 129.335497 -231.892852) (xy 129.305473 -231.936889)
			(xy 129.269221 -231.97596) (xy 129.22755 -232.009191) (xy 129.181392 -232.03584) (xy 129.131778 -232.055312)
			(xy 129.079816 -232.067172) (xy 129.026666 -232.071156) (xy 128.973516 -232.067172) (xy 128.921554 -232.055312)
			(xy 128.87194 -232.03584) (xy 128.825782 -232.009191) (xy 128.784111 -231.97596) (xy 128.747859 -231.936889)
			(xy 128.717835 -231.892852) (xy 128.694709 -231.844831) (xy 128.678999 -231.793901) (xy 128.671056 -231.741197)
			(xy 128.442222 -231.741197) (xy 128.434279 -231.793901) (xy 128.418569 -231.844831) (xy 128.395443 -231.892852)
			(xy 128.365419 -231.936889) (xy 128.329167 -231.97596) (xy 128.287496 -232.009191) (xy 128.241338 -232.03584)
			(xy 128.191724 -232.055312) (xy 128.139762 -232.067172) (xy 128.086612 -232.071156) (xy 128.033462 -232.067172)
			(xy 127.9815 -232.055312) (xy 127.931886 -232.03584) (xy 127.885728 -232.009191) (xy 127.844057 -231.97596)
			(xy 127.807805 -231.936889) (xy 127.777781 -231.892852) (xy 127.754655 -231.844831) (xy 127.738945 -231.793901)
			(xy 127.731002 -231.741197) (xy 127.502422 -231.741197) (xy 127.494479 -231.793901) (xy 127.478769 -231.844831)
			(xy 127.455643 -231.892852) (xy 127.425619 -231.936889) (xy 127.389367 -231.97596) (xy 127.347696 -232.009191)
			(xy 127.301538 -232.03584) (xy 127.251924 -232.055312) (xy 127.199962 -232.067172) (xy 127.146812 -232.071156)
			(xy 127.093662 -232.067172) (xy 127.0417 -232.055312) (xy 126.992086 -232.03584) (xy 126.945928 -232.009191)
			(xy 126.904257 -231.97596) (xy 126.868005 -231.936889) (xy 126.837981 -231.892852) (xy 126.814855 -231.844831)
			(xy 126.799145 -231.793901) (xy 126.791202 -231.741197) (xy 126.562622 -231.741197) (xy 126.554679 -231.793901)
			(xy 126.538969 -231.844831) (xy 126.515843 -231.892852) (xy 126.485819 -231.936889) (xy 126.449567 -231.97596)
			(xy 126.407896 -232.009191) (xy 126.361738 -232.03584) (xy 126.312124 -232.055312) (xy 126.260162 -232.067172)
			(xy 126.207012 -232.071156) (xy 126.153862 -232.067172) (xy 126.1019 -232.055312) (xy 126.052286 -232.03584)
			(xy 126.006128 -232.009191) (xy 125.964457 -231.97596) (xy 125.928205 -231.936889) (xy 125.898181 -231.892852)
			(xy 125.875055 -231.844831) (xy 125.859345 -231.793901) (xy 125.851402 -231.741197) (xy 125.622822 -231.741197)
			(xy 125.614879 -231.793901) (xy 125.599169 -231.844831) (xy 125.576043 -231.892852) (xy 125.546019 -231.936889)
			(xy 125.509767 -231.97596) (xy 125.468096 -232.009191) (xy 125.421938 -232.03584) (xy 125.372324 -232.055312)
			(xy 125.320362 -232.067172) (xy 125.267212 -232.071156) (xy 125.214062 -232.067172) (xy 125.1621 -232.055312)
			(xy 125.112486 -232.03584) (xy 125.066328 -232.009191) (xy 125.024657 -231.97596) (xy 124.988405 -231.936889)
			(xy 124.958381 -231.892852) (xy 124.935255 -231.844831) (xy 124.919545 -231.793901) (xy 124.911602 -231.741197)
			(xy 124.683022 -231.741197) (xy 124.675079 -231.793901) (xy 124.659369 -231.844831) (xy 124.636243 -231.892852)
			(xy 124.606219 -231.936889) (xy 124.569967 -231.97596) (xy 124.528296 -232.009191) (xy 124.482138 -232.03584)
			(xy 124.432524 -232.055312) (xy 124.380562 -232.067172) (xy 124.327412 -232.071156) (xy 124.274262 -232.067172)
			(xy 124.2223 -232.055312) (xy 124.172686 -232.03584) (xy 124.126528 -232.009191) (xy 124.084857 -231.97596)
			(xy 124.048605 -231.936889) (xy 124.018581 -231.892852) (xy 123.995455 -231.844831) (xy 123.979745 -231.793901)
			(xy 123.971802 -231.741197) (xy 123.743222 -231.741197) (xy 123.735279 -231.793901) (xy 123.719569 -231.844831)
			(xy 123.696443 -231.892852) (xy 123.666419 -231.936889) (xy 123.630167 -231.97596) (xy 123.588496 -232.009191)
			(xy 123.542338 -232.03584) (xy 123.492724 -232.055312) (xy 123.440762 -232.067172) (xy 123.387612 -232.071156)
			(xy 123.334462 -232.067172) (xy 123.2825 -232.055312) (xy 123.232886 -232.03584) (xy 123.186728 -232.009191)
			(xy 123.145057 -231.97596) (xy 123.108805 -231.936889) (xy 123.078781 -231.892852) (xy 123.055655 -231.844831)
			(xy 123.039945 -231.793901) (xy 123.032002 -231.741197) (xy 122.803676 -231.741197) (xy 122.795733 -231.793901)
			(xy 122.780023 -231.844831) (xy 122.756897 -231.892852) (xy 122.726873 -231.936889) (xy 122.690621 -231.97596)
			(xy 122.64895 -232.009191) (xy 122.602792 -232.03584) (xy 122.553178 -232.055312) (xy 122.501216 -232.067172)
			(xy 122.448066 -232.071156) (xy 122.394916 -232.067172) (xy 122.342954 -232.055312) (xy 122.29334 -232.03584)
			(xy 122.247182 -232.009191) (xy 122.205511 -231.97596) (xy 122.169259 -231.936889) (xy 122.139235 -231.892852)
			(xy 122.116109 -231.844831) (xy 122.100399 -231.793901) (xy 122.092456 -231.741197) (xy 121.86413 -231.741197)
			(xy 121.856187 -231.793901) (xy 121.840477 -231.844831) (xy 121.817351 -231.892852) (xy 121.787327 -231.936889)
			(xy 121.751075 -231.97596) (xy 121.709404 -232.009191) (xy 121.663246 -232.03584) (xy 121.613632 -232.055312)
			(xy 121.56167 -232.067172) (xy 121.50852 -232.071156) (xy 121.45537 -232.067172) (xy 121.403408 -232.055312)
			(xy 121.353794 -232.03584) (xy 121.307636 -232.009191) (xy 121.265965 -231.97596) (xy 121.229713 -231.936889)
			(xy 121.199689 -231.892852) (xy 121.176563 -231.844831) (xy 121.160853 -231.793901) (xy 121.15291 -231.741197)
			(xy 120.923822 -231.741197) (xy 120.915879 -231.793901) (xy 120.900169 -231.844831) (xy 120.877043 -231.892852)
			(xy 120.847019 -231.936889) (xy 120.810767 -231.97596) (xy 120.769096 -232.009191) (xy 120.722938 -232.03584)
			(xy 120.673324 -232.055312) (xy 120.621362 -232.067172) (xy 120.568212 -232.071156) (xy 120.515062 -232.067172)
			(xy 120.4631 -232.055312) (xy 120.413486 -232.03584) (xy 120.367328 -232.009191) (xy 120.325657 -231.97596)
			(xy 120.289405 -231.936889) (xy 120.259381 -231.892852) (xy 120.236255 -231.844831) (xy 120.220545 -231.793901)
			(xy 120.212602 -231.741197) (xy 119.98453 -231.741197) (xy 119.976587 -231.793901) (xy 119.960877 -231.844831)
			(xy 119.937751 -231.892852) (xy 119.907727 -231.936889) (xy 119.871475 -231.97596) (xy 119.829804 -232.009191)
			(xy 119.783646 -232.03584) (xy 119.734032 -232.055312) (xy 119.68207 -232.067172) (xy 119.62892 -232.071156)
			(xy 119.57577 -232.067172) (xy 119.523808 -232.055312) (xy 119.474194 -232.03584) (xy 119.428036 -232.009191)
			(xy 119.386365 -231.97596) (xy 119.350113 -231.936889) (xy 119.320089 -231.892852) (xy 119.296963 -231.844831)
			(xy 119.281253 -231.793901) (xy 119.27331 -231.741197) (xy 119.044222 -231.741197) (xy 119.036279 -231.793901)
			(xy 119.020569 -231.844831) (xy 118.997443 -231.892852) (xy 118.967419 -231.936889) (xy 118.931167 -231.97596)
			(xy 118.889496 -232.009191) (xy 118.843338 -232.03584) (xy 118.793724 -232.055312) (xy 118.741762 -232.067172)
			(xy 118.688612 -232.071156) (xy 118.635462 -232.067172) (xy 118.5835 -232.055312) (xy 118.533886 -232.03584)
			(xy 118.487728 -232.009191) (xy 118.446057 -231.97596) (xy 118.409805 -231.936889) (xy 118.379781 -231.892852)
			(xy 118.356655 -231.844831) (xy 118.340945 -231.793901) (xy 118.333002 -231.741197) (xy 118.104422 -231.741197)
			(xy 118.096479 -231.793901) (xy 118.080769 -231.844831) (xy 118.057643 -231.892852) (xy 118.027619 -231.936889)
			(xy 117.991367 -231.97596) (xy 117.949696 -232.009191) (xy 117.903538 -232.03584) (xy 117.853924 -232.055312)
			(xy 117.801962 -232.067172) (xy 117.748812 -232.071156) (xy 117.695662 -232.067172) (xy 117.6437 -232.055312)
			(xy 117.594086 -232.03584) (xy 117.547928 -232.009191) (xy 117.506257 -231.97596) (xy 117.470005 -231.936889)
			(xy 117.439981 -231.892852) (xy 117.416855 -231.844831) (xy 117.401145 -231.793901) (xy 117.393202 -231.741197)
			(xy 117.164622 -231.741197) (xy 117.156679 -231.793901) (xy 117.140969 -231.844831) (xy 117.117843 -231.892852)
			(xy 117.087819 -231.936889) (xy 117.051567 -231.97596) (xy 117.009896 -232.009191) (xy 116.963738 -232.03584)
			(xy 116.914124 -232.055312) (xy 116.862162 -232.067172) (xy 116.809012 -232.071156) (xy 116.755862 -232.067172)
			(xy 116.7039 -232.055312) (xy 116.654286 -232.03584) (xy 116.608128 -232.009191) (xy 116.566457 -231.97596)
			(xy 116.530205 -231.936889) (xy 116.500181 -231.892852) (xy 116.477055 -231.844831) (xy 116.461345 -231.793901)
			(xy 116.453402 -231.741197) (xy 116.224822 -231.741197) (xy 116.216879 -231.793901) (xy 116.201169 -231.844831)
			(xy 116.178043 -231.892852) (xy 116.148019 -231.936889) (xy 116.111767 -231.97596) (xy 116.070096 -232.009191)
			(xy 116.023938 -232.03584) (xy 115.974324 -232.055312) (xy 115.922362 -232.067172) (xy 115.869212 -232.071156)
			(xy 115.816062 -232.067172) (xy 115.7641 -232.055312) (xy 115.714486 -232.03584) (xy 115.668328 -232.009191)
			(xy 115.626657 -231.97596) (xy 115.590405 -231.936889) (xy 115.560381 -231.892852) (xy 115.537255 -231.844831)
			(xy 115.521545 -231.793901) (xy 115.513602 -231.741197) (xy 115.285022 -231.741197) (xy 115.277079 -231.793901)
			(xy 115.261369 -231.844831) (xy 115.238243 -231.892852) (xy 115.208219 -231.936889) (xy 115.171967 -231.97596)
			(xy 115.130296 -232.009191) (xy 115.084138 -232.03584) (xy 115.034524 -232.055312) (xy 114.982562 -232.067172)
			(xy 114.929412 -232.071156) (xy 114.876262 -232.067172) (xy 114.8243 -232.055312) (xy 114.774686 -232.03584)
			(xy 114.728528 -232.009191) (xy 114.686857 -231.97596) (xy 114.650605 -231.936889) (xy 114.620581 -231.892852)
			(xy 114.597455 -231.844831) (xy 114.581745 -231.793901) (xy 114.573802 -231.741197) (xy 114.34573 -231.741197)
			(xy 114.337787 -231.793901) (xy 114.322077 -231.844831) (xy 114.298951 -231.892852) (xy 114.268927 -231.936889)
			(xy 114.232675 -231.97596) (xy 114.191004 -232.009191) (xy 114.144846 -232.03584) (xy 114.095232 -232.055312)
			(xy 114.04327 -232.067172) (xy 113.99012 -232.071156) (xy 113.93697 -232.067172) (xy 113.885008 -232.055312)
			(xy 113.835394 -232.03584) (xy 113.789236 -232.009191) (xy 113.747565 -231.97596) (xy 113.711313 -231.936889)
			(xy 113.681289 -231.892852) (xy 113.658163 -231.844831) (xy 113.642453 -231.793901) (xy 113.63451 -231.741197)
			(xy 113.40593 -231.741197) (xy 113.397987 -231.793901) (xy 113.382277 -231.844831) (xy 113.359151 -231.892852)
			(xy 113.329127 -231.936889) (xy 113.292875 -231.97596) (xy 113.251204 -232.009191) (xy 113.205046 -232.03584)
			(xy 113.155432 -232.055312) (xy 113.10347 -232.067172) (xy 113.05032 -232.071156) (xy 112.99717 -232.067172)
			(xy 112.945208 -232.055312) (xy 112.895594 -232.03584) (xy 112.849436 -232.009191) (xy 112.807765 -231.97596)
			(xy 112.771513 -231.936889) (xy 112.741489 -231.892852) (xy 112.718363 -231.844831) (xy 112.702653 -231.793901)
			(xy 112.69471 -231.741197) (xy 112.46613 -231.741197) (xy 112.458187 -231.793901) (xy 112.442477 -231.844831)
			(xy 112.419351 -231.892852) (xy 112.389327 -231.936889) (xy 112.353075 -231.97596) (xy 112.311404 -232.009191)
			(xy 112.265246 -232.03584) (xy 112.215632 -232.055312) (xy 112.16367 -232.067172) (xy 112.11052 -232.071156)
			(xy 112.05737 -232.067172) (xy 112.005408 -232.055312) (xy 111.955794 -232.03584) (xy 111.909636 -232.009191)
			(xy 111.867965 -231.97596) (xy 111.831713 -231.936889) (xy 111.801689 -231.892852) (xy 111.778563 -231.844831)
			(xy 111.762853 -231.793901) (xy 111.75491 -231.741197) (xy 111.525793 -231.741197) (xy 111.525767 -231.742529)
			(xy 111.517007 -231.797801) (xy 111.499708 -231.851022) (xy 111.474297 -231.900883) (xy 111.441401 -231.946155)
			(xy 111.401828 -231.985724) (xy 111.356552 -232.018616) (xy 111.306689 -232.044022) (xy 111.253466 -232.061315)
			(xy 111.198193 -232.07007) (xy 111.170212 -232.070656) (xy 111.149246 -232.070336) (xy 111.107609 -232.065365)
			(xy 111.087154 -232.06075) (xy 111.059722 -232.054146) (xy 110.96625 -232.147618) (xy 110.9557 -232.159001)
			(xy 110.941421 -232.18654) (xy 110.936056 -232.217093) (xy 110.940098 -232.247849) (xy 110.953175 -232.275978)
			(xy 110.963202 -232.287826) (xy 110.980693 -232.307633) (xy 111.010231 -232.351446) (xy 111.032966 -232.399145)
			(xy 111.048398 -232.449681) (xy 111.056188 -232.501944) (xy 111.056674 -232.528364) (xy 111.056181 -232.555013)
			(xy 111.284756 -232.555013) (xy 111.284756 -232.501715) (xy 111.292699 -232.449011) (xy 111.308409 -232.398081)
			(xy 111.331535 -232.35006) (xy 111.361559 -232.306023) (xy 111.397811 -232.266952) (xy 111.439482 -232.233721)
			(xy 111.48564 -232.207072) (xy 111.535254 -232.1876) (xy 111.587216 -232.17574) (xy 111.640366 -232.171757)
			(xy 111.693516 -232.17574) (xy 111.745478 -232.1876) (xy 111.795092 -232.207072) (xy 111.84125 -232.233721)
			(xy 111.882921 -232.266952) (xy 111.919173 -232.306023) (xy 111.949197 -232.35006) (xy 111.972323 -232.398081)
			(xy 111.988033 -232.449011) (xy 111.995976 -232.501715) (xy 111.996474 -232.528364) (xy 111.995976 -232.555013)
			(xy 112.224556 -232.555013) (xy 112.224556 -232.501715) (xy 112.232499 -232.449011) (xy 112.248209 -232.398081)
			(xy 112.271335 -232.35006) (xy 112.301359 -232.306023) (xy 112.337611 -232.266952) (xy 112.379282 -232.233721)
			(xy 112.42544 -232.207072) (xy 112.475054 -232.1876) (xy 112.527016 -232.17574) (xy 112.580166 -232.171757)
			(xy 112.633316 -232.17574) (xy 112.685278 -232.1876) (xy 112.734892 -232.207072) (xy 112.78105 -232.233721)
			(xy 112.822721 -232.266952) (xy 112.858973 -232.306023) (xy 112.888997 -232.35006) (xy 112.912123 -232.398081)
			(xy 112.927833 -232.449011) (xy 112.935776 -232.501715) (xy 112.936274 -232.528364) (xy 112.935776 -232.555013)
			(xy 113.164356 -232.555013) (xy 113.164356 -232.501715) (xy 113.172299 -232.449011) (xy 113.188009 -232.398081)
			(xy 113.211135 -232.35006) (xy 113.241159 -232.306023) (xy 113.277411 -232.266952) (xy 113.319082 -232.233721)
			(xy 113.36524 -232.207072) (xy 113.414854 -232.1876) (xy 113.466816 -232.17574) (xy 113.519966 -232.171757)
			(xy 113.573116 -232.17574) (xy 113.625078 -232.1876) (xy 113.674692 -232.207072) (xy 113.72085 -232.233721)
			(xy 113.762521 -232.266952) (xy 113.798773 -232.306023) (xy 113.828797 -232.35006) (xy 113.851923 -232.398081)
			(xy 113.867633 -232.449011) (xy 113.875576 -232.501715) (xy 113.876074 -232.528364) (xy 113.875576 -232.555013)
			(xy 114.104156 -232.555013) (xy 114.104156 -232.501715) (xy 114.112099 -232.449011) (xy 114.127809 -232.398081)
			(xy 114.150935 -232.35006) (xy 114.180959 -232.306023) (xy 114.217211 -232.266952) (xy 114.258882 -232.233721)
			(xy 114.30504 -232.207072) (xy 114.354654 -232.1876) (xy 114.406616 -232.17574) (xy 114.459766 -232.171757)
			(xy 114.512916 -232.17574) (xy 114.564878 -232.1876) (xy 114.614492 -232.207072) (xy 114.66065 -232.233721)
			(xy 114.702321 -232.266952) (xy 114.738573 -232.306023) (xy 114.768597 -232.35006) (xy 114.791723 -232.398081)
			(xy 114.807433 -232.449011) (xy 114.815376 -232.501715) (xy 114.815874 -232.528364) (xy 114.815376 -232.555013)
			(xy 115.043956 -232.555013) (xy 115.043956 -232.501715) (xy 115.051899 -232.449011) (xy 115.067609 -232.398081)
			(xy 115.090735 -232.35006) (xy 115.120759 -232.306023) (xy 115.157011 -232.266952) (xy 115.198682 -232.233721)
			(xy 115.24484 -232.207072) (xy 115.294454 -232.1876) (xy 115.346416 -232.17574) (xy 115.399566 -232.171757)
			(xy 115.452716 -232.17574) (xy 115.504678 -232.1876) (xy 115.554292 -232.207072) (xy 115.60045 -232.233721)
			(xy 115.642121 -232.266952) (xy 115.678373 -232.306023) (xy 115.708397 -232.35006) (xy 115.731523 -232.398081)
			(xy 115.747233 -232.449011) (xy 115.755176 -232.501715) (xy 115.755674 -232.528364) (xy 115.755176 -232.555013)
			(xy 115.983756 -232.555013) (xy 115.983756 -232.501715) (xy 115.991699 -232.449011) (xy 116.007409 -232.398081)
			(xy 116.030535 -232.35006) (xy 116.060559 -232.306023) (xy 116.096811 -232.266952) (xy 116.138482 -232.233721)
			(xy 116.18464 -232.207072) (xy 116.234254 -232.1876) (xy 116.286216 -232.17574) (xy 116.339366 -232.171757)
			(xy 116.392516 -232.17574) (xy 116.444478 -232.1876) (xy 116.494092 -232.207072) (xy 116.54025 -232.233721)
			(xy 116.581921 -232.266952) (xy 116.618173 -232.306023) (xy 116.648197 -232.35006) (xy 116.671323 -232.398081)
			(xy 116.687033 -232.449011) (xy 116.694976 -232.501715) (xy 116.695474 -232.528364) (xy 116.694976 -232.555013)
			(xy 116.923556 -232.555013) (xy 116.923556 -232.501715) (xy 116.931499 -232.449011) (xy 116.947209 -232.398081)
			(xy 116.970335 -232.35006) (xy 117.000359 -232.306023) (xy 117.036611 -232.266952) (xy 117.078282 -232.233721)
			(xy 117.12444 -232.207072) (xy 117.174054 -232.1876) (xy 117.226016 -232.17574) (xy 117.279166 -232.171757)
			(xy 117.332316 -232.17574) (xy 117.384278 -232.1876) (xy 117.433892 -232.207072) (xy 117.48005 -232.233721)
			(xy 117.521721 -232.266952) (xy 117.557973 -232.306023) (xy 117.587997 -232.35006) (xy 117.611123 -232.398081)
			(xy 117.626833 -232.449011) (xy 117.634776 -232.501715) (xy 117.635274 -232.528364) (xy 117.634776 -232.555013)
			(xy 117.863356 -232.555013) (xy 117.863356 -232.501715) (xy 117.871299 -232.449011) (xy 117.887009 -232.398081)
			(xy 117.910135 -232.35006) (xy 117.940159 -232.306023) (xy 117.976411 -232.266952) (xy 118.018082 -232.233721)
			(xy 118.06424 -232.207072) (xy 118.113854 -232.1876) (xy 118.165816 -232.17574) (xy 118.218966 -232.171757)
			(xy 118.272116 -232.17574) (xy 118.324078 -232.1876) (xy 118.373692 -232.207072) (xy 118.41985 -232.233721)
			(xy 118.461521 -232.266952) (xy 118.497773 -232.306023) (xy 118.527797 -232.35006) (xy 118.550923 -232.398081)
			(xy 118.566633 -232.449011) (xy 118.574576 -232.501715) (xy 118.575074 -232.528364) (xy 118.574576 -232.555013)
			(xy 118.803156 -232.555013) (xy 118.803156 -232.501715) (xy 118.811099 -232.449011) (xy 118.826809 -232.398081)
			(xy 118.849935 -232.35006) (xy 118.879959 -232.306023) (xy 118.916211 -232.266952) (xy 118.957882 -232.233721)
			(xy 119.00404 -232.207072) (xy 119.053654 -232.1876) (xy 119.105616 -232.17574) (xy 119.158766 -232.171757)
			(xy 119.211916 -232.17574) (xy 119.263878 -232.1876) (xy 119.313492 -232.207072) (xy 119.35965 -232.233721)
			(xy 119.401321 -232.266952) (xy 119.437573 -232.306023) (xy 119.467597 -232.35006) (xy 119.490723 -232.398081)
			(xy 119.506433 -232.449011) (xy 119.514376 -232.501715) (xy 119.514874 -232.528364) (xy 119.514376 -232.555013)
			(xy 119.742702 -232.555013) (xy 119.742702 -232.501715) (xy 119.750645 -232.449011) (xy 119.766355 -232.398081)
			(xy 119.789481 -232.35006) (xy 119.819505 -232.306023) (xy 119.855757 -232.266952) (xy 119.897428 -232.233721)
			(xy 119.943586 -232.207072) (xy 119.9932 -232.1876) (xy 120.045162 -232.17574) (xy 120.098312 -232.171757)
			(xy 120.151462 -232.17574) (xy 120.203424 -232.1876) (xy 120.253038 -232.207072) (xy 120.299196 -232.233721)
			(xy 120.340867 -232.266952) (xy 120.377119 -232.306023) (xy 120.407143 -232.35006) (xy 120.430269 -232.398081)
			(xy 120.445979 -232.449011) (xy 120.453922 -232.501715) (xy 120.45442 -232.528364) (xy 120.453922 -232.555013)
			(xy 120.682756 -232.555013) (xy 120.682756 -232.501715) (xy 120.690699 -232.449011) (xy 120.706409 -232.398081)
			(xy 120.729535 -232.35006) (xy 120.759559 -232.306023) (xy 120.795811 -232.266952) (xy 120.837482 -232.233721)
			(xy 120.88364 -232.207072) (xy 120.933254 -232.1876) (xy 120.985216 -232.17574) (xy 121.038366 -232.171757)
			(xy 121.091516 -232.17574) (xy 121.143478 -232.1876) (xy 121.193092 -232.207072) (xy 121.23925 -232.233721)
			(xy 121.280921 -232.266952) (xy 121.317173 -232.306023) (xy 121.347197 -232.35006) (xy 121.370323 -232.398081)
			(xy 121.386033 -232.449011) (xy 121.393976 -232.501715) (xy 121.394474 -232.528364) (xy 121.393976 -232.555013)
			(xy 121.622556 -232.555013) (xy 121.622556 -232.501715) (xy 121.630499 -232.449011) (xy 121.646209 -232.398081)
			(xy 121.669335 -232.35006) (xy 121.699359 -232.306023) (xy 121.735611 -232.266952) (xy 121.777282 -232.233721)
			(xy 121.82344 -232.207072) (xy 121.873054 -232.1876) (xy 121.925016 -232.17574) (xy 121.978166 -232.171757)
			(xy 122.031316 -232.17574) (xy 122.083278 -232.1876) (xy 122.132892 -232.207072) (xy 122.17905 -232.233721)
			(xy 122.220721 -232.266952) (xy 122.256973 -232.306023) (xy 122.286997 -232.35006) (xy 122.310123 -232.398081)
			(xy 122.325833 -232.449011) (xy 122.333776 -232.501715) (xy 122.334274 -232.528364) (xy 122.333776 -232.555013)
			(xy 122.562356 -232.555013) (xy 122.562356 -232.501715) (xy 122.570299 -232.449011) (xy 122.586009 -232.398081)
			(xy 122.609135 -232.35006) (xy 122.639159 -232.306023) (xy 122.675411 -232.266952) (xy 122.717082 -232.233721)
			(xy 122.76324 -232.207072) (xy 122.812854 -232.1876) (xy 122.864816 -232.17574) (xy 122.917966 -232.171757)
			(xy 122.971116 -232.17574) (xy 123.023078 -232.1876) (xy 123.072692 -232.207072) (xy 123.11885 -232.233721)
			(xy 123.160521 -232.266952) (xy 123.196773 -232.306023) (xy 123.226797 -232.35006) (xy 123.249923 -232.398081)
			(xy 123.265633 -232.449011) (xy 123.273576 -232.501715) (xy 123.274074 -232.528364) (xy 123.273576 -232.555013)
			(xy 123.502156 -232.555013) (xy 123.502156 -232.501715) (xy 123.510099 -232.449011) (xy 123.525809 -232.398081)
			(xy 123.548935 -232.35006) (xy 123.578959 -232.306023) (xy 123.615211 -232.266952) (xy 123.656882 -232.233721)
			(xy 123.70304 -232.207072) (xy 123.752654 -232.1876) (xy 123.804616 -232.17574) (xy 123.857766 -232.171757)
			(xy 123.910916 -232.17574) (xy 123.962878 -232.1876) (xy 124.012492 -232.207072) (xy 124.05865 -232.233721)
			(xy 124.100321 -232.266952) (xy 124.136573 -232.306023) (xy 124.166597 -232.35006) (xy 124.189723 -232.398081)
			(xy 124.205433 -232.449011) (xy 124.213376 -232.501715) (xy 124.213874 -232.528364) (xy 124.213376 -232.555013)
			(xy 124.441956 -232.555013) (xy 124.441956 -232.501715) (xy 124.449899 -232.449011) (xy 124.465609 -232.398081)
			(xy 124.488735 -232.35006) (xy 124.518759 -232.306023) (xy 124.555011 -232.266952) (xy 124.596682 -232.233721)
			(xy 124.64284 -232.207072) (xy 124.692454 -232.1876) (xy 124.744416 -232.17574) (xy 124.797566 -232.171757)
			(xy 124.850716 -232.17574) (xy 124.902678 -232.1876) (xy 124.952292 -232.207072) (xy 124.99845 -232.233721)
			(xy 125.040121 -232.266952) (xy 125.076373 -232.306023) (xy 125.106397 -232.35006) (xy 125.129523 -232.398081)
			(xy 125.145233 -232.449011) (xy 125.153176 -232.501715) (xy 125.153674 -232.528364) (xy 125.153176 -232.555013)
			(xy 125.381756 -232.555013) (xy 125.381756 -232.501715) (xy 125.389699 -232.449011) (xy 125.405409 -232.398081)
			(xy 125.428535 -232.35006) (xy 125.458559 -232.306023) (xy 125.494811 -232.266952) (xy 125.536482 -232.233721)
			(xy 125.58264 -232.207072) (xy 125.632254 -232.1876) (xy 125.684216 -232.17574) (xy 125.737366 -232.171757)
			(xy 125.790516 -232.17574) (xy 125.842478 -232.1876) (xy 125.892092 -232.207072) (xy 125.93825 -232.233721)
			(xy 125.979921 -232.266952) (xy 126.016173 -232.306023) (xy 126.046197 -232.35006) (xy 126.069323 -232.398081)
			(xy 126.085033 -232.449011) (xy 126.092976 -232.501715) (xy 126.093474 -232.528364) (xy 126.092976 -232.555013)
			(xy 126.321302 -232.555013) (xy 126.321302 -232.501715) (xy 126.329245 -232.449011) (xy 126.344955 -232.398081)
			(xy 126.368081 -232.35006) (xy 126.398105 -232.306023) (xy 126.434357 -232.266952) (xy 126.476028 -232.233721)
			(xy 126.522186 -232.207072) (xy 126.5718 -232.1876) (xy 126.623762 -232.17574) (xy 126.676912 -232.171757)
			(xy 126.730062 -232.17574) (xy 126.782024 -232.1876) (xy 126.831638 -232.207072) (xy 126.877796 -232.233721)
			(xy 126.919467 -232.266952) (xy 126.955719 -232.306023) (xy 126.985743 -232.35006) (xy 127.008869 -232.398081)
			(xy 127.024579 -232.449011) (xy 127.032522 -232.501715) (xy 127.03302 -232.528364) (xy 127.032522 -232.555013)
			(xy 127.261356 -232.555013) (xy 127.261356 -232.501715) (xy 127.269299 -232.449011) (xy 127.285009 -232.398081)
			(xy 127.308135 -232.35006) (xy 127.338159 -232.306023) (xy 127.374411 -232.266952) (xy 127.416082 -232.233721)
			(xy 127.46224 -232.207072) (xy 127.511854 -232.1876) (xy 127.563816 -232.17574) (xy 127.616966 -232.171757)
			(xy 127.670116 -232.17574) (xy 127.722078 -232.1876) (xy 127.771692 -232.207072) (xy 127.81785 -232.233721)
			(xy 127.859521 -232.266952) (xy 127.895773 -232.306023) (xy 127.925797 -232.35006) (xy 127.948923 -232.398081)
			(xy 127.964633 -232.449011) (xy 127.972576 -232.501715) (xy 127.973074 -232.528364) (xy 127.972576 -232.555013)
			(xy 128.201156 -232.555013) (xy 128.201156 -232.501715) (xy 128.209099 -232.449011) (xy 128.224809 -232.398081)
			(xy 128.247935 -232.35006) (xy 128.277959 -232.306023) (xy 128.314211 -232.266952) (xy 128.355882 -232.233721)
			(xy 128.40204 -232.207072) (xy 128.451654 -232.1876) (xy 128.503616 -232.17574) (xy 128.556766 -232.171757)
			(xy 128.609916 -232.17574) (xy 128.661878 -232.1876) (xy 128.711492 -232.207072) (xy 128.75765 -232.233721)
			(xy 128.799321 -232.266952) (xy 128.835573 -232.306023) (xy 128.865597 -232.35006) (xy 128.888723 -232.398081)
			(xy 128.904433 -232.449011) (xy 128.912376 -232.501715) (xy 128.912874 -232.528364) (xy 128.912376 -232.555013)
			(xy 129.140956 -232.555013) (xy 129.140956 -232.501715) (xy 129.148899 -232.449011) (xy 129.164609 -232.398081)
			(xy 129.187735 -232.35006) (xy 129.217759 -232.306023) (xy 129.254011 -232.266952) (xy 129.295682 -232.233721)
			(xy 129.34184 -232.207072) (xy 129.391454 -232.1876) (xy 129.443416 -232.17574) (xy 129.496566 -232.171757)
			(xy 129.549716 -232.17574) (xy 129.601678 -232.1876) (xy 129.651292 -232.207072) (xy 129.69745 -232.233721)
			(xy 129.739121 -232.266952) (xy 129.775373 -232.306023) (xy 129.805397 -232.35006) (xy 129.828523 -232.398081)
			(xy 129.844233 -232.449011) (xy 129.852176 -232.501715) (xy 129.852674 -232.528364) (xy 129.852176 -232.555013)
			(xy 130.080756 -232.555013) (xy 130.080756 -232.501715) (xy 130.088699 -232.449011) (xy 130.104409 -232.398081)
			(xy 130.127535 -232.35006) (xy 130.157559 -232.306023) (xy 130.193811 -232.266952) (xy 130.235482 -232.233721)
			(xy 130.28164 -232.207072) (xy 130.331254 -232.1876) (xy 130.383216 -232.17574) (xy 130.436366 -232.171757)
			(xy 130.489516 -232.17574) (xy 130.541478 -232.1876) (xy 130.591092 -232.207072) (xy 130.63725 -232.233721)
			(xy 130.678921 -232.266952) (xy 130.715173 -232.306023) (xy 130.745197 -232.35006) (xy 130.768323 -232.398081)
			(xy 130.784033 -232.449011) (xy 130.791976 -232.501715) (xy 130.792474 -232.528364) (xy 130.791976 -232.555013)
			(xy 131.020556 -232.555013) (xy 131.020556 -232.501715) (xy 131.028499 -232.449011) (xy 131.044209 -232.398081)
			(xy 131.067335 -232.35006) (xy 131.097359 -232.306023) (xy 131.133611 -232.266952) (xy 131.175282 -232.233721)
			(xy 131.22144 -232.207072) (xy 131.271054 -232.1876) (xy 131.323016 -232.17574) (xy 131.376166 -232.171757)
			(xy 131.429316 -232.17574) (xy 131.481278 -232.1876) (xy 131.530892 -232.207072) (xy 131.57705 -232.233721)
			(xy 131.618721 -232.266952) (xy 131.654973 -232.306023) (xy 131.684997 -232.35006) (xy 131.708123 -232.398081)
			(xy 131.723833 -232.449011) (xy 131.731776 -232.501715) (xy 131.732274 -232.528364) (xy 131.731776 -232.555013)
			(xy 131.960356 -232.555013) (xy 131.960356 -232.501715) (xy 131.968299 -232.449011) (xy 131.984009 -232.398081)
			(xy 132.007135 -232.35006) (xy 132.037159 -232.306023) (xy 132.073411 -232.266952) (xy 132.115082 -232.233721)
			(xy 132.16124 -232.207072) (xy 132.210854 -232.1876) (xy 132.262816 -232.17574) (xy 132.315966 -232.171757)
			(xy 132.369116 -232.17574) (xy 132.421078 -232.1876) (xy 132.470692 -232.207072) (xy 132.51685 -232.233721)
			(xy 132.558521 -232.266952) (xy 132.594773 -232.306023) (xy 132.624797 -232.35006) (xy 132.647923 -232.398081)
			(xy 132.663633 -232.449011) (xy 132.671576 -232.501715) (xy 132.672074 -232.528364) (xy 132.671576 -232.555013)
			(xy 132.899902 -232.555013) (xy 132.899902 -232.501715) (xy 132.907845 -232.449011) (xy 132.923555 -232.398081)
			(xy 132.946681 -232.35006) (xy 132.976705 -232.306023) (xy 133.012957 -232.266952) (xy 133.054628 -232.233721)
			(xy 133.100786 -232.207072) (xy 133.1504 -232.1876) (xy 133.202362 -232.17574) (xy 133.255512 -232.171757)
			(xy 133.308662 -232.17574) (xy 133.360624 -232.1876) (xy 133.410238 -232.207072) (xy 133.456396 -232.233721)
			(xy 133.498067 -232.266952) (xy 133.534319 -232.306023) (xy 133.564343 -232.35006) (xy 133.587469 -232.398081)
			(xy 133.603179 -232.449011) (xy 133.611122 -232.501715) (xy 133.61162 -232.528364) (xy 133.611122 -232.555013)
			(xy 133.839956 -232.555013) (xy 133.839956 -232.501715) (xy 133.847899 -232.449011) (xy 133.863609 -232.398081)
			(xy 133.886735 -232.35006) (xy 133.916759 -232.306023) (xy 133.953011 -232.266952) (xy 133.994682 -232.233721)
			(xy 134.04084 -232.207072) (xy 134.090454 -232.1876) (xy 134.142416 -232.17574) (xy 134.195566 -232.171757)
			(xy 134.248716 -232.17574) (xy 134.300678 -232.1876) (xy 134.350292 -232.207072) (xy 134.39645 -232.233721)
			(xy 134.438121 -232.266952) (xy 134.474373 -232.306023) (xy 134.504397 -232.35006) (xy 134.527523 -232.398081)
			(xy 134.543233 -232.449011) (xy 134.551176 -232.501715) (xy 134.551674 -232.528364) (xy 134.551176 -232.555013)
			(xy 134.543233 -232.607717) (xy 134.527523 -232.658647) (xy 134.504397 -232.706668) (xy 134.474373 -232.750705)
			(xy 134.438121 -232.789776) (xy 134.39645 -232.823007) (xy 134.350292 -232.849656) (xy 134.300678 -232.869128)
			(xy 134.248716 -232.880988) (xy 134.195566 -232.884972) (xy 134.142416 -232.880988) (xy 134.090454 -232.869128)
			(xy 134.04084 -232.849656) (xy 133.994682 -232.823007) (xy 133.953011 -232.789776) (xy 133.916759 -232.750705)
			(xy 133.886735 -232.706668) (xy 133.863609 -232.658647) (xy 133.847899 -232.607717) (xy 133.839956 -232.555013)
			(xy 133.611122 -232.555013) (xy 133.603179 -232.607717) (xy 133.587469 -232.658647) (xy 133.564343 -232.706668)
			(xy 133.534319 -232.750705) (xy 133.498067 -232.789776) (xy 133.456396 -232.823007) (xy 133.410238 -232.849656)
			(xy 133.360624 -232.869128) (xy 133.308662 -232.880988) (xy 133.255512 -232.884972) (xy 133.202362 -232.880988)
			(xy 133.1504 -232.869128) (xy 133.100786 -232.849656) (xy 133.054628 -232.823007) (xy 133.012957 -232.789776)
			(xy 132.976705 -232.750705) (xy 132.946681 -232.706668) (xy 132.923555 -232.658647) (xy 132.907845 -232.607717)
			(xy 132.899902 -232.555013) (xy 132.671576 -232.555013) (xy 132.663633 -232.607717) (xy 132.647923 -232.658647)
			(xy 132.624797 -232.706668) (xy 132.594773 -232.750705) (xy 132.558521 -232.789776) (xy 132.51685 -232.823007)
			(xy 132.470692 -232.849656) (xy 132.421078 -232.869128) (xy 132.369116 -232.880988) (xy 132.315966 -232.884972)
			(xy 132.262816 -232.880988) (xy 132.210854 -232.869128) (xy 132.16124 -232.849656) (xy 132.115082 -232.823007)
			(xy 132.073411 -232.789776) (xy 132.037159 -232.750705) (xy 132.007135 -232.706668) (xy 131.984009 -232.658647)
			(xy 131.968299 -232.607717) (xy 131.960356 -232.555013) (xy 131.731776 -232.555013) (xy 131.723833 -232.607717)
			(xy 131.708123 -232.658647) (xy 131.684997 -232.706668) (xy 131.654973 -232.750705) (xy 131.618721 -232.789776)
			(xy 131.57705 -232.823007) (xy 131.530892 -232.849656) (xy 131.481278 -232.869128) (xy 131.429316 -232.880988)
			(xy 131.376166 -232.884972) (xy 131.323016 -232.880988) (xy 131.271054 -232.869128) (xy 131.22144 -232.849656)
			(xy 131.175282 -232.823007) (xy 131.133611 -232.789776) (xy 131.097359 -232.750705) (xy 131.067335 -232.706668)
			(xy 131.044209 -232.658647) (xy 131.028499 -232.607717) (xy 131.020556 -232.555013) (xy 130.791976 -232.555013)
			(xy 130.784033 -232.607717) (xy 130.768323 -232.658647) (xy 130.745197 -232.706668) (xy 130.715173 -232.750705)
			(xy 130.678921 -232.789776) (xy 130.63725 -232.823007) (xy 130.591092 -232.849656) (xy 130.541478 -232.869128)
			(xy 130.489516 -232.880988) (xy 130.436366 -232.884972) (xy 130.383216 -232.880988) (xy 130.331254 -232.869128)
			(xy 130.28164 -232.849656) (xy 130.235482 -232.823007) (xy 130.193811 -232.789776) (xy 130.157559 -232.750705)
			(xy 130.127535 -232.706668) (xy 130.104409 -232.658647) (xy 130.088699 -232.607717) (xy 130.080756 -232.555013)
			(xy 129.852176 -232.555013) (xy 129.844233 -232.607717) (xy 129.828523 -232.658647) (xy 129.805397 -232.706668)
			(xy 129.775373 -232.750705) (xy 129.739121 -232.789776) (xy 129.69745 -232.823007) (xy 129.651292 -232.849656)
			(xy 129.601678 -232.869128) (xy 129.549716 -232.880988) (xy 129.496566 -232.884972) (xy 129.443416 -232.880988)
			(xy 129.391454 -232.869128) (xy 129.34184 -232.849656) (xy 129.295682 -232.823007) (xy 129.254011 -232.789776)
			(xy 129.217759 -232.750705) (xy 129.187735 -232.706668) (xy 129.164609 -232.658647) (xy 129.148899 -232.607717)
			(xy 129.140956 -232.555013) (xy 128.912376 -232.555013) (xy 128.904433 -232.607717) (xy 128.888723 -232.658647)
			(xy 128.865597 -232.706668) (xy 128.835573 -232.750705) (xy 128.799321 -232.789776) (xy 128.75765 -232.823007)
			(xy 128.711492 -232.849656) (xy 128.661878 -232.869128) (xy 128.609916 -232.880988) (xy 128.556766 -232.884972)
			(xy 128.503616 -232.880988) (xy 128.451654 -232.869128) (xy 128.40204 -232.849656) (xy 128.355882 -232.823007)
			(xy 128.314211 -232.789776) (xy 128.277959 -232.750705) (xy 128.247935 -232.706668) (xy 128.224809 -232.658647)
			(xy 128.209099 -232.607717) (xy 128.201156 -232.555013) (xy 127.972576 -232.555013) (xy 127.964633 -232.607717)
			(xy 127.948923 -232.658647) (xy 127.925797 -232.706668) (xy 127.895773 -232.750705) (xy 127.859521 -232.789776)
			(xy 127.81785 -232.823007) (xy 127.771692 -232.849656) (xy 127.722078 -232.869128) (xy 127.670116 -232.880988)
			(xy 127.616966 -232.884972) (xy 127.563816 -232.880988) (xy 127.511854 -232.869128) (xy 127.46224 -232.849656)
			(xy 127.416082 -232.823007) (xy 127.374411 -232.789776) (xy 127.338159 -232.750705) (xy 127.308135 -232.706668)
			(xy 127.285009 -232.658647) (xy 127.269299 -232.607717) (xy 127.261356 -232.555013) (xy 127.032522 -232.555013)
			(xy 127.024579 -232.607717) (xy 127.008869 -232.658647) (xy 126.985743 -232.706668) (xy 126.955719 -232.750705)
			(xy 126.919467 -232.789776) (xy 126.877796 -232.823007) (xy 126.831638 -232.849656) (xy 126.782024 -232.869128)
			(xy 126.730062 -232.880988) (xy 126.676912 -232.884972) (xy 126.623762 -232.880988) (xy 126.5718 -232.869128)
			(xy 126.522186 -232.849656) (xy 126.476028 -232.823007) (xy 126.434357 -232.789776) (xy 126.398105 -232.750705)
			(xy 126.368081 -232.706668) (xy 126.344955 -232.658647) (xy 126.329245 -232.607717) (xy 126.321302 -232.555013)
			(xy 126.092976 -232.555013) (xy 126.085033 -232.607717) (xy 126.069323 -232.658647) (xy 126.046197 -232.706668)
			(xy 126.016173 -232.750705) (xy 125.979921 -232.789776) (xy 125.93825 -232.823007) (xy 125.892092 -232.849656)
			(xy 125.842478 -232.869128) (xy 125.790516 -232.880988) (xy 125.737366 -232.884972) (xy 125.684216 -232.880988)
			(xy 125.632254 -232.869128) (xy 125.58264 -232.849656) (xy 125.536482 -232.823007) (xy 125.494811 -232.789776)
			(xy 125.458559 -232.750705) (xy 125.428535 -232.706668) (xy 125.405409 -232.658647) (xy 125.389699 -232.607717)
			(xy 125.381756 -232.555013) (xy 125.153176 -232.555013) (xy 125.145233 -232.607717) (xy 125.129523 -232.658647)
			(xy 125.106397 -232.706668) (xy 125.076373 -232.750705) (xy 125.040121 -232.789776) (xy 124.99845 -232.823007)
			(xy 124.952292 -232.849656) (xy 124.902678 -232.869128) (xy 124.850716 -232.880988) (xy 124.797566 -232.884972)
			(xy 124.744416 -232.880988) (xy 124.692454 -232.869128) (xy 124.64284 -232.849656) (xy 124.596682 -232.823007)
			(xy 124.555011 -232.789776) (xy 124.518759 -232.750705) (xy 124.488735 -232.706668) (xy 124.465609 -232.658647)
			(xy 124.449899 -232.607717) (xy 124.441956 -232.555013) (xy 124.213376 -232.555013) (xy 124.205433 -232.607717)
			(xy 124.189723 -232.658647) (xy 124.166597 -232.706668) (xy 124.136573 -232.750705) (xy 124.100321 -232.789776)
			(xy 124.05865 -232.823007) (xy 124.012492 -232.849656) (xy 123.962878 -232.869128) (xy 123.910916 -232.880988)
			(xy 123.857766 -232.884972) (xy 123.804616 -232.880988) (xy 123.752654 -232.869128) (xy 123.70304 -232.849656)
			(xy 123.656882 -232.823007) (xy 123.615211 -232.789776) (xy 123.578959 -232.750705) (xy 123.548935 -232.706668)
			(xy 123.525809 -232.658647) (xy 123.510099 -232.607717) (xy 123.502156 -232.555013) (xy 123.273576 -232.555013)
			(xy 123.265633 -232.607717) (xy 123.249923 -232.658647) (xy 123.226797 -232.706668) (xy 123.196773 -232.750705)
			(xy 123.160521 -232.789776) (xy 123.11885 -232.823007) (xy 123.072692 -232.849656) (xy 123.023078 -232.869128)
			(xy 122.971116 -232.880988) (xy 122.917966 -232.884972) (xy 122.864816 -232.880988) (xy 122.812854 -232.869128)
			(xy 122.76324 -232.849656) (xy 122.717082 -232.823007) (xy 122.675411 -232.789776) (xy 122.639159 -232.750705)
			(xy 122.609135 -232.706668) (xy 122.586009 -232.658647) (xy 122.570299 -232.607717) (xy 122.562356 -232.555013)
			(xy 122.333776 -232.555013) (xy 122.325833 -232.607717) (xy 122.310123 -232.658647) (xy 122.286997 -232.706668)
			(xy 122.256973 -232.750705) (xy 122.220721 -232.789776) (xy 122.17905 -232.823007) (xy 122.132892 -232.849656)
			(xy 122.083278 -232.869128) (xy 122.031316 -232.880988) (xy 121.978166 -232.884972) (xy 121.925016 -232.880988)
			(xy 121.873054 -232.869128) (xy 121.82344 -232.849656) (xy 121.777282 -232.823007) (xy 121.735611 -232.789776)
			(xy 121.699359 -232.750705) (xy 121.669335 -232.706668) (xy 121.646209 -232.658647) (xy 121.630499 -232.607717)
			(xy 121.622556 -232.555013) (xy 121.393976 -232.555013) (xy 121.386033 -232.607717) (xy 121.370323 -232.658647)
			(xy 121.347197 -232.706668) (xy 121.317173 -232.750705) (xy 121.280921 -232.789776) (xy 121.23925 -232.823007)
			(xy 121.193092 -232.849656) (xy 121.143478 -232.869128) (xy 121.091516 -232.880988) (xy 121.038366 -232.884972)
			(xy 120.985216 -232.880988) (xy 120.933254 -232.869128) (xy 120.88364 -232.849656) (xy 120.837482 -232.823007)
			(xy 120.795811 -232.789776) (xy 120.759559 -232.750705) (xy 120.729535 -232.706668) (xy 120.706409 -232.658647)
			(xy 120.690699 -232.607717) (xy 120.682756 -232.555013) (xy 120.453922 -232.555013) (xy 120.445979 -232.607717)
			(xy 120.430269 -232.658647) (xy 120.407143 -232.706668) (xy 120.377119 -232.750705) (xy 120.340867 -232.789776)
			(xy 120.299196 -232.823007) (xy 120.253038 -232.849656) (xy 120.203424 -232.869128) (xy 120.151462 -232.880988)
			(xy 120.098312 -232.884972) (xy 120.045162 -232.880988) (xy 119.9932 -232.869128) (xy 119.943586 -232.849656)
			(xy 119.897428 -232.823007) (xy 119.855757 -232.789776) (xy 119.819505 -232.750705) (xy 119.789481 -232.706668)
			(xy 119.766355 -232.658647) (xy 119.750645 -232.607717) (xy 119.742702 -232.555013) (xy 119.514376 -232.555013)
			(xy 119.506433 -232.607717) (xy 119.490723 -232.658647) (xy 119.467597 -232.706668) (xy 119.437573 -232.750705)
			(xy 119.401321 -232.789776) (xy 119.35965 -232.823007) (xy 119.313492 -232.849656) (xy 119.263878 -232.869128)
			(xy 119.211916 -232.880988) (xy 119.158766 -232.884972) (xy 119.105616 -232.880988) (xy 119.053654 -232.869128)
			(xy 119.00404 -232.849656) (xy 118.957882 -232.823007) (xy 118.916211 -232.789776) (xy 118.879959 -232.750705)
			(xy 118.849935 -232.706668) (xy 118.826809 -232.658647) (xy 118.811099 -232.607717) (xy 118.803156 -232.555013)
			(xy 118.574576 -232.555013) (xy 118.566633 -232.607717) (xy 118.550923 -232.658647) (xy 118.527797 -232.706668)
			(xy 118.497773 -232.750705) (xy 118.461521 -232.789776) (xy 118.41985 -232.823007) (xy 118.373692 -232.849656)
			(xy 118.324078 -232.869128) (xy 118.272116 -232.880988) (xy 118.218966 -232.884972) (xy 118.165816 -232.880988)
			(xy 118.113854 -232.869128) (xy 118.06424 -232.849656) (xy 118.018082 -232.823007) (xy 117.976411 -232.789776)
			(xy 117.940159 -232.750705) (xy 117.910135 -232.706668) (xy 117.887009 -232.658647) (xy 117.871299 -232.607717)
			(xy 117.863356 -232.555013) (xy 117.634776 -232.555013) (xy 117.626833 -232.607717) (xy 117.611123 -232.658647)
			(xy 117.587997 -232.706668) (xy 117.557973 -232.750705) (xy 117.521721 -232.789776) (xy 117.48005 -232.823007)
			(xy 117.433892 -232.849656) (xy 117.384278 -232.869128) (xy 117.332316 -232.880988) (xy 117.279166 -232.884972)
			(xy 117.226016 -232.880988) (xy 117.174054 -232.869128) (xy 117.12444 -232.849656) (xy 117.078282 -232.823007)
			(xy 117.036611 -232.789776) (xy 117.000359 -232.750705) (xy 116.970335 -232.706668) (xy 116.947209 -232.658647)
			(xy 116.931499 -232.607717) (xy 116.923556 -232.555013) (xy 116.694976 -232.555013) (xy 116.687033 -232.607717)
			(xy 116.671323 -232.658647) (xy 116.648197 -232.706668) (xy 116.618173 -232.750705) (xy 116.581921 -232.789776)
			(xy 116.54025 -232.823007) (xy 116.494092 -232.849656) (xy 116.444478 -232.869128) (xy 116.392516 -232.880988)
			(xy 116.339366 -232.884972) (xy 116.286216 -232.880988) (xy 116.234254 -232.869128) (xy 116.18464 -232.849656)
			(xy 116.138482 -232.823007) (xy 116.096811 -232.789776) (xy 116.060559 -232.750705) (xy 116.030535 -232.706668)
			(xy 116.007409 -232.658647) (xy 115.991699 -232.607717) (xy 115.983756 -232.555013) (xy 115.755176 -232.555013)
			(xy 115.747233 -232.607717) (xy 115.731523 -232.658647) (xy 115.708397 -232.706668) (xy 115.678373 -232.750705)
			(xy 115.642121 -232.789776) (xy 115.60045 -232.823007) (xy 115.554292 -232.849656) (xy 115.504678 -232.869128)
			(xy 115.452716 -232.880988) (xy 115.399566 -232.884972) (xy 115.346416 -232.880988) (xy 115.294454 -232.869128)
			(xy 115.24484 -232.849656) (xy 115.198682 -232.823007) (xy 115.157011 -232.789776) (xy 115.120759 -232.750705)
			(xy 115.090735 -232.706668) (xy 115.067609 -232.658647) (xy 115.051899 -232.607717) (xy 115.043956 -232.555013)
			(xy 114.815376 -232.555013) (xy 114.807433 -232.607717) (xy 114.791723 -232.658647) (xy 114.768597 -232.706668)
			(xy 114.738573 -232.750705) (xy 114.702321 -232.789776) (xy 114.66065 -232.823007) (xy 114.614492 -232.849656)
			(xy 114.564878 -232.869128) (xy 114.512916 -232.880988) (xy 114.459766 -232.884972) (xy 114.406616 -232.880988)
			(xy 114.354654 -232.869128) (xy 114.30504 -232.849656) (xy 114.258882 -232.823007) (xy 114.217211 -232.789776)
			(xy 114.180959 -232.750705) (xy 114.150935 -232.706668) (xy 114.127809 -232.658647) (xy 114.112099 -232.607717)
			(xy 114.104156 -232.555013) (xy 113.875576 -232.555013) (xy 113.867633 -232.607717) (xy 113.851923 -232.658647)
			(xy 113.828797 -232.706668) (xy 113.798773 -232.750705) (xy 113.762521 -232.789776) (xy 113.72085 -232.823007)
			(xy 113.674692 -232.849656) (xy 113.625078 -232.869128) (xy 113.573116 -232.880988) (xy 113.519966 -232.884972)
			(xy 113.466816 -232.880988) (xy 113.414854 -232.869128) (xy 113.36524 -232.849656) (xy 113.319082 -232.823007)
			(xy 113.277411 -232.789776) (xy 113.241159 -232.750705) (xy 113.211135 -232.706668) (xy 113.188009 -232.658647)
			(xy 113.172299 -232.607717) (xy 113.164356 -232.555013) (xy 112.935776 -232.555013) (xy 112.927833 -232.607717)
			(xy 112.912123 -232.658647) (xy 112.888997 -232.706668) (xy 112.858973 -232.750705) (xy 112.822721 -232.789776)
			(xy 112.78105 -232.823007) (xy 112.734892 -232.849656) (xy 112.685278 -232.869128) (xy 112.633316 -232.880988)
			(xy 112.580166 -232.884972) (xy 112.527016 -232.880988) (xy 112.475054 -232.869128) (xy 112.42544 -232.849656)
			(xy 112.379282 -232.823007) (xy 112.337611 -232.789776) (xy 112.301359 -232.750705) (xy 112.271335 -232.706668)
			(xy 112.248209 -232.658647) (xy 112.232499 -232.607717) (xy 112.224556 -232.555013) (xy 111.995976 -232.555013)
			(xy 111.988033 -232.607717) (xy 111.972323 -232.658647) (xy 111.949197 -232.706668) (xy 111.919173 -232.750705)
			(xy 111.882921 -232.789776) (xy 111.84125 -232.823007) (xy 111.795092 -232.849656) (xy 111.745478 -232.869128)
			(xy 111.693516 -232.880988) (xy 111.640366 -232.884972) (xy 111.587216 -232.880988) (xy 111.535254 -232.869128)
			(xy 111.48564 -232.849656) (xy 111.439482 -232.823007) (xy 111.397811 -232.789776) (xy 111.361559 -232.750705)
			(xy 111.331535 -232.706668) (xy 111.308409 -232.658647) (xy 111.292699 -232.607717) (xy 111.284756 -232.555013)
			(xy 111.056181 -232.555013) (xy 111.056156 -232.55635) (xy 111.047405 -232.611634) (xy 111.030111 -232.664868)
			(xy 111.004703 -232.714741) (xy 110.971804 -232.760024) (xy 110.932226 -232.799603) (xy 110.886943 -232.832502)
			(xy 110.83707 -232.857911) (xy 110.783836 -232.875204) (xy 110.728552 -232.883956) (xy 110.700566 -232.884472)
			(xy 110.674147 -232.88399) (xy 110.621888 -232.876183) (xy 110.571354 -232.860745) (xy 110.523654 -232.838015)
			(xy 110.479833 -232.808491) (xy 110.460028 -232.791) (xy 110.448208 -232.780923) (xy 110.420072 -232.767803)
			(xy 110.389294 -232.763746) (xy 110.358719 -232.769129) (xy 110.331177 -232.783453) (xy 110.31982 -232.794048)
			(xy 110.283752 -232.830116) (xy 110.273489 -232.841207) (xy 110.259375 -232.867908) (xy 110.253679 -232.897568)
			(xy 110.256901 -232.927597) (xy 110.268758 -232.955374) (xy 110.288215 -232.978473) (xy 110.313573 -232.994877)
			(xy 110.327948 -232.999534) (xy 110.352474 -233.006955) (xy 110.399256 -233.027863) (xy 110.442557 -233.055262)
			(xy 110.481482 -233.088586) (xy 110.515226 -233.127148) (xy 110.543093 -233.170149) (xy 110.564507 -233.216702)
			(xy 110.579024 -233.265844) (xy 110.586345 -233.316559) (xy 110.586774 -233.34218) (xy 110.58628 -233.368829)
			(xy 110.814602 -233.368829) (xy 110.814602 -233.315531) (xy 110.822545 -233.262827) (xy 110.838255 -233.211897)
			(xy 110.861381 -233.163876) (xy 110.891405 -233.119839) (xy 110.927657 -233.080768) (xy 110.969328 -233.047537)
			(xy 111.015486 -233.020888) (xy 111.0651 -233.001416) (xy 111.117062 -232.989556) (xy 111.170212 -232.985573)
			(xy 111.223362 -232.989556) (xy 111.275324 -233.001416) (xy 111.324938 -233.020888) (xy 111.371096 -233.047537)
			(xy 111.412767 -233.080768) (xy 111.449019 -233.119839) (xy 111.479043 -233.163876) (xy 111.502169 -233.211897)
			(xy 111.517879 -233.262827) (xy 111.525822 -233.315531) (xy 111.52632 -233.34218) (xy 111.525822 -233.368829)
			(xy 111.754402 -233.368829) (xy 111.754402 -233.315531) (xy 111.762345 -233.262827) (xy 111.778055 -233.211897)
			(xy 111.801181 -233.163876) (xy 111.831205 -233.119839) (xy 111.867457 -233.080768) (xy 111.909128 -233.047537)
			(xy 111.955286 -233.020888) (xy 112.0049 -233.001416) (xy 112.056862 -232.989556) (xy 112.110012 -232.985573)
			(xy 112.163162 -232.989556) (xy 112.215124 -233.001416) (xy 112.264738 -233.020888) (xy 112.310896 -233.047537)
			(xy 112.352567 -233.080768) (xy 112.388819 -233.119839) (xy 112.418843 -233.163876) (xy 112.441969 -233.211897)
			(xy 112.457679 -233.262827) (xy 112.465622 -233.315531) (xy 112.46612 -233.34218) (xy 112.465622 -233.368829)
			(xy 112.694202 -233.368829) (xy 112.694202 -233.315531) (xy 112.702145 -233.262827) (xy 112.717855 -233.211897)
			(xy 112.740981 -233.163876) (xy 112.771005 -233.119839) (xy 112.807257 -233.080768) (xy 112.848928 -233.047537)
			(xy 112.895086 -233.020888) (xy 112.9447 -233.001416) (xy 112.996662 -232.989556) (xy 113.049812 -232.985573)
			(xy 113.102962 -232.989556) (xy 113.154924 -233.001416) (xy 113.204538 -233.020888) (xy 113.250696 -233.047537)
			(xy 113.292367 -233.080768) (xy 113.328619 -233.119839) (xy 113.358643 -233.163876) (xy 113.381769 -233.211897)
			(xy 113.397479 -233.262827) (xy 113.405422 -233.315531) (xy 113.40592 -233.34218) (xy 113.405422 -233.368829)
			(xy 113.634256 -233.368829) (xy 113.634256 -233.315531) (xy 113.642199 -233.262827) (xy 113.657909 -233.211897)
			(xy 113.681035 -233.163876) (xy 113.711059 -233.119839) (xy 113.747311 -233.080768) (xy 113.788982 -233.047537)
			(xy 113.83514 -233.020888) (xy 113.884754 -233.001416) (xy 113.936716 -232.989556) (xy 113.989866 -232.985573)
			(xy 114.043016 -232.989556) (xy 114.094978 -233.001416) (xy 114.144592 -233.020888) (xy 114.19075 -233.047537)
			(xy 114.232421 -233.080768) (xy 114.268673 -233.119839) (xy 114.298697 -233.163876) (xy 114.321823 -233.211897)
			(xy 114.337533 -233.262827) (xy 114.345476 -233.315531) (xy 114.345974 -233.34218) (xy 114.345476 -233.368829)
			(xy 114.573802 -233.368829) (xy 114.573802 -233.315531) (xy 114.581745 -233.262827) (xy 114.597455 -233.211897)
			(xy 114.620581 -233.163876) (xy 114.650605 -233.119839) (xy 114.686857 -233.080768) (xy 114.728528 -233.047537)
			(xy 114.774686 -233.020888) (xy 114.8243 -233.001416) (xy 114.876262 -232.989556) (xy 114.929412 -232.985573)
			(xy 114.982562 -232.989556) (xy 115.034524 -233.001416) (xy 115.084138 -233.020888) (xy 115.130296 -233.047537)
			(xy 115.171967 -233.080768) (xy 115.208219 -233.119839) (xy 115.238243 -233.163876) (xy 115.261369 -233.211897)
			(xy 115.277079 -233.262827) (xy 115.285022 -233.315531) (xy 115.28552 -233.34218) (xy 115.285022 -233.368829)
			(xy 115.513602 -233.368829) (xy 115.513602 -233.315531) (xy 115.521545 -233.262827) (xy 115.537255 -233.211897)
			(xy 115.560381 -233.163876) (xy 115.590405 -233.119839) (xy 115.626657 -233.080768) (xy 115.668328 -233.047537)
			(xy 115.714486 -233.020888) (xy 115.7641 -233.001416) (xy 115.816062 -232.989556) (xy 115.869212 -232.985573)
			(xy 115.922362 -232.989556) (xy 115.974324 -233.001416) (xy 116.023938 -233.020888) (xy 116.070096 -233.047537)
			(xy 116.111767 -233.080768) (xy 116.148019 -233.119839) (xy 116.178043 -233.163876) (xy 116.201169 -233.211897)
			(xy 116.216879 -233.262827) (xy 116.224822 -233.315531) (xy 116.22532 -233.34218) (xy 116.224822 -233.368829)
			(xy 116.453402 -233.368829) (xy 116.453402 -233.315531) (xy 116.461345 -233.262827) (xy 116.477055 -233.211897)
			(xy 116.500181 -233.163876) (xy 116.530205 -233.119839) (xy 116.566457 -233.080768) (xy 116.608128 -233.047537)
			(xy 116.654286 -233.020888) (xy 116.7039 -233.001416) (xy 116.755862 -232.989556) (xy 116.809012 -232.985573)
			(xy 116.862162 -232.989556) (xy 116.914124 -233.001416) (xy 116.963738 -233.020888) (xy 117.009896 -233.047537)
			(xy 117.051567 -233.080768) (xy 117.087819 -233.119839) (xy 117.117843 -233.163876) (xy 117.140969 -233.211897)
			(xy 117.156679 -233.262827) (xy 117.164622 -233.315531) (xy 117.16512 -233.34218) (xy 117.164622 -233.368829)
			(xy 117.393202 -233.368829) (xy 117.393202 -233.315531) (xy 117.401145 -233.262827) (xy 117.416855 -233.211897)
			(xy 117.439981 -233.163876) (xy 117.470005 -233.119839) (xy 117.506257 -233.080768) (xy 117.547928 -233.047537)
			(xy 117.594086 -233.020888) (xy 117.6437 -233.001416) (xy 117.695662 -232.989556) (xy 117.748812 -232.985573)
			(xy 117.801962 -232.989556) (xy 117.853924 -233.001416) (xy 117.903538 -233.020888) (xy 117.949696 -233.047537)
			(xy 117.991367 -233.080768) (xy 118.027619 -233.119839) (xy 118.057643 -233.163876) (xy 118.080769 -233.211897)
			(xy 118.096479 -233.262827) (xy 118.104422 -233.315531) (xy 118.10492 -233.34218) (xy 118.104422 -233.368829)
			(xy 118.333002 -233.368829) (xy 118.333002 -233.315531) (xy 118.340945 -233.262827) (xy 118.356655 -233.211897)
			(xy 118.379781 -233.163876) (xy 118.409805 -233.119839) (xy 118.446057 -233.080768) (xy 118.487728 -233.047537)
			(xy 118.533886 -233.020888) (xy 118.5835 -233.001416) (xy 118.635462 -232.989556) (xy 118.688612 -232.985573)
			(xy 118.741762 -232.989556) (xy 118.793724 -233.001416) (xy 118.843338 -233.020888) (xy 118.889496 -233.047537)
			(xy 118.931167 -233.080768) (xy 118.967419 -233.119839) (xy 118.997443 -233.163876) (xy 119.020569 -233.211897)
			(xy 119.036279 -233.262827) (xy 119.044222 -233.315531) (xy 119.04472 -233.34218) (xy 119.044222 -233.368829)
			(xy 119.272802 -233.368829) (xy 119.272802 -233.315531) (xy 119.280745 -233.262827) (xy 119.296455 -233.211897)
			(xy 119.319581 -233.163876) (xy 119.349605 -233.119839) (xy 119.385857 -233.080768) (xy 119.427528 -233.047537)
			(xy 119.473686 -233.020888) (xy 119.5233 -233.001416) (xy 119.575262 -232.989556) (xy 119.628412 -232.985573)
			(xy 119.681562 -232.989556) (xy 119.733524 -233.001416) (xy 119.783138 -233.020888) (xy 119.829296 -233.047537)
			(xy 119.870967 -233.080768) (xy 119.907219 -233.119839) (xy 119.937243 -233.163876) (xy 119.960369 -233.211897)
			(xy 119.976079 -233.262827) (xy 119.984022 -233.315531) (xy 119.98452 -233.34218) (xy 119.984022 -233.368829)
			(xy 120.212602 -233.368829) (xy 120.212602 -233.315531) (xy 120.220545 -233.262827) (xy 120.236255 -233.211897)
			(xy 120.259381 -233.163876) (xy 120.289405 -233.119839) (xy 120.325657 -233.080768) (xy 120.367328 -233.047537)
			(xy 120.413486 -233.020888) (xy 120.4631 -233.001416) (xy 120.515062 -232.989556) (xy 120.568212 -232.985573)
			(xy 120.621362 -232.989556) (xy 120.673324 -233.001416) (xy 120.722938 -233.020888) (xy 120.769096 -233.047537)
			(xy 120.810767 -233.080768) (xy 120.847019 -233.119839) (xy 120.877043 -233.163876) (xy 120.900169 -233.211897)
			(xy 120.915879 -233.262827) (xy 120.923822 -233.315531) (xy 120.92432 -233.34218) (xy 120.923822 -233.368829)
			(xy 121.152656 -233.368829) (xy 121.152656 -233.315531) (xy 121.160599 -233.262827) (xy 121.176309 -233.211897)
			(xy 121.199435 -233.163876) (xy 121.229459 -233.119839) (xy 121.265711 -233.080768) (xy 121.307382 -233.047537)
			(xy 121.35354 -233.020888) (xy 121.403154 -233.001416) (xy 121.455116 -232.989556) (xy 121.508266 -232.985573)
			(xy 121.561416 -232.989556) (xy 121.613378 -233.001416) (xy 121.662992 -233.020888) (xy 121.70915 -233.047537)
			(xy 121.750821 -233.080768) (xy 121.787073 -233.119839) (xy 121.817097 -233.163876) (xy 121.840223 -233.211897)
			(xy 121.855933 -233.262827) (xy 121.863876 -233.315531) (xy 121.864374 -233.34218) (xy 121.863876 -233.368829)
			(xy 122.092202 -233.368829) (xy 122.092202 -233.315531) (xy 122.100145 -233.262827) (xy 122.115855 -233.211897)
			(xy 122.138981 -233.163876) (xy 122.169005 -233.119839) (xy 122.205257 -233.080768) (xy 122.246928 -233.047537)
			(xy 122.293086 -233.020888) (xy 122.3427 -233.001416) (xy 122.394662 -232.989556) (xy 122.447812 -232.985573)
			(xy 122.500962 -232.989556) (xy 122.552924 -233.001416) (xy 122.602538 -233.020888) (xy 122.648696 -233.047537)
			(xy 122.690367 -233.080768) (xy 122.726619 -233.119839) (xy 122.756643 -233.163876) (xy 122.779769 -233.211897)
			(xy 122.795479 -233.262827) (xy 122.803422 -233.315531) (xy 122.80392 -233.34218) (xy 122.803422 -233.368829)
			(xy 123.032002 -233.368829) (xy 123.032002 -233.315531) (xy 123.039945 -233.262827) (xy 123.055655 -233.211897)
			(xy 123.078781 -233.163876) (xy 123.108805 -233.119839) (xy 123.145057 -233.080768) (xy 123.186728 -233.047537)
			(xy 123.232886 -233.020888) (xy 123.2825 -233.001416) (xy 123.334462 -232.989556) (xy 123.387612 -232.985573)
			(xy 123.440762 -232.989556) (xy 123.492724 -233.001416) (xy 123.542338 -233.020888) (xy 123.588496 -233.047537)
			(xy 123.630167 -233.080768) (xy 123.666419 -233.119839) (xy 123.696443 -233.163876) (xy 123.719569 -233.211897)
			(xy 123.735279 -233.262827) (xy 123.743222 -233.315531) (xy 123.74372 -233.34218) (xy 123.743222 -233.368829)
			(xy 123.971802 -233.368829) (xy 123.971802 -233.315531) (xy 123.979745 -233.262827) (xy 123.995455 -233.211897)
			(xy 124.018581 -233.163876) (xy 124.048605 -233.119839) (xy 124.084857 -233.080768) (xy 124.126528 -233.047537)
			(xy 124.172686 -233.020888) (xy 124.2223 -233.001416) (xy 124.274262 -232.989556) (xy 124.327412 -232.985573)
			(xy 124.380562 -232.989556) (xy 124.432524 -233.001416) (xy 124.482138 -233.020888) (xy 124.528296 -233.047537)
			(xy 124.569967 -233.080768) (xy 124.606219 -233.119839) (xy 124.636243 -233.163876) (xy 124.659369 -233.211897)
			(xy 124.675079 -233.262827) (xy 124.683022 -233.315531) (xy 124.68352 -233.34218) (xy 124.683022 -233.368829)
			(xy 124.911602 -233.368829) (xy 124.911602 -233.315531) (xy 124.919545 -233.262827) (xy 124.935255 -233.211897)
			(xy 124.958381 -233.163876) (xy 124.988405 -233.119839) (xy 125.024657 -233.080768) (xy 125.066328 -233.047537)
			(xy 125.112486 -233.020888) (xy 125.1621 -233.001416) (xy 125.214062 -232.989556) (xy 125.267212 -232.985573)
			(xy 125.320362 -232.989556) (xy 125.372324 -233.001416) (xy 125.421938 -233.020888) (xy 125.468096 -233.047537)
			(xy 125.509767 -233.080768) (xy 125.546019 -233.119839) (xy 125.576043 -233.163876) (xy 125.599169 -233.211897)
			(xy 125.614879 -233.262827) (xy 125.622822 -233.315531) (xy 125.62332 -233.34218) (xy 125.622822 -233.368829)
			(xy 125.851656 -233.368829) (xy 125.851656 -233.315531) (xy 125.859599 -233.262827) (xy 125.875309 -233.211897)
			(xy 125.898435 -233.163876) (xy 125.928459 -233.119839) (xy 125.964711 -233.080768) (xy 126.006382 -233.047537)
			(xy 126.05254 -233.020888) (xy 126.102154 -233.001416) (xy 126.154116 -232.989556) (xy 126.207266 -232.985573)
			(xy 126.260416 -232.989556) (xy 126.312378 -233.001416) (xy 126.361992 -233.020888) (xy 126.40815 -233.047537)
			(xy 126.449821 -233.080768) (xy 126.486073 -233.119839) (xy 126.516097 -233.163876) (xy 126.539223 -233.211897)
			(xy 126.554933 -233.262827) (xy 126.562876 -233.315531) (xy 126.563374 -233.34218) (xy 126.562876 -233.368829)
			(xy 126.791202 -233.368829) (xy 126.791202 -233.315531) (xy 126.799145 -233.262827) (xy 126.814855 -233.211897)
			(xy 126.837981 -233.163876) (xy 126.868005 -233.119839) (xy 126.904257 -233.080768) (xy 126.945928 -233.047537)
			(xy 126.992086 -233.020888) (xy 127.0417 -233.001416) (xy 127.093662 -232.989556) (xy 127.146812 -232.985573)
			(xy 127.199962 -232.989556) (xy 127.251924 -233.001416) (xy 127.301538 -233.020888) (xy 127.347696 -233.047537)
			(xy 127.389367 -233.080768) (xy 127.425619 -233.119839) (xy 127.455643 -233.163876) (xy 127.478769 -233.211897)
			(xy 127.494479 -233.262827) (xy 127.502422 -233.315531) (xy 127.50292 -233.34218) (xy 127.502422 -233.368829)
			(xy 127.731002 -233.368829) (xy 127.731002 -233.315531) (xy 127.738945 -233.262827) (xy 127.754655 -233.211897)
			(xy 127.777781 -233.163876) (xy 127.807805 -233.119839) (xy 127.844057 -233.080768) (xy 127.885728 -233.047537)
			(xy 127.931886 -233.020888) (xy 127.9815 -233.001416) (xy 128.033462 -232.989556) (xy 128.086612 -232.985573)
			(xy 128.139762 -232.989556) (xy 128.191724 -233.001416) (xy 128.241338 -233.020888) (xy 128.287496 -233.047537)
			(xy 128.329167 -233.080768) (xy 128.365419 -233.119839) (xy 128.395443 -233.163876) (xy 128.418569 -233.211897)
			(xy 128.434279 -233.262827) (xy 128.442222 -233.315531) (xy 128.44272 -233.34218) (xy 128.442222 -233.368829)
			(xy 128.670802 -233.368829) (xy 128.670802 -233.315531) (xy 128.678745 -233.262827) (xy 128.694455 -233.211897)
			(xy 128.717581 -233.163876) (xy 128.747605 -233.119839) (xy 128.783857 -233.080768) (xy 128.825528 -233.047537)
			(xy 128.871686 -233.020888) (xy 128.9213 -233.001416) (xy 128.973262 -232.989556) (xy 129.026412 -232.985573)
			(xy 129.079562 -232.989556) (xy 129.131524 -233.001416) (xy 129.181138 -233.020888) (xy 129.227296 -233.047537)
			(xy 129.268967 -233.080768) (xy 129.305219 -233.119839) (xy 129.335243 -233.163876) (xy 129.358369 -233.211897)
			(xy 129.374079 -233.262827) (xy 129.382022 -233.315531) (xy 129.38252 -233.34218) (xy 129.382022 -233.368829)
			(xy 129.610602 -233.368829) (xy 129.610602 -233.315531) (xy 129.618545 -233.262827) (xy 129.634255 -233.211897)
			(xy 129.657381 -233.163876) (xy 129.687405 -233.119839) (xy 129.723657 -233.080768) (xy 129.765328 -233.047537)
			(xy 129.811486 -233.020888) (xy 129.8611 -233.001416) (xy 129.913062 -232.989556) (xy 129.966212 -232.985573)
			(xy 130.019362 -232.989556) (xy 130.071324 -233.001416) (xy 130.120938 -233.020888) (xy 130.167096 -233.047537)
			(xy 130.208767 -233.080768) (xy 130.245019 -233.119839) (xy 130.275043 -233.163876) (xy 130.298169 -233.211897)
			(xy 130.313879 -233.262827) (xy 130.321822 -233.315531) (xy 130.32232 -233.34218) (xy 130.321822 -233.368829)
			(xy 130.550402 -233.368829) (xy 130.550402 -233.315531) (xy 130.558345 -233.262827) (xy 130.574055 -233.211897)
			(xy 130.597181 -233.163876) (xy 130.627205 -233.119839) (xy 130.663457 -233.080768) (xy 130.705128 -233.047537)
			(xy 130.751286 -233.020888) (xy 130.8009 -233.001416) (xy 130.852862 -232.989556) (xy 130.906012 -232.985573)
			(xy 130.959162 -232.989556) (xy 131.011124 -233.001416) (xy 131.060738 -233.020888) (xy 131.106896 -233.047537)
			(xy 131.148567 -233.080768) (xy 131.184819 -233.119839) (xy 131.214843 -233.163876) (xy 131.237969 -233.211897)
			(xy 131.253679 -233.262827) (xy 131.261622 -233.315531) (xy 131.26212 -233.34218) (xy 131.261622 -233.368829)
			(xy 131.490202 -233.368829) (xy 131.490202 -233.315531) (xy 131.498145 -233.262827) (xy 131.513855 -233.211897)
			(xy 131.536981 -233.163876) (xy 131.567005 -233.119839) (xy 131.603257 -233.080768) (xy 131.644928 -233.047537)
			(xy 131.691086 -233.020888) (xy 131.7407 -233.001416) (xy 131.792662 -232.989556) (xy 131.845812 -232.985573)
			(xy 131.898962 -232.989556) (xy 131.950924 -233.001416) (xy 132.000538 -233.020888) (xy 132.046696 -233.047537)
			(xy 132.088367 -233.080768) (xy 132.124619 -233.119839) (xy 132.154643 -233.163876) (xy 132.177769 -233.211897)
			(xy 132.193479 -233.262827) (xy 132.201422 -233.315531) (xy 132.20192 -233.34218) (xy 132.201422 -233.368829)
			(xy 132.430256 -233.368829) (xy 132.430256 -233.315531) (xy 132.438199 -233.262827) (xy 132.453909 -233.211897)
			(xy 132.477035 -233.163876) (xy 132.507059 -233.119839) (xy 132.543311 -233.080768) (xy 132.584982 -233.047537)
			(xy 132.63114 -233.020888) (xy 132.680754 -233.001416) (xy 132.732716 -232.989556) (xy 132.785866 -232.985573)
			(xy 132.839016 -232.989556) (xy 132.890978 -233.001416) (xy 132.940592 -233.020888) (xy 132.98675 -233.047537)
			(xy 133.028421 -233.080768) (xy 133.064673 -233.119839) (xy 133.094697 -233.163876) (xy 133.117823 -233.211897)
			(xy 133.133533 -233.262827) (xy 133.141476 -233.315531) (xy 133.141974 -233.34218) (xy 133.141476 -233.368829)
			(xy 133.370056 -233.368829) (xy 133.370056 -233.315531) (xy 133.377999 -233.262827) (xy 133.393709 -233.211897)
			(xy 133.416835 -233.163876) (xy 133.446859 -233.119839) (xy 133.483111 -233.080768) (xy 133.524782 -233.047537)
			(xy 133.57094 -233.020888) (xy 133.620554 -233.001416) (xy 133.672516 -232.989556) (xy 133.725666 -232.985573)
			(xy 133.778816 -232.989556) (xy 133.830778 -233.001416) (xy 133.880392 -233.020888) (xy 133.92655 -233.047537)
			(xy 133.968221 -233.080768) (xy 134.004473 -233.119839) (xy 134.034497 -233.163876) (xy 134.057623 -233.211897)
			(xy 134.073333 -233.262827) (xy 134.081276 -233.315531) (xy 134.081774 -233.34218) (xy 134.081276 -233.368829)
			(xy 134.309856 -233.368829) (xy 134.309856 -233.315531) (xy 134.317799 -233.262827) (xy 134.333509 -233.211897)
			(xy 134.356635 -233.163876) (xy 134.386659 -233.119839) (xy 134.422911 -233.080768) (xy 134.464582 -233.047537)
			(xy 134.51074 -233.020888) (xy 134.560354 -233.001416) (xy 134.612316 -232.989556) (xy 134.665466 -232.985573)
			(xy 134.718616 -232.989556) (xy 134.770578 -233.001416) (xy 134.820192 -233.020888) (xy 134.86635 -233.047537)
			(xy 134.908021 -233.080768) (xy 134.944273 -233.119839) (xy 134.974297 -233.163876) (xy 134.997423 -233.211897)
			(xy 135.013133 -233.262827) (xy 135.021076 -233.315531) (xy 135.021574 -233.34218) (xy 135.021076 -233.368829)
			(xy 135.013133 -233.421533) (xy 134.997423 -233.472463) (xy 134.974297 -233.520484) (xy 134.944273 -233.564521)
			(xy 134.908021 -233.603592) (xy 134.86635 -233.636823) (xy 134.820192 -233.663472) (xy 134.770578 -233.682944)
			(xy 134.718616 -233.694804) (xy 134.665466 -233.698788) (xy 134.612316 -233.694804) (xy 134.560354 -233.682944)
			(xy 134.51074 -233.663472) (xy 134.464582 -233.636823) (xy 134.422911 -233.603592) (xy 134.386659 -233.564521)
			(xy 134.356635 -233.520484) (xy 134.333509 -233.472463) (xy 134.317799 -233.421533) (xy 134.309856 -233.368829)
			(xy 134.081276 -233.368829) (xy 134.073333 -233.421533) (xy 134.057623 -233.472463) (xy 134.034497 -233.520484)
			(xy 134.004473 -233.564521) (xy 133.968221 -233.603592) (xy 133.92655 -233.636823) (xy 133.880392 -233.663472)
			(xy 133.830778 -233.682944) (xy 133.778816 -233.694804) (xy 133.725666 -233.698788) (xy 133.672516 -233.694804)
			(xy 133.620554 -233.682944) (xy 133.57094 -233.663472) (xy 133.524782 -233.636823) (xy 133.483111 -233.603592)
			(xy 133.446859 -233.564521) (xy 133.416835 -233.520484) (xy 133.393709 -233.472463) (xy 133.377999 -233.421533)
			(xy 133.370056 -233.368829) (xy 133.141476 -233.368829) (xy 133.133533 -233.421533) (xy 133.117823 -233.472463)
			(xy 133.094697 -233.520484) (xy 133.064673 -233.564521) (xy 133.028421 -233.603592) (xy 132.98675 -233.636823)
			(xy 132.940592 -233.663472) (xy 132.890978 -233.682944) (xy 132.839016 -233.694804) (xy 132.785866 -233.698788)
			(xy 132.732716 -233.694804) (xy 132.680754 -233.682944) (xy 132.63114 -233.663472) (xy 132.584982 -233.636823)
			(xy 132.543311 -233.603592) (xy 132.507059 -233.564521) (xy 132.477035 -233.520484) (xy 132.453909 -233.472463)
			(xy 132.438199 -233.421533) (xy 132.430256 -233.368829) (xy 132.201422 -233.368829) (xy 132.193479 -233.421533)
			(xy 132.177769 -233.472463) (xy 132.154643 -233.520484) (xy 132.124619 -233.564521) (xy 132.088367 -233.603592)
			(xy 132.046696 -233.636823) (xy 132.000538 -233.663472) (xy 131.950924 -233.682944) (xy 131.898962 -233.694804)
			(xy 131.845812 -233.698788) (xy 131.792662 -233.694804) (xy 131.7407 -233.682944) (xy 131.691086 -233.663472)
			(xy 131.644928 -233.636823) (xy 131.603257 -233.603592) (xy 131.567005 -233.564521) (xy 131.536981 -233.520484)
			(xy 131.513855 -233.472463) (xy 131.498145 -233.421533) (xy 131.490202 -233.368829) (xy 131.261622 -233.368829)
			(xy 131.253679 -233.421533) (xy 131.237969 -233.472463) (xy 131.214843 -233.520484) (xy 131.184819 -233.564521)
			(xy 131.148567 -233.603592) (xy 131.106896 -233.636823) (xy 131.060738 -233.663472) (xy 131.011124 -233.682944)
			(xy 130.959162 -233.694804) (xy 130.906012 -233.698788) (xy 130.852862 -233.694804) (xy 130.8009 -233.682944)
			(xy 130.751286 -233.663472) (xy 130.705128 -233.636823) (xy 130.663457 -233.603592) (xy 130.627205 -233.564521)
			(xy 130.597181 -233.520484) (xy 130.574055 -233.472463) (xy 130.558345 -233.421533) (xy 130.550402 -233.368829)
			(xy 130.321822 -233.368829) (xy 130.313879 -233.421533) (xy 130.298169 -233.472463) (xy 130.275043 -233.520484)
			(xy 130.245019 -233.564521) (xy 130.208767 -233.603592) (xy 130.167096 -233.636823) (xy 130.120938 -233.663472)
			(xy 130.071324 -233.682944) (xy 130.019362 -233.694804) (xy 129.966212 -233.698788) (xy 129.913062 -233.694804)
			(xy 129.8611 -233.682944) (xy 129.811486 -233.663472) (xy 129.765328 -233.636823) (xy 129.723657 -233.603592)
			(xy 129.687405 -233.564521) (xy 129.657381 -233.520484) (xy 129.634255 -233.472463) (xy 129.618545 -233.421533)
			(xy 129.610602 -233.368829) (xy 129.382022 -233.368829) (xy 129.374079 -233.421533) (xy 129.358369 -233.472463)
			(xy 129.335243 -233.520484) (xy 129.305219 -233.564521) (xy 129.268967 -233.603592) (xy 129.227296 -233.636823)
			(xy 129.181138 -233.663472) (xy 129.131524 -233.682944) (xy 129.079562 -233.694804) (xy 129.026412 -233.698788)
			(xy 128.973262 -233.694804) (xy 128.9213 -233.682944) (xy 128.871686 -233.663472) (xy 128.825528 -233.636823)
			(xy 128.783857 -233.603592) (xy 128.747605 -233.564521) (xy 128.717581 -233.520484) (xy 128.694455 -233.472463)
			(xy 128.678745 -233.421533) (xy 128.670802 -233.368829) (xy 128.442222 -233.368829) (xy 128.434279 -233.421533)
			(xy 128.418569 -233.472463) (xy 128.395443 -233.520484) (xy 128.365419 -233.564521) (xy 128.329167 -233.603592)
			(xy 128.287496 -233.636823) (xy 128.241338 -233.663472) (xy 128.191724 -233.682944) (xy 128.139762 -233.694804)
			(xy 128.086612 -233.698788) (xy 128.033462 -233.694804) (xy 127.9815 -233.682944) (xy 127.931886 -233.663472)
			(xy 127.885728 -233.636823) (xy 127.844057 -233.603592) (xy 127.807805 -233.564521) (xy 127.777781 -233.520484)
			(xy 127.754655 -233.472463) (xy 127.738945 -233.421533) (xy 127.731002 -233.368829) (xy 127.502422 -233.368829)
			(xy 127.494479 -233.421533) (xy 127.478769 -233.472463) (xy 127.455643 -233.520484) (xy 127.425619 -233.564521)
			(xy 127.389367 -233.603592) (xy 127.347696 -233.636823) (xy 127.301538 -233.663472) (xy 127.251924 -233.682944)
			(xy 127.199962 -233.694804) (xy 127.146812 -233.698788) (xy 127.093662 -233.694804) (xy 127.0417 -233.682944)
			(xy 126.992086 -233.663472) (xy 126.945928 -233.636823) (xy 126.904257 -233.603592) (xy 126.868005 -233.564521)
			(xy 126.837981 -233.520484) (xy 126.814855 -233.472463) (xy 126.799145 -233.421533) (xy 126.791202 -233.368829)
			(xy 126.562876 -233.368829) (xy 126.554933 -233.421533) (xy 126.539223 -233.472463) (xy 126.516097 -233.520484)
			(xy 126.486073 -233.564521) (xy 126.449821 -233.603592) (xy 126.40815 -233.636823) (xy 126.361992 -233.663472)
			(xy 126.312378 -233.682944) (xy 126.260416 -233.694804) (xy 126.207266 -233.698788) (xy 126.154116 -233.694804)
			(xy 126.102154 -233.682944) (xy 126.05254 -233.663472) (xy 126.006382 -233.636823) (xy 125.964711 -233.603592)
			(xy 125.928459 -233.564521) (xy 125.898435 -233.520484) (xy 125.875309 -233.472463) (xy 125.859599 -233.421533)
			(xy 125.851656 -233.368829) (xy 125.622822 -233.368829) (xy 125.614879 -233.421533) (xy 125.599169 -233.472463)
			(xy 125.576043 -233.520484) (xy 125.546019 -233.564521) (xy 125.509767 -233.603592) (xy 125.468096 -233.636823)
			(xy 125.421938 -233.663472) (xy 125.372324 -233.682944) (xy 125.320362 -233.694804) (xy 125.267212 -233.698788)
			(xy 125.214062 -233.694804) (xy 125.1621 -233.682944) (xy 125.112486 -233.663472) (xy 125.066328 -233.636823)
			(xy 125.024657 -233.603592) (xy 124.988405 -233.564521) (xy 124.958381 -233.520484) (xy 124.935255 -233.472463)
			(xy 124.919545 -233.421533) (xy 124.911602 -233.368829) (xy 124.683022 -233.368829) (xy 124.675079 -233.421533)
			(xy 124.659369 -233.472463) (xy 124.636243 -233.520484) (xy 124.606219 -233.564521) (xy 124.569967 -233.603592)
			(xy 124.528296 -233.636823) (xy 124.482138 -233.663472) (xy 124.432524 -233.682944) (xy 124.380562 -233.694804)
			(xy 124.327412 -233.698788) (xy 124.274262 -233.694804) (xy 124.2223 -233.682944) (xy 124.172686 -233.663472)
			(xy 124.126528 -233.636823) (xy 124.084857 -233.603592) (xy 124.048605 -233.564521) (xy 124.018581 -233.520484)
			(xy 123.995455 -233.472463) (xy 123.979745 -233.421533) (xy 123.971802 -233.368829) (xy 123.743222 -233.368829)
			(xy 123.735279 -233.421533) (xy 123.719569 -233.472463) (xy 123.696443 -233.520484) (xy 123.666419 -233.564521)
			(xy 123.630167 -233.603592) (xy 123.588496 -233.636823) (xy 123.542338 -233.663472) (xy 123.492724 -233.682944)
			(xy 123.440762 -233.694804) (xy 123.387612 -233.698788) (xy 123.334462 -233.694804) (xy 123.2825 -233.682944)
			(xy 123.232886 -233.663472) (xy 123.186728 -233.636823) (xy 123.145057 -233.603592) (xy 123.108805 -233.564521)
			(xy 123.078781 -233.520484) (xy 123.055655 -233.472463) (xy 123.039945 -233.421533) (xy 123.032002 -233.368829)
			(xy 122.803422 -233.368829) (xy 122.795479 -233.421533) (xy 122.779769 -233.472463) (xy 122.756643 -233.520484)
			(xy 122.726619 -233.564521) (xy 122.690367 -233.603592) (xy 122.648696 -233.636823) (xy 122.602538 -233.663472)
			(xy 122.552924 -233.682944) (xy 122.500962 -233.694804) (xy 122.447812 -233.698788) (xy 122.394662 -233.694804)
			(xy 122.3427 -233.682944) (xy 122.293086 -233.663472) (xy 122.246928 -233.636823) (xy 122.205257 -233.603592)
			(xy 122.169005 -233.564521) (xy 122.138981 -233.520484) (xy 122.115855 -233.472463) (xy 122.100145 -233.421533)
			(xy 122.092202 -233.368829) (xy 121.863876 -233.368829) (xy 121.855933 -233.421533) (xy 121.840223 -233.472463)
			(xy 121.817097 -233.520484) (xy 121.787073 -233.564521) (xy 121.750821 -233.603592) (xy 121.70915 -233.636823)
			(xy 121.662992 -233.663472) (xy 121.613378 -233.682944) (xy 121.561416 -233.694804) (xy 121.508266 -233.698788)
			(xy 121.455116 -233.694804) (xy 121.403154 -233.682944) (xy 121.35354 -233.663472) (xy 121.307382 -233.636823)
			(xy 121.265711 -233.603592) (xy 121.229459 -233.564521) (xy 121.199435 -233.520484) (xy 121.176309 -233.472463)
			(xy 121.160599 -233.421533) (xy 121.152656 -233.368829) (xy 120.923822 -233.368829) (xy 120.915879 -233.421533)
			(xy 120.900169 -233.472463) (xy 120.877043 -233.520484) (xy 120.847019 -233.564521) (xy 120.810767 -233.603592)
			(xy 120.769096 -233.636823) (xy 120.722938 -233.663472) (xy 120.673324 -233.682944) (xy 120.621362 -233.694804)
			(xy 120.568212 -233.698788) (xy 120.515062 -233.694804) (xy 120.4631 -233.682944) (xy 120.413486 -233.663472)
			(xy 120.367328 -233.636823) (xy 120.325657 -233.603592) (xy 120.289405 -233.564521) (xy 120.259381 -233.520484)
			(xy 120.236255 -233.472463) (xy 120.220545 -233.421533) (xy 120.212602 -233.368829) (xy 119.984022 -233.368829)
			(xy 119.976079 -233.421533) (xy 119.960369 -233.472463) (xy 119.937243 -233.520484) (xy 119.907219 -233.564521)
			(xy 119.870967 -233.603592) (xy 119.829296 -233.636823) (xy 119.783138 -233.663472) (xy 119.733524 -233.682944)
			(xy 119.681562 -233.694804) (xy 119.628412 -233.698788) (xy 119.575262 -233.694804) (xy 119.5233 -233.682944)
			(xy 119.473686 -233.663472) (xy 119.427528 -233.636823) (xy 119.385857 -233.603592) (xy 119.349605 -233.564521)
			(xy 119.319581 -233.520484) (xy 119.296455 -233.472463) (xy 119.280745 -233.421533) (xy 119.272802 -233.368829)
			(xy 119.044222 -233.368829) (xy 119.036279 -233.421533) (xy 119.020569 -233.472463) (xy 118.997443 -233.520484)
			(xy 118.967419 -233.564521) (xy 118.931167 -233.603592) (xy 118.889496 -233.636823) (xy 118.843338 -233.663472)
			(xy 118.793724 -233.682944) (xy 118.741762 -233.694804) (xy 118.688612 -233.698788) (xy 118.635462 -233.694804)
			(xy 118.5835 -233.682944) (xy 118.533886 -233.663472) (xy 118.487728 -233.636823) (xy 118.446057 -233.603592)
			(xy 118.409805 -233.564521) (xy 118.379781 -233.520484) (xy 118.356655 -233.472463) (xy 118.340945 -233.421533)
			(xy 118.333002 -233.368829) (xy 118.104422 -233.368829) (xy 118.096479 -233.421533) (xy 118.080769 -233.472463)
			(xy 118.057643 -233.520484) (xy 118.027619 -233.564521) (xy 117.991367 -233.603592) (xy 117.949696 -233.636823)
			(xy 117.903538 -233.663472) (xy 117.853924 -233.682944) (xy 117.801962 -233.694804) (xy 117.748812 -233.698788)
			(xy 117.695662 -233.694804) (xy 117.6437 -233.682944) (xy 117.594086 -233.663472) (xy 117.547928 -233.636823)
			(xy 117.506257 -233.603592) (xy 117.470005 -233.564521) (xy 117.439981 -233.520484) (xy 117.416855 -233.472463)
			(xy 117.401145 -233.421533) (xy 117.393202 -233.368829) (xy 117.164622 -233.368829) (xy 117.156679 -233.421533)
			(xy 117.140969 -233.472463) (xy 117.117843 -233.520484) (xy 117.087819 -233.564521) (xy 117.051567 -233.603592)
			(xy 117.009896 -233.636823) (xy 116.963738 -233.663472) (xy 116.914124 -233.682944) (xy 116.862162 -233.694804)
			(xy 116.809012 -233.698788) (xy 116.755862 -233.694804) (xy 116.7039 -233.682944) (xy 116.654286 -233.663472)
			(xy 116.608128 -233.636823) (xy 116.566457 -233.603592) (xy 116.530205 -233.564521) (xy 116.500181 -233.520484)
			(xy 116.477055 -233.472463) (xy 116.461345 -233.421533) (xy 116.453402 -233.368829) (xy 116.224822 -233.368829)
			(xy 116.216879 -233.421533) (xy 116.201169 -233.472463) (xy 116.178043 -233.520484) (xy 116.148019 -233.564521)
			(xy 116.111767 -233.603592) (xy 116.070096 -233.636823) (xy 116.023938 -233.663472) (xy 115.974324 -233.682944)
			(xy 115.922362 -233.694804) (xy 115.869212 -233.698788) (xy 115.816062 -233.694804) (xy 115.7641 -233.682944)
			(xy 115.714486 -233.663472) (xy 115.668328 -233.636823) (xy 115.626657 -233.603592) (xy 115.590405 -233.564521)
			(xy 115.560381 -233.520484) (xy 115.537255 -233.472463) (xy 115.521545 -233.421533) (xy 115.513602 -233.368829)
			(xy 115.285022 -233.368829) (xy 115.277079 -233.421533) (xy 115.261369 -233.472463) (xy 115.238243 -233.520484)
			(xy 115.208219 -233.564521) (xy 115.171967 -233.603592) (xy 115.130296 -233.636823) (xy 115.084138 -233.663472)
			(xy 115.034524 -233.682944) (xy 114.982562 -233.694804) (xy 114.929412 -233.698788) (xy 114.876262 -233.694804)
			(xy 114.8243 -233.682944) (xy 114.774686 -233.663472) (xy 114.728528 -233.636823) (xy 114.686857 -233.603592)
			(xy 114.650605 -233.564521) (xy 114.620581 -233.520484) (xy 114.597455 -233.472463) (xy 114.581745 -233.421533)
			(xy 114.573802 -233.368829) (xy 114.345476 -233.368829) (xy 114.337533 -233.421533) (xy 114.321823 -233.472463)
			(xy 114.298697 -233.520484) (xy 114.268673 -233.564521) (xy 114.232421 -233.603592) (xy 114.19075 -233.636823)
			(xy 114.144592 -233.663472) (xy 114.094978 -233.682944) (xy 114.043016 -233.694804) (xy 113.989866 -233.698788)
			(xy 113.936716 -233.694804) (xy 113.884754 -233.682944) (xy 113.83514 -233.663472) (xy 113.788982 -233.636823)
			(xy 113.747311 -233.603592) (xy 113.711059 -233.564521) (xy 113.681035 -233.520484) (xy 113.657909 -233.472463)
			(xy 113.642199 -233.421533) (xy 113.634256 -233.368829) (xy 113.405422 -233.368829) (xy 113.397479 -233.421533)
			(xy 113.381769 -233.472463) (xy 113.358643 -233.520484) (xy 113.328619 -233.564521) (xy 113.292367 -233.603592)
			(xy 113.250696 -233.636823) (xy 113.204538 -233.663472) (xy 113.154924 -233.682944) (xy 113.102962 -233.694804)
			(xy 113.049812 -233.698788) (xy 112.996662 -233.694804) (xy 112.9447 -233.682944) (xy 112.895086 -233.663472)
			(xy 112.848928 -233.636823) (xy 112.807257 -233.603592) (xy 112.771005 -233.564521) (xy 112.740981 -233.520484)
			(xy 112.717855 -233.472463) (xy 112.702145 -233.421533) (xy 112.694202 -233.368829) (xy 112.465622 -233.368829)
			(xy 112.457679 -233.421533) (xy 112.441969 -233.472463) (xy 112.418843 -233.520484) (xy 112.388819 -233.564521)
			(xy 112.352567 -233.603592) (xy 112.310896 -233.636823) (xy 112.264738 -233.663472) (xy 112.215124 -233.682944)
			(xy 112.163162 -233.694804) (xy 112.110012 -233.698788) (xy 112.056862 -233.694804) (xy 112.0049 -233.682944)
			(xy 111.955286 -233.663472) (xy 111.909128 -233.636823) (xy 111.867457 -233.603592) (xy 111.831205 -233.564521)
			(xy 111.801181 -233.520484) (xy 111.778055 -233.472463) (xy 111.762345 -233.421533) (xy 111.754402 -233.368829)
			(xy 111.525822 -233.368829) (xy 111.517879 -233.421533) (xy 111.502169 -233.472463) (xy 111.479043 -233.520484)
			(xy 111.449019 -233.564521) (xy 111.412767 -233.603592) (xy 111.371096 -233.636823) (xy 111.324938 -233.663472)
			(xy 111.275324 -233.682944) (xy 111.223362 -233.694804) (xy 111.170212 -233.698788) (xy 111.117062 -233.694804)
			(xy 111.0651 -233.682944) (xy 111.015486 -233.663472) (xy 110.969328 -233.636823) (xy 110.927657 -233.603592)
			(xy 110.891405 -233.564521) (xy 110.861381 -233.520484) (xy 110.838255 -233.472463) (xy 110.822545 -233.421533)
			(xy 110.814602 -233.368829) (xy 110.58628 -233.368829) (xy 110.586255 -233.370165) (xy 110.577501 -233.425447)
			(xy 110.560207 -233.478679) (xy 110.534797 -233.52855) (xy 110.501898 -233.573831) (xy 110.46232 -233.613407)
			(xy 110.417038 -233.646305) (xy 110.367166 -233.671712) (xy 110.313934 -233.689005) (xy 110.258651 -233.697756)
			(xy 110.230666 -233.698288) (xy 110.205049 -233.697841) (xy 110.154342 -233.690497) (xy 110.105211 -233.675966)
			(xy 110.058668 -233.654547) (xy 110.015673 -233.626683) (xy 109.977112 -233.592947) (xy 109.943782 -233.554035)
			(xy 109.916369 -233.510751) (xy 109.895438 -233.463986) (xy 109.88802 -233.439462) (xy 109.883386 -233.425068)
			(xy 109.867017 -233.399662) (xy 109.843923 -233.380168) (xy 109.81613 -233.368296) (xy 109.786078 -233.365089)
			(xy 109.756406 -233.370828) (xy 109.729718 -233.385011) (xy 109.718602 -233.395266) (xy 109.605826 -233.508042)
			(xy 109.60227 -233.514392) (xy 109.589816 -233.536061) (xy 109.559768 -233.575997) (xy 109.52443 -233.611339)
			(xy 109.484497 -233.641393) (xy 109.462824 -233.653838) (xy 109.456474 -233.657394) (xy 109.132878 -233.98099)
			(xy 109.146848 -234.01274) (xy 109.156399 -234.035447) (xy 109.169859 -234.082832) (xy 109.176658 -234.13162)
			(xy 109.177074 -234.15625) (xy 109.176547 -234.182899) (xy 109.405156 -234.182899) (xy 109.405156 -234.129601)
			(xy 109.413099 -234.076897) (xy 109.428809 -234.025967) (xy 109.451935 -233.977946) (xy 109.481959 -233.933909)
			(xy 109.518211 -233.894838) (xy 109.559882 -233.861607) (xy 109.60604 -233.834958) (xy 109.655654 -233.815486)
			(xy 109.707616 -233.803626) (xy 109.760766 -233.799643) (xy 109.813916 -233.803626) (xy 109.865878 -233.815486)
			(xy 109.915492 -233.834958) (xy 109.96165 -233.861607) (xy 110.003321 -233.894838) (xy 110.039573 -233.933909)
			(xy 110.069597 -233.977946) (xy 110.092723 -234.025967) (xy 110.108433 -234.076897) (xy 110.116376 -234.129601)
			(xy 110.116874 -234.15625) (xy 110.116376 -234.182899) (xy 110.344956 -234.182899) (xy 110.344956 -234.129601)
			(xy 110.352899 -234.076897) (xy 110.368609 -234.025967) (xy 110.391735 -233.977946) (xy 110.421759 -233.933909)
			(xy 110.458011 -233.894838) (xy 110.499682 -233.861607) (xy 110.54584 -233.834958) (xy 110.595454 -233.815486)
			(xy 110.647416 -233.803626) (xy 110.700566 -233.799643) (xy 110.753716 -233.803626) (xy 110.805678 -233.815486)
			(xy 110.855292 -233.834958) (xy 110.90145 -233.861607) (xy 110.943121 -233.894838) (xy 110.979373 -233.933909)
			(xy 111.009397 -233.977946) (xy 111.032523 -234.025967) (xy 111.048233 -234.076897) (xy 111.056176 -234.129601)
			(xy 111.056674 -234.15625) (xy 111.056176 -234.182899) (xy 111.284756 -234.182899) (xy 111.284756 -234.129601)
			(xy 111.292699 -234.076897) (xy 111.308409 -234.025967) (xy 111.331535 -233.977946) (xy 111.361559 -233.933909)
			(xy 111.397811 -233.894838) (xy 111.439482 -233.861607) (xy 111.48564 -233.834958) (xy 111.535254 -233.815486)
			(xy 111.587216 -233.803626) (xy 111.640366 -233.799643) (xy 111.693516 -233.803626) (xy 111.745478 -233.815486)
			(xy 111.795092 -233.834958) (xy 111.84125 -233.861607) (xy 111.882921 -233.894838) (xy 111.919173 -233.933909)
			(xy 111.949197 -233.977946) (xy 111.972323 -234.025967) (xy 111.988033 -234.076897) (xy 111.995976 -234.129601)
			(xy 111.996474 -234.15625) (xy 111.995976 -234.182899) (xy 112.224556 -234.182899) (xy 112.224556 -234.129601)
			(xy 112.232499 -234.076897) (xy 112.248209 -234.025967) (xy 112.271335 -233.977946) (xy 112.301359 -233.933909)
			(xy 112.337611 -233.894838) (xy 112.379282 -233.861607) (xy 112.42544 -233.834958) (xy 112.475054 -233.815486)
			(xy 112.527016 -233.803626) (xy 112.580166 -233.799643) (xy 112.633316 -233.803626) (xy 112.685278 -233.815486)
			(xy 112.734892 -233.834958) (xy 112.78105 -233.861607) (xy 112.822721 -233.894838) (xy 112.858973 -233.933909)
			(xy 112.888997 -233.977946) (xy 112.912123 -234.025967) (xy 112.927833 -234.076897) (xy 112.935776 -234.129601)
			(xy 112.936274 -234.15625) (xy 112.935776 -234.182899) (xy 113.164356 -234.182899) (xy 113.164356 -234.129601)
			(xy 113.172299 -234.076897) (xy 113.188009 -234.025967) (xy 113.211135 -233.977946) (xy 113.241159 -233.933909)
			(xy 113.277411 -233.894838) (xy 113.319082 -233.861607) (xy 113.36524 -233.834958) (xy 113.414854 -233.815486)
			(xy 113.466816 -233.803626) (xy 113.519966 -233.799643) (xy 113.573116 -233.803626) (xy 113.625078 -233.815486)
			(xy 113.674692 -233.834958) (xy 113.72085 -233.861607) (xy 113.762521 -233.894838) (xy 113.798773 -233.933909)
			(xy 113.828797 -233.977946) (xy 113.851923 -234.025967) (xy 113.867633 -234.076897) (xy 113.875576 -234.129601)
			(xy 113.876074 -234.15625) (xy 113.875576 -234.182899) (xy 114.104156 -234.182899) (xy 114.104156 -234.129601)
			(xy 114.112099 -234.076897) (xy 114.127809 -234.025967) (xy 114.150935 -233.977946) (xy 114.180959 -233.933909)
			(xy 114.217211 -233.894838) (xy 114.258882 -233.861607) (xy 114.30504 -233.834958) (xy 114.354654 -233.815486)
			(xy 114.406616 -233.803626) (xy 114.459766 -233.799643) (xy 114.512916 -233.803626) (xy 114.564878 -233.815486)
			(xy 114.614492 -233.834958) (xy 114.66065 -233.861607) (xy 114.702321 -233.894838) (xy 114.738573 -233.933909)
			(xy 114.768597 -233.977946) (xy 114.791723 -234.025967) (xy 114.807433 -234.076897) (xy 114.815376 -234.129601)
			(xy 114.815874 -234.15625) (xy 114.815376 -234.182899) (xy 115.043956 -234.182899) (xy 115.043956 -234.129601)
			(xy 115.051899 -234.076897) (xy 115.067609 -234.025967) (xy 115.090735 -233.977946) (xy 115.120759 -233.933909)
			(xy 115.157011 -233.894838) (xy 115.198682 -233.861607) (xy 115.24484 -233.834958) (xy 115.294454 -233.815486)
			(xy 115.346416 -233.803626) (xy 115.399566 -233.799643) (xy 115.452716 -233.803626) (xy 115.504678 -233.815486)
			(xy 115.554292 -233.834958) (xy 115.60045 -233.861607) (xy 115.642121 -233.894838) (xy 115.678373 -233.933909)
			(xy 115.708397 -233.977946) (xy 115.731523 -234.025967) (xy 115.747233 -234.076897) (xy 115.755176 -234.129601)
			(xy 115.755674 -234.15625) (xy 115.755176 -234.182899) (xy 115.983756 -234.182899) (xy 115.983756 -234.129601)
			(xy 115.991699 -234.076897) (xy 116.007409 -234.025967) (xy 116.030535 -233.977946) (xy 116.060559 -233.933909)
			(xy 116.096811 -233.894838) (xy 116.138482 -233.861607) (xy 116.18464 -233.834958) (xy 116.234254 -233.815486)
			(xy 116.286216 -233.803626) (xy 116.339366 -233.799643) (xy 116.392516 -233.803626) (xy 116.444478 -233.815486)
			(xy 116.494092 -233.834958) (xy 116.54025 -233.861607) (xy 116.581921 -233.894838) (xy 116.618173 -233.933909)
			(xy 116.648197 -233.977946) (xy 116.671323 -234.025967) (xy 116.687033 -234.076897) (xy 116.694976 -234.129601)
			(xy 116.695474 -234.15625) (xy 116.694976 -234.182899) (xy 116.923556 -234.182899) (xy 116.923556 -234.129601)
			(xy 116.931499 -234.076897) (xy 116.947209 -234.025967) (xy 116.970335 -233.977946) (xy 117.000359 -233.933909)
			(xy 117.036611 -233.894838) (xy 117.078282 -233.861607) (xy 117.12444 -233.834958) (xy 117.174054 -233.815486)
			(xy 117.226016 -233.803626) (xy 117.279166 -233.799643) (xy 117.332316 -233.803626) (xy 117.384278 -233.815486)
			(xy 117.433892 -233.834958) (xy 117.48005 -233.861607) (xy 117.521721 -233.894838) (xy 117.557973 -233.933909)
			(xy 117.587997 -233.977946) (xy 117.611123 -234.025967) (xy 117.626833 -234.076897) (xy 117.634776 -234.129601)
			(xy 117.635274 -234.15625) (xy 117.634776 -234.182899) (xy 117.863356 -234.182899) (xy 117.863356 -234.129601)
			(xy 117.871299 -234.076897) (xy 117.887009 -234.025967) (xy 117.910135 -233.977946) (xy 117.940159 -233.933909)
			(xy 117.976411 -233.894838) (xy 118.018082 -233.861607) (xy 118.06424 -233.834958) (xy 118.113854 -233.815486)
			(xy 118.165816 -233.803626) (xy 118.218966 -233.799643) (xy 118.272116 -233.803626) (xy 118.324078 -233.815486)
			(xy 118.373692 -233.834958) (xy 118.41985 -233.861607) (xy 118.461521 -233.894838) (xy 118.497773 -233.933909)
			(xy 118.527797 -233.977946) (xy 118.550923 -234.025967) (xy 118.566633 -234.076897) (xy 118.574576 -234.129601)
			(xy 118.575074 -234.15625) (xy 118.574576 -234.182899) (xy 118.803156 -234.182899) (xy 118.803156 -234.129601)
			(xy 118.811099 -234.076897) (xy 118.826809 -234.025967) (xy 118.849935 -233.977946) (xy 118.879959 -233.933909)
			(xy 118.916211 -233.894838) (xy 118.957882 -233.861607) (xy 119.00404 -233.834958) (xy 119.053654 -233.815486)
			(xy 119.105616 -233.803626) (xy 119.158766 -233.799643) (xy 119.211916 -233.803626) (xy 119.263878 -233.815486)
			(xy 119.313492 -233.834958) (xy 119.35965 -233.861607) (xy 119.401321 -233.894838) (xy 119.437573 -233.933909)
			(xy 119.467597 -233.977946) (xy 119.490723 -234.025967) (xy 119.506433 -234.076897) (xy 119.514376 -234.129601)
			(xy 119.514874 -234.15625) (xy 119.514376 -234.182899) (xy 119.742956 -234.182899) (xy 119.742956 -234.129601)
			(xy 119.750899 -234.076897) (xy 119.766609 -234.025967) (xy 119.789735 -233.977946) (xy 119.819759 -233.933909)
			(xy 119.856011 -233.894838) (xy 119.897682 -233.861607) (xy 119.94384 -233.834958) (xy 119.993454 -233.815486)
			(xy 120.045416 -233.803626) (xy 120.098566 -233.799643) (xy 120.151716 -233.803626) (xy 120.203678 -233.815486)
			(xy 120.253292 -233.834958) (xy 120.29945 -233.861607) (xy 120.341121 -233.894838) (xy 120.377373 -233.933909)
			(xy 120.407397 -233.977946) (xy 120.430523 -234.025967) (xy 120.446233 -234.076897) (xy 120.454176 -234.129601)
			(xy 120.454674 -234.15625) (xy 120.454176 -234.182899) (xy 120.682502 -234.182899) (xy 120.682502 -234.129601)
			(xy 120.690445 -234.076897) (xy 120.706155 -234.025967) (xy 120.729281 -233.977946) (xy 120.759305 -233.933909)
			(xy 120.795557 -233.894838) (xy 120.837228 -233.861607) (xy 120.883386 -233.834958) (xy 120.933 -233.815486)
			(xy 120.984962 -233.803626) (xy 121.038112 -233.799643) (xy 121.091262 -233.803626) (xy 121.143224 -233.815486)
			(xy 121.192838 -233.834958) (xy 121.238996 -233.861607) (xy 121.280667 -233.894838) (xy 121.316919 -233.933909)
			(xy 121.346943 -233.977946) (xy 121.370069 -234.025967) (xy 121.385779 -234.076897) (xy 121.393722 -234.129601)
			(xy 121.39422 -234.15625) (xy 121.393722 -234.182899) (xy 121.622556 -234.182899) (xy 121.622556 -234.129601)
			(xy 121.630499 -234.076897) (xy 121.646209 -234.025967) (xy 121.669335 -233.977946) (xy 121.699359 -233.933909)
			(xy 121.735611 -233.894838) (xy 121.777282 -233.861607) (xy 121.82344 -233.834958) (xy 121.873054 -233.815486)
			(xy 121.925016 -233.803626) (xy 121.978166 -233.799643) (xy 122.031316 -233.803626) (xy 122.083278 -233.815486)
			(xy 122.132892 -233.834958) (xy 122.17905 -233.861607) (xy 122.220721 -233.894838) (xy 122.256973 -233.933909)
			(xy 122.286997 -233.977946) (xy 122.310123 -234.025967) (xy 122.325833 -234.076897) (xy 122.333776 -234.129601)
			(xy 122.334274 -234.15625) (xy 122.333776 -234.182899) (xy 122.562102 -234.182899) (xy 122.562102 -234.129601)
			(xy 122.570045 -234.076897) (xy 122.585755 -234.025967) (xy 122.608881 -233.977946) (xy 122.638905 -233.933909)
			(xy 122.675157 -233.894838) (xy 122.716828 -233.861607) (xy 122.762986 -233.834958) (xy 122.8126 -233.815486)
			(xy 122.864562 -233.803626) (xy 122.917712 -233.799643) (xy 122.970862 -233.803626) (xy 123.022824 -233.815486)
			(xy 123.072438 -233.834958) (xy 123.118596 -233.861607) (xy 123.160267 -233.894838) (xy 123.196519 -233.933909)
			(xy 123.226543 -233.977946) (xy 123.249669 -234.025967) (xy 123.265379 -234.076897) (xy 123.273322 -234.129601)
			(xy 123.27382 -234.15625) (xy 123.273322 -234.182899) (xy 123.502156 -234.182899) (xy 123.502156 -234.129601)
			(xy 123.510099 -234.076897) (xy 123.525809 -234.025967) (xy 123.548935 -233.977946) (xy 123.578959 -233.933909)
			(xy 123.615211 -233.894838) (xy 123.656882 -233.861607) (xy 123.70304 -233.834958) (xy 123.752654 -233.815486)
			(xy 123.804616 -233.803626) (xy 123.857766 -233.799643) (xy 123.910916 -233.803626) (xy 123.962878 -233.815486)
			(xy 124.012492 -233.834958) (xy 124.05865 -233.861607) (xy 124.100321 -233.894838) (xy 124.136573 -233.933909)
			(xy 124.166597 -233.977946) (xy 124.189723 -234.025967) (xy 124.205433 -234.076897) (xy 124.213376 -234.129601)
			(xy 124.213874 -234.15625) (xy 124.213376 -234.182899) (xy 124.441956 -234.182899) (xy 124.441956 -234.129601)
			(xy 124.449899 -234.076897) (xy 124.465609 -234.025967) (xy 124.488735 -233.977946) (xy 124.518759 -233.933909)
			(xy 124.555011 -233.894838) (xy 124.596682 -233.861607) (xy 124.64284 -233.834958) (xy 124.692454 -233.815486)
			(xy 124.744416 -233.803626) (xy 124.797566 -233.799643) (xy 124.850716 -233.803626) (xy 124.902678 -233.815486)
			(xy 124.952292 -233.834958) (xy 124.99845 -233.861607) (xy 125.040121 -233.894838) (xy 125.076373 -233.933909)
			(xy 125.106397 -233.977946) (xy 125.129523 -234.025967) (xy 125.145233 -234.076897) (xy 125.153176 -234.129601)
			(xy 125.153674 -234.15625) (xy 125.153176 -234.182899) (xy 125.381756 -234.182899) (xy 125.381756 -234.129601)
			(xy 125.389699 -234.076897) (xy 125.405409 -234.025967) (xy 125.428535 -233.977946) (xy 125.458559 -233.933909)
			(xy 125.494811 -233.894838) (xy 125.536482 -233.861607) (xy 125.58264 -233.834958) (xy 125.632254 -233.815486)
			(xy 125.684216 -233.803626) (xy 125.737366 -233.799643) (xy 125.790516 -233.803626) (xy 125.842478 -233.815486)
			(xy 125.892092 -233.834958) (xy 125.93825 -233.861607) (xy 125.979921 -233.894838) (xy 126.016173 -233.933909)
			(xy 126.046197 -233.977946) (xy 126.069323 -234.025967) (xy 126.085033 -234.076897) (xy 126.092976 -234.129601)
			(xy 126.093474 -234.15625) (xy 126.092976 -234.182899) (xy 126.321556 -234.182899) (xy 126.321556 -234.129601)
			(xy 126.329499 -234.076897) (xy 126.345209 -234.025967) (xy 126.368335 -233.977946) (xy 126.398359 -233.933909)
			(xy 126.434611 -233.894838) (xy 126.476282 -233.861607) (xy 126.52244 -233.834958) (xy 126.572054 -233.815486)
			(xy 126.624016 -233.803626) (xy 126.677166 -233.799643) (xy 126.730316 -233.803626) (xy 126.782278 -233.815486)
			(xy 126.831892 -233.834958) (xy 126.87805 -233.861607) (xy 126.919721 -233.894838) (xy 126.955973 -233.933909)
			(xy 126.985997 -233.977946) (xy 127.009123 -234.025967) (xy 127.024833 -234.076897) (xy 127.032776 -234.129601)
			(xy 127.033274 -234.15625) (xy 127.032776 -234.182899) (xy 127.261356 -234.182899) (xy 127.261356 -234.129601)
			(xy 127.269299 -234.076897) (xy 127.285009 -234.025967) (xy 127.308135 -233.977946) (xy 127.338159 -233.933909)
			(xy 127.374411 -233.894838) (xy 127.416082 -233.861607) (xy 127.46224 -233.834958) (xy 127.511854 -233.815486)
			(xy 127.563816 -233.803626) (xy 127.616966 -233.799643) (xy 127.670116 -233.803626) (xy 127.722078 -233.815486)
			(xy 127.771692 -233.834958) (xy 127.81785 -233.861607) (xy 127.859521 -233.894838) (xy 127.895773 -233.933909)
			(xy 127.925797 -233.977946) (xy 127.948923 -234.025967) (xy 127.964633 -234.076897) (xy 127.972576 -234.129601)
			(xy 127.973074 -234.15625) (xy 127.972576 -234.182899) (xy 128.201156 -234.182899) (xy 128.201156 -234.129601)
			(xy 128.209099 -234.076897) (xy 128.224809 -234.025967) (xy 128.247935 -233.977946) (xy 128.277959 -233.933909)
			(xy 128.314211 -233.894838) (xy 128.355882 -233.861607) (xy 128.40204 -233.834958) (xy 128.451654 -233.815486)
			(xy 128.503616 -233.803626) (xy 128.556766 -233.799643) (xy 128.609916 -233.803626) (xy 128.661878 -233.815486)
			(xy 128.711492 -233.834958) (xy 128.75765 -233.861607) (xy 128.799321 -233.894838) (xy 128.835573 -233.933909)
			(xy 128.865597 -233.977946) (xy 128.888723 -234.025967) (xy 128.904433 -234.076897) (xy 128.912376 -234.129601)
			(xy 128.912874 -234.15625) (xy 128.912376 -234.182899) (xy 129.140702 -234.182899) (xy 129.140702 -234.129601)
			(xy 129.148645 -234.076897) (xy 129.164355 -234.025967) (xy 129.187481 -233.977946) (xy 129.217505 -233.933909)
			(xy 129.253757 -233.894838) (xy 129.295428 -233.861607) (xy 129.341586 -233.834958) (xy 129.3912 -233.815486)
			(xy 129.443162 -233.803626) (xy 129.496312 -233.799643) (xy 129.549462 -233.803626) (xy 129.601424 -233.815486)
			(xy 129.651038 -233.834958) (xy 129.697196 -233.861607) (xy 129.738867 -233.894838) (xy 129.775119 -233.933909)
			(xy 129.805143 -233.977946) (xy 129.828269 -234.025967) (xy 129.843979 -234.076897) (xy 129.851922 -234.129601)
			(xy 129.85242 -234.15625) (xy 129.851922 -234.182899) (xy 130.080756 -234.182899) (xy 130.080756 -234.129601)
			(xy 130.088699 -234.076897) (xy 130.104409 -234.025967) (xy 130.127535 -233.977946) (xy 130.157559 -233.933909)
			(xy 130.193811 -233.894838) (xy 130.235482 -233.861607) (xy 130.28164 -233.834958) (xy 130.331254 -233.815486)
			(xy 130.383216 -233.803626) (xy 130.436366 -233.799643) (xy 130.489516 -233.803626) (xy 130.541478 -233.815486)
			(xy 130.591092 -233.834958) (xy 130.63725 -233.861607) (xy 130.678921 -233.894838) (xy 130.715173 -233.933909)
			(xy 130.745197 -233.977946) (xy 130.768323 -234.025967) (xy 130.784033 -234.076897) (xy 130.791976 -234.129601)
			(xy 130.792474 -234.15625) (xy 130.791976 -234.182899) (xy 131.020556 -234.182899) (xy 131.020556 -234.129601)
			(xy 131.028499 -234.076897) (xy 131.044209 -234.025967) (xy 131.067335 -233.977946) (xy 131.097359 -233.933909)
			(xy 131.133611 -233.894838) (xy 131.175282 -233.861607) (xy 131.22144 -233.834958) (xy 131.271054 -233.815486)
			(xy 131.323016 -233.803626) (xy 131.376166 -233.799643) (xy 131.429316 -233.803626) (xy 131.481278 -233.815486)
			(xy 131.530892 -233.834958) (xy 131.57705 -233.861607) (xy 131.618721 -233.894838) (xy 131.654973 -233.933909)
			(xy 131.684997 -233.977946) (xy 131.708123 -234.025967) (xy 131.723833 -234.076897) (xy 131.731776 -234.129601)
			(xy 131.732274 -234.15625) (xy 131.731776 -234.182899) (xy 131.960356 -234.182899) (xy 131.960356 -234.129601)
			(xy 131.968299 -234.076897) (xy 131.984009 -234.025967) (xy 132.007135 -233.977946) (xy 132.037159 -233.933909)
			(xy 132.073411 -233.894838) (xy 132.115082 -233.861607) (xy 132.16124 -233.834958) (xy 132.210854 -233.815486)
			(xy 132.262816 -233.803626) (xy 132.315966 -233.799643) (xy 132.369116 -233.803626) (xy 132.421078 -233.815486)
			(xy 132.470692 -233.834958) (xy 132.51685 -233.861607) (xy 132.558521 -233.894838) (xy 132.594773 -233.933909)
			(xy 132.624797 -233.977946) (xy 132.647923 -234.025967) (xy 132.663633 -234.076897) (xy 132.671576 -234.129601)
			(xy 132.672074 -234.15625) (xy 132.671576 -234.182899) (xy 132.900156 -234.182899) (xy 132.900156 -234.129601)
			(xy 132.908099 -234.076897) (xy 132.923809 -234.025967) (xy 132.946935 -233.977946) (xy 132.976959 -233.933909)
			(xy 133.013211 -233.894838) (xy 133.054882 -233.861607) (xy 133.10104 -233.834958) (xy 133.150654 -233.815486)
			(xy 133.202616 -233.803626) (xy 133.255766 -233.799643) (xy 133.308916 -233.803626) (xy 133.360878 -233.815486)
			(xy 133.410492 -233.834958) (xy 133.45665 -233.861607) (xy 133.498321 -233.894838) (xy 133.534573 -233.933909)
			(xy 133.564597 -233.977946) (xy 133.587723 -234.025967) (xy 133.603433 -234.076897) (xy 133.611376 -234.129601)
			(xy 133.611874 -234.15625) (xy 133.611376 -234.182899) (xy 133.839956 -234.182899) (xy 133.839956 -234.129601)
			(xy 133.847899 -234.076897) (xy 133.863609 -234.025967) (xy 133.886735 -233.977946) (xy 133.916759 -233.933909)
			(xy 133.953011 -233.894838) (xy 133.994682 -233.861607) (xy 134.04084 -233.834958) (xy 134.090454 -233.815486)
			(xy 134.142416 -233.803626) (xy 134.195566 -233.799643) (xy 134.248716 -233.803626) (xy 134.300678 -233.815486)
			(xy 134.350292 -233.834958) (xy 134.39645 -233.861607) (xy 134.438121 -233.894838) (xy 134.474373 -233.933909)
			(xy 134.504397 -233.977946) (xy 134.527523 -234.025967) (xy 134.543233 -234.076897) (xy 134.551176 -234.129601)
			(xy 134.551674 -234.15625) (xy 134.551176 -234.182899) (xy 134.543233 -234.235603) (xy 134.527523 -234.286533)
			(xy 134.504397 -234.334554) (xy 134.474373 -234.378591) (xy 134.438121 -234.417662) (xy 134.39645 -234.450893)
			(xy 134.350292 -234.477542) (xy 134.300678 -234.497014) (xy 134.248716 -234.508874) (xy 134.195566 -234.512858)
			(xy 134.142416 -234.508874) (xy 134.090454 -234.497014) (xy 134.04084 -234.477542) (xy 133.994682 -234.450893)
			(xy 133.953011 -234.417662) (xy 133.916759 -234.378591) (xy 133.886735 -234.334554) (xy 133.863609 -234.286533)
			(xy 133.847899 -234.235603) (xy 133.839956 -234.182899) (xy 133.611376 -234.182899) (xy 133.603433 -234.235603)
			(xy 133.587723 -234.286533) (xy 133.564597 -234.334554) (xy 133.534573 -234.378591) (xy 133.498321 -234.417662)
			(xy 133.45665 -234.450893) (xy 133.410492 -234.477542) (xy 133.360878 -234.497014) (xy 133.308916 -234.508874)
			(xy 133.255766 -234.512858) (xy 133.202616 -234.508874) (xy 133.150654 -234.497014) (xy 133.10104 -234.477542)
			(xy 133.054882 -234.450893) (xy 133.013211 -234.417662) (xy 132.976959 -234.378591) (xy 132.946935 -234.334554)
			(xy 132.923809 -234.286533) (xy 132.908099 -234.235603) (xy 132.900156 -234.182899) (xy 132.671576 -234.182899)
			(xy 132.663633 -234.235603) (xy 132.647923 -234.286533) (xy 132.624797 -234.334554) (xy 132.594773 -234.378591)
			(xy 132.558521 -234.417662) (xy 132.51685 -234.450893) (xy 132.470692 -234.477542) (xy 132.421078 -234.497014)
			(xy 132.369116 -234.508874) (xy 132.315966 -234.512858) (xy 132.262816 -234.508874) (xy 132.210854 -234.497014)
			(xy 132.16124 -234.477542) (xy 132.115082 -234.450893) (xy 132.073411 -234.417662) (xy 132.037159 -234.378591)
			(xy 132.007135 -234.334554) (xy 131.984009 -234.286533) (xy 131.968299 -234.235603) (xy 131.960356 -234.182899)
			(xy 131.731776 -234.182899) (xy 131.723833 -234.235603) (xy 131.708123 -234.286533) (xy 131.684997 -234.334554)
			(xy 131.654973 -234.378591) (xy 131.618721 -234.417662) (xy 131.57705 -234.450893) (xy 131.530892 -234.477542)
			(xy 131.481278 -234.497014) (xy 131.429316 -234.508874) (xy 131.376166 -234.512858) (xy 131.323016 -234.508874)
			(xy 131.271054 -234.497014) (xy 131.22144 -234.477542) (xy 131.175282 -234.450893) (xy 131.133611 -234.417662)
			(xy 131.097359 -234.378591) (xy 131.067335 -234.334554) (xy 131.044209 -234.286533) (xy 131.028499 -234.235603)
			(xy 131.020556 -234.182899) (xy 130.791976 -234.182899) (xy 130.784033 -234.235603) (xy 130.768323 -234.286533)
			(xy 130.745197 -234.334554) (xy 130.715173 -234.378591) (xy 130.678921 -234.417662) (xy 130.63725 -234.450893)
			(xy 130.591092 -234.477542) (xy 130.541478 -234.497014) (xy 130.489516 -234.508874) (xy 130.436366 -234.512858)
			(xy 130.383216 -234.508874) (xy 130.331254 -234.497014) (xy 130.28164 -234.477542) (xy 130.235482 -234.450893)
			(xy 130.193811 -234.417662) (xy 130.157559 -234.378591) (xy 130.127535 -234.334554) (xy 130.104409 -234.286533)
			(xy 130.088699 -234.235603) (xy 130.080756 -234.182899) (xy 129.851922 -234.182899) (xy 129.843979 -234.235603)
			(xy 129.828269 -234.286533) (xy 129.805143 -234.334554) (xy 129.775119 -234.378591) (xy 129.738867 -234.417662)
			(xy 129.697196 -234.450893) (xy 129.651038 -234.477542) (xy 129.601424 -234.497014) (xy 129.549462 -234.508874)
			(xy 129.496312 -234.512858) (xy 129.443162 -234.508874) (xy 129.3912 -234.497014) (xy 129.341586 -234.477542)
			(xy 129.295428 -234.450893) (xy 129.253757 -234.417662) (xy 129.217505 -234.378591) (xy 129.187481 -234.334554)
			(xy 129.164355 -234.286533) (xy 129.148645 -234.235603) (xy 129.140702 -234.182899) (xy 128.912376 -234.182899)
			(xy 128.904433 -234.235603) (xy 128.888723 -234.286533) (xy 128.865597 -234.334554) (xy 128.835573 -234.378591)
			(xy 128.799321 -234.417662) (xy 128.75765 -234.450893) (xy 128.711492 -234.477542) (xy 128.661878 -234.497014)
			(xy 128.609916 -234.508874) (xy 128.556766 -234.512858) (xy 128.503616 -234.508874) (xy 128.451654 -234.497014)
			(xy 128.40204 -234.477542) (xy 128.355882 -234.450893) (xy 128.314211 -234.417662) (xy 128.277959 -234.378591)
			(xy 128.247935 -234.334554) (xy 128.224809 -234.286533) (xy 128.209099 -234.235603) (xy 128.201156 -234.182899)
			(xy 127.972576 -234.182899) (xy 127.964633 -234.235603) (xy 127.948923 -234.286533) (xy 127.925797 -234.334554)
			(xy 127.895773 -234.378591) (xy 127.859521 -234.417662) (xy 127.81785 -234.450893) (xy 127.771692 -234.477542)
			(xy 127.722078 -234.497014) (xy 127.670116 -234.508874) (xy 127.616966 -234.512858) (xy 127.563816 -234.508874)
			(xy 127.511854 -234.497014) (xy 127.46224 -234.477542) (xy 127.416082 -234.450893) (xy 127.374411 -234.417662)
			(xy 127.338159 -234.378591) (xy 127.308135 -234.334554) (xy 127.285009 -234.286533) (xy 127.269299 -234.235603)
			(xy 127.261356 -234.182899) (xy 127.032776 -234.182899) (xy 127.024833 -234.235603) (xy 127.009123 -234.286533)
			(xy 126.985997 -234.334554) (xy 126.955973 -234.378591) (xy 126.919721 -234.417662) (xy 126.87805 -234.450893)
			(xy 126.831892 -234.477542) (xy 126.782278 -234.497014) (xy 126.730316 -234.508874) (xy 126.677166 -234.512858)
			(xy 126.624016 -234.508874) (xy 126.572054 -234.497014) (xy 126.52244 -234.477542) (xy 126.476282 -234.450893)
			(xy 126.434611 -234.417662) (xy 126.398359 -234.378591) (xy 126.368335 -234.334554) (xy 126.345209 -234.286533)
			(xy 126.329499 -234.235603) (xy 126.321556 -234.182899) (xy 126.092976 -234.182899) (xy 126.085033 -234.235603)
			(xy 126.069323 -234.286533) (xy 126.046197 -234.334554) (xy 126.016173 -234.378591) (xy 125.979921 -234.417662)
			(xy 125.93825 -234.450893) (xy 125.892092 -234.477542) (xy 125.842478 -234.497014) (xy 125.790516 -234.508874)
			(xy 125.737366 -234.512858) (xy 125.684216 -234.508874) (xy 125.632254 -234.497014) (xy 125.58264 -234.477542)
			(xy 125.536482 -234.450893) (xy 125.494811 -234.417662) (xy 125.458559 -234.378591) (xy 125.428535 -234.334554)
			(xy 125.405409 -234.286533) (xy 125.389699 -234.235603) (xy 125.381756 -234.182899) (xy 125.153176 -234.182899)
			(xy 125.145233 -234.235603) (xy 125.129523 -234.286533) (xy 125.106397 -234.334554) (xy 125.076373 -234.378591)
			(xy 125.040121 -234.417662) (xy 124.99845 -234.450893) (xy 124.952292 -234.477542) (xy 124.902678 -234.497014)
			(xy 124.850716 -234.508874) (xy 124.797566 -234.512858) (xy 124.744416 -234.508874) (xy 124.692454 -234.497014)
			(xy 124.64284 -234.477542) (xy 124.596682 -234.450893) (xy 124.555011 -234.417662) (xy 124.518759 -234.378591)
			(xy 124.488735 -234.334554) (xy 124.465609 -234.286533) (xy 124.449899 -234.235603) (xy 124.441956 -234.182899)
			(xy 124.213376 -234.182899) (xy 124.205433 -234.235603) (xy 124.189723 -234.286533) (xy 124.166597 -234.334554)
			(xy 124.136573 -234.378591) (xy 124.100321 -234.417662) (xy 124.05865 -234.450893) (xy 124.012492 -234.477542)
			(xy 123.962878 -234.497014) (xy 123.910916 -234.508874) (xy 123.857766 -234.512858) (xy 123.804616 -234.508874)
			(xy 123.752654 -234.497014) (xy 123.70304 -234.477542) (xy 123.656882 -234.450893) (xy 123.615211 -234.417662)
			(xy 123.578959 -234.378591) (xy 123.548935 -234.334554) (xy 123.525809 -234.286533) (xy 123.510099 -234.235603)
			(xy 123.502156 -234.182899) (xy 123.273322 -234.182899) (xy 123.265379 -234.235603) (xy 123.249669 -234.286533)
			(xy 123.226543 -234.334554) (xy 123.196519 -234.378591) (xy 123.160267 -234.417662) (xy 123.118596 -234.450893)
			(xy 123.072438 -234.477542) (xy 123.022824 -234.497014) (xy 122.970862 -234.508874) (xy 122.917712 -234.512858)
			(xy 122.864562 -234.508874) (xy 122.8126 -234.497014) (xy 122.762986 -234.477542) (xy 122.716828 -234.450893)
			(xy 122.675157 -234.417662) (xy 122.638905 -234.378591) (xy 122.608881 -234.334554) (xy 122.585755 -234.286533)
			(xy 122.570045 -234.235603) (xy 122.562102 -234.182899) (xy 122.333776 -234.182899) (xy 122.325833 -234.235603)
			(xy 122.310123 -234.286533) (xy 122.286997 -234.334554) (xy 122.256973 -234.378591) (xy 122.220721 -234.417662)
			(xy 122.17905 -234.450893) (xy 122.132892 -234.477542) (xy 122.083278 -234.497014) (xy 122.031316 -234.508874)
			(xy 121.978166 -234.512858) (xy 121.925016 -234.508874) (xy 121.873054 -234.497014) (xy 121.82344 -234.477542)
			(xy 121.777282 -234.450893) (xy 121.735611 -234.417662) (xy 121.699359 -234.378591) (xy 121.669335 -234.334554)
			(xy 121.646209 -234.286533) (xy 121.630499 -234.235603) (xy 121.622556 -234.182899) (xy 121.393722 -234.182899)
			(xy 121.385779 -234.235603) (xy 121.370069 -234.286533) (xy 121.346943 -234.334554) (xy 121.316919 -234.378591)
			(xy 121.280667 -234.417662) (xy 121.238996 -234.450893) (xy 121.192838 -234.477542) (xy 121.143224 -234.497014)
			(xy 121.091262 -234.508874) (xy 121.038112 -234.512858) (xy 120.984962 -234.508874) (xy 120.933 -234.497014)
			(xy 120.883386 -234.477542) (xy 120.837228 -234.450893) (xy 120.795557 -234.417662) (xy 120.759305 -234.378591)
			(xy 120.729281 -234.334554) (xy 120.706155 -234.286533) (xy 120.690445 -234.235603) (xy 120.682502 -234.182899)
			(xy 120.454176 -234.182899) (xy 120.446233 -234.235603) (xy 120.430523 -234.286533) (xy 120.407397 -234.334554)
			(xy 120.377373 -234.378591) (xy 120.341121 -234.417662) (xy 120.29945 -234.450893) (xy 120.253292 -234.477542)
			(xy 120.203678 -234.497014) (xy 120.151716 -234.508874) (xy 120.098566 -234.512858) (xy 120.045416 -234.508874)
			(xy 119.993454 -234.497014) (xy 119.94384 -234.477542) (xy 119.897682 -234.450893) (xy 119.856011 -234.417662)
			(xy 119.819759 -234.378591) (xy 119.789735 -234.334554) (xy 119.766609 -234.286533) (xy 119.750899 -234.235603)
			(xy 119.742956 -234.182899) (xy 119.514376 -234.182899) (xy 119.506433 -234.235603) (xy 119.490723 -234.286533)
			(xy 119.467597 -234.334554) (xy 119.437573 -234.378591) (xy 119.401321 -234.417662) (xy 119.35965 -234.450893)
			(xy 119.313492 -234.477542) (xy 119.263878 -234.497014) (xy 119.211916 -234.508874) (xy 119.158766 -234.512858)
			(xy 119.105616 -234.508874) (xy 119.053654 -234.497014) (xy 119.00404 -234.477542) (xy 118.957882 -234.450893)
			(xy 118.916211 -234.417662) (xy 118.879959 -234.378591) (xy 118.849935 -234.334554) (xy 118.826809 -234.286533)
			(xy 118.811099 -234.235603) (xy 118.803156 -234.182899) (xy 118.574576 -234.182899) (xy 118.566633 -234.235603)
			(xy 118.550923 -234.286533) (xy 118.527797 -234.334554) (xy 118.497773 -234.378591) (xy 118.461521 -234.417662)
			(xy 118.41985 -234.450893) (xy 118.373692 -234.477542) (xy 118.324078 -234.497014) (xy 118.272116 -234.508874)
			(xy 118.218966 -234.512858) (xy 118.165816 -234.508874) (xy 118.113854 -234.497014) (xy 118.06424 -234.477542)
			(xy 118.018082 -234.450893) (xy 117.976411 -234.417662) (xy 117.940159 -234.378591) (xy 117.910135 -234.334554)
			(xy 117.887009 -234.286533) (xy 117.871299 -234.235603) (xy 117.863356 -234.182899) (xy 117.634776 -234.182899)
			(xy 117.626833 -234.235603) (xy 117.611123 -234.286533) (xy 117.587997 -234.334554) (xy 117.557973 -234.378591)
			(xy 117.521721 -234.417662) (xy 117.48005 -234.450893) (xy 117.433892 -234.477542) (xy 117.384278 -234.497014)
			(xy 117.332316 -234.508874) (xy 117.279166 -234.512858) (xy 117.226016 -234.508874) (xy 117.174054 -234.497014)
			(xy 117.12444 -234.477542) (xy 117.078282 -234.450893) (xy 117.036611 -234.417662) (xy 117.000359 -234.378591)
			(xy 116.970335 -234.334554) (xy 116.947209 -234.286533) (xy 116.931499 -234.235603) (xy 116.923556 -234.182899)
			(xy 116.694976 -234.182899) (xy 116.687033 -234.235603) (xy 116.671323 -234.286533) (xy 116.648197 -234.334554)
			(xy 116.618173 -234.378591) (xy 116.581921 -234.417662) (xy 116.54025 -234.450893) (xy 116.494092 -234.477542)
			(xy 116.444478 -234.497014) (xy 116.392516 -234.508874) (xy 116.339366 -234.512858) (xy 116.286216 -234.508874)
			(xy 116.234254 -234.497014) (xy 116.18464 -234.477542) (xy 116.138482 -234.450893) (xy 116.096811 -234.417662)
			(xy 116.060559 -234.378591) (xy 116.030535 -234.334554) (xy 116.007409 -234.286533) (xy 115.991699 -234.235603)
			(xy 115.983756 -234.182899) (xy 115.755176 -234.182899) (xy 115.747233 -234.235603) (xy 115.731523 -234.286533)
			(xy 115.708397 -234.334554) (xy 115.678373 -234.378591) (xy 115.642121 -234.417662) (xy 115.60045 -234.450893)
			(xy 115.554292 -234.477542) (xy 115.504678 -234.497014) (xy 115.452716 -234.508874) (xy 115.399566 -234.512858)
			(xy 115.346416 -234.508874) (xy 115.294454 -234.497014) (xy 115.24484 -234.477542) (xy 115.198682 -234.450893)
			(xy 115.157011 -234.417662) (xy 115.120759 -234.378591) (xy 115.090735 -234.334554) (xy 115.067609 -234.286533)
			(xy 115.051899 -234.235603) (xy 115.043956 -234.182899) (xy 114.815376 -234.182899) (xy 114.807433 -234.235603)
			(xy 114.791723 -234.286533) (xy 114.768597 -234.334554) (xy 114.738573 -234.378591) (xy 114.702321 -234.417662)
			(xy 114.66065 -234.450893) (xy 114.614492 -234.477542) (xy 114.564878 -234.497014) (xy 114.512916 -234.508874)
			(xy 114.459766 -234.512858) (xy 114.406616 -234.508874) (xy 114.354654 -234.497014) (xy 114.30504 -234.477542)
			(xy 114.258882 -234.450893) (xy 114.217211 -234.417662) (xy 114.180959 -234.378591) (xy 114.150935 -234.334554)
			(xy 114.127809 -234.286533) (xy 114.112099 -234.235603) (xy 114.104156 -234.182899) (xy 113.875576 -234.182899)
			(xy 113.867633 -234.235603) (xy 113.851923 -234.286533) (xy 113.828797 -234.334554) (xy 113.798773 -234.378591)
			(xy 113.762521 -234.417662) (xy 113.72085 -234.450893) (xy 113.674692 -234.477542) (xy 113.625078 -234.497014)
			(xy 113.573116 -234.508874) (xy 113.519966 -234.512858) (xy 113.466816 -234.508874) (xy 113.414854 -234.497014)
			(xy 113.36524 -234.477542) (xy 113.319082 -234.450893) (xy 113.277411 -234.417662) (xy 113.241159 -234.378591)
			(xy 113.211135 -234.334554) (xy 113.188009 -234.286533) (xy 113.172299 -234.235603) (xy 113.164356 -234.182899)
			(xy 112.935776 -234.182899) (xy 112.927833 -234.235603) (xy 112.912123 -234.286533) (xy 112.888997 -234.334554)
			(xy 112.858973 -234.378591) (xy 112.822721 -234.417662) (xy 112.78105 -234.450893) (xy 112.734892 -234.477542)
			(xy 112.685278 -234.497014) (xy 112.633316 -234.508874) (xy 112.580166 -234.512858) (xy 112.527016 -234.508874)
			(xy 112.475054 -234.497014) (xy 112.42544 -234.477542) (xy 112.379282 -234.450893) (xy 112.337611 -234.417662)
			(xy 112.301359 -234.378591) (xy 112.271335 -234.334554) (xy 112.248209 -234.286533) (xy 112.232499 -234.235603)
			(xy 112.224556 -234.182899) (xy 111.995976 -234.182899) (xy 111.988033 -234.235603) (xy 111.972323 -234.286533)
			(xy 111.949197 -234.334554) (xy 111.919173 -234.378591) (xy 111.882921 -234.417662) (xy 111.84125 -234.450893)
			(xy 111.795092 -234.477542) (xy 111.745478 -234.497014) (xy 111.693516 -234.508874) (xy 111.640366 -234.512858)
			(xy 111.587216 -234.508874) (xy 111.535254 -234.497014) (xy 111.48564 -234.477542) (xy 111.439482 -234.450893)
			(xy 111.397811 -234.417662) (xy 111.361559 -234.378591) (xy 111.331535 -234.334554) (xy 111.308409 -234.286533)
			(xy 111.292699 -234.235603) (xy 111.284756 -234.182899) (xy 111.056176 -234.182899) (xy 111.048233 -234.235603)
			(xy 111.032523 -234.286533) (xy 111.009397 -234.334554) (xy 110.979373 -234.378591) (xy 110.943121 -234.417662)
			(xy 110.90145 -234.450893) (xy 110.855292 -234.477542) (xy 110.805678 -234.497014) (xy 110.753716 -234.508874)
			(xy 110.700566 -234.512858) (xy 110.647416 -234.508874) (xy 110.595454 -234.497014) (xy 110.54584 -234.477542)
			(xy 110.499682 -234.450893) (xy 110.458011 -234.417662) (xy 110.421759 -234.378591) (xy 110.391735 -234.334554)
			(xy 110.368609 -234.286533) (xy 110.352899 -234.235603) (xy 110.344956 -234.182899) (xy 110.116376 -234.182899)
			(xy 110.108433 -234.235603) (xy 110.092723 -234.286533) (xy 110.069597 -234.334554) (xy 110.039573 -234.378591)
			(xy 110.003321 -234.417662) (xy 109.96165 -234.450893) (xy 109.915492 -234.477542) (xy 109.865878 -234.497014)
			(xy 109.813916 -234.508874) (xy 109.760766 -234.512858) (xy 109.707616 -234.508874) (xy 109.655654 -234.497014)
			(xy 109.60604 -234.477542) (xy 109.559882 -234.450893) (xy 109.518211 -234.417662) (xy 109.481959 -234.378591)
			(xy 109.451935 -234.334554) (xy 109.428809 -234.286533) (xy 109.413099 -234.235603) (xy 109.405156 -234.182899)
			(xy 109.176547 -234.182899) (xy 109.176521 -234.18423) (xy 109.16776 -234.239499) (xy 109.15046 -234.292717)
			(xy 109.125049 -234.342574) (xy 109.092152 -234.387842) (xy 109.052578 -234.427406) (xy 109.007302 -234.460293)
			(xy 108.957439 -234.485693) (xy 108.904217 -234.502979) (xy 108.848946 -234.511728) (xy 108.820966 -234.512358)
			(xy 108.795237 -234.51191) (xy 108.744313 -234.504514) (xy 108.694984 -234.489866) (xy 108.648276 -234.468272)
			(xy 108.605162 -234.440181) (xy 108.56654 -234.406178) (xy 108.533213 -234.36697) (xy 108.505875 -234.323375)
			(xy 108.495084 -234.300014) (xy 108.481876 -234.269788) (xy 108.220256 -234.269788) (xy 108.207048 -234.300014)
			(xy 108.195493 -234.324909) (xy 108.165873 -234.371113) (xy 108.129517 -234.412228) (xy 108.087287 -234.447282)
			(xy 108.040181 -234.475445) (xy 107.989313 -234.496051) (xy 107.935887 -234.508613) (xy 107.881166 -234.512834)
			(xy 107.826445 -234.508613) (xy 107.773019 -234.496051) (xy 107.722151 -234.475445) (xy 107.675045 -234.447282)
			(xy 107.632815 -234.412228) (xy 107.596459 -234.371113) (xy 107.566839 -234.324909) (xy 107.555284 -234.300014)
			(xy 107.542076 -234.269788) (xy 107.280456 -234.269788) (xy 107.267248 -234.300014) (xy 107.255693 -234.324909)
			(xy 107.226073 -234.371113) (xy 107.189717 -234.412228) (xy 107.147487 -234.447282) (xy 107.100381 -234.475445)
			(xy 107.049513 -234.496051) (xy 106.996087 -234.508613) (xy 106.941366 -234.512834) (xy 106.886645 -234.508613)
			(xy 106.833219 -234.496051) (xy 106.782351 -234.475445) (xy 106.735245 -234.447282) (xy 106.693015 -234.412228)
			(xy 106.656659 -234.371113) (xy 106.627039 -234.324909) (xy 106.615484 -234.300014) (xy 106.602276 -234.269788)
			(xy 106.340656 -234.269788) (xy 106.327448 -234.300014) (xy 106.315893 -234.324909) (xy 106.286273 -234.371113)
			(xy 106.249917 -234.412228) (xy 106.207687 -234.447282) (xy 106.160581 -234.475445) (xy 106.109713 -234.496051)
			(xy 106.056287 -234.508613) (xy 106.001566 -234.512834) (xy 105.946845 -234.508613) (xy 105.893419 -234.496051)
			(xy 105.842551 -234.475445) (xy 105.795445 -234.447282) (xy 105.753215 -234.412228) (xy 105.716859 -234.371113)
			(xy 105.687239 -234.324909) (xy 105.675684 -234.300014) (xy 105.662476 -234.269788) (xy 104.461056 -234.269788)
			(xy 104.447848 -234.300014) (xy 104.436293 -234.324909) (xy 104.406673 -234.371113) (xy 104.370317 -234.412228)
			(xy 104.328087 -234.447282) (xy 104.280981 -234.475445) (xy 104.230113 -234.496051) (xy 104.176687 -234.508613)
			(xy 104.121966 -234.512834) (xy 104.067245 -234.508613) (xy 104.013819 -234.496051) (xy 103.962951 -234.475445)
			(xy 103.915845 -234.447282) (xy 103.873615 -234.412228) (xy 103.837259 -234.371113) (xy 103.807639 -234.324909)
			(xy 103.796084 -234.300014) (xy 103.782876 -234.269788) (xy 103.5812 -234.269788) (xy 102.807283 -235.043705)
			(xy 104.259878 -235.043705) (xy 104.259878 -234.990407) (xy 104.267821 -234.937703) (xy 104.283531 -234.886773)
			(xy 104.306657 -234.838752) (xy 104.336681 -234.794715) (xy 104.372933 -234.755644) (xy 104.414604 -234.722413)
			(xy 104.460762 -234.695764) (xy 104.510376 -234.676292) (xy 104.562338 -234.664432) (xy 104.615488 -234.660449)
			(xy 104.668638 -234.664432) (xy 104.7206 -234.676292) (xy 104.770214 -234.695764) (xy 104.816372 -234.722413)
			(xy 104.858043 -234.755644) (xy 104.894295 -234.794715) (xy 104.924319 -234.838752) (xy 104.947445 -234.886773)
			(xy 104.963155 -234.937703) (xy 104.971098 -234.990407) (xy 104.971216 -234.996715) (xy 108.935256 -234.996715)
			(xy 108.935256 -234.943417) (xy 108.943199 -234.890713) (xy 108.958909 -234.839783) (xy 108.982035 -234.791762)
			(xy 109.012059 -234.747725) (xy 109.048311 -234.708654) (xy 109.089982 -234.675423) (xy 109.13614 -234.648774)
			(xy 109.185754 -234.629302) (xy 109.237716 -234.617442) (xy 109.290866 -234.613459) (xy 109.344016 -234.617442)
			(xy 109.395978 -234.629302) (xy 109.445592 -234.648774) (xy 109.49175 -234.675423) (xy 109.533421 -234.708654)
			(xy 109.569673 -234.747725) (xy 109.599697 -234.791762) (xy 109.622823 -234.839783) (xy 109.638533 -234.890713)
			(xy 109.646476 -234.943417) (xy 109.646974 -234.970066) (xy 109.646476 -234.996715) (xy 109.87531 -234.996715)
			(xy 109.87531 -234.943417) (xy 109.883253 -234.890713) (xy 109.898963 -234.839783) (xy 109.922089 -234.791762)
			(xy 109.952113 -234.747725) (xy 109.988365 -234.708654) (xy 110.030036 -234.675423) (xy 110.076194 -234.648774)
			(xy 110.125808 -234.629302) (xy 110.17777 -234.617442) (xy 110.23092 -234.613459) (xy 110.28407 -234.617442)
			(xy 110.336032 -234.629302) (xy 110.385646 -234.648774) (xy 110.431804 -234.675423) (xy 110.473475 -234.708654)
			(xy 110.509727 -234.747725) (xy 110.539751 -234.791762) (xy 110.562877 -234.839783) (xy 110.578587 -234.890713)
			(xy 110.58653 -234.943417) (xy 110.587028 -234.970066) (xy 110.58653 -234.996715) (xy 110.814856 -234.996715)
			(xy 110.814856 -234.943417) (xy 110.822799 -234.890713) (xy 110.838509 -234.839783) (xy 110.861635 -234.791762)
			(xy 110.891659 -234.747725) (xy 110.927911 -234.708654) (xy 110.969582 -234.675423) (xy 111.01574 -234.648774)
			(xy 111.065354 -234.629302) (xy 111.117316 -234.617442) (xy 111.170466 -234.613459) (xy 111.223616 -234.617442)
			(xy 111.275578 -234.629302) (xy 111.325192 -234.648774) (xy 111.37135 -234.675423) (xy 111.413021 -234.708654)
			(xy 111.449273 -234.747725) (xy 111.479297 -234.791762) (xy 111.502423 -234.839783) (xy 111.518133 -234.890713)
			(xy 111.526076 -234.943417) (xy 111.526574 -234.970066) (xy 111.526076 -234.996715) (xy 111.754656 -234.996715)
			(xy 111.754656 -234.943417) (xy 111.762599 -234.890713) (xy 111.778309 -234.839783) (xy 111.801435 -234.791762)
			(xy 111.831459 -234.747725) (xy 111.867711 -234.708654) (xy 111.909382 -234.675423) (xy 111.95554 -234.648774)
			(xy 112.005154 -234.629302) (xy 112.057116 -234.617442) (xy 112.110266 -234.613459) (xy 112.163416 -234.617442)
			(xy 112.215378 -234.629302) (xy 112.264992 -234.648774) (xy 112.31115 -234.675423) (xy 112.352821 -234.708654)
			(xy 112.389073 -234.747725) (xy 112.419097 -234.791762) (xy 112.442223 -234.839783) (xy 112.457933 -234.890713)
			(xy 112.465876 -234.943417) (xy 112.466374 -234.970066) (xy 112.465876 -234.996715) (xy 112.694456 -234.996715)
			(xy 112.694456 -234.943417) (xy 112.702399 -234.890713) (xy 112.718109 -234.839783) (xy 112.741235 -234.791762)
			(xy 112.771259 -234.747725) (xy 112.807511 -234.708654) (xy 112.849182 -234.675423) (xy 112.89534 -234.648774)
			(xy 112.944954 -234.629302) (xy 112.996916 -234.617442) (xy 113.050066 -234.613459) (xy 113.103216 -234.617442)
			(xy 113.155178 -234.629302) (xy 113.204792 -234.648774) (xy 113.25095 -234.675423) (xy 113.292621 -234.708654)
			(xy 113.328873 -234.747725) (xy 113.358897 -234.791762) (xy 113.382023 -234.839783) (xy 113.397733 -234.890713)
			(xy 113.405676 -234.943417) (xy 113.406174 -234.970066) (xy 113.405676 -234.996715) (xy 113.63451 -234.996715)
			(xy 113.63451 -234.943417) (xy 113.642453 -234.890713) (xy 113.658163 -234.839783) (xy 113.681289 -234.791762)
			(xy 113.711313 -234.747725) (xy 113.747565 -234.708654) (xy 113.789236 -234.675423) (xy 113.835394 -234.648774)
			(xy 113.885008 -234.629302) (xy 113.93697 -234.617442) (xy 113.99012 -234.613459) (xy 114.04327 -234.617442)
			(xy 114.095232 -234.629302) (xy 114.144846 -234.648774) (xy 114.191004 -234.675423) (xy 114.232675 -234.708654)
			(xy 114.268927 -234.747725) (xy 114.298951 -234.791762) (xy 114.322077 -234.839783) (xy 114.337787 -234.890713)
			(xy 114.34573 -234.943417) (xy 114.346228 -234.970066) (xy 114.34573 -234.996715) (xy 121.152402 -234.996715)
			(xy 121.152402 -234.943417) (xy 121.160345 -234.890713) (xy 121.176055 -234.839783) (xy 121.199181 -234.791762)
			(xy 121.229205 -234.747725) (xy 121.265457 -234.708654) (xy 121.307128 -234.675423) (xy 121.353286 -234.648774)
			(xy 121.4029 -234.629302) (xy 121.454862 -234.617442) (xy 121.508012 -234.613459) (xy 121.561162 -234.617442)
			(xy 121.613124 -234.629302) (xy 121.662738 -234.648774) (xy 121.708896 -234.675423) (xy 121.750567 -234.708654)
			(xy 121.786819 -234.747725) (xy 121.816843 -234.791762) (xy 121.839969 -234.839783) (xy 121.855679 -234.890713)
			(xy 121.863622 -234.943417) (xy 121.86412 -234.970066) (xy 121.863622 -234.996715) (xy 122.092202 -234.996715)
			(xy 122.092202 -234.943417) (xy 122.100145 -234.890713) (xy 122.115855 -234.839783) (xy 122.138981 -234.791762)
			(xy 122.169005 -234.747725) (xy 122.205257 -234.708654) (xy 122.246928 -234.675423) (xy 122.293086 -234.648774)
			(xy 122.3427 -234.629302) (xy 122.394662 -234.617442) (xy 122.447812 -234.613459) (xy 122.500962 -234.617442)
			(xy 122.552924 -234.629302) (xy 122.602538 -234.648774) (xy 122.648696 -234.675423) (xy 122.690367 -234.708654)
			(xy 122.726619 -234.747725) (xy 122.756643 -234.791762) (xy 122.779769 -234.839783) (xy 122.795479 -234.890713)
			(xy 122.803422 -234.943417) (xy 122.80392 -234.970066) (xy 122.803422 -234.996715) (xy 123.032002 -234.996715)
			(xy 123.032002 -234.943417) (xy 123.039945 -234.890713) (xy 123.055655 -234.839783) (xy 123.078781 -234.791762)
			(xy 123.108805 -234.747725) (xy 123.145057 -234.708654) (xy 123.186728 -234.675423) (xy 123.232886 -234.648774)
			(xy 123.2825 -234.629302) (xy 123.334462 -234.617442) (xy 123.387612 -234.613459) (xy 123.440762 -234.617442)
			(xy 123.492724 -234.629302) (xy 123.542338 -234.648774) (xy 123.588496 -234.675423) (xy 123.630167 -234.708654)
			(xy 123.666419 -234.747725) (xy 123.696443 -234.791762) (xy 123.719569 -234.839783) (xy 123.735279 -234.890713)
			(xy 123.743222 -234.943417) (xy 123.74372 -234.970066) (xy 123.743222 -234.996715) (xy 123.971802 -234.996715)
			(xy 123.971802 -234.943417) (xy 123.979745 -234.890713) (xy 123.995455 -234.839783) (xy 124.018581 -234.791762)
			(xy 124.048605 -234.747725) (xy 124.084857 -234.708654) (xy 124.126528 -234.675423) (xy 124.172686 -234.648774)
			(xy 124.2223 -234.629302) (xy 124.274262 -234.617442) (xy 124.327412 -234.613459) (xy 124.380562 -234.617442)
			(xy 124.432524 -234.629302) (xy 124.482138 -234.648774) (xy 124.528296 -234.675423) (xy 124.569967 -234.708654)
			(xy 124.606219 -234.747725) (xy 124.636243 -234.791762) (xy 124.659369 -234.839783) (xy 124.675079 -234.890713)
			(xy 124.683022 -234.943417) (xy 124.68352 -234.970066) (xy 124.683022 -234.996715) (xy 124.911856 -234.996715)
			(xy 124.911856 -234.943417) (xy 124.919799 -234.890713) (xy 124.935509 -234.839783) (xy 124.958635 -234.791762)
			(xy 124.988659 -234.747725) (xy 125.024911 -234.708654) (xy 125.066582 -234.675423) (xy 125.11274 -234.648774)
			(xy 125.162354 -234.629302) (xy 125.214316 -234.617442) (xy 125.267466 -234.613459) (xy 125.320616 -234.617442)
			(xy 125.372578 -234.629302) (xy 125.422192 -234.648774) (xy 125.46835 -234.675423) (xy 125.510021 -234.708654)
			(xy 125.546273 -234.747725) (xy 125.576297 -234.791762) (xy 125.599423 -234.839783) (xy 125.615133 -234.890713)
			(xy 125.623076 -234.943417) (xy 125.623574 -234.970066) (xy 125.623076 -234.996715) (xy 125.851402 -234.996715)
			(xy 125.851402 -234.943417) (xy 125.859345 -234.890713) (xy 125.875055 -234.839783) (xy 125.898181 -234.791762)
			(xy 125.928205 -234.747725) (xy 125.964457 -234.708654) (xy 126.006128 -234.675423) (xy 126.052286 -234.648774)
			(xy 126.1019 -234.629302) (xy 126.153862 -234.617442) (xy 126.207012 -234.613459) (xy 126.260162 -234.617442)
			(xy 126.312124 -234.629302) (xy 126.361738 -234.648774) (xy 126.407896 -234.675423) (xy 126.449567 -234.708654)
			(xy 126.485819 -234.747725) (xy 126.515843 -234.791762) (xy 126.538969 -234.839783) (xy 126.554679 -234.890713)
			(xy 126.562622 -234.943417) (xy 126.56312 -234.970066) (xy 126.562622 -234.996715) (xy 126.791202 -234.996715)
			(xy 126.791202 -234.943417) (xy 126.799145 -234.890713) (xy 126.814855 -234.839783) (xy 126.837981 -234.791762)
			(xy 126.868005 -234.747725) (xy 126.904257 -234.708654) (xy 126.945928 -234.675423) (xy 126.992086 -234.648774)
			(xy 127.0417 -234.629302) (xy 127.093662 -234.617442) (xy 127.146812 -234.613459) (xy 127.199962 -234.617442)
			(xy 127.251924 -234.629302) (xy 127.301538 -234.648774) (xy 127.347696 -234.675423) (xy 127.389367 -234.708654)
			(xy 127.425619 -234.747725) (xy 127.455643 -234.791762) (xy 127.478769 -234.839783) (xy 127.494479 -234.890713)
			(xy 127.502422 -234.943417) (xy 127.50292 -234.970066) (xy 127.502422 -234.996715) (xy 127.731002 -234.996715)
			(xy 127.731002 -234.943417) (xy 127.738945 -234.890713) (xy 127.754655 -234.839783) (xy 127.777781 -234.791762)
			(xy 127.807805 -234.747725) (xy 127.844057 -234.708654) (xy 127.885728 -234.675423) (xy 127.931886 -234.648774)
			(xy 127.9815 -234.629302) (xy 128.033462 -234.617442) (xy 128.086612 -234.613459) (xy 128.139762 -234.617442)
			(xy 128.191724 -234.629302) (xy 128.241338 -234.648774) (xy 128.287496 -234.675423) (xy 128.329167 -234.708654)
			(xy 128.365419 -234.747725) (xy 128.395443 -234.791762) (xy 128.418569 -234.839783) (xy 128.434279 -234.890713)
			(xy 128.442222 -234.943417) (xy 128.44272 -234.970066) (xy 128.442222 -234.996715) (xy 128.670802 -234.996715)
			(xy 128.670802 -234.943417) (xy 128.678745 -234.890713) (xy 128.694455 -234.839783) (xy 128.717581 -234.791762)
			(xy 128.747605 -234.747725) (xy 128.783857 -234.708654) (xy 128.825528 -234.675423) (xy 128.871686 -234.648774)
			(xy 128.9213 -234.629302) (xy 128.973262 -234.617442) (xy 129.026412 -234.613459) (xy 129.079562 -234.617442)
			(xy 129.131524 -234.629302) (xy 129.181138 -234.648774) (xy 129.227296 -234.675423) (xy 129.268967 -234.708654)
			(xy 129.305219 -234.747725) (xy 129.335243 -234.791762) (xy 129.358369 -234.839783) (xy 129.374079 -234.890713)
			(xy 129.382022 -234.943417) (xy 129.38252 -234.970066) (xy 129.382022 -234.996715) (xy 129.610602 -234.996715)
			(xy 129.610602 -234.943417) (xy 129.618545 -234.890713) (xy 129.634255 -234.839783) (xy 129.657381 -234.791762)
			(xy 129.687405 -234.747725) (xy 129.723657 -234.708654) (xy 129.765328 -234.675423) (xy 129.811486 -234.648774)
			(xy 129.8611 -234.629302) (xy 129.913062 -234.617442) (xy 129.966212 -234.613459) (xy 130.019362 -234.617442)
			(xy 130.071324 -234.629302) (xy 130.120938 -234.648774) (xy 130.167096 -234.675423) (xy 130.208767 -234.708654)
			(xy 130.245019 -234.747725) (xy 130.275043 -234.791762) (xy 130.298169 -234.839783) (xy 130.313879 -234.890713)
			(xy 130.321822 -234.943417) (xy 130.32232 -234.970066) (xy 130.321822 -234.996715) (xy 130.550402 -234.996715)
			(xy 130.550402 -234.943417) (xy 130.558345 -234.890713) (xy 130.574055 -234.839783) (xy 130.597181 -234.791762)
			(xy 130.627205 -234.747725) (xy 130.663457 -234.708654) (xy 130.705128 -234.675423) (xy 130.751286 -234.648774)
			(xy 130.8009 -234.629302) (xy 130.852862 -234.617442) (xy 130.906012 -234.613459) (xy 130.959162 -234.617442)
			(xy 131.011124 -234.629302) (xy 131.060738 -234.648774) (xy 131.106896 -234.675423) (xy 131.148567 -234.708654)
			(xy 131.184819 -234.747725) (xy 131.214843 -234.791762) (xy 131.237969 -234.839783) (xy 131.253679 -234.890713)
			(xy 131.261622 -234.943417) (xy 131.26212 -234.970066) (xy 131.261622 -234.996715) (xy 131.490456 -234.996715)
			(xy 131.490456 -234.943417) (xy 131.498399 -234.890713) (xy 131.514109 -234.839783) (xy 131.537235 -234.791762)
			(xy 131.567259 -234.747725) (xy 131.603511 -234.708654) (xy 131.645182 -234.675423) (xy 131.69134 -234.648774)
			(xy 131.740954 -234.629302) (xy 131.792916 -234.617442) (xy 131.846066 -234.613459) (xy 131.899216 -234.617442)
			(xy 131.951178 -234.629302) (xy 132.000792 -234.648774) (xy 132.04695 -234.675423) (xy 132.088621 -234.708654)
			(xy 132.124873 -234.747725) (xy 132.154897 -234.791762) (xy 132.178023 -234.839783) (xy 132.193733 -234.890713)
			(xy 132.201676 -234.943417) (xy 132.202174 -234.970066) (xy 132.201676 -234.996715) (xy 132.430002 -234.996715)
			(xy 132.430002 -234.943417) (xy 132.437945 -234.890713) (xy 132.453655 -234.839783) (xy 132.476781 -234.791762)
			(xy 132.506805 -234.747725) (xy 132.543057 -234.708654) (xy 132.584728 -234.675423) (xy 132.630886 -234.648774)
			(xy 132.6805 -234.629302) (xy 132.732462 -234.617442) (xy 132.785612 -234.613459) (xy 132.838762 -234.617442)
			(xy 132.890724 -234.629302) (xy 132.940338 -234.648774) (xy 132.986496 -234.675423) (xy 133.028167 -234.708654)
			(xy 133.064419 -234.747725) (xy 133.094443 -234.791762) (xy 133.117569 -234.839783) (xy 133.133279 -234.890713)
			(xy 133.141222 -234.943417) (xy 133.14172 -234.970066) (xy 133.141222 -234.996715) (xy 133.370056 -234.996715)
			(xy 133.370056 -234.943417) (xy 133.377999 -234.890713) (xy 133.393709 -234.839783) (xy 133.416835 -234.791762)
			(xy 133.446859 -234.747725) (xy 133.483111 -234.708654) (xy 133.524782 -234.675423) (xy 133.57094 -234.648774)
			(xy 133.620554 -234.629302) (xy 133.672516 -234.617442) (xy 133.725666 -234.613459) (xy 133.778816 -234.617442)
			(xy 133.830778 -234.629302) (xy 133.880392 -234.648774) (xy 133.92655 -234.675423) (xy 133.968221 -234.708654)
			(xy 134.004473 -234.747725) (xy 134.034497 -234.791762) (xy 134.057623 -234.839783) (xy 134.073333 -234.890713)
			(xy 134.081276 -234.943417) (xy 134.081774 -234.970066) (xy 134.081276 -234.996715) (xy 134.309856 -234.996715)
			(xy 134.309856 -234.943417) (xy 134.317799 -234.890713) (xy 134.333509 -234.839783) (xy 134.356635 -234.791762)
			(xy 134.386659 -234.747725) (xy 134.422911 -234.708654) (xy 134.464582 -234.675423) (xy 134.51074 -234.648774)
			(xy 134.560354 -234.629302) (xy 134.612316 -234.617442) (xy 134.665466 -234.613459) (xy 134.718616 -234.617442)
			(xy 134.770578 -234.629302) (xy 134.820192 -234.648774) (xy 134.86635 -234.675423) (xy 134.908021 -234.708654)
			(xy 134.944273 -234.747725) (xy 134.974297 -234.791762) (xy 134.997423 -234.839783) (xy 135.013133 -234.890713)
			(xy 135.021076 -234.943417) (xy 135.021574 -234.970066) (xy 135.021076 -234.996715) (xy 135.013133 -235.049419)
			(xy 134.997423 -235.100349) (xy 134.974297 -235.14837) (xy 134.944273 -235.192407) (xy 134.908021 -235.231478)
			(xy 134.86635 -235.264709) (xy 134.820192 -235.291358) (xy 134.770578 -235.31083) (xy 134.718616 -235.32269)
			(xy 134.665466 -235.326674) (xy 134.612316 -235.32269) (xy 134.560354 -235.31083) (xy 134.51074 -235.291358)
			(xy 134.464582 -235.264709) (xy 134.422911 -235.231478) (xy 134.386659 -235.192407) (xy 134.356635 -235.14837)
			(xy 134.333509 -235.100349) (xy 134.317799 -235.049419) (xy 134.309856 -234.996715) (xy 134.081276 -234.996715)
			(xy 134.073333 -235.049419) (xy 134.057623 -235.100349) (xy 134.034497 -235.14837) (xy 134.004473 -235.192407)
			(xy 133.968221 -235.231478) (xy 133.92655 -235.264709) (xy 133.880392 -235.291358) (xy 133.830778 -235.31083)
			(xy 133.778816 -235.32269) (xy 133.725666 -235.326674) (xy 133.672516 -235.32269) (xy 133.620554 -235.31083)
			(xy 133.57094 -235.291358) (xy 133.524782 -235.264709) (xy 133.483111 -235.231478) (xy 133.446859 -235.192407)
			(xy 133.416835 -235.14837) (xy 133.393709 -235.100349) (xy 133.377999 -235.049419) (xy 133.370056 -234.996715)
			(xy 133.141222 -234.996715) (xy 133.133279 -235.049419) (xy 133.117569 -235.100349) (xy 133.094443 -235.14837)
			(xy 133.064419 -235.192407) (xy 133.028167 -235.231478) (xy 132.986496 -235.264709) (xy 132.940338 -235.291358)
			(xy 132.890724 -235.31083) (xy 132.838762 -235.32269) (xy 132.785612 -235.326674) (xy 132.732462 -235.32269)
			(xy 132.6805 -235.31083) (xy 132.630886 -235.291358) (xy 132.584728 -235.264709) (xy 132.543057 -235.231478)
			(xy 132.506805 -235.192407) (xy 132.476781 -235.14837) (xy 132.453655 -235.100349) (xy 132.437945 -235.049419)
			(xy 132.430002 -234.996715) (xy 132.201676 -234.996715) (xy 132.193733 -235.049419) (xy 132.178023 -235.100349)
			(xy 132.154897 -235.14837) (xy 132.124873 -235.192407) (xy 132.088621 -235.231478) (xy 132.04695 -235.264709)
			(xy 132.000792 -235.291358) (xy 131.951178 -235.31083) (xy 131.899216 -235.32269) (xy 131.846066 -235.326674)
			(xy 131.792916 -235.32269) (xy 131.740954 -235.31083) (xy 131.69134 -235.291358) (xy 131.645182 -235.264709)
			(xy 131.603511 -235.231478) (xy 131.567259 -235.192407) (xy 131.537235 -235.14837) (xy 131.514109 -235.100349)
			(xy 131.498399 -235.049419) (xy 131.490456 -234.996715) (xy 131.261622 -234.996715) (xy 131.253679 -235.049419)
			(xy 131.237969 -235.100349) (xy 131.214843 -235.14837) (xy 131.184819 -235.192407) (xy 131.148567 -235.231478)
			(xy 131.106896 -235.264709) (xy 131.060738 -235.291358) (xy 131.011124 -235.31083) (xy 130.959162 -235.32269)
			(xy 130.906012 -235.326674) (xy 130.852862 -235.32269) (xy 130.8009 -235.31083) (xy 130.751286 -235.291358)
			(xy 130.705128 -235.264709) (xy 130.663457 -235.231478) (xy 130.627205 -235.192407) (xy 130.597181 -235.14837)
			(xy 130.574055 -235.100349) (xy 130.558345 -235.049419) (xy 130.550402 -234.996715) (xy 130.321822 -234.996715)
			(xy 130.313879 -235.049419) (xy 130.298169 -235.100349) (xy 130.275043 -235.14837) (xy 130.245019 -235.192407)
			(xy 130.208767 -235.231478) (xy 130.167096 -235.264709) (xy 130.120938 -235.291358) (xy 130.071324 -235.31083)
			(xy 130.019362 -235.32269) (xy 129.966212 -235.326674) (xy 129.913062 -235.32269) (xy 129.8611 -235.31083)
			(xy 129.811486 -235.291358) (xy 129.765328 -235.264709) (xy 129.723657 -235.231478) (xy 129.687405 -235.192407)
			(xy 129.657381 -235.14837) (xy 129.634255 -235.100349) (xy 129.618545 -235.049419) (xy 129.610602 -234.996715)
			(xy 129.382022 -234.996715) (xy 129.374079 -235.049419) (xy 129.358369 -235.100349) (xy 129.335243 -235.14837)
			(xy 129.305219 -235.192407) (xy 129.268967 -235.231478) (xy 129.227296 -235.264709) (xy 129.181138 -235.291358)
			(xy 129.131524 -235.31083) (xy 129.079562 -235.32269) (xy 129.026412 -235.326674) (xy 128.973262 -235.32269)
			(xy 128.9213 -235.31083) (xy 128.871686 -235.291358) (xy 128.825528 -235.264709) (xy 128.783857 -235.231478)
			(xy 128.747605 -235.192407) (xy 128.717581 -235.14837) (xy 128.694455 -235.100349) (xy 128.678745 -235.049419)
			(xy 128.670802 -234.996715) (xy 128.442222 -234.996715) (xy 128.434279 -235.049419) (xy 128.418569 -235.100349)
			(xy 128.395443 -235.14837) (xy 128.365419 -235.192407) (xy 128.329167 -235.231478) (xy 128.287496 -235.264709)
			(xy 128.241338 -235.291358) (xy 128.191724 -235.31083) (xy 128.139762 -235.32269) (xy 128.086612 -235.326674)
			(xy 128.033462 -235.32269) (xy 127.9815 -235.31083) (xy 127.931886 -235.291358) (xy 127.885728 -235.264709)
			(xy 127.844057 -235.231478) (xy 127.807805 -235.192407) (xy 127.777781 -235.14837) (xy 127.754655 -235.100349)
			(xy 127.738945 -235.049419) (xy 127.731002 -234.996715) (xy 127.502422 -234.996715) (xy 127.494479 -235.049419)
			(xy 127.478769 -235.100349) (xy 127.455643 -235.14837) (xy 127.425619 -235.192407) (xy 127.389367 -235.231478)
			(xy 127.347696 -235.264709) (xy 127.301538 -235.291358) (xy 127.251924 -235.31083) (xy 127.199962 -235.32269)
			(xy 127.146812 -235.326674) (xy 127.093662 -235.32269) (xy 127.0417 -235.31083) (xy 126.992086 -235.291358)
			(xy 126.945928 -235.264709) (xy 126.904257 -235.231478) (xy 126.868005 -235.192407) (xy 126.837981 -235.14837)
			(xy 126.814855 -235.100349) (xy 126.799145 -235.049419) (xy 126.791202 -234.996715) (xy 126.562622 -234.996715)
			(xy 126.554679 -235.049419) (xy 126.538969 -235.100349) (xy 126.515843 -235.14837) (xy 126.485819 -235.192407)
			(xy 126.449567 -235.231478) (xy 126.407896 -235.264709) (xy 126.361738 -235.291358) (xy 126.312124 -235.31083)
			(xy 126.260162 -235.32269) (xy 126.207012 -235.326674) (xy 126.153862 -235.32269) (xy 126.1019 -235.31083)
			(xy 126.052286 -235.291358) (xy 126.006128 -235.264709) (xy 125.964457 -235.231478) (xy 125.928205 -235.192407)
			(xy 125.898181 -235.14837) (xy 125.875055 -235.100349) (xy 125.859345 -235.049419) (xy 125.851402 -234.996715)
			(xy 125.623076 -234.996715) (xy 125.615133 -235.049419) (xy 125.599423 -235.100349) (xy 125.576297 -235.14837)
			(xy 125.546273 -235.192407) (xy 125.510021 -235.231478) (xy 125.46835 -235.264709) (xy 125.422192 -235.291358)
			(xy 125.372578 -235.31083) (xy 125.320616 -235.32269) (xy 125.267466 -235.326674) (xy 125.214316 -235.32269)
			(xy 125.162354 -235.31083) (xy 125.11274 -235.291358) (xy 125.066582 -235.264709) (xy 125.024911 -235.231478)
			(xy 124.988659 -235.192407) (xy 124.958635 -235.14837) (xy 124.935509 -235.100349) (xy 124.919799 -235.049419)
			(xy 124.911856 -234.996715) (xy 124.683022 -234.996715) (xy 124.675079 -235.049419) (xy 124.659369 -235.100349)
			(xy 124.636243 -235.14837) (xy 124.606219 -235.192407) (xy 124.569967 -235.231478) (xy 124.528296 -235.264709)
			(xy 124.482138 -235.291358) (xy 124.432524 -235.31083) (xy 124.380562 -235.32269) (xy 124.327412 -235.326674)
			(xy 124.274262 -235.32269) (xy 124.2223 -235.31083) (xy 124.172686 -235.291358) (xy 124.126528 -235.264709)
			(xy 124.084857 -235.231478) (xy 124.048605 -235.192407) (xy 124.018581 -235.14837) (xy 123.995455 -235.100349)
			(xy 123.979745 -235.049419) (xy 123.971802 -234.996715) (xy 123.743222 -234.996715) (xy 123.735279 -235.049419)
			(xy 123.719569 -235.100349) (xy 123.696443 -235.14837) (xy 123.666419 -235.192407) (xy 123.630167 -235.231478)
			(xy 123.588496 -235.264709) (xy 123.542338 -235.291358) (xy 123.492724 -235.31083) (xy 123.440762 -235.32269)
			(xy 123.387612 -235.326674) (xy 123.334462 -235.32269) (xy 123.2825 -235.31083) (xy 123.232886 -235.291358)
			(xy 123.186728 -235.264709) (xy 123.145057 -235.231478) (xy 123.108805 -235.192407) (xy 123.078781 -235.14837)
			(xy 123.055655 -235.100349) (xy 123.039945 -235.049419) (xy 123.032002 -234.996715) (xy 122.803422 -234.996715)
			(xy 122.795479 -235.049419) (xy 122.779769 -235.100349) (xy 122.756643 -235.14837) (xy 122.726619 -235.192407)
			(xy 122.690367 -235.231478) (xy 122.648696 -235.264709) (xy 122.602538 -235.291358) (xy 122.552924 -235.31083)
			(xy 122.500962 -235.32269) (xy 122.447812 -235.326674) (xy 122.394662 -235.32269) (xy 122.3427 -235.31083)
			(xy 122.293086 -235.291358) (xy 122.246928 -235.264709) (xy 122.205257 -235.231478) (xy 122.169005 -235.192407)
			(xy 122.138981 -235.14837) (xy 122.115855 -235.100349) (xy 122.100145 -235.049419) (xy 122.092202 -234.996715)
			(xy 121.863622 -234.996715) (xy 121.855679 -235.049419) (xy 121.839969 -235.100349) (xy 121.816843 -235.14837)
			(xy 121.786819 -235.192407) (xy 121.750567 -235.231478) (xy 121.708896 -235.264709) (xy 121.662738 -235.291358)
			(xy 121.613124 -235.31083) (xy 121.561162 -235.32269) (xy 121.508012 -235.326674) (xy 121.454862 -235.32269)
			(xy 121.4029 -235.31083) (xy 121.353286 -235.291358) (xy 121.307128 -235.264709) (xy 121.265457 -235.231478)
			(xy 121.229205 -235.192407) (xy 121.199181 -235.14837) (xy 121.176055 -235.100349) (xy 121.160345 -235.049419)
			(xy 121.152402 -234.996715) (xy 114.34573 -234.996715) (xy 114.337787 -235.049419) (xy 114.322077 -235.100349)
			(xy 114.298951 -235.14837) (xy 114.268927 -235.192407) (xy 114.232675 -235.231478) (xy 114.191004 -235.264709)
			(xy 114.144846 -235.291358) (xy 114.095232 -235.31083) (xy 114.04327 -235.32269) (xy 113.99012 -235.326674)
			(xy 113.93697 -235.32269) (xy 113.885008 -235.31083) (xy 113.835394 -235.291358) (xy 113.789236 -235.264709)
			(xy 113.747565 -235.231478) (xy 113.711313 -235.192407) (xy 113.681289 -235.14837) (xy 113.658163 -235.100349)
			(xy 113.642453 -235.049419) (xy 113.63451 -234.996715) (xy 113.405676 -234.996715) (xy 113.397733 -235.049419)
			(xy 113.382023 -235.100349) (xy 113.358897 -235.14837) (xy 113.328873 -235.192407) (xy 113.292621 -235.231478)
			(xy 113.25095 -235.264709) (xy 113.204792 -235.291358) (xy 113.155178 -235.31083) (xy 113.103216 -235.32269)
			(xy 113.050066 -235.326674) (xy 112.996916 -235.32269) (xy 112.944954 -235.31083) (xy 112.89534 -235.291358)
			(xy 112.849182 -235.264709) (xy 112.807511 -235.231478) (xy 112.771259 -235.192407) (xy 112.741235 -235.14837)
			(xy 112.718109 -235.100349) (xy 112.702399 -235.049419) (xy 112.694456 -234.996715) (xy 112.465876 -234.996715)
			(xy 112.457933 -235.049419) (xy 112.442223 -235.100349) (xy 112.419097 -235.14837) (xy 112.389073 -235.192407)
			(xy 112.352821 -235.231478) (xy 112.31115 -235.264709) (xy 112.264992 -235.291358) (xy 112.215378 -235.31083)
			(xy 112.163416 -235.32269) (xy 112.110266 -235.326674) (xy 112.057116 -235.32269) (xy 112.005154 -235.31083)
			(xy 111.95554 -235.291358) (xy 111.909382 -235.264709) (xy 111.867711 -235.231478) (xy 111.831459 -235.192407)
			(xy 111.801435 -235.14837) (xy 111.778309 -235.100349) (xy 111.762599 -235.049419) (xy 111.754656 -234.996715)
			(xy 111.526076 -234.996715) (xy 111.518133 -235.049419) (xy 111.502423 -235.100349) (xy 111.479297 -235.14837)
			(xy 111.449273 -235.192407) (xy 111.413021 -235.231478) (xy 111.37135 -235.264709) (xy 111.325192 -235.291358)
			(xy 111.275578 -235.31083) (xy 111.223616 -235.32269) (xy 111.170466 -235.326674) (xy 111.117316 -235.32269)
			(xy 111.065354 -235.31083) (xy 111.01574 -235.291358) (xy 110.969582 -235.264709) (xy 110.927911 -235.231478)
			(xy 110.891659 -235.192407) (xy 110.861635 -235.14837) (xy 110.838509 -235.100349) (xy 110.822799 -235.049419)
			(xy 110.814856 -234.996715) (xy 110.58653 -234.996715) (xy 110.578587 -235.049419) (xy 110.562877 -235.100349)
			(xy 110.539751 -235.14837) (xy 110.509727 -235.192407) (xy 110.473475 -235.231478) (xy 110.431804 -235.264709)
			(xy 110.385646 -235.291358) (xy 110.336032 -235.31083) (xy 110.28407 -235.32269) (xy 110.23092 -235.326674)
			(xy 110.17777 -235.32269) (xy 110.125808 -235.31083) (xy 110.076194 -235.291358) (xy 110.030036 -235.264709)
			(xy 109.988365 -235.231478) (xy 109.952113 -235.192407) (xy 109.922089 -235.14837) (xy 109.898963 -235.100349)
			(xy 109.883253 -235.049419) (xy 109.87531 -234.996715) (xy 109.646476 -234.996715) (xy 109.638533 -235.049419)
			(xy 109.622823 -235.100349) (xy 109.599697 -235.14837) (xy 109.569673 -235.192407) (xy 109.533421 -235.231478)
			(xy 109.49175 -235.264709) (xy 109.445592 -235.291358) (xy 109.395978 -235.31083) (xy 109.344016 -235.32269)
			(xy 109.290866 -235.326674) (xy 109.237716 -235.32269) (xy 109.185754 -235.31083) (xy 109.13614 -235.291358)
			(xy 109.089982 -235.264709) (xy 109.048311 -235.231478) (xy 109.012059 -235.192407) (xy 108.982035 -235.14837)
			(xy 108.958909 -235.100349) (xy 108.943199 -235.049419) (xy 108.935256 -234.996715) (xy 104.971216 -234.996715)
			(xy 104.971596 -235.017056) (xy 104.971098 -235.043705) (xy 104.963155 -235.096409) (xy 104.947445 -235.147339)
			(xy 104.924319 -235.19536) (xy 104.894295 -235.239397) (xy 104.858043 -235.278468) (xy 104.816372 -235.311699)
			(xy 104.770214 -235.338348) (xy 104.7206 -235.35782) (xy 104.668638 -235.36968) (xy 104.615488 -235.373664)
			(xy 104.562338 -235.36968) (xy 104.510376 -235.35782) (xy 104.460762 -235.338348) (xy 104.414604 -235.311699)
			(xy 104.372933 -235.278468) (xy 104.336681 -235.239397) (xy 104.306657 -235.19536) (xy 104.283531 -235.147339)
			(xy 104.267821 -235.096409) (xy 104.259878 -235.043705) (xy 102.807283 -235.043705) (xy 102.478078 -235.37291)
			(xy 102.468679 -235.382937) (xy 102.455125 -235.406833) (xy 102.448432 -235.433478) (xy 102.449022 -235.458233)
			(xy 105.874556 -235.458233) (xy 105.874556 -235.404935) (xy 105.882499 -235.352231) (xy 105.898209 -235.301301)
			(xy 105.921335 -235.25328) (xy 105.951359 -235.209243) (xy 105.987611 -235.170172) (xy 106.029282 -235.136941)
			(xy 106.07544 -235.110292) (xy 106.125054 -235.09082) (xy 106.177016 -235.07896) (xy 106.230166 -235.074977)
			(xy 106.283316 -235.07896) (xy 106.335278 -235.09082) (xy 106.384892 -235.110292) (xy 106.43105 -235.136941)
			(xy 106.472721 -235.170172) (xy 106.508973 -235.209243) (xy 106.538997 -235.25328) (xy 106.562123 -235.301301)
			(xy 106.577833 -235.352231) (xy 106.585776 -235.404935) (xy 106.586274 -235.431584) (xy 106.585776 -235.458233)
			(xy 106.577833 -235.510937) (xy 106.574183 -235.52277) (xy 106.94035 -235.52277) (xy 106.940913 -235.494788)
			(xy 106.949671 -235.439514) (xy 106.966967 -235.38629) (xy 106.992376 -235.336427) (xy 107.02527 -235.291151)
			(xy 107.064842 -235.251578) (xy 107.110116 -235.218682) (xy 107.159979 -235.193272) (xy 107.213202 -235.175974)
			(xy 107.268476 -235.167214) (xy 107.296458 -235.166662) (xy 107.323777 -235.167219) (xy 107.377777 -235.17555)
			(xy 107.429872 -235.192023) (xy 107.478844 -235.216253) (xy 107.523546 -235.247671) (xy 107.5436 -235.26623)
			(xy 107.555222 -235.276627) (xy 107.583156 -235.290451) (xy 107.613958 -235.295207) (xy 107.64476 -235.290451)
			(xy 107.672694 -235.276627) (xy 107.684316 -235.26623) (xy 107.704335 -235.247623) (xy 107.749025 -235.216165)
			(xy 107.798003 -235.191914) (xy 107.850114 -235.175441) (xy 107.904131 -235.167134) (xy 107.931458 -235.166662)
			(xy 107.959441 -235.167251) (xy 108.014718 -235.176) (xy 108.067946 -235.193288) (xy 108.117814 -235.21869)
			(xy 108.163095 -235.251581) (xy 108.202672 -235.291151) (xy 108.235572 -235.336424) (xy 108.260984 -235.386287)
			(xy 108.278283 -235.439512) (xy 108.287043 -235.494787) (xy 108.287566 -235.52277) (xy 108.287195 -235.545193)
			(xy 108.281537 -235.589682) (xy 108.270358 -235.633113) (xy 108.26242 -235.654088) (xy 108.257658 -235.667604)
			(xy 108.254988 -235.696123) (xy 108.260334 -235.724262) (xy 108.273277 -235.749814) (xy 108.292801 -235.770772)
			(xy 108.304838 -235.778548) (xy 108.327107 -235.792432) (xy 108.349133 -235.810531) (xy 109.40541 -235.810531)
			(xy 109.40541 -235.757233) (xy 109.413353 -235.704529) (xy 109.429063 -235.653599) (xy 109.452189 -235.605578)
			(xy 109.482213 -235.561541) (xy 109.518465 -235.52247) (xy 109.560136 -235.489239) (xy 109.606294 -235.46259)
			(xy 109.655908 -235.443118) (xy 109.70787 -235.431258) (xy 109.76102 -235.427275) (xy 109.81417 -235.431258)
			(xy 109.866132 -235.443118) (xy 109.915746 -235.46259) (xy 109.961904 -235.489239) (xy 110.003575 -235.52247)
			(xy 110.039827 -235.561541) (xy 110.069851 -235.605578) (xy 110.092977 -235.653599) (xy 110.108687 -235.704529)
			(xy 110.11663 -235.757233) (xy 110.117128 -235.783882) (xy 110.11663 -235.810531) (xy 110.34521 -235.810531)
			(xy 110.34521 -235.757233) (xy 110.353153 -235.704529) (xy 110.368863 -235.653599) (xy 110.391989 -235.605578)
			(xy 110.422013 -235.561541) (xy 110.458265 -235.52247) (xy 110.499936 -235.489239) (xy 110.546094 -235.46259)
			(xy 110.595708 -235.443118) (xy 110.64767 -235.431258) (xy 110.70082 -235.427275) (xy 110.75397 -235.431258)
			(xy 110.805932 -235.443118) (xy 110.855546 -235.46259) (xy 110.901704 -235.489239) (xy 110.943375 -235.52247)
			(xy 110.979627 -235.561541) (xy 111.009651 -235.605578) (xy 111.032777 -235.653599) (xy 111.048487 -235.704529)
			(xy 111.05643 -235.757233) (xy 111.056928 -235.783882) (xy 111.05643 -235.810531) (xy 111.28501 -235.810531)
			(xy 111.28501 -235.757233) (xy 111.292953 -235.704529) (xy 111.308663 -235.653599) (xy 111.331789 -235.605578)
			(xy 111.361813 -235.561541) (xy 111.398065 -235.52247) (xy 111.439736 -235.489239) (xy 111.485894 -235.46259)
			(xy 111.535508 -235.443118) (xy 111.58747 -235.431258) (xy 111.64062 -235.427275) (xy 111.69377 -235.431258)
			(xy 111.745732 -235.443118) (xy 111.795346 -235.46259) (xy 111.841504 -235.489239) (xy 111.883175 -235.52247)
			(xy 111.919427 -235.561541) (xy 111.949451 -235.605578) (xy 111.972577 -235.653599) (xy 111.988287 -235.704529)
			(xy 111.99623 -235.757233) (xy 111.996728 -235.783882) (xy 111.99623 -235.810531) (xy 112.22481 -235.810531)
			(xy 112.22481 -235.757233) (xy 112.232753 -235.704529) (xy 112.248463 -235.653599) (xy 112.271589 -235.605578)
			(xy 112.301613 -235.561541) (xy 112.337865 -235.52247) (xy 112.379536 -235.489239) (xy 112.425694 -235.46259)
			(xy 112.475308 -235.443118) (xy 112.52727 -235.431258) (xy 112.58042 -235.427275) (xy 112.63357 -235.431258)
			(xy 112.685532 -235.443118) (xy 112.735146 -235.46259) (xy 112.781304 -235.489239) (xy 112.822975 -235.52247)
			(xy 112.859227 -235.561541) (xy 112.889251 -235.605578) (xy 112.912377 -235.653599) (xy 112.928087 -235.704529)
			(xy 112.93603 -235.757233) (xy 112.936528 -235.783882) (xy 112.93603 -235.810531) (xy 113.16461 -235.810531)
			(xy 113.16461 -235.757233) (xy 113.172553 -235.704529) (xy 113.188263 -235.653599) (xy 113.211389 -235.605578)
			(xy 113.241413 -235.561541) (xy 113.277665 -235.52247) (xy 113.319336 -235.489239) (xy 113.365494 -235.46259)
			(xy 113.415108 -235.443118) (xy 113.46707 -235.431258) (xy 113.52022 -235.427275) (xy 113.57337 -235.431258)
			(xy 113.625332 -235.443118) (xy 113.674946 -235.46259) (xy 113.721104 -235.489239) (xy 113.762775 -235.52247)
			(xy 113.799027 -235.561541) (xy 113.829051 -235.605578) (xy 113.852177 -235.653599) (xy 113.867887 -235.704529)
			(xy 113.87583 -235.757233) (xy 113.876328 -235.783882) (xy 113.87583 -235.810531) (xy 114.10441 -235.810531)
			(xy 114.10441 -235.757233) (xy 114.112353 -235.704529) (xy 114.128063 -235.653599) (xy 114.151189 -235.605578)
			(xy 114.181213 -235.561541) (xy 114.217465 -235.52247) (xy 114.259136 -235.489239) (xy 114.305294 -235.46259)
			(xy 114.354908 -235.443118) (xy 114.40687 -235.431258) (xy 114.46002 -235.427275) (xy 114.51317 -235.431258)
			(xy 114.565132 -235.443118) (xy 114.614746 -235.46259) (xy 114.660904 -235.489239) (xy 114.702575 -235.52247)
			(xy 114.738827 -235.561541) (xy 114.768851 -235.605578) (xy 114.791977 -235.653599) (xy 114.807687 -235.704529)
			(xy 114.81563 -235.757233) (xy 114.816128 -235.783882) (xy 114.815816 -235.8006) (xy 116.238514 -235.8006)
			(xy 116.242497 -235.747449) (xy 116.254359 -235.695486) (xy 116.273833 -235.645872) (xy 116.300484 -235.599714)
			(xy 116.333718 -235.558045) (xy 116.372792 -235.521794) (xy 116.416832 -235.491773) (xy 116.464856 -235.468651)
			(xy 116.515789 -235.452946) (xy 116.568494 -235.445008) (xy 116.595144 -235.444538) (xy 116.619813 -235.444976)
			(xy 116.668679 -235.451774) (xy 116.716137 -235.465262) (xy 116.761274 -235.48518) (xy 116.803225 -235.511146)
			(xy 116.822474 -235.52658) (xy 116.833604 -235.535207) (xy 116.859364 -235.546554) (xy 116.887244 -235.550435)
			(xy 116.915124 -235.546554) (xy 116.940884 -235.535207) (xy 116.952014 -235.52658) (xy 116.97343 -235.509457)
			(xy 117.020487 -235.481318) (xy 117.071304 -235.460729) (xy 117.124677 -235.448177) (xy 117.179344 -235.44396)
			(xy 117.234011 -235.448177) (xy 117.287384 -235.460729) (xy 117.338201 -235.481318) (xy 117.385258 -235.509457)
			(xy 117.406674 -235.52658) (xy 117.417804 -235.535207) (xy 117.443564 -235.546554) (xy 117.471444 -235.550435)
			(xy 117.499324 -235.546554) (xy 117.525084 -235.535207) (xy 117.536214 -235.52658) (xy 117.55763 -235.509457)
			(xy 117.604687 -235.481318) (xy 117.655504 -235.460729) (xy 117.708877 -235.448177) (xy 117.763544 -235.44396)
			(xy 117.818211 -235.448177) (xy 117.871584 -235.460729) (xy 117.922401 -235.481318) (xy 117.969458 -235.509457)
			(xy 117.990874 -235.52658) (xy 118.002004 -235.535207) (xy 118.027764 -235.546554) (xy 118.055644 -235.550435)
			(xy 118.083524 -235.546554) (xy 118.109284 -235.535207) (xy 118.120414 -235.52658) (xy 118.14183 -235.509457)
			(xy 118.188887 -235.481318) (xy 118.239704 -235.460729) (xy 118.293077 -235.448177) (xy 118.347744 -235.44396)
			(xy 118.402411 -235.448177) (xy 118.455784 -235.460729) (xy 118.506601 -235.481318) (xy 118.553658 -235.509457)
			(xy 118.575074 -235.52658) (xy 118.586204 -235.535207) (xy 118.611964 -235.546554) (xy 118.639844 -235.550435)
			(xy 118.667724 -235.546554) (xy 118.693484 -235.535207) (xy 118.704614 -235.52658) (xy 118.72603 -235.509457)
			(xy 118.773087 -235.481318) (xy 118.823904 -235.460729) (xy 118.877277 -235.448177) (xy 118.931944 -235.44396)
			(xy 118.986611 -235.448177) (xy 119.039984 -235.460729) (xy 119.090801 -235.481318) (xy 119.137858 -235.509457)
			(xy 119.159274 -235.52658) (xy 119.170404 -235.535207) (xy 119.196164 -235.546554) (xy 119.224044 -235.550435)
			(xy 119.251924 -235.546554) (xy 119.277684 -235.535207) (xy 119.288814 -235.52658) (xy 119.308075 -235.511163)
			(xy 119.350027 -235.485201) (xy 119.395162 -235.46528) (xy 119.442614 -235.451781) (xy 119.491476 -235.444962)
			(xy 119.516144 -235.444538) (xy 119.542795 -235.444947) (xy 119.5955 -235.452897) (xy 119.646431 -235.468613)
			(xy 119.694452 -235.491744) (xy 119.73849 -235.521773) (xy 119.77756 -235.558029) (xy 119.81079 -235.599704)
			(xy 119.837439 -235.645865) (xy 119.856911 -235.695483) (xy 119.868771 -235.747448) (xy 119.872754 -235.8006)
			(xy 119.87201 -235.810531) (xy 121.622556 -235.810531) (xy 121.622556 -235.757233) (xy 121.630499 -235.704529)
			(xy 121.646209 -235.653599) (xy 121.669335 -235.605578) (xy 121.699359 -235.561541) (xy 121.735611 -235.52247)
			(xy 121.777282 -235.489239) (xy 121.82344 -235.46259) (xy 121.873054 -235.443118) (xy 121.925016 -235.431258)
			(xy 121.978166 -235.427275) (xy 122.031316 -235.431258) (xy 122.083278 -235.443118) (xy 122.132892 -235.46259)
			(xy 122.17905 -235.489239) (xy 122.220721 -235.52247) (xy 122.256973 -235.561541) (xy 122.286997 -235.605578)
			(xy 122.310123 -235.653599) (xy 122.325833 -235.704529) (xy 122.333776 -235.757233) (xy 122.334274 -235.783882)
			(xy 122.333776 -235.810531) (xy 122.562356 -235.810531) (xy 122.562356 -235.757233) (xy 122.570299 -235.704529)
			(xy 122.586009 -235.653599) (xy 122.609135 -235.605578) (xy 122.639159 -235.561541) (xy 122.675411 -235.52247)
			(xy 122.717082 -235.489239) (xy 122.76324 -235.46259) (xy 122.812854 -235.443118) (xy 122.864816 -235.431258)
			(xy 122.917966 -235.427275) (xy 122.971116 -235.431258) (xy 123.023078 -235.443118) (xy 123.072692 -235.46259)
			(xy 123.11885 -235.489239) (xy 123.160521 -235.52247) (xy 123.196773 -235.561541) (xy 123.226797 -235.605578)
			(xy 123.249923 -235.653599) (xy 123.265633 -235.704529) (xy 123.273576 -235.757233) (xy 123.274074 -235.783882)
			(xy 123.273576 -235.810531) (xy 123.502156 -235.810531) (xy 123.502156 -235.757233) (xy 123.510099 -235.704529)
			(xy 123.525809 -235.653599) (xy 123.548935 -235.605578) (xy 123.578959 -235.561541) (xy 123.615211 -235.52247)
			(xy 123.656882 -235.489239) (xy 123.70304 -235.46259) (xy 123.752654 -235.443118) (xy 123.804616 -235.431258)
			(xy 123.857766 -235.427275) (xy 123.910916 -235.431258) (xy 123.962878 -235.443118) (xy 124.012492 -235.46259)
			(xy 124.05865 -235.489239) (xy 124.100321 -235.52247) (xy 124.136573 -235.561541) (xy 124.166597 -235.605578)
			(xy 124.189723 -235.653599) (xy 124.205433 -235.704529) (xy 124.213376 -235.757233) (xy 124.213874 -235.783882)
			(xy 124.213376 -235.810531) (xy 124.441956 -235.810531) (xy 124.441956 -235.757233) (xy 124.449899 -235.704529)
			(xy 124.465609 -235.653599) (xy 124.488735 -235.605578) (xy 124.518759 -235.561541) (xy 124.555011 -235.52247)
			(xy 124.596682 -235.489239) (xy 124.64284 -235.46259) (xy 124.692454 -235.443118) (xy 124.744416 -235.431258)
			(xy 124.797566 -235.427275) (xy 124.850716 -235.431258) (xy 124.902678 -235.443118) (xy 124.952292 -235.46259)
			(xy 124.99845 -235.489239) (xy 125.040121 -235.52247) (xy 125.076373 -235.561541) (xy 125.106397 -235.605578)
			(xy 125.129523 -235.653599) (xy 125.145233 -235.704529) (xy 125.153176 -235.757233) (xy 125.153674 -235.783882)
			(xy 125.153176 -235.810531) (xy 125.381502 -235.810531) (xy 125.381502 -235.757233) (xy 125.389445 -235.704529)
			(xy 125.405155 -235.653599) (xy 125.428281 -235.605578) (xy 125.458305 -235.561541) (xy 125.494557 -235.52247)
			(xy 125.536228 -235.489239) (xy 125.582386 -235.46259) (xy 125.632 -235.443118) (xy 125.683962 -235.431258)
			(xy 125.737112 -235.427275) (xy 125.790262 -235.431258) (xy 125.842224 -235.443118) (xy 125.891838 -235.46259)
			(xy 125.937996 -235.489239) (xy 125.979667 -235.52247) (xy 126.015919 -235.561541) (xy 126.045943 -235.605578)
			(xy 126.069069 -235.653599) (xy 126.084779 -235.704529) (xy 126.092722 -235.757233) (xy 126.09322 -235.783882)
			(xy 126.092722 -235.810531) (xy 126.321556 -235.810531) (xy 126.321556 -235.757233) (xy 126.329499 -235.704529)
			(xy 126.345209 -235.653599) (xy 126.368335 -235.605578) (xy 126.398359 -235.561541) (xy 126.434611 -235.52247)
			(xy 126.476282 -235.489239) (xy 126.52244 -235.46259) (xy 126.572054 -235.443118) (xy 126.624016 -235.431258)
			(xy 126.677166 -235.427275) (xy 126.730316 -235.431258) (xy 126.782278 -235.443118) (xy 126.831892 -235.46259)
			(xy 126.87805 -235.489239) (xy 126.919721 -235.52247) (xy 126.955973 -235.561541) (xy 126.985997 -235.605578)
			(xy 127.009123 -235.653599) (xy 127.024833 -235.704529) (xy 127.032776 -235.757233) (xy 127.033274 -235.783882)
			(xy 127.032776 -235.810531) (xy 127.261356 -235.810531) (xy 127.261356 -235.757233) (xy 127.269299 -235.704529)
			(xy 127.285009 -235.653599) (xy 127.308135 -235.605578) (xy 127.338159 -235.561541) (xy 127.374411 -235.52247)
			(xy 127.416082 -235.489239) (xy 127.46224 -235.46259) (xy 127.511854 -235.443118) (xy 127.563816 -235.431258)
			(xy 127.616966 -235.427275) (xy 127.670116 -235.431258) (xy 127.722078 -235.443118) (xy 127.771692 -235.46259)
			(xy 127.81785 -235.489239) (xy 127.859521 -235.52247) (xy 127.895773 -235.561541) (xy 127.925797 -235.605578)
			(xy 127.948923 -235.653599) (xy 127.964633 -235.704529) (xy 127.972576 -235.757233) (xy 127.973074 -235.783882)
			(xy 127.972576 -235.810531) (xy 128.201156 -235.810531) (xy 128.201156 -235.757233) (xy 128.209099 -235.704529)
			(xy 128.224809 -235.653599) (xy 128.247935 -235.605578) (xy 128.277959 -235.561541) (xy 128.314211 -235.52247)
			(xy 128.355882 -235.489239) (xy 128.40204 -235.46259) (xy 128.451654 -235.443118) (xy 128.503616 -235.431258)
			(xy 128.556766 -235.427275) (xy 128.609916 -235.431258) (xy 128.661878 -235.443118) (xy 128.711492 -235.46259)
			(xy 128.75765 -235.489239) (xy 128.799321 -235.52247) (xy 128.835573 -235.561541) (xy 128.865597 -235.605578)
			(xy 128.888723 -235.653599) (xy 128.904433 -235.704529) (xy 128.912376 -235.757233) (xy 128.912874 -235.783882)
			(xy 128.912376 -235.810531) (xy 129.140956 -235.810531) (xy 129.140956 -235.757233) (xy 129.148899 -235.704529)
			(xy 129.164609 -235.653599) (xy 129.187735 -235.605578) (xy 129.217759 -235.561541) (xy 129.254011 -235.52247)
			(xy 129.295682 -235.489239) (xy 129.34184 -235.46259) (xy 129.391454 -235.443118) (xy 129.443416 -235.431258)
			(xy 129.496566 -235.427275) (xy 129.549716 -235.431258) (xy 129.601678 -235.443118) (xy 129.651292 -235.46259)
			(xy 129.69745 -235.489239) (xy 129.739121 -235.52247) (xy 129.775373 -235.561541) (xy 129.805397 -235.605578)
			(xy 129.828523 -235.653599) (xy 129.844233 -235.704529) (xy 129.852176 -235.757233) (xy 129.852674 -235.783882)
			(xy 129.852176 -235.810531) (xy 130.080756 -235.810531) (xy 130.080756 -235.757233) (xy 130.088699 -235.704529)
			(xy 130.104409 -235.653599) (xy 130.127535 -235.605578) (xy 130.157559 -235.561541) (xy 130.193811 -235.52247)
			(xy 130.235482 -235.489239) (xy 130.28164 -235.46259) (xy 130.331254 -235.443118) (xy 130.383216 -235.431258)
			(xy 130.436366 -235.427275) (xy 130.489516 -235.431258) (xy 130.541478 -235.443118) (xy 130.591092 -235.46259)
			(xy 130.63725 -235.489239) (xy 130.678921 -235.52247) (xy 130.715173 -235.561541) (xy 130.745197 -235.605578)
			(xy 130.768323 -235.653599) (xy 130.784033 -235.704529) (xy 130.791976 -235.757233) (xy 130.792474 -235.783882)
			(xy 130.791976 -235.810531) (xy 131.020556 -235.810531) (xy 131.020556 -235.757233) (xy 131.028499 -235.704529)
			(xy 131.044209 -235.653599) (xy 131.067335 -235.605578) (xy 131.097359 -235.561541) (xy 131.133611 -235.52247)
			(xy 131.175282 -235.489239) (xy 131.22144 -235.46259) (xy 131.271054 -235.443118) (xy 131.323016 -235.431258)
			(xy 131.376166 -235.427275) (xy 131.429316 -235.431258) (xy 131.481278 -235.443118) (xy 131.530892 -235.46259)
			(xy 131.57705 -235.489239) (xy 131.618721 -235.52247) (xy 131.654973 -235.561541) (xy 131.684997 -235.605578)
			(xy 131.708123 -235.653599) (xy 131.723833 -235.704529) (xy 131.731776 -235.757233) (xy 131.732274 -235.783882)
			(xy 131.731776 -235.810531) (xy 131.960102 -235.810531) (xy 131.960102 -235.757233) (xy 131.968045 -235.704529)
			(xy 131.983755 -235.653599) (xy 132.006881 -235.605578) (xy 132.036905 -235.561541) (xy 132.073157 -235.52247)
			(xy 132.114828 -235.489239) (xy 132.160986 -235.46259) (xy 132.2106 -235.443118) (xy 132.262562 -235.431258)
			(xy 132.315712 -235.427275) (xy 132.368862 -235.431258) (xy 132.420824 -235.443118) (xy 132.470438 -235.46259)
			(xy 132.516596 -235.489239) (xy 132.558267 -235.52247) (xy 132.594519 -235.561541) (xy 132.624543 -235.605578)
			(xy 132.647669 -235.653599) (xy 132.663379 -235.704529) (xy 132.671322 -235.757233) (xy 132.67182 -235.783882)
			(xy 132.671322 -235.810531) (xy 132.900156 -235.810531) (xy 132.900156 -235.757233) (xy 132.908099 -235.704529)
			(xy 132.923809 -235.653599) (xy 132.946935 -235.605578) (xy 132.976959 -235.561541) (xy 133.013211 -235.52247)
			(xy 133.054882 -235.489239) (xy 133.10104 -235.46259) (xy 133.150654 -235.443118) (xy 133.202616 -235.431258)
			(xy 133.255766 -235.427275) (xy 133.308916 -235.431258) (xy 133.360878 -235.443118) (xy 133.410492 -235.46259)
			(xy 133.45665 -235.489239) (xy 133.498321 -235.52247) (xy 133.534573 -235.561541) (xy 133.564597 -235.605578)
			(xy 133.587723 -235.653599) (xy 133.603433 -235.704529) (xy 133.611376 -235.757233) (xy 133.611874 -235.783882)
			(xy 133.611376 -235.810531) (xy 133.839956 -235.810531) (xy 133.839956 -235.757233) (xy 133.847899 -235.704529)
			(xy 133.863609 -235.653599) (xy 133.886735 -235.605578) (xy 133.916759 -235.561541) (xy 133.953011 -235.52247)
			(xy 133.994682 -235.489239) (xy 134.04084 -235.46259) (xy 134.090454 -235.443118) (xy 134.142416 -235.431258)
			(xy 134.195566 -235.427275) (xy 134.248716 -235.431258) (xy 134.300678 -235.443118) (xy 134.350292 -235.46259)
			(xy 134.39645 -235.489239) (xy 134.438121 -235.52247) (xy 134.474373 -235.561541) (xy 134.504397 -235.605578)
			(xy 134.527523 -235.653599) (xy 134.543233 -235.704529) (xy 134.551176 -235.757233) (xy 134.551674 -235.783882)
			(xy 134.551176 -235.810531) (xy 134.543233 -235.863235) (xy 134.527523 -235.914165) (xy 134.504397 -235.962186)
			(xy 134.474373 -236.006223) (xy 134.438121 -236.045294) (xy 134.39645 -236.078525) (xy 134.350292 -236.105174)
			(xy 134.300678 -236.124646) (xy 134.248716 -236.136506) (xy 134.195566 -236.14049) (xy 134.142416 -236.136506)
			(xy 134.090454 -236.124646) (xy 134.04084 -236.105174) (xy 133.994682 -236.078525) (xy 133.953011 -236.045294)
			(xy 133.916759 -236.006223) (xy 133.886735 -235.962186) (xy 133.863609 -235.914165) (xy 133.847899 -235.863235)
			(xy 133.839956 -235.810531) (xy 133.611376 -235.810531) (xy 133.603433 -235.863235) (xy 133.587723 -235.914165)
			(xy 133.564597 -235.962186) (xy 133.534573 -236.006223) (xy 133.498321 -236.045294) (xy 133.45665 -236.078525)
			(xy 133.410492 -236.105174) (xy 133.360878 -236.124646) (xy 133.308916 -236.136506) (xy 133.255766 -236.14049)
			(xy 133.202616 -236.136506) (xy 133.150654 -236.124646) (xy 133.10104 -236.105174) (xy 133.054882 -236.078525)
			(xy 133.013211 -236.045294) (xy 132.976959 -236.006223) (xy 132.946935 -235.962186) (xy 132.923809 -235.914165)
			(xy 132.908099 -235.863235) (xy 132.900156 -235.810531) (xy 132.671322 -235.810531) (xy 132.663379 -235.863235)
			(xy 132.647669 -235.914165) (xy 132.624543 -235.962186) (xy 132.594519 -236.006223) (xy 132.558267 -236.045294)
			(xy 132.516596 -236.078525) (xy 132.470438 -236.105174) (xy 132.420824 -236.124646) (xy 132.368862 -236.136506)
			(xy 132.315712 -236.14049) (xy 132.262562 -236.136506) (xy 132.2106 -236.124646) (xy 132.160986 -236.105174)
			(xy 132.114828 -236.078525) (xy 132.073157 -236.045294) (xy 132.036905 -236.006223) (xy 132.006881 -235.962186)
			(xy 131.983755 -235.914165) (xy 131.968045 -235.863235) (xy 131.960102 -235.810531) (xy 131.731776 -235.810531)
			(xy 131.723833 -235.863235) (xy 131.708123 -235.914165) (xy 131.684997 -235.962186) (xy 131.654973 -236.006223)
			(xy 131.618721 -236.045294) (xy 131.57705 -236.078525) (xy 131.530892 -236.105174) (xy 131.481278 -236.124646)
			(xy 131.429316 -236.136506) (xy 131.376166 -236.14049) (xy 131.323016 -236.136506) (xy 131.271054 -236.124646)
			(xy 131.22144 -236.105174) (xy 131.175282 -236.078525) (xy 131.133611 -236.045294) (xy 131.097359 -236.006223)
			(xy 131.067335 -235.962186) (xy 131.044209 -235.914165) (xy 131.028499 -235.863235) (xy 131.020556 -235.810531)
			(xy 130.791976 -235.810531) (xy 130.784033 -235.863235) (xy 130.768323 -235.914165) (xy 130.745197 -235.962186)
			(xy 130.715173 -236.006223) (xy 130.678921 -236.045294) (xy 130.63725 -236.078525) (xy 130.591092 -236.105174)
			(xy 130.541478 -236.124646) (xy 130.489516 -236.136506) (xy 130.436366 -236.14049) (xy 130.383216 -236.136506)
			(xy 130.331254 -236.124646) (xy 130.28164 -236.105174) (xy 130.235482 -236.078525) (xy 130.193811 -236.045294)
			(xy 130.157559 -236.006223) (xy 130.127535 -235.962186) (xy 130.104409 -235.914165) (xy 130.088699 -235.863235)
			(xy 130.080756 -235.810531) (xy 129.852176 -235.810531) (xy 129.844233 -235.863235) (xy 129.828523 -235.914165)
			(xy 129.805397 -235.962186) (xy 129.775373 -236.006223) (xy 129.739121 -236.045294) (xy 129.69745 -236.078525)
			(xy 129.651292 -236.105174) (xy 129.601678 -236.124646) (xy 129.549716 -236.136506) (xy 129.496566 -236.14049)
			(xy 129.443416 -236.136506) (xy 129.391454 -236.124646) (xy 129.34184 -236.105174) (xy 129.295682 -236.078525)
			(xy 129.254011 -236.045294) (xy 129.217759 -236.006223) (xy 129.187735 -235.962186) (xy 129.164609 -235.914165)
			(xy 129.148899 -235.863235) (xy 129.140956 -235.810531) (xy 128.912376 -235.810531) (xy 128.904433 -235.863235)
			(xy 128.888723 -235.914165) (xy 128.865597 -235.962186) (xy 128.835573 -236.006223) (xy 128.799321 -236.045294)
			(xy 128.75765 -236.078525) (xy 128.711492 -236.105174) (xy 128.661878 -236.124646) (xy 128.609916 -236.136506)
			(xy 128.556766 -236.14049) (xy 128.503616 -236.136506) (xy 128.451654 -236.124646) (xy 128.40204 -236.105174)
			(xy 128.355882 -236.078525) (xy 128.314211 -236.045294) (xy 128.277959 -236.006223) (xy 128.247935 -235.962186)
			(xy 128.224809 -235.914165) (xy 128.209099 -235.863235) (xy 128.201156 -235.810531) (xy 127.972576 -235.810531)
			(xy 127.964633 -235.863235) (xy 127.948923 -235.914165) (xy 127.925797 -235.962186) (xy 127.895773 -236.006223)
			(xy 127.859521 -236.045294) (xy 127.81785 -236.078525) (xy 127.771692 -236.105174) (xy 127.722078 -236.124646)
			(xy 127.670116 -236.136506) (xy 127.616966 -236.14049) (xy 127.563816 -236.136506) (xy 127.511854 -236.124646)
			(xy 127.46224 -236.105174) (xy 127.416082 -236.078525) (xy 127.374411 -236.045294) (xy 127.338159 -236.006223)
			(xy 127.308135 -235.962186) (xy 127.285009 -235.914165) (xy 127.269299 -235.863235) (xy 127.261356 -235.810531)
			(xy 127.032776 -235.810531) (xy 127.024833 -235.863235) (xy 127.009123 -235.914165) (xy 126.985997 -235.962186)
			(xy 126.955973 -236.006223) (xy 126.919721 -236.045294) (xy 126.87805 -236.078525) (xy 126.831892 -236.105174)
			(xy 126.782278 -236.124646) (xy 126.730316 -236.136506) (xy 126.677166 -236.14049) (xy 126.624016 -236.136506)
			(xy 126.572054 -236.124646) (xy 126.52244 -236.105174) (xy 126.476282 -236.078525) (xy 126.434611 -236.045294)
			(xy 126.398359 -236.006223) (xy 126.368335 -235.962186) (xy 126.345209 -235.914165) (xy 126.329499 -235.863235)
			(xy 126.321556 -235.810531) (xy 126.092722 -235.810531) (xy 126.084779 -235.863235) (xy 126.069069 -235.914165)
			(xy 126.045943 -235.962186) (xy 126.015919 -236.006223) (xy 125.979667 -236.045294) (xy 125.937996 -236.078525)
			(xy 125.891838 -236.105174) (xy 125.842224 -236.124646) (xy 125.790262 -236.136506) (xy 125.737112 -236.14049)
			(xy 125.683962 -236.136506) (xy 125.632 -236.124646) (xy 125.582386 -236.105174) (xy 125.536228 -236.078525)
			(xy 125.494557 -236.045294) (xy 125.458305 -236.006223) (xy 125.428281 -235.962186) (xy 125.405155 -235.914165)
			(xy 125.389445 -235.863235) (xy 125.381502 -235.810531) (xy 125.153176 -235.810531) (xy 125.145233 -235.863235)
			(xy 125.129523 -235.914165) (xy 125.106397 -235.962186) (xy 125.076373 -236.006223) (xy 125.040121 -236.045294)
			(xy 124.99845 -236.078525) (xy 124.952292 -236.105174) (xy 124.902678 -236.124646) (xy 124.850716 -236.136506)
			(xy 124.797566 -236.14049) (xy 124.744416 -236.136506) (xy 124.692454 -236.124646) (xy 124.64284 -236.105174)
			(xy 124.596682 -236.078525) (xy 124.555011 -236.045294) (xy 124.518759 -236.006223) (xy 124.488735 -235.962186)
			(xy 124.465609 -235.914165) (xy 124.449899 -235.863235) (xy 124.441956 -235.810531) (xy 124.213376 -235.810531)
			(xy 124.205433 -235.863235) (xy 124.189723 -235.914165) (xy 124.166597 -235.962186) (xy 124.136573 -236.006223)
			(xy 124.100321 -236.045294) (xy 124.05865 -236.078525) (xy 124.012492 -236.105174) (xy 123.962878 -236.124646)
			(xy 123.910916 -236.136506) (xy 123.857766 -236.14049) (xy 123.804616 -236.136506) (xy 123.752654 -236.124646)
			(xy 123.70304 -236.105174) (xy 123.656882 -236.078525) (xy 123.615211 -236.045294) (xy 123.578959 -236.006223)
			(xy 123.548935 -235.962186) (xy 123.525809 -235.914165) (xy 123.510099 -235.863235) (xy 123.502156 -235.810531)
			(xy 123.273576 -235.810531) (xy 123.265633 -235.863235) (xy 123.249923 -235.914165) (xy 123.226797 -235.962186)
			(xy 123.196773 -236.006223) (xy 123.160521 -236.045294) (xy 123.11885 -236.078525) (xy 123.072692 -236.105174)
			(xy 123.023078 -236.124646) (xy 122.971116 -236.136506) (xy 122.917966 -236.14049) (xy 122.864816 -236.136506)
			(xy 122.812854 -236.124646) (xy 122.76324 -236.105174) (xy 122.717082 -236.078525) (xy 122.675411 -236.045294)
			(xy 122.639159 -236.006223) (xy 122.609135 -235.962186) (xy 122.586009 -235.914165) (xy 122.570299 -235.863235)
			(xy 122.562356 -235.810531) (xy 122.333776 -235.810531) (xy 122.325833 -235.863235) (xy 122.310123 -235.914165)
			(xy 122.286997 -235.962186) (xy 122.256973 -236.006223) (xy 122.220721 -236.045294) (xy 122.17905 -236.078525)
			(xy 122.132892 -236.105174) (xy 122.083278 -236.124646) (xy 122.031316 -236.136506) (xy 121.978166 -236.14049)
			(xy 121.925016 -236.136506) (xy 121.873054 -236.124646) (xy 121.82344 -236.105174) (xy 121.777282 -236.078525)
			(xy 121.735611 -236.045294) (xy 121.699359 -236.006223) (xy 121.669335 -235.962186) (xy 121.646209 -235.914165)
			(xy 121.630499 -235.863235) (xy 121.622556 -235.810531) (xy 119.87201 -235.810531) (xy 119.868771 -235.853752)
			(xy 119.856911 -235.905717) (xy 119.837439 -235.955335) (xy 119.81079 -236.001496) (xy 119.77756 -236.043171)
			(xy 119.73849 -236.079427) (xy 119.694452 -236.109456) (xy 119.646431 -236.132587) (xy 119.5955 -236.148303)
			(xy 119.542795 -236.156253) (xy 119.516144 -236.156754) (xy 119.491475 -236.156324) (xy 119.442608 -236.149524)
			(xy 119.395151 -236.136035) (xy 119.350013 -236.116115) (xy 119.308062 -236.090146) (xy 119.288814 -236.074712)
			(xy 119.277684 -236.066085) (xy 119.251924 -236.054738) (xy 119.224044 -236.050857) (xy 119.196164 -236.054738)
			(xy 119.170404 -236.066085) (xy 119.159274 -236.074712) (xy 119.137858 -236.091835) (xy 119.090801 -236.119974)
			(xy 119.039984 -236.140563) (xy 118.986611 -236.153115) (xy 118.931944 -236.157332) (xy 118.877277 -236.153115)
			(xy 118.823904 -236.140563) (xy 118.773087 -236.119974) (xy 118.72603 -236.091835) (xy 118.704614 -236.074712)
			(xy 118.693484 -236.066085) (xy 118.667724 -236.054738) (xy 118.639844 -236.050857) (xy 118.611964 -236.054738)
			(xy 118.586204 -236.066085) (xy 118.575074 -236.074712) (xy 118.553658 -236.091835) (xy 118.506601 -236.119974)
			(xy 118.455784 -236.140563) (xy 118.402411 -236.153115) (xy 118.347744 -236.157332) (xy 118.293077 -236.153115)
			(xy 118.239704 -236.140563) (xy 118.188887 -236.119974) (xy 118.14183 -236.091835) (xy 118.120414 -236.074712)
			(xy 118.109284 -236.066085) (xy 118.083524 -236.054738) (xy 118.055644 -236.050857) (xy 118.027764 -236.054738)
			(xy 118.002004 -236.066085) (xy 117.990874 -236.074712) (xy 117.969458 -236.091835) (xy 117.922401 -236.119974)
			(xy 117.871584 -236.140563) (xy 117.818211 -236.153115) (xy 117.763544 -236.157332) (xy 117.708877 -236.153115)
			(xy 117.655504 -236.140563) (xy 117.604687 -236.119974) (xy 117.55763 -236.091835) (xy 117.536214 -236.074712)
			(xy 117.525084 -236.066085) (xy 117.499324 -236.054738) (xy 117.471444 -236.050857) (xy 117.443564 -236.054738)
			(xy 117.417804 -236.066085) (xy 117.406674 -236.074712) (xy 117.385258 -236.091835) (xy 117.338201 -236.119974)
			(xy 117.287384 -236.140563) (xy 117.234011 -236.153115) (xy 117.179344 -236.157332) (xy 117.124677 -236.153115)
			(xy 117.071304 -236.140563) (xy 117.020487 -236.119974) (xy 116.97343 -236.091835) (xy 116.952014 -236.074712)
			(xy 116.940884 -236.066085) (xy 116.915124 -236.054738) (xy 116.887244 -236.050857) (xy 116.859364 -236.054738)
			(xy 116.833604 -236.066085) (xy 116.822474 -236.074712) (xy 116.803216 -236.090134) (xy 116.761263 -236.116095)
			(xy 116.716128 -236.136015) (xy 116.668674 -236.149513) (xy 116.619812 -236.156331) (xy 116.595144 -236.156754)
			(xy 116.568494 -236.156192) (xy 116.515789 -236.148254) (xy 116.464856 -236.132549) (xy 116.416832 -236.109427)
			(xy 116.372792 -236.079406) (xy 116.333718 -236.043155) (xy 116.300484 -236.001486) (xy 116.273833 -235.955328)
			(xy 116.254359 -235.905714) (xy 116.242497 -235.853751) (xy 116.238514 -235.8006) (xy 114.815816 -235.8006)
			(xy 114.81563 -235.810531) (xy 114.807687 -235.863235) (xy 114.791977 -235.914165) (xy 114.768851 -235.962186)
			(xy 114.738827 -236.006223) (xy 114.702575 -236.045294) (xy 114.660904 -236.078525) (xy 114.614746 -236.105174)
			(xy 114.565132 -236.124646) (xy 114.51317 -236.136506) (xy 114.46002 -236.14049) (xy 114.40687 -236.136506)
			(xy 114.354908 -236.124646) (xy 114.305294 -236.105174) (xy 114.259136 -236.078525) (xy 114.217465 -236.045294)
			(xy 114.181213 -236.006223) (xy 114.151189 -235.962186) (xy 114.128063 -235.914165) (xy 114.112353 -235.863235)
			(xy 114.10441 -235.810531) (xy 113.87583 -235.810531) (xy 113.867887 -235.863235) (xy 113.852177 -235.914165)
			(xy 113.829051 -235.962186) (xy 113.799027 -236.006223) (xy 113.762775 -236.045294) (xy 113.721104 -236.078525)
			(xy 113.674946 -236.105174) (xy 113.625332 -236.124646) (xy 113.57337 -236.136506) (xy 113.52022 -236.14049)
			(xy 113.46707 -236.136506) (xy 113.415108 -236.124646) (xy 113.365494 -236.105174) (xy 113.319336 -236.078525)
			(xy 113.277665 -236.045294) (xy 113.241413 -236.006223) (xy 113.211389 -235.962186) (xy 113.188263 -235.914165)
			(xy 113.172553 -235.863235) (xy 113.16461 -235.810531) (xy 112.93603 -235.810531) (xy 112.928087 -235.863235)
			(xy 112.912377 -235.914165) (xy 112.889251 -235.962186) (xy 112.859227 -236.006223) (xy 112.822975 -236.045294)
			(xy 112.781304 -236.078525) (xy 112.735146 -236.105174) (xy 112.685532 -236.124646) (xy 112.63357 -236.136506)
			(xy 112.58042 -236.14049) (xy 112.52727 -236.136506) (xy 112.475308 -236.124646) (xy 112.425694 -236.105174)
			(xy 112.379536 -236.078525) (xy 112.337865 -236.045294) (xy 112.301613 -236.006223) (xy 112.271589 -235.962186)
			(xy 112.248463 -235.914165) (xy 112.232753 -235.863235) (xy 112.22481 -235.810531) (xy 111.99623 -235.810531)
			(xy 111.988287 -235.863235) (xy 111.972577 -235.914165) (xy 111.949451 -235.962186) (xy 111.919427 -236.006223)
			(xy 111.883175 -236.045294) (xy 111.841504 -236.078525) (xy 111.795346 -236.105174) (xy 111.745732 -236.124646)
			(xy 111.69377 -236.136506) (xy 111.64062 -236.14049) (xy 111.58747 -236.136506) (xy 111.535508 -236.124646)
			(xy 111.485894 -236.105174) (xy 111.439736 -236.078525) (xy 111.398065 -236.045294) (xy 111.361813 -236.006223)
			(xy 111.331789 -235.962186) (xy 111.308663 -235.914165) (xy 111.292953 -235.863235) (xy 111.28501 -235.810531)
			(xy 111.05643 -235.810531) (xy 111.048487 -235.863235) (xy 111.032777 -235.914165) (xy 111.009651 -235.962186)
			(xy 110.979627 -236.006223) (xy 110.943375 -236.045294) (xy 110.901704 -236.078525) (xy 110.855546 -236.105174)
			(xy 110.805932 -236.124646) (xy 110.75397 -236.136506) (xy 110.70082 -236.14049) (xy 110.64767 -236.136506)
			(xy 110.595708 -236.124646) (xy 110.546094 -236.105174) (xy 110.499936 -236.078525) (xy 110.458265 -236.045294)
			(xy 110.422013 -236.006223) (xy 110.391989 -235.962186) (xy 110.368863 -235.914165) (xy 110.353153 -235.863235)
			(xy 110.34521 -235.810531) (xy 110.11663 -235.810531) (xy 110.108687 -235.863235) (xy 110.092977 -235.914165)
			(xy 110.069851 -235.962186) (xy 110.039827 -236.006223) (xy 110.003575 -236.045294) (xy 109.961904 -236.078525)
			(xy 109.915746 -236.105174) (xy 109.866132 -236.124646) (xy 109.81417 -236.136506) (xy 109.76102 -236.14049)
			(xy 109.70787 -236.136506) (xy 109.655908 -236.124646) (xy 109.606294 -236.105174) (xy 109.560136 -236.078525)
			(xy 109.518465 -236.045294) (xy 109.482213 -236.006223) (xy 109.452189 -235.962186) (xy 109.429063 -235.914165)
			(xy 109.413353 -235.863235) (xy 109.40541 -235.810531) (xy 108.349133 -235.810531) (xy 108.367652 -235.825748)
			(xy 108.402873 -235.864649) (xy 108.432009 -235.908294) (xy 108.454431 -235.95574) (xy 108.469653 -236.005961)
			(xy 108.477346 -236.057871) (xy 108.477812 -236.08411) (xy 108.477268 -236.112093) (xy 108.468512 -236.16737)
			(xy 108.451216 -236.220597) (xy 108.425807 -236.270463) (xy 108.39291 -236.31574) (xy 108.353336 -236.355314)
			(xy 108.308058 -236.38821) (xy 108.258192 -236.413619) (xy 108.204964 -236.430913) (xy 108.149687 -236.439669)
			(xy 108.121704 -236.440218) (xy 108.094384 -236.43969) (xy 108.040383 -236.431352) (xy 107.988286 -236.414873)
			(xy 107.939315 -236.390637) (xy 107.894615 -236.359212) (xy 107.874562 -236.34065) (xy 107.86294 -236.330253)
			(xy 107.835006 -236.316429) (xy 107.804204 -236.311673) (xy 107.773402 -236.316429) (xy 107.745468 -236.330253)
			(xy 107.733846 -236.34065) (xy 107.713798 -236.359224) (xy 107.669116 -236.390688) (xy 107.620146 -236.414945)
			(xy 107.568041 -236.431426) (xy 107.514029 -236.439741) (xy 107.486704 -236.440218) (xy 107.458722 -236.439655)
			(xy 107.403445 -236.430901) (xy 107.350219 -236.413608) (xy 107.300354 -236.388201) (xy 107.255077 -236.355307)
			(xy 107.215503 -236.315734) (xy 107.182606 -236.270458) (xy 107.157197 -236.220594) (xy 107.139902 -236.167368)
			(xy 107.131146 -236.112092) (xy 107.130596 -236.08411) (xy 107.130958 -236.061686) (xy 107.136619 -236.017197)
			(xy 107.147802 -235.973766) (xy 107.155742 -235.952792) (xy 107.160542 -235.939287) (xy 107.163209 -235.910761)
			(xy 107.157856 -235.882616) (xy 107.144903 -235.857061) (xy 107.125367 -235.836105) (xy 107.113324 -235.828332)
			(xy 107.09106 -235.81444) (xy 107.050512 -235.781128) (xy 107.015288 -235.742229) (xy 106.98615 -235.698585)
			(xy 106.963728 -235.65114) (xy 106.948506 -235.600919) (xy 106.940814 -235.549009) (xy 106.94035 -235.52277)
			(xy 106.574183 -235.52277) (xy 106.562123 -235.561867) (xy 106.538997 -235.609888) (xy 106.508973 -235.653925)
			(xy 106.472721 -235.692996) (xy 106.43105 -235.726227) (xy 106.384892 -235.752876) (xy 106.335278 -235.772348)
			(xy 106.283316 -235.784208) (xy 106.230166 -235.788192) (xy 106.177016 -235.784208) (xy 106.125054 -235.772348)
			(xy 106.07544 -235.752876) (xy 106.029282 -235.726227) (xy 105.987611 -235.692996) (xy 105.951359 -235.653925)
			(xy 105.921335 -235.609888) (xy 105.898209 -235.561867) (xy 105.882499 -235.510937) (xy 105.874556 -235.458233)
			(xy 102.449022 -235.458233) (xy 102.449087 -235.460943) (xy 102.457041 -235.487239) (xy 102.471719 -235.510462)
			(xy 102.481634 -235.519976) (xy 102.499697 -235.536938) (xy 102.531427 -235.574994) (xy 102.557576 -235.617081)
			(xy 102.57764 -235.662386) (xy 102.591231 -235.710035) (xy 102.598087 -235.759107) (xy 102.598474 -235.783882)
			(xy 102.597955 -235.811867) (xy 102.589201 -235.867149) (xy 102.571906 -235.920381) (xy 102.546497 -235.970251)
			(xy 102.513598 -236.015532) (xy 102.47402 -236.055108) (xy 102.428737 -236.088005) (xy 102.378866 -236.113412)
			(xy 102.325633 -236.130705) (xy 102.270351 -236.139456) (xy 102.242366 -236.13999) (xy 102.217594 -236.139563)
			(xy 102.168527 -236.132699) (xy 102.120883 -236.119109) (xy 102.075578 -236.099055) (xy 102.033487 -236.072921)
			(xy 101.995418 -236.041212) (xy 101.97846 -236.02315) (xy 101.968891 -236.013295) (xy 101.945675 -235.998633)
			(xy 101.919393 -235.990681) (xy 101.891943 -235.990011) (xy 101.865305 -235.996674) (xy 101.841402 -236.010187)
			(xy 101.831394 -236.019594) (xy 101.776276 -236.074712) (xy 101.766721 -236.084857) (xy 101.753053 -236.109135)
			(xy 101.74646 -236.136203) (xy 101.747431 -236.164047) (xy 101.755895 -236.19059) (xy 101.77122 -236.213856)
			(xy 101.792266 -236.232112) (xy 101.817464 -236.243996) (xy 101.83114 -236.24667) (xy 101.858477 -236.251794)
			(xy 101.911233 -236.269403) (xy 101.960608 -236.295002) (xy 102.005402 -236.327967) (xy 102.044526 -236.367496)
			(xy 102.077026 -236.412628) (xy 102.08391 -236.426248) (xy 102.526084 -236.426248) (xy 102.526566 -236.400553)
			(xy 102.533973 -236.349699) (xy 102.548611 -236.300438) (xy 102.570177 -236.253791) (xy 102.598222 -236.210728)
			(xy 102.632164 -236.172143) (xy 102.6713 -236.138835) (xy 102.714815 -236.111497) (xy 102.761808 -236.090697)
			(xy 102.786434 -236.083348) (xy 102.79897 -236.07931) (xy 102.821659 -236.065968) (xy 102.840193 -236.047278)
			(xy 102.853343 -236.024477) (xy 102.86024 -235.999075) (xy 102.860425 -235.972754) (xy 102.857554 -235.959904)
			(xy 102.852229 -235.938065) (xy 102.846497 -235.89348) (xy 102.846124 -235.871004) (xy 102.846616 -235.843017)
			(xy 102.855373 -235.787733) (xy 102.87267 -235.734499) (xy 102.898082 -235.684626) (xy 102.930984 -235.639344)
			(xy 102.970565 -235.599766) (xy 103.01585 -235.566868) (xy 103.065725 -235.541459) (xy 103.11896 -235.524166)
			(xy 103.174245 -235.515414) (xy 103.202232 -235.514896) (xy 103.229154 -235.515359) (xy 103.282382 -235.523481)
			(xy 103.333782 -235.539522) (xy 103.382182 -235.563116) (xy 103.42648 -235.593724) (xy 103.465668 -235.63065)
			(xy 103.482648 -235.651548) (xy 103.491786 -235.662398) (xy 103.514735 -235.679048) (xy 103.541374 -235.688753)
			(xy 103.569656 -235.690766) (xy 103.597401 -235.684931) (xy 103.610156 -235.678726) (xy 103.635943 -235.665722)
			(xy 103.690667 -235.647276) (xy 103.747652 -235.637908) (xy 103.776526 -235.637324) (xy 103.803176 -235.63776)
			(xy 103.855882 -235.645707) (xy 103.906814 -235.661421) (xy 103.954835 -235.68455) (xy 103.998873 -235.714577)
			(xy 104.037944 -235.750833) (xy 104.071175 -235.792506) (xy 104.097824 -235.838667) (xy 104.117296 -235.888283)
			(xy 104.129157 -235.940248) (xy 104.13314 -235.9934) (xy 104.129157 -236.046552) (xy 104.117296 -236.098517)
			(xy 104.097824 -236.148133) (xy 104.071175 -236.194294) (xy 104.037944 -236.235967) (xy 103.998873 -236.272223)
			(xy 103.954835 -236.30225) (xy 103.906814 -236.325379) (xy 103.855882 -236.341093) (xy 103.803176 -236.34904)
			(xy 103.776526 -236.34954) (xy 103.749606 -236.349022) (xy 103.696381 -236.340909) (xy 103.644983 -236.324878)
			(xy 103.596583 -236.301295) (xy 103.552283 -236.270697) (xy 103.513093 -236.233781) (xy 103.49611 -236.212888)
			(xy 103.487003 -236.202009) (xy 103.464047 -236.185356) (xy 103.437398 -236.175654) (xy 103.409108 -236.17365)
			(xy 103.381357 -236.179497) (xy 103.368602 -236.18571) (xy 103.351651 -236.194405) (xy 103.316267 -236.20853)
			(xy 103.29799 -236.213904) (xy 103.28542 -236.217843) (xy 103.262729 -236.231208) (xy 103.244199 -236.24992)
			(xy 103.231055 -236.27274) (xy 103.224168 -236.298158) (xy 103.223993 -236.324492) (xy 103.22687 -236.337348)
			(xy 103.232186 -236.359189) (xy 103.237924 -236.403773) (xy 103.2383 -236.426248) (xy 103.237802 -236.452897)
			(xy 103.229859 -236.505601) (xy 103.214149 -236.556531) (xy 103.191023 -236.604552) (xy 103.160999 -236.648589)
			(xy 103.124747 -236.68766) (xy 103.083076 -236.720891) (xy 103.036918 -236.74754) (xy 102.987304 -236.767012)
			(xy 102.935342 -236.778872) (xy 102.882192 -236.782856) (xy 102.829042 -236.778872) (xy 102.77708 -236.767012)
			(xy 102.727466 -236.74754) (xy 102.681308 -236.720891) (xy 102.639637 -236.68766) (xy 102.603385 -236.648589)
			(xy 102.573361 -236.604552) (xy 102.550235 -236.556531) (xy 102.534525 -236.505601) (xy 102.526582 -236.452897)
			(xy 102.526084 -236.426248) (xy 102.08391 -236.426248) (xy 102.102114 -236.462265) (xy 102.119177 -236.5152)
			(xy 102.127802 -236.570143) (xy 102.12832 -236.597952) (xy 102.127804 -236.62594) (xy 102.119054 -236.681228)
			(xy 102.101762 -236.734467) (xy 102.076355 -236.784345) (xy 102.043457 -236.829634) (xy 102.003879 -236.869218)
			(xy 101.958596 -236.902123) (xy 101.908722 -236.927539) (xy 101.855487 -236.94484) (xy 101.8002 -236.953599)
			(xy 101.772212 -236.95406) (xy 101.74441 -236.953519) (xy 101.689482 -236.944867) (xy 101.636566 -236.927786)
			(xy 101.586946 -236.90269) (xy 101.541828 -236.870191) (xy 101.502307 -236.831076) (xy 101.469343 -236.786296)
			(xy 101.443736 -236.736939) (xy 101.426108 -236.684202) (xy 101.42093 -236.65688) (xy 101.418122 -236.643249)
			(xy 101.406214 -236.618108) (xy 101.387965 -236.597111) (xy 101.364729 -236.581815) (xy 101.338228 -236.573355)
			(xy 101.310427 -236.572358) (xy 101.283388 -236.578898) (xy 101.259115 -236.59249) (xy 101.248972 -236.602016)
			(xy 101.181916 -236.669072) (xy 101.178614 -236.682788) (xy 101.171494 -236.709608) (xy 101.150086 -236.7608)
			(xy 101.120998 -236.808052) (xy 101.084934 -236.850222) (xy 101.042766 -236.886288) (xy 100.995515 -236.915379)
			(xy 100.944324 -236.936789) (xy 100.917502 -236.9439) (xy 100.903786 -236.947202) (xy 100.651564 -237.199424)
			(xy 100.671122 -237.233206) (xy 100.68614 -237.260497) (xy 100.707442 -237.319029) (xy 100.718257 -237.38037)
			(xy 100.718874 -237.411514) (xy 100.718377 -237.438163) (xy 100.946956 -237.438163) (xy 100.946956 -237.384865)
			(xy 100.954899 -237.332161) (xy 100.970609 -237.281231) (xy 100.993735 -237.23321) (xy 101.023759 -237.189173)
			(xy 101.060011 -237.150102) (xy 101.101682 -237.116871) (xy 101.14784 -237.090222) (xy 101.197454 -237.07075)
			(xy 101.249416 -237.05889) (xy 101.302566 -237.054907) (xy 101.355716 -237.05889) (xy 101.407678 -237.07075)
			(xy 101.457292 -237.090222) (xy 101.50345 -237.116871) (xy 101.545121 -237.150102) (xy 101.581373 -237.189173)
			(xy 101.611397 -237.23321) (xy 101.634523 -237.281231) (xy 101.650233 -237.332161) (xy 101.658176 -237.384865)
			(xy 101.658674 -237.4115) (xy 101.885806 -237.4115) (xy 101.889789 -237.358356) (xy 101.901647 -237.306398)
			(xy 101.921116 -237.256789) (xy 101.947761 -237.210634) (xy 101.980987 -237.168967) (xy 102.020052 -237.132716)
			(xy 102.064084 -237.102692) (xy 102.112098 -237.079566) (xy 102.163022 -237.063854) (xy 102.215719 -237.055906)
			(xy 102.242366 -237.055406) (xy 102.270351 -237.055939) (xy 102.325635 -237.064682) (xy 102.378867 -237.081973)
			(xy 102.428735 -237.107387) (xy 102.474009 -237.140295) (xy 102.513572 -237.179886) (xy 102.546448 -237.225184)
			(xy 102.571825 -237.275071) (xy 102.580948 -237.301532) (xy 102.585951 -237.315247) (xy 102.602424 -237.33933)
			(xy 102.625043 -237.357763) (xy 102.651955 -237.369037) (xy 102.680958 -237.372229) (xy 102.709678 -237.367078)
			(xy 102.722934 -237.360968) (xy 102.747793 -237.349119) (xy 102.800249 -237.332368) (xy 102.854659 -237.32389)
			(xy 102.882192 -237.323376) (xy 102.910174 -237.323948) (xy 102.965449 -237.332702) (xy 103.018675 -237.349994)
			(xy 103.06854 -237.3754) (xy 103.113817 -237.408293) (xy 103.153391 -237.447865) (xy 103.186288 -237.493139)
			(xy 103.211697 -237.543003) (xy 103.228993 -237.596227) (xy 103.23775 -237.651502) (xy 103.2383 -237.679484)
			(xy 103.237876 -237.704153) (xy 103.231073 -237.75302) (xy 103.217582 -237.800477) (xy 103.197661 -237.845615)
			(xy 103.171693 -237.887565) (xy 103.156258 -237.906814) (xy 103.147647 -237.917955) (xy 103.136299 -237.943711)
			(xy 103.132416 -237.971588) (xy 103.136292 -237.999465) (xy 103.147634 -238.025224) (xy 103.156258 -238.036354)
			(xy 103.1717 -238.055596) (xy 103.197656 -238.097554) (xy 103.217572 -238.142694) (xy 103.231066 -238.19015)
			(xy 103.237879 -238.239015) (xy 103.2383 -238.263684) (xy 103.237802 -238.290333) (xy 103.229859 -238.343037)
			(xy 103.214149 -238.393967) (xy 103.191023 -238.441988) (xy 103.160999 -238.486025) (xy 103.124747 -238.525096)
			(xy 103.083076 -238.558327) (xy 103.036918 -238.584976) (xy 102.987304 -238.604448) (xy 102.935342 -238.616308)
			(xy 102.882192 -238.620292) (xy 102.829042 -238.616308) (xy 102.77708 -238.604448) (xy 102.727466 -238.584976)
			(xy 102.681308 -238.558327) (xy 102.639637 -238.525096) (xy 102.603385 -238.486025) (xy 102.573361 -238.441988)
			(xy 102.550235 -238.393967) (xy 102.534525 -238.343037) (xy 102.526582 -238.290333) (xy 102.526084 -238.263684)
			(xy 102.526471 -238.239013) (xy 102.53328 -238.190145) (xy 102.546779 -238.142686) (xy 102.566709 -238.097549)
			(xy 102.592687 -238.055601) (xy 102.608126 -238.036354) (xy 102.616768 -238.025235) (xy 102.628114 -237.999471)
			(xy 102.631992 -237.971588) (xy 102.628108 -237.943705) (xy 102.616755 -237.917944) (xy 102.608126 -237.906814)
			(xy 102.594053 -237.889305) (xy 102.569973 -237.851381) (xy 102.550859 -237.810728) (xy 102.54361 -237.789466)
			(xy 102.53866 -237.775729) (xy 102.522177 -237.751641) (xy 102.499547 -237.733207) (xy 102.472623 -237.721936)
			(xy 102.44361 -237.718751) (xy 102.414883 -237.723913) (xy 102.401624 -237.73003) (xy 102.376772 -237.741893)
			(xy 102.324312 -237.758639) (xy 102.2699 -237.767111) (xy 102.242366 -237.767622) (xy 102.215719 -237.767094)
			(xy 102.163022 -237.759146) (xy 102.112098 -237.743434) (xy 102.064084 -237.720308) (xy 102.020052 -237.690284)
			(xy 101.980987 -237.654033) (xy 101.947761 -237.612366) (xy 101.921116 -237.566211) (xy 101.901647 -237.516602)
			(xy 101.889789 -237.464644) (xy 101.885806 -237.4115) (xy 101.658674 -237.4115) (xy 101.658674 -237.411514)
			(xy 101.658176 -237.438163) (xy 101.650233 -237.490867) (xy 101.634523 -237.541797) (xy 101.611397 -237.589818)
			(xy 101.581373 -237.633855) (xy 101.545121 -237.672926) (xy 101.50345 -237.706157) (xy 101.457292 -237.732806)
			(xy 101.407678 -237.752278) (xy 101.355716 -237.764138) (xy 101.302566 -237.768122) (xy 101.249416 -237.764138)
			(xy 101.197454 -237.752278) (xy 101.14784 -237.732806) (xy 101.101682 -237.706157) (xy 101.060011 -237.672926)
			(xy 101.023759 -237.633855) (xy 100.993735 -237.589818) (xy 100.970609 -237.541797) (xy 100.954899 -237.490867)
			(xy 100.946956 -237.438163) (xy 100.718377 -237.438163) (xy 100.718352 -237.439498) (xy 100.709595 -237.494776)
			(xy 100.692297 -237.548003) (xy 100.666886 -237.597869) (xy 100.633986 -237.643145) (xy 100.594409 -237.682717)
			(xy 100.549128 -237.715611) (xy 100.499258 -237.741016) (xy 100.446029 -237.758306) (xy 100.39075 -237.767056)
			(xy 100.362766 -237.767622) (xy 100.339415 -237.767277) (xy 100.293108 -237.76121) (xy 100.247995 -237.749132)
			(xy 100.204851 -237.731251) (xy 100.184458 -237.71987) (xy 100.150676 -237.700312) (xy 100.05822 -237.792768)
			(xy 100.05822 -237.91037) (xy 100.080861 -237.922785) (xy 100.122622 -237.95315) (xy 100.15956 -237.989229)
			(xy 100.1909 -238.030264) (xy 100.215985 -238.075395) (xy 100.234288 -238.123676) (xy 100.245426 -238.174094)
			(xy 100.249166 -238.225593) (xy 100.247232 -238.252233) (xy 100.476802 -238.252233) (xy 100.476802 -238.198935)
			(xy 100.484745 -238.146231) (xy 100.500455 -238.095301) (xy 100.523581 -238.04728) (xy 100.553605 -238.003243)
			(xy 100.589857 -237.964172) (xy 100.631528 -237.930941) (xy 100.677686 -237.904292) (xy 100.7273 -237.88482)
			(xy 100.779262 -237.87296) (xy 100.832412 -237.868977) (xy 100.885562 -237.87296) (xy 100.937524 -237.88482)
			(xy 100.987138 -237.904292) (xy 101.033296 -237.930941) (xy 101.074967 -237.964172) (xy 101.111219 -238.003243)
			(xy 101.141243 -238.04728) (xy 101.164369 -238.095301) (xy 101.180079 -238.146231) (xy 101.188022 -238.198935)
			(xy 101.18852 -238.225584) (xy 101.188022 -238.252233) (xy 101.416602 -238.252233) (xy 101.416602 -238.198935)
			(xy 101.424545 -238.146231) (xy 101.440255 -238.095301) (xy 101.463381 -238.04728) (xy 101.493405 -238.003243)
			(xy 101.529657 -237.964172) (xy 101.571328 -237.930941) (xy 101.617486 -237.904292) (xy 101.6671 -237.88482)
			(xy 101.719062 -237.87296) (xy 101.772212 -237.868977) (xy 101.825362 -237.87296) (xy 101.877324 -237.88482)
			(xy 101.926938 -237.904292) (xy 101.973096 -237.930941) (xy 102.014767 -237.964172) (xy 102.051019 -238.003243)
			(xy 102.081043 -238.04728) (xy 102.104169 -238.095301) (xy 102.119879 -238.146231) (xy 102.127822 -238.198935)
			(xy 102.12832 -238.225584) (xy 102.127822 -238.252233) (xy 102.119879 -238.304937) (xy 102.104169 -238.355867)
			(xy 102.081043 -238.403888) (xy 102.051019 -238.447925) (xy 102.014767 -238.486996) (xy 101.973096 -238.520227)
			(xy 101.926938 -238.546876) (xy 101.877324 -238.566348) (xy 101.825362 -238.578208) (xy 101.772212 -238.582192)
			(xy 101.719062 -238.578208) (xy 101.6671 -238.566348) (xy 101.617486 -238.546876) (xy 101.571328 -238.520227)
			(xy 101.529657 -238.486996) (xy 101.493405 -238.447925) (xy 101.463381 -238.403888) (xy 101.440255 -238.355867)
			(xy 101.424545 -238.304937) (xy 101.416602 -238.252233) (xy 101.188022 -238.252233) (xy 101.180079 -238.304937)
			(xy 101.164369 -238.355867) (xy 101.141243 -238.403888) (xy 101.111219 -238.447925) (xy 101.074967 -238.486996)
			(xy 101.033296 -238.520227) (xy 100.987138 -238.546876) (xy 100.937524 -238.566348) (xy 100.885562 -238.578208)
			(xy 100.832412 -238.582192) (xy 100.779262 -238.578208) (xy 100.7273 -238.566348) (xy 100.677686 -238.546876)
			(xy 100.631528 -238.520227) (xy 100.589857 -238.486996) (xy 100.553605 -238.447925) (xy 100.523581 -238.403888)
			(xy 100.500455 -238.355867) (xy 100.484745 -238.304937) (xy 100.476802 -238.252233) (xy 100.247232 -238.252233)
			(xy 100.245428 -238.277091) (xy 100.234292 -238.32751) (xy 100.215991 -238.375792) (xy 100.190908 -238.420924)
			(xy 100.15957 -238.46196) (xy 100.122634 -238.49804) (xy 100.080873 -238.528407) (xy 100.05822 -238.540798)
			(xy 100.05822 -238.62919) (xy 100.058705 -238.643947) (xy 100.067128 -238.672232) (xy 100.083299 -238.69692)
			(xy 100.105864 -238.715942) (xy 100.132932 -238.727703) (xy 100.162235 -238.731219) (xy 100.191317 -238.726194)
			(xy 100.204778 -238.720122) (xy 100.229476 -238.7085) (xy 100.281527 -238.692072) (xy 100.335475 -238.683781)
			(xy 100.362766 -238.683292) (xy 100.389419 -238.683763) (xy 100.44213 -238.691703) (xy 100.493068 -238.707411)
			(xy 100.541096 -238.730536) (xy 100.585141 -238.760562) (xy 100.624219 -238.796817) (xy 100.657456 -238.838491)
			(xy 100.68411 -238.884654) (xy 100.703586 -238.934275) (xy 100.715448 -238.986244) (xy 100.719432 -239.0394)
			(xy 100.717435 -239.066049) (xy 100.946702 -239.066049) (xy 100.946702 -239.012751) (xy 100.954645 -238.960047)
			(xy 100.970355 -238.909117) (xy 100.993481 -238.861096) (xy 101.023505 -238.817059) (xy 101.059757 -238.777988)
			(xy 101.101428 -238.744757) (xy 101.147586 -238.718108) (xy 101.1972 -238.698636) (xy 101.249162 -238.686776)
			(xy 101.302312 -238.682793) (xy 101.355462 -238.686776) (xy 101.407424 -238.698636) (xy 101.457038 -238.718108)
			(xy 101.503196 -238.744757) (xy 101.544867 -238.777988) (xy 101.581119 -238.817059) (xy 101.611143 -238.861096)
			(xy 101.634269 -238.909117) (xy 101.649979 -238.960047) (xy 101.657922 -239.012751) (xy 101.65842 -239.0394)
			(xy 101.657922 -239.066049) (xy 101.649979 -239.118753) (xy 101.634269 -239.169683) (xy 101.611143 -239.217704)
			(xy 101.581119 -239.261741) (xy 101.544867 -239.300812) (xy 101.503196 -239.334043) (xy 101.457038 -239.360692)
			(xy 101.407424 -239.380164) (xy 101.355462 -239.392024) (xy 101.302312 -239.396008) (xy 101.249162 -239.392024)
			(xy 101.1972 -239.380164) (xy 101.147586 -239.360692) (xy 101.101428 -239.334043) (xy 101.059757 -239.300812)
			(xy 101.023505 -239.261741) (xy 100.993481 -239.217704) (xy 100.970355 -239.169683) (xy 100.954645 -239.118753)
			(xy 100.946702 -239.066049) (xy 100.717435 -239.066049) (xy 100.715448 -239.092556) (xy 100.703586 -239.144525)
			(xy 100.68411 -239.194146) (xy 100.657456 -239.240309) (xy 100.624219 -239.281983) (xy 100.585141 -239.318238)
			(xy 100.541096 -239.348264) (xy 100.493068 -239.371389) (xy 100.44213 -239.387097) (xy 100.389419 -239.395037)
			(xy 100.362766 -239.395508) (xy 100.335475 -239.395008) (xy 100.281526 -239.386724) (xy 100.229471 -239.370309)
			(xy 100.204778 -239.358678) (xy 100.191334 -239.352595) (xy 100.162259 -239.347637) (xy 100.132979 -239.35119)
			(xy 100.105933 -239.362958) (xy 100.083374 -239.38196) (xy 100.067182 -239.406613) (xy 100.058705 -239.434863)
			(xy 100.05822 -239.44961) (xy 100.05822 -239.538002) (xy 100.080858 -239.550417) (xy 100.122615 -239.580781)
			(xy 100.159549 -239.616858) (xy 100.190884 -239.657892) (xy 100.215965 -239.70302) (xy 100.234265 -239.751298)
			(xy 100.2454 -239.801713) (xy 100.249137 -239.853207) (xy 100.247201 -239.879865) (xy 100.476802 -239.879865)
			(xy 100.476802 -239.826567) (xy 100.484745 -239.773863) (xy 100.500455 -239.722933) (xy 100.523581 -239.674912)
			(xy 100.553605 -239.630875) (xy 100.589857 -239.591804) (xy 100.631528 -239.558573) (xy 100.677686 -239.531924)
			(xy 100.7273 -239.512452) (xy 100.779262 -239.500592) (xy 100.832412 -239.496609) (xy 100.885562 -239.500592)
			(xy 100.937524 -239.512452) (xy 100.987138 -239.531924) (xy 101.033296 -239.558573) (xy 101.074967 -239.591804)
			(xy 101.111219 -239.630875) (xy 101.141243 -239.674912) (xy 101.164369 -239.722933) (xy 101.180079 -239.773863)
			(xy 101.188022 -239.826567) (xy 101.18852 -239.853216) (xy 101.188022 -239.879865) (xy 101.416856 -239.879865)
			(xy 101.416856 -239.826567) (xy 101.424799 -239.773863) (xy 101.440509 -239.722933) (xy 101.463635 -239.674912)
			(xy 101.493659 -239.630875) (xy 101.529911 -239.591804) (xy 101.571582 -239.558573) (xy 101.61774 -239.531924)
			(xy 101.667354 -239.512452) (xy 101.719316 -239.500592) (xy 101.772466 -239.496609) (xy 101.825616 -239.500592)
			(xy 101.877578 -239.512452) (xy 101.927192 -239.531924) (xy 101.97335 -239.558573) (xy 102.015021 -239.591804)
			(xy 102.051273 -239.630875) (xy 102.081297 -239.674912) (xy 102.104423 -239.722933) (xy 102.120133 -239.773863)
			(xy 102.128076 -239.826567) (xy 102.128574 -239.853216) (xy 102.128076 -239.879865) (xy 102.120133 -239.932569)
			(xy 102.104423 -239.983499) (xy 102.081297 -240.03152) (xy 102.051273 -240.075557) (xy 102.015021 -240.114628)
			(xy 101.97335 -240.147859) (xy 101.927192 -240.174508) (xy 101.877578 -240.19398) (xy 101.825616 -240.20584)
			(xy 101.772466 -240.209824) (xy 101.719316 -240.20584) (xy 101.667354 -240.19398) (xy 101.61774 -240.174508)
			(xy 101.571582 -240.147859) (xy 101.529911 -240.114628) (xy 101.493659 -240.075557) (xy 101.463635 -240.03152)
			(xy 101.440509 -239.983499) (xy 101.424799 -239.932569) (xy 101.416856 -239.879865) (xy 101.188022 -239.879865)
			(xy 101.180079 -239.932569) (xy 101.164369 -239.983499) (xy 101.141243 -240.03152) (xy 101.111219 -240.075557)
			(xy 101.074967 -240.114628) (xy 101.033296 -240.147859) (xy 100.987138 -240.174508) (xy 100.937524 -240.19398)
			(xy 100.885562 -240.20584) (xy 100.832412 -240.209824) (xy 100.779262 -240.20584) (xy 100.7273 -240.19398)
			(xy 100.677686 -240.174508) (xy 100.631528 -240.147859) (xy 100.589857 -240.114628) (xy 100.553605 -240.075557)
			(xy 100.523581 -240.03152) (xy 100.500455 -239.983499) (xy 100.484745 -239.932569) (xy 100.476802 -239.879865)
			(xy 100.247201 -239.879865) (xy 100.245398 -239.904702) (xy 100.234261 -239.955116) (xy 100.215959 -240.003393)
			(xy 100.190876 -240.048521) (xy 100.159539 -240.089553) (xy 100.122604 -240.125628) (xy 100.080846 -240.155991)
			(xy 100.05822 -240.16843) (xy 100.05822 -240.257076) (xy 100.058703 -240.271834) (xy 100.067124 -240.300124)
			(xy 100.083295 -240.324815) (xy 100.105861 -240.34384) (xy 100.132931 -240.355603) (xy 100.162237 -240.359118)
			(xy 100.191322 -240.354092) (xy 100.204778 -240.348008) (xy 100.229465 -240.336359) (xy 100.281519 -240.319925)
			(xy 100.335472 -240.311632) (xy 100.362766 -240.311178) (xy 100.38942 -240.311649) (xy 100.442133 -240.319589)
			(xy 100.493073 -240.335298) (xy 100.541103 -240.358424) (xy 100.58515 -240.388451) (xy 100.624229 -240.424707)
			(xy 100.657467 -240.466383) (xy 100.684123 -240.512548) (xy 100.703599 -240.562171) (xy 100.715462 -240.614141)
			(xy 100.719446 -240.6673) (xy 100.71745 -240.693935) (xy 100.946956 -240.693935) (xy 100.946956 -240.640637)
			(xy 100.954899 -240.587933) (xy 100.970609 -240.537003) (xy 100.993735 -240.488982) (xy 101.023759 -240.444945)
			(xy 101.060011 -240.405874) (xy 101.101682 -240.372643) (xy 101.14784 -240.345994) (xy 101.197454 -240.326522)
			(xy 101.249416 -240.314662) (xy 101.302566 -240.310679) (xy 101.355716 -240.314662) (xy 101.407678 -240.326522)
			(xy 101.457292 -240.345994) (xy 101.50345 -240.372643) (xy 101.545121 -240.405874) (xy 101.581373 -240.444945)
			(xy 101.611397 -240.488982) (xy 101.634523 -240.537003) (xy 101.650233 -240.587933) (xy 101.658176 -240.640637)
			(xy 101.658674 -240.667286) (xy 101.658176 -240.693935) (xy 101.650233 -240.746639) (xy 101.634523 -240.797569)
			(xy 101.611397 -240.84559) (xy 101.581373 -240.889627) (xy 101.545121 -240.928698) (xy 101.50345 -240.961929)
			(xy 101.457292 -240.988578) (xy 101.407678 -241.00805) (xy 101.355716 -241.01991) (xy 101.302566 -241.023894)
			(xy 101.249416 -241.01991) (xy 101.197454 -241.00805) (xy 101.14784 -240.988578) (xy 101.101682 -240.961929)
			(xy 101.060011 -240.928698) (xy 101.023759 -240.889627) (xy 100.993735 -240.84559) (xy 100.970609 -240.797569)
			(xy 100.954899 -240.746639) (xy 100.946956 -240.693935) (xy 100.71745 -240.693935) (xy 100.715462 -240.720459)
			(xy 100.703599 -240.772429) (xy 100.684123 -240.822052) (xy 100.657467 -240.868217) (xy 100.624229 -240.909893)
			(xy 100.58515 -240.946149) (xy 100.541103 -240.976176) (xy 100.493073 -240.999302) (xy 100.442133 -241.015011)
			(xy 100.38942 -241.022951) (xy 100.362766 -241.023394) (xy 100.335475 -241.022894) (xy 100.281526 -241.014609)
			(xy 100.229472 -240.998194) (xy 100.204778 -240.986564) (xy 100.191334 -240.980482) (xy 100.162257 -240.975525)
			(xy 100.132976 -240.979078) (xy 100.105929 -240.990845) (xy 100.083369 -241.009846) (xy 100.067175 -241.034499)
			(xy 100.058695 -241.062749) (xy 100.05822 -241.077496) (xy 100.05822 -241.165888) (xy 100.080859 -241.178303)
			(xy 100.122618 -241.208668) (xy 100.159554 -241.244745) (xy 100.190891 -241.285779) (xy 100.215974 -241.330909)
			(xy 100.234275 -241.379188) (xy 100.245412 -241.429605) (xy 100.24915 -241.481101) (xy 100.247215 -241.507751)
			(xy 100.477056 -241.507751) (xy 100.477056 -241.454453) (xy 100.484999 -241.401749) (xy 100.500709 -241.350819)
			(xy 100.523835 -241.302798) (xy 100.553859 -241.258761) (xy 100.590111 -241.21969) (xy 100.631782 -241.186459)
			(xy 100.67794 -241.15981) (xy 100.727554 -241.140338) (xy 100.779516 -241.128478) (xy 100.832666 -241.124495)
			(xy 100.885816 -241.128478) (xy 100.937778 -241.140338) (xy 100.987392 -241.15981) (xy 101.03355 -241.186459)
			(xy 101.075221 -241.21969) (xy 101.111473 -241.258761) (xy 101.141497 -241.302798) (xy 101.164623 -241.350819)
			(xy 101.180333 -241.401749) (xy 101.188276 -241.454453) (xy 101.188774 -241.481102) (xy 101.188276 -241.507751)
			(xy 101.180333 -241.560455) (xy 101.164623 -241.611385) (xy 101.141497 -241.659406) (xy 101.111473 -241.703443)
			(xy 101.075221 -241.742514) (xy 101.03355 -241.775745) (xy 100.987392 -241.802394) (xy 100.937778 -241.821866)
			(xy 100.885816 -241.833726) (xy 100.832666 -241.83771) (xy 100.779516 -241.833726) (xy 100.727554 -241.821866)
			(xy 100.67794 -241.802394) (xy 100.631782 -241.775745) (xy 100.590111 -241.742514) (xy 100.553859 -241.703443)
			(xy 100.523835 -241.659406) (xy 100.500709 -241.611385) (xy 100.484999 -241.560455) (xy 100.477056 -241.507751)
			(xy 100.247215 -241.507751) (xy 100.245411 -241.532597) (xy 100.234275 -241.583013) (xy 100.215973 -241.631293)
			(xy 100.19089 -241.676422) (xy 100.159552 -241.717456) (xy 100.122617 -241.753534) (xy 100.080858 -241.783898)
			(xy 100.05822 -241.796316) (xy 100.05822 -241.884708) (xy 100.058707 -241.899463) (xy 100.067133 -241.927744)
			(xy 100.083305 -241.952427) (xy 100.105869 -241.971444) (xy 100.132934 -241.983203) (xy 100.162233 -241.986719)
			(xy 100.191311 -241.981695) (xy 100.204778 -241.97564) (xy 100.229476 -241.964017) (xy 100.281526 -241.947588)
			(xy 100.335475 -241.939297) (xy 100.362766 -241.93881) (xy 100.389417 -241.939281) (xy 100.442126 -241.947221)
			(xy 100.493062 -241.962928) (xy 100.541087 -241.986052) (xy 100.58513 -242.016076) (xy 100.624206 -242.052329)
			(xy 100.657441 -242.094001) (xy 100.684094 -242.140162) (xy 100.703569 -242.18978) (xy 100.71543 -242.241746)
			(xy 100.719414 -242.2949) (xy 100.71543 -242.348054) (xy 100.703569 -242.40002) (xy 100.684094 -242.449638)
			(xy 100.657441 -242.495799) (xy 100.624206 -242.537471) (xy 100.58513 -242.573724) (xy 100.541087 -242.603748)
			(xy 100.493062 -242.626872) (xy 100.442126 -242.642579) (xy 100.389417 -242.650519) (xy 100.362766 -242.651026)
			(xy 100.335475 -242.650525) (xy 100.281527 -242.642239) (xy 100.229474 -242.625821) (xy 100.204778 -242.614196)
			(xy 100.191335 -242.608112) (xy 100.162261 -242.603154) (xy 100.132982 -242.606706) (xy 100.105937 -242.618474)
			(xy 100.08338 -242.637477) (xy 100.067191 -242.662131) (xy 100.058719 -242.690382) (xy 100.05822 -242.705128)
			(xy 100.05822 -242.793774) (xy 100.08086 -242.806189) (xy 100.122621 -242.836554) (xy 100.159559 -242.872632)
			(xy 100.190898 -242.913667) (xy 100.215982 -242.958798) (xy 100.234285 -243.007079) (xy 100.245423 -243.057497)
			(xy 100.249162 -243.108994) (xy 100.247229 -243.135637) (xy 100.476802 -243.135637) (xy 100.476802 -243.082339)
			(xy 100.484745 -243.029635) (xy 100.500455 -242.978705) (xy 100.523581 -242.930684) (xy 100.553605 -242.886647)
			(xy 100.589857 -242.847576) (xy 100.631528 -242.814345) (xy 100.677686 -242.787696) (xy 100.7273 -242.768224)
			(xy 100.779262 -242.756364) (xy 100.832412 -242.752381) (xy 100.885562 -242.756364) (xy 100.937524 -242.768224)
			(xy 100.987138 -242.787696) (xy 101.033296 -242.814345) (xy 101.074967 -242.847576) (xy 101.111219 -242.886647)
			(xy 101.141243 -242.930684) (xy 101.164369 -242.978705) (xy 101.180079 -243.029635) (xy 101.188022 -243.082339)
			(xy 101.18852 -243.108988) (xy 101.188022 -243.135637) (xy 101.416602 -243.135637) (xy 101.416602 -243.082339)
			(xy 101.424545 -243.029635) (xy 101.440255 -242.978705) (xy 101.463381 -242.930684) (xy 101.493405 -242.886647)
			(xy 101.529657 -242.847576) (xy 101.571328 -242.814345) (xy 101.617486 -242.787696) (xy 101.6671 -242.768224)
			(xy 101.719062 -242.756364) (xy 101.772212 -242.752381) (xy 101.825362 -242.756364) (xy 101.877324 -242.768224)
			(xy 101.926938 -242.787696) (xy 101.973096 -242.814345) (xy 102.014767 -242.847576) (xy 102.051019 -242.886647)
			(xy 102.081043 -242.930684) (xy 102.104169 -242.978705) (xy 102.119879 -243.029635) (xy 102.127822 -243.082339)
			(xy 102.12832 -243.108988) (xy 102.127822 -243.135637) (xy 102.119879 -243.188341) (xy 102.104169 -243.239271)
			(xy 102.081043 -243.287292) (xy 102.051019 -243.331329) (xy 102.014767 -243.3704) (xy 101.973096 -243.403631)
			(xy 101.926938 -243.43028) (xy 101.877324 -243.449752) (xy 101.825362 -243.461612) (xy 101.772212 -243.465596)
			(xy 101.719062 -243.461612) (xy 101.6671 -243.449752) (xy 101.617486 -243.43028) (xy 101.571328 -243.403631)
			(xy 101.529657 -243.3704) (xy 101.493405 -243.331329) (xy 101.463381 -243.287292) (xy 101.440255 -243.239271)
			(xy 101.424545 -243.188341) (xy 101.416602 -243.135637) (xy 101.188022 -243.135637) (xy 101.180079 -243.188341)
			(xy 101.164369 -243.239271) (xy 101.141243 -243.287292) (xy 101.111219 -243.331329) (xy 101.074967 -243.3704)
			(xy 101.033296 -243.403631) (xy 100.987138 -243.43028) (xy 100.937524 -243.449752) (xy 100.885562 -243.461612)
			(xy 100.832412 -243.465596) (xy 100.779262 -243.461612) (xy 100.7273 -243.449752) (xy 100.677686 -243.43028)
			(xy 100.631528 -243.403631) (xy 100.589857 -243.3704) (xy 100.553605 -243.331329) (xy 100.523581 -243.287292)
			(xy 100.500455 -243.239271) (xy 100.484745 -243.188341) (xy 100.476802 -243.135637) (xy 100.247229 -243.135637)
			(xy 100.245425 -243.160492) (xy 100.234288 -243.210911) (xy 100.215987 -243.259192) (xy 100.190904 -243.304324)
			(xy 100.159566 -243.345359) (xy 100.12263 -243.381439) (xy 100.08087 -243.411805) (xy 100.05822 -243.424202)
			(xy 100.05822 -243.512594) (xy 100.058706 -243.527351) (xy 100.067129 -243.555635) (xy 100.0833 -243.580322)
			(xy 100.105865 -243.599342) (xy 100.132933 -243.611103) (xy 100.162234 -243.614619) (xy 100.191316 -243.609594)
			(xy 100.204778 -243.603526) (xy 100.229476 -243.591904) (xy 100.281526 -243.575475) (xy 100.335475 -243.567184)
			(xy 100.362766 -243.566696) (xy 100.389419 -243.567167) (xy 100.442129 -243.575107) (xy 100.493067 -243.590815)
			(xy 100.541094 -243.61394) (xy 100.585139 -243.643965) (xy 100.624216 -243.680219) (xy 100.657453 -243.721894)
			(xy 100.684107 -243.768056) (xy 100.703582 -243.817676) (xy 100.715444 -243.869644) (xy 100.719428 -243.9228)
			(xy 100.71743 -243.949453) (xy 100.946702 -243.949453) (xy 100.946702 -243.896155) (xy 100.954645 -243.843451)
			(xy 100.970355 -243.792521) (xy 100.993481 -243.7445) (xy 101.023505 -243.700463) (xy 101.059757 -243.661392)
			(xy 101.101428 -243.628161) (xy 101.147586 -243.601512) (xy 101.1972 -243.58204) (xy 101.249162 -243.57018)
			(xy 101.302312 -243.566197) (xy 101.355462 -243.57018) (xy 101.407424 -243.58204) (xy 101.457038 -243.601512)
			(xy 101.503196 -243.628161) (xy 101.544867 -243.661392) (xy 101.581119 -243.700463) (xy 101.611143 -243.7445)
			(xy 101.634269 -243.792521) (xy 101.649979 -243.843451) (xy 101.657922 -243.896155) (xy 101.65842 -243.922804)
			(xy 101.657922 -243.949453) (xy 101.886756 -243.949453) (xy 101.886756 -243.896155) (xy 101.894699 -243.843451)
			(xy 101.910409 -243.792521) (xy 101.933535 -243.7445) (xy 101.963559 -243.700463) (xy 101.999811 -243.661392)
			(xy 102.041482 -243.628161) (xy 102.08764 -243.601512) (xy 102.137254 -243.58204) (xy 102.189216 -243.57018)
			(xy 102.242366 -243.566197) (xy 102.295516 -243.57018) (xy 102.347478 -243.58204) (xy 102.397092 -243.601512)
			(xy 102.44325 -243.628161) (xy 102.484921 -243.661392) (xy 102.521173 -243.700463) (xy 102.551197 -243.7445)
			(xy 102.574323 -243.792521) (xy 102.590033 -243.843451) (xy 102.597976 -243.896155) (xy 102.598474 -243.922804)
			(xy 102.597976 -243.949453) (xy 102.590033 -244.002157) (xy 102.574323 -244.053087) (xy 102.551197 -244.101108)
			(xy 102.521173 -244.145145) (xy 102.484921 -244.184216) (xy 102.44325 -244.217447) (xy 102.397092 -244.244096)
			(xy 102.347478 -244.263568) (xy 102.295516 -244.275428) (xy 102.242366 -244.279412) (xy 102.189216 -244.275428)
			(xy 102.137254 -244.263568) (xy 102.08764 -244.244096) (xy 102.041482 -244.217447) (xy 101.999811 -244.184216)
			(xy 101.963559 -244.145145) (xy 101.933535 -244.101108) (xy 101.910409 -244.053087) (xy 101.894699 -244.002157)
			(xy 101.886756 -243.949453) (xy 101.657922 -243.949453) (xy 101.649979 -244.002157) (xy 101.634269 -244.053087)
			(xy 101.611143 -244.101108) (xy 101.581119 -244.145145) (xy 101.544867 -244.184216) (xy 101.503196 -244.217447)
			(xy 101.457038 -244.244096) (xy 101.407424 -244.263568) (xy 101.355462 -244.275428) (xy 101.302312 -244.279412)
			(xy 101.249162 -244.275428) (xy 101.1972 -244.263568) (xy 101.147586 -244.244096) (xy 101.101428 -244.217447)
			(xy 101.059757 -244.184216) (xy 101.023505 -244.145145) (xy 100.993481 -244.101108) (xy 100.970355 -244.053087)
			(xy 100.954645 -244.002157) (xy 100.946702 -243.949453) (xy 100.71743 -243.949453) (xy 100.715444 -243.975956)
			(xy 100.703582 -244.027924) (xy 100.684107 -244.077544) (xy 100.657453 -244.123706) (xy 100.624216 -244.165381)
			(xy 100.585139 -244.201635) (xy 100.541094 -244.23166) (xy 100.493067 -244.254785) (xy 100.442129 -244.270493)
			(xy 100.389419 -244.278433) (xy 100.362766 -244.278912) (xy 100.335475 -244.278412) (xy 100.281526 -244.270128)
			(xy 100.229471 -244.253713) (xy 100.204778 -244.242082) (xy 100.191335 -244.235999) (xy 100.162259 -244.231041)
			(xy 100.132979 -244.234594) (xy 100.105934 -244.246362) (xy 100.083376 -244.265363) (xy 100.067184 -244.290017)
			(xy 100.058708 -244.318267) (xy 100.05822 -244.333014) (xy 100.05822 -244.421406) (xy 100.080858 -244.433821)
			(xy 100.122614 -244.464185) (xy 100.159547 -244.500262) (xy 100.190882 -244.541295) (xy 100.215963 -244.586423)
			(xy 100.234262 -244.634701) (xy 100.245397 -244.685115) (xy 100.249134 -244.736609) (xy 100.247198 -244.763269)
			(xy 100.476802 -244.763269) (xy 100.476802 -244.709971) (xy 100.484745 -244.657267) (xy 100.500455 -244.606337)
			(xy 100.523581 -244.558316) (xy 100.553605 -244.514279) (xy 100.589857 -244.475208) (xy 100.631528 -244.441977)
			(xy 100.677686 -244.415328) (xy 100.7273 -244.395856) (xy 100.779262 -244.383996) (xy 100.832412 -244.380013)
			(xy 100.885562 -244.383996) (xy 100.937524 -244.395856) (xy 100.987138 -244.415328) (xy 101.033296 -244.441977)
			(xy 101.074967 -244.475208) (xy 101.111219 -244.514279) (xy 101.141243 -244.558316) (xy 101.164369 -244.606337)
			(xy 101.180079 -244.657267) (xy 101.188022 -244.709971) (xy 101.18852 -244.73662) (xy 101.188022 -244.763269)
			(xy 101.416602 -244.763269) (xy 101.416602 -244.709971) (xy 101.424545 -244.657267) (xy 101.440255 -244.606337)
			(xy 101.463381 -244.558316) (xy 101.493405 -244.514279) (xy 101.529657 -244.475208) (xy 101.571328 -244.441977)
			(xy 101.617486 -244.415328) (xy 101.6671 -244.395856) (xy 101.719062 -244.383996) (xy 101.772212 -244.380013)
			(xy 101.825362 -244.383996) (xy 101.877324 -244.395856) (xy 101.926938 -244.415328) (xy 101.973096 -244.441977)
			(xy 102.014767 -244.475208) (xy 102.051019 -244.514279) (xy 102.081043 -244.558316) (xy 102.104169 -244.606337)
			(xy 102.119879 -244.657267) (xy 102.127822 -244.709971) (xy 102.12832 -244.73662) (xy 102.127822 -244.763269)
			(xy 102.119879 -244.815973) (xy 102.104169 -244.866903) (xy 102.081043 -244.914924) (xy 102.051019 -244.958961)
			(xy 102.014767 -244.998032) (xy 101.973096 -245.031263) (xy 101.926938 -245.057912) (xy 101.877324 -245.077384)
			(xy 101.825362 -245.089244) (xy 101.772212 -245.093228) (xy 101.719062 -245.089244) (xy 101.6671 -245.077384)
			(xy 101.617486 -245.057912) (xy 101.571328 -245.031263) (xy 101.529657 -244.998032) (xy 101.493405 -244.958961)
			(xy 101.463381 -244.914924) (xy 101.440255 -244.866903) (xy 101.424545 -244.815973) (xy 101.416602 -244.763269)
			(xy 101.188022 -244.763269) (xy 101.180079 -244.815973) (xy 101.164369 -244.866903) (xy 101.141243 -244.914924)
			(xy 101.111219 -244.958961) (xy 101.074967 -244.998032) (xy 101.033296 -245.031263) (xy 100.987138 -245.057912)
			(xy 100.937524 -245.077384) (xy 100.885562 -245.089244) (xy 100.832412 -245.093228) (xy 100.779262 -245.089244)
			(xy 100.7273 -245.077384) (xy 100.677686 -245.057912) (xy 100.631528 -245.031263) (xy 100.589857 -244.998032)
			(xy 100.553605 -244.958961) (xy 100.523581 -244.914924) (xy 100.500455 -244.866903) (xy 100.484745 -244.815973)
			(xy 100.476802 -244.763269) (xy 100.247198 -244.763269) (xy 100.245394 -244.788103) (xy 100.234257 -244.838517)
			(xy 100.215955 -244.886793) (xy 100.190872 -244.93192) (xy 100.159535 -244.972952) (xy 100.1226 -245.009027)
			(xy 100.080842 -245.039389) (xy 100.05822 -245.051834) (xy 100.05822 -245.14048) (xy 100.058704 -245.155238)
			(xy 100.067125 -245.183526) (xy 100.083296 -245.208217) (xy 100.105862 -245.22724) (xy 100.132932 -245.239003)
			(xy 100.162236 -245.242518) (xy 100.19132 -245.237492) (xy 100.204778 -245.231412) (xy 100.229465 -245.219762)
			(xy 100.281519 -245.203329) (xy 100.335472 -245.195035) (xy 100.362766 -245.194582) (xy 100.38942 -245.195053)
			(xy 100.442132 -245.202993) (xy 100.493072 -245.218702) (xy 100.541101 -245.241828) (xy 100.585147 -245.271854)
			(xy 100.624226 -245.30811) (xy 100.657464 -245.349786) (xy 100.684119 -245.39595) (xy 100.703595 -245.445572)
			(xy 100.715458 -245.497542) (xy 100.719442 -245.5507) (xy 100.717446 -245.577339) (xy 100.946956 -245.577339)
			(xy 100.946956 -245.524041) (xy 100.954899 -245.471337) (xy 100.970609 -245.420407) (xy 100.993735 -245.372386)
			(xy 101.023759 -245.328349) (xy 101.060011 -245.289278) (xy 101.101682 -245.256047) (xy 101.14784 -245.229398)
			(xy 101.197454 -245.209926) (xy 101.249416 -245.198066) (xy 101.302566 -245.194083) (xy 101.355716 -245.198066)
			(xy 101.407678 -245.209926) (xy 101.457292 -245.229398) (xy 101.50345 -245.256047) (xy 101.545121 -245.289278)
			(xy 101.581373 -245.328349) (xy 101.611397 -245.372386) (xy 101.634523 -245.420407) (xy 101.650233 -245.471337)
			(xy 101.658176 -245.524041) (xy 101.658674 -245.55069) (xy 101.658674 -245.5507) (xy 101.885782 -245.5507)
			(xy 101.889765 -245.497552) (xy 101.901624 -245.445591) (xy 101.921095 -245.395978) (xy 101.947741 -245.349821)
			(xy 101.98097 -245.30815) (xy 102.020037 -245.271897) (xy 102.064072 -245.241872) (xy 102.112089 -245.218744)
			(xy 102.163017 -245.20303) (xy 102.215718 -245.195082) (xy 102.242366 -245.194582) (xy 102.266609 -245.195007)
			(xy 102.314645 -245.201592) (xy 102.361341 -245.214645) (xy 102.405829 -245.233923) (xy 102.42677 -245.246144)
			(xy 102.43946 -245.253283) (xy 102.467599 -245.260719) (xy 102.496694 -245.25993) (xy 102.524389 -245.250979)
			(xy 102.548443 -245.23459) (xy 102.566907 -245.212092) (xy 102.573074 -245.1989) (xy 102.583619 -245.17509)
			(xy 102.610648 -245.130583) (xy 102.626922 -245.110254) (xy 102.635565 -245.099135) (xy 102.646911 -245.073371)
			(xy 102.650789 -245.045488) (xy 102.646904 -245.017605) (xy 102.635552 -244.991844) (xy 102.626922 -244.980714)
			(xy 102.611509 -244.96145) (xy 102.585548 -244.919498) (xy 102.565627 -244.874364) (xy 102.552127 -244.826912)
			(xy 102.545305 -244.778051) (xy 102.54488 -244.753384) (xy 102.545378 -244.726735) (xy 102.553321 -244.674031)
			(xy 102.569031 -244.623101) (xy 102.592157 -244.57508) (xy 102.622181 -244.531043) (xy 102.658433 -244.491972)
			(xy 102.700104 -244.458741) (xy 102.746262 -244.432092) (xy 102.795876 -244.41262) (xy 102.847838 -244.40076)
			(xy 102.900988 -244.396777) (xy 102.954138 -244.40076) (xy 103.0061 -244.41262) (xy 103.055714 -244.432092)
			(xy 103.101872 -244.458741) (xy 103.143543 -244.491972) (xy 103.179795 -244.531043) (xy 103.209819 -244.57508)
			(xy 103.232945 -244.623101) (xy 103.248655 -244.674031) (xy 103.256598 -244.726735) (xy 103.257096 -244.753384)
			(xy 103.256673 -244.778053) (xy 103.24987 -244.82692) (xy 103.236379 -244.874377) (xy 103.216457 -244.919515)
			(xy 103.190489 -244.961466) (xy 103.175054 -244.980714) (xy 103.166444 -244.991855) (xy 103.155096 -245.017611)
			(xy 103.151213 -245.045488) (xy 103.155089 -245.073365) (xy 103.166431 -245.099124) (xy 103.175054 -245.110254)
			(xy 103.190495 -245.129497) (xy 103.216452 -245.171454) (xy 103.236368 -245.216594) (xy 103.249862 -245.26405)
			(xy 103.256675 -245.312915) (xy 103.257096 -245.337584) (xy 103.256573 -245.36557) (xy 103.247819 -245.420852)
			(xy 103.230524 -245.474084) (xy 103.205115 -245.523955) (xy 103.172217 -245.569237) (xy 103.13264 -245.608814)
			(xy 103.087358 -245.641713) (xy 103.037487 -245.667123) (xy 102.984256 -245.684418) (xy 102.928973 -245.693172)
			(xy 102.900988 -245.693692) (xy 102.876744 -245.693291) (xy 102.828707 -245.6867) (xy 102.782011 -245.67364)
			(xy 102.737524 -245.654355) (xy 102.716584 -245.64213) (xy 102.703856 -245.635067) (xy 102.675732 -245.627625)
			(xy 102.64665 -245.628403) (xy 102.618964 -245.63734) (xy 102.594916 -245.653711) (xy 102.57645 -245.676191)
			(xy 102.57028 -245.689374) (xy 102.559697 -245.713201) (xy 102.532624 -245.757754) (xy 102.499342 -245.797881)
			(xy 102.460561 -245.832723) (xy 102.417113 -245.861535) (xy 102.369925 -245.8837) (xy 102.320009 -245.898744)
			(xy 102.268433 -245.906345) (xy 102.242366 -245.906798) (xy 102.215718 -245.906318) (xy 102.163017 -245.89837)
			(xy 102.112089 -245.882656) (xy 102.064072 -245.859528) (xy 102.020037 -245.829503) (xy 101.98097 -245.79325)
			(xy 101.947741 -245.751579) (xy 101.921095 -245.705422) (xy 101.901624 -245.655809) (xy 101.889765 -245.603848)
			(xy 101.885782 -245.5507) (xy 101.658674 -245.5507) (xy 101.658176 -245.577339) (xy 101.650233 -245.630043)
			(xy 101.634523 -245.680973) (xy 101.611397 -245.728994) (xy 101.581373 -245.773031) (xy 101.545121 -245.812102)
			(xy 101.50345 -245.845333) (xy 101.457292 -245.871982) (xy 101.407678 -245.891454) (xy 101.355716 -245.903314)
			(xy 101.302566 -245.907298) (xy 101.249416 -245.903314) (xy 101.197454 -245.891454) (xy 101.14784 -245.871982)
			(xy 101.101682 -245.845333) (xy 101.060011 -245.812102) (xy 101.023759 -245.773031) (xy 100.993735 -245.728994)
			(xy 100.970609 -245.680973) (xy 100.954899 -245.630043) (xy 100.946956 -245.577339) (xy 100.717446 -245.577339)
			(xy 100.715458 -245.603858) (xy 100.703595 -245.655828) (xy 100.684119 -245.70545) (xy 100.657464 -245.751614)
			(xy 100.624226 -245.79329) (xy 100.585147 -245.829546) (xy 100.541101 -245.859572) (xy 100.493072 -245.882698)
			(xy 100.442132 -245.898407) (xy 100.38942 -245.906347) (xy 100.362766 -245.906798) (xy 100.335475 -245.906298)
			(xy 100.281526 -245.898013) (xy 100.229472 -245.881598) (xy 100.204778 -245.869968) (xy 100.191334 -245.863885)
			(xy 100.162258 -245.858928) (xy 100.132977 -245.862482) (xy 100.10593 -245.874249) (xy 100.083371 -245.89325)
			(xy 100.067177 -245.917903) (xy 100.058698 -245.946153) (xy 100.05822 -245.9609) (xy 100.05822 -246.049292)
			(xy 100.080859 -246.061707) (xy 100.122617 -246.092072) (xy 100.159552 -246.128149) (xy 100.190889 -246.169183)
			(xy 100.215971 -246.214312) (xy 100.234272 -246.262591) (xy 100.245408 -246.313007) (xy 100.249146 -246.364503)
			(xy 100.247211 -246.391155) (xy 100.477056 -246.391155) (xy 100.477056 -246.337857) (xy 100.484999 -246.285153)
			(xy 100.500709 -246.234223) (xy 100.523835 -246.186202) (xy 100.553859 -246.142165) (xy 100.590111 -246.103094)
			(xy 100.631782 -246.069863) (xy 100.67794 -246.043214) (xy 100.727554 -246.023742) (xy 100.779516 -246.011882)
			(xy 100.832666 -246.007899) (xy 100.885816 -246.011882) (xy 100.937778 -246.023742) (xy 100.987392 -246.043214)
			(xy 101.03355 -246.069863) (xy 101.075221 -246.103094) (xy 101.111473 -246.142165) (xy 101.141497 -246.186202)
			(xy 101.164623 -246.234223) (xy 101.180333 -246.285153) (xy 101.188276 -246.337857) (xy 101.188774 -246.364506)
			(xy 101.188276 -246.391155) (xy 101.416602 -246.391155) (xy 101.416602 -246.337857) (xy 101.424545 -246.285153)
			(xy 101.440255 -246.234223) (xy 101.463381 -246.186202) (xy 101.493405 -246.142165) (xy 101.529657 -246.103094)
			(xy 101.571328 -246.069863) (xy 101.617486 -246.043214) (xy 101.6671 -246.023742) (xy 101.719062 -246.011882)
			(xy 101.772212 -246.007899) (xy 101.825362 -246.011882) (xy 101.877324 -246.023742) (xy 101.926938 -246.043214)
			(xy 101.973096 -246.069863) (xy 102.014767 -246.103094) (xy 102.051019 -246.142165) (xy 102.081043 -246.186202)
			(xy 102.104169 -246.234223) (xy 102.119879 -246.285153) (xy 102.127822 -246.337857) (xy 102.12832 -246.364506)
			(xy 102.127822 -246.391155) (xy 102.119879 -246.443859) (xy 102.104169 -246.494789) (xy 102.081043 -246.54281)
			(xy 102.051019 -246.586847) (xy 102.014767 -246.625918) (xy 101.973096 -246.659149) (xy 101.926938 -246.685798)
			(xy 101.877324 -246.70527) (xy 101.825362 -246.71713) (xy 101.772212 -246.721114) (xy 101.719062 -246.71713)
			(xy 101.6671 -246.70527) (xy 101.617486 -246.685798) (xy 101.571328 -246.659149) (xy 101.529657 -246.625918)
			(xy 101.493405 -246.586847) (xy 101.463381 -246.54281) (xy 101.440255 -246.494789) (xy 101.424545 -246.443859)
			(xy 101.416602 -246.391155) (xy 101.188276 -246.391155) (xy 101.180333 -246.443859) (xy 101.164623 -246.494789)
			(xy 101.141497 -246.54281) (xy 101.111473 -246.586847) (xy 101.075221 -246.625918) (xy 101.03355 -246.659149)
			(xy 100.987392 -246.685798) (xy 100.937778 -246.70527) (xy 100.885816 -246.71713) (xy 100.832666 -246.721114)
			(xy 100.779516 -246.71713) (xy 100.727554 -246.70527) (xy 100.67794 -246.685798) (xy 100.631782 -246.659149)
			(xy 100.590111 -246.625918) (xy 100.553859 -246.586847) (xy 100.523835 -246.54281) (xy 100.500709 -246.494789)
			(xy 100.484999 -246.443859) (xy 100.477056 -246.391155) (xy 100.247211 -246.391155) (xy 100.245408 -246.415998)
			(xy 100.234271 -246.466414) (xy 100.215969 -246.514693) (xy 100.190886 -246.559822) (xy 100.159549 -246.600855)
			(xy 100.122613 -246.636932) (xy 100.080854 -246.667296) (xy 100.05822 -246.67972) (xy 100.05822 -246.768112)
			(xy 100.058708 -246.782867) (xy 100.067134 -246.811146) (xy 100.083306 -246.835828) (xy 100.10587 -246.854845)
			(xy 100.132934 -246.866603) (xy 100.162232 -246.870119) (xy 100.19131 -246.865096) (xy 100.204778 -246.859044)
			(xy 100.229476 -246.847421) (xy 100.281526 -246.830992) (xy 100.335475 -246.822701) (xy 100.362766 -246.822214)
			(xy 100.389417 -246.822685) (xy 100.442125 -246.830624) (xy 100.49306 -246.846332) (xy 100.541085 -246.869455)
			(xy 100.585127 -246.899479) (xy 100.624203 -246.935732) (xy 100.657438 -246.977404) (xy 100.68409 -247.023564)
			(xy 100.703565 -247.073181) (xy 100.715426 -247.125147) (xy 100.71941 -247.1783) (xy 100.717411 -247.204971)
			(xy 100.946956 -247.204971) (xy 100.946956 -247.151673) (xy 100.954899 -247.098969) (xy 100.970609 -247.048039)
			(xy 100.993735 -247.000018) (xy 101.023759 -246.955981) (xy 101.060011 -246.91691) (xy 101.101682 -246.883679)
			(xy 101.14784 -246.85703) (xy 101.197454 -246.837558) (xy 101.249416 -246.825698) (xy 101.302566 -246.821715)
			(xy 101.355716 -246.825698) (xy 101.407678 -246.837558) (xy 101.457292 -246.85703) (xy 101.50345 -246.883679)
			(xy 101.545121 -246.91691) (xy 101.581373 -246.955981) (xy 101.611397 -247.000018) (xy 101.634523 -247.048039)
			(xy 101.650233 -247.098969) (xy 101.658176 -247.151673) (xy 101.658674 -247.178322) (xy 101.658176 -247.204971)
			(xy 101.886756 -247.204971) (xy 101.886756 -247.151673) (xy 101.894699 -247.098969) (xy 101.910409 -247.048039)
			(xy 101.933535 -247.000018) (xy 101.963559 -246.955981) (xy 101.999811 -246.91691) (xy 102.041482 -246.883679)
			(xy 102.08764 -246.85703) (xy 102.137254 -246.837558) (xy 102.189216 -246.825698) (xy 102.242366 -246.821715)
			(xy 102.295516 -246.825698) (xy 102.347478 -246.837558) (xy 102.397092 -246.85703) (xy 102.44325 -246.883679)
			(xy 102.484921 -246.91691) (xy 102.521173 -246.955981) (xy 102.551197 -247.000018) (xy 102.574323 -247.048039)
			(xy 102.590033 -247.098969) (xy 102.597976 -247.151673) (xy 102.598474 -247.178322) (xy 102.597976 -247.204971)
			(xy 102.590033 -247.257675) (xy 102.574323 -247.308605) (xy 102.551197 -247.356626) (xy 102.521173 -247.400663)
			(xy 102.484921 -247.439734) (xy 102.44325 -247.472965) (xy 102.397092 -247.499614) (xy 102.347478 -247.519086)
			(xy 102.295516 -247.530946) (xy 102.242366 -247.53493) (xy 102.189216 -247.530946) (xy 102.137254 -247.519086)
			(xy 102.08764 -247.499614) (xy 102.041482 -247.472965) (xy 101.999811 -247.439734) (xy 101.963559 -247.400663)
			(xy 101.933535 -247.356626) (xy 101.910409 -247.308605) (xy 101.894699 -247.257675) (xy 101.886756 -247.204971)
			(xy 101.658176 -247.204971) (xy 101.650233 -247.257675) (xy 101.634523 -247.308605) (xy 101.611397 -247.356626)
			(xy 101.581373 -247.400663) (xy 101.545121 -247.439734) (xy 101.50345 -247.472965) (xy 101.457292 -247.499614)
			(xy 101.407678 -247.519086) (xy 101.355716 -247.530946) (xy 101.302566 -247.53493) (xy 101.249416 -247.530946)
			(xy 101.197454 -247.519086) (xy 101.14784 -247.499614) (xy 101.101682 -247.472965) (xy 101.060011 -247.439734)
			(xy 101.023759 -247.400663) (xy 100.993735 -247.356626) (xy 100.970609 -247.308605) (xy 100.954899 -247.257675)
			(xy 100.946956 -247.204971) (xy 100.717411 -247.204971) (xy 100.715426 -247.231453) (xy 100.703565 -247.283419)
			(xy 100.68409 -247.333036) (xy 100.657438 -247.379196) (xy 100.624203 -247.420868) (xy 100.585127 -247.457121)
			(xy 100.541085 -247.487145) (xy 100.49306 -247.510268) (xy 100.442125 -247.525976) (xy 100.389417 -247.533915)
			(xy 100.362766 -247.53443) (xy 100.335475 -247.533929) (xy 100.281527 -247.525643) (xy 100.229474 -247.509225)
			(xy 100.204778 -247.4976) (xy 100.191335 -247.491516) (xy 100.162261 -247.486557) (xy 100.132982 -247.49011)
			(xy 100.105938 -247.501878) (xy 100.083382 -247.520881) (xy 100.067193 -247.545535) (xy 100.058722 -247.573786)
			(xy 100.05822 -247.588532) (xy 100.05822 -247.676924) (xy 100.080857 -247.689339) (xy 100.122611 -247.719703)
			(xy 100.159541 -247.755779) (xy 100.190874 -247.796811) (xy 100.215952 -247.841938) (xy 100.234249 -247.890214)
			(xy 100.245383 -247.940626) (xy 100.249118 -247.992118) (xy 100.24718 -248.018787) (xy 100.476802 -248.018787)
			(xy 100.476802 -247.965489) (xy 100.484745 -247.912785) (xy 100.500455 -247.861855) (xy 100.523581 -247.813834)
			(xy 100.553605 -247.769797) (xy 100.589857 -247.730726) (xy 100.631528 -247.697495) (xy 100.677686 -247.670846)
			(xy 100.7273 -247.651374) (xy 100.779262 -247.639514) (xy 100.832412 -247.635531) (xy 100.885562 -247.639514)
			(xy 100.937524 -247.651374) (xy 100.987138 -247.670846) (xy 101.033296 -247.697495) (xy 101.074967 -247.730726)
			(xy 101.111219 -247.769797) (xy 101.141243 -247.813834) (xy 101.164369 -247.861855) (xy 101.180079 -247.912785)
			(xy 101.188022 -247.965489) (xy 101.18852 -247.992138) (xy 101.188022 -248.018787) (xy 101.416602 -248.018787)
			(xy 101.416602 -247.965489) (xy 101.424545 -247.912785) (xy 101.440255 -247.861855) (xy 101.463381 -247.813834)
			(xy 101.493405 -247.769797) (xy 101.529657 -247.730726) (xy 101.571328 -247.697495) (xy 101.617486 -247.670846)
			(xy 101.6671 -247.651374) (xy 101.719062 -247.639514) (xy 101.772212 -247.635531) (xy 101.825362 -247.639514)
			(xy 101.877324 -247.651374) (xy 101.926938 -247.670846) (xy 101.973096 -247.697495) (xy 102.014767 -247.730726)
			(xy 102.051019 -247.769797) (xy 102.081043 -247.813834) (xy 102.104169 -247.861855) (xy 102.119879 -247.912785)
			(xy 102.127822 -247.965489) (xy 102.12832 -247.992138) (xy 102.127822 -248.018787) (xy 102.119879 -248.071491)
			(xy 102.104169 -248.122421) (xy 102.081043 -248.170442) (xy 102.051019 -248.214479) (xy 102.014767 -248.25355)
			(xy 101.973096 -248.286781) (xy 101.926938 -248.31343) (xy 101.877324 -248.332902) (xy 101.825362 -248.344762)
			(xy 101.772212 -248.348746) (xy 101.719062 -248.344762) (xy 101.6671 -248.332902) (xy 101.617486 -248.31343)
			(xy 101.571328 -248.286781) (xy 101.529657 -248.25355) (xy 101.493405 -248.214479) (xy 101.463381 -248.170442)
			(xy 101.440255 -248.122421) (xy 101.424545 -248.071491) (xy 101.416602 -248.018787) (xy 101.188022 -248.018787)
			(xy 101.180079 -248.071491) (xy 101.164369 -248.122421) (xy 101.141243 -248.170442) (xy 101.111219 -248.214479)
			(xy 101.074967 -248.25355) (xy 101.033296 -248.286781) (xy 100.987138 -248.31343) (xy 100.937524 -248.332902)
			(xy 100.885562 -248.344762) (xy 100.832412 -248.348746) (xy 100.779262 -248.344762) (xy 100.7273 -248.332902)
			(xy 100.677686 -248.31343) (xy 100.631528 -248.286781) (xy 100.589857 -248.25355) (xy 100.553605 -248.214479)
			(xy 100.523581 -248.170442) (xy 100.500455 -248.122421) (xy 100.484745 -248.071491) (xy 100.476802 -248.018787)
			(xy 100.24718 -248.018787) (xy 100.245377 -248.043609) (xy 100.234239 -248.09402) (xy 100.215937 -248.142294)
			(xy 100.190854 -248.187419) (xy 100.159517 -248.228447) (xy 100.122583 -248.26452) (xy 100.080827 -248.29488)
			(xy 100.05822 -248.307352) (xy 100.05822 -248.395998) (xy 100.058706 -248.410754) (xy 100.06713 -248.439037)
			(xy 100.083302 -248.463723) (xy 100.105866 -248.482743) (xy 100.132933 -248.494503) (xy 100.162234 -248.498019)
			(xy 100.191314 -248.492994) (xy 100.204778 -248.48693) (xy 100.229476 -248.475308) (xy 100.281526 -248.458879)
			(xy 100.335475 -248.450588) (xy 100.362766 -248.4501) (xy 100.389418 -248.450571) (xy 100.442128 -248.458511)
			(xy 100.493065 -248.474219) (xy 100.541092 -248.497343) (xy 100.585136 -248.527368) (xy 100.624213 -248.563622)
			(xy 100.657449 -248.605296) (xy 100.684103 -248.651458) (xy 100.703578 -248.701077) (xy 100.71544 -248.753045)
			(xy 100.719424 -248.8062) (xy 100.717426 -248.832857) (xy 100.946702 -248.832857) (xy 100.946702 -248.779559)
			(xy 100.954645 -248.726855) (xy 100.970355 -248.675925) (xy 100.993481 -248.627904) (xy 101.023505 -248.583867)
			(xy 101.059757 -248.544796) (xy 101.101428 -248.511565) (xy 101.147586 -248.484916) (xy 101.1972 -248.465444)
			(xy 101.249162 -248.453584) (xy 101.302312 -248.449601) (xy 101.355462 -248.453584) (xy 101.407424 -248.465444)
			(xy 101.457038 -248.484916) (xy 101.503196 -248.511565) (xy 101.544867 -248.544796) (xy 101.581119 -248.583867)
			(xy 101.611143 -248.627904) (xy 101.634269 -248.675925) (xy 101.649979 -248.726855) (xy 101.657922 -248.779559)
			(xy 101.65842 -248.8062) (xy 101.8858 -248.8062) (xy 101.889783 -248.753055) (xy 101.901641 -248.701097)
			(xy 101.921111 -248.651486) (xy 101.947756 -248.605331) (xy 101.980983 -248.563663) (xy 102.020049 -248.527411)
			(xy 102.064081 -248.497387) (xy 102.112095 -248.47426) (xy 102.163021 -248.458548) (xy 102.215719 -248.4506)
			(xy 102.242366 -248.4501) (xy 102.271189 -248.450661) (xy 102.328081 -248.459949) (xy 102.382732 -248.478287)
			(xy 102.408482 -248.491248) (xy 102.421896 -248.497633) (xy 102.451043 -248.50328) (xy 102.480584 -248.50031)
			(xy 102.508024 -248.488974) (xy 102.531047 -248.470228) (xy 102.5398 -248.458228) (xy 102.55406 -248.437913)
			(xy 102.58738 -248.401124) (xy 102.625479 -248.369311) (xy 102.667623 -248.34309) (xy 102.712996 -248.322967)
			(xy 102.760721 -248.309331) (xy 102.809876 -248.302447) (xy 102.834694 -248.302018) (xy 102.86268 -248.302518)
			(xy 102.917964 -248.311274) (xy 102.971198 -248.32857) (xy 103.02107 -248.353982) (xy 103.066352 -248.386883)
			(xy 103.10593 -248.426463) (xy 103.138828 -248.471747) (xy 103.164237 -248.521621) (xy 103.181531 -248.574855)
			(xy 103.190283 -248.630139) (xy 103.190802 -248.658126) (xy 103.190402 -248.682796) (xy 103.183593 -248.731664)
			(xy 103.170096 -248.779121) (xy 103.15017 -248.824258) (xy 103.124197 -248.866208) (xy 103.10876 -248.885456)
			(xy 103.100109 -248.896568) (xy 103.088766 -248.922335) (xy 103.08489 -248.95022) (xy 103.088777 -248.978104)
			(xy 103.10013 -249.003866) (xy 103.10876 -249.014996) (xy 103.124175 -249.034259) (xy 103.150136 -249.076211)
			(xy 103.170057 -249.121345) (xy 103.183557 -249.168797) (xy 103.190378 -249.217659) (xy 103.190802 -249.242326)
			(xy 103.190283 -249.27031) (xy 103.181524 -249.325589) (xy 103.164225 -249.378817) (xy 103.138814 -249.428683)
			(xy 103.105914 -249.473961) (xy 103.066337 -249.513535) (xy 103.021056 -249.54643) (xy 102.971187 -249.571838)
			(xy 102.917958 -249.589131) (xy 102.862678 -249.597886) (xy 102.834694 -249.598434) (xy 102.806763 -249.59787)
			(xy 102.751585 -249.589147) (xy 102.698447 -249.571914) (xy 102.648651 -249.546596) (xy 102.603419 -249.513814)
			(xy 102.56386 -249.47437) (xy 102.530946 -249.429234) (xy 102.505483 -249.379512) (xy 102.488097 -249.326423)
			(xy 102.479213 -249.271272) (xy 102.478586 -249.243342) (xy 102.478178 -249.229766) (xy 102.47093 -249.203595)
			(xy 102.457041 -249.18026) (xy 102.437494 -249.16141) (xy 102.413671 -249.148377) (xy 102.387255 -249.142083)
			(xy 102.360114 -249.142972) (xy 102.347014 -249.146568) (xy 102.321475 -249.153908) (xy 102.268933 -249.161822)
			(xy 102.242366 -249.162316) (xy 102.215719 -249.1618) (xy 102.163021 -249.153852) (xy 102.112095 -249.13814)
			(xy 102.064081 -249.115013) (xy 102.020049 -249.084989) (xy 101.980983 -249.048737) (xy 101.947756 -249.007069)
			(xy 101.921111 -248.960914) (xy 101.901641 -248.911303) (xy 101.889783 -248.859345) (xy 101.8858 -248.8062)
			(xy 101.65842 -248.8062) (xy 101.65842 -248.806208) (xy 101.657922 -248.832857) (xy 101.649979 -248.885561)
			(xy 101.634269 -248.936491) (xy 101.611143 -248.984512) (xy 101.581119 -249.028549) (xy 101.544867 -249.06762)
			(xy 101.503196 -249.100851) (xy 101.457038 -249.1275) (xy 101.407424 -249.146972) (xy 101.355462 -249.158832)
			(xy 101.302312 -249.162816) (xy 101.249162 -249.158832) (xy 101.1972 -249.146972) (xy 101.147586 -249.1275)
			(xy 101.101428 -249.100851) (xy 101.059757 -249.06762) (xy 101.023505 -249.028549) (xy 100.993481 -248.984512)
			(xy 100.970355 -248.936491) (xy 100.954645 -248.885561) (xy 100.946702 -248.832857) (xy 100.717426 -248.832857)
			(xy 100.71544 -248.859355) (xy 100.703578 -248.911323) (xy 100.684103 -248.960942) (xy 100.657449 -249.007104)
			(xy 100.624213 -249.048778) (xy 100.585136 -249.085032) (xy 100.541092 -249.115057) (xy 100.493065 -249.138181)
			(xy 100.442128 -249.153889) (xy 100.389418 -249.161829) (xy 100.362766 -249.162316) (xy 100.335475 -249.161816)
			(xy 100.281526 -249.153532) (xy 100.229471 -249.137117) (xy 100.204778 -249.125486) (xy 100.191335 -249.119403)
			(xy 100.16226 -249.114445) (xy 100.13298 -249.117998) (xy 100.105935 -249.129765) (xy 100.083377 -249.148767)
			(xy 100.067186 -249.173421) (xy 100.058711 -249.201672) (xy 100.05822 -249.216418) (xy 100.05822 -249.30481)
			(xy 100.080858 -249.317225) (xy 100.122614 -249.347589) (xy 100.159546 -249.383666) (xy 100.190881 -249.424699)
			(xy 100.21596 -249.469827) (xy 100.234259 -249.518104) (xy 100.245394 -249.568518) (xy 100.24913 -249.620011)
			(xy 100.247194 -249.646673) (xy 100.476802 -249.646673) (xy 100.476802 -249.593375) (xy 100.484745 -249.540671)
			(xy 100.500455 -249.489741) (xy 100.523581 -249.44172) (xy 100.553605 -249.397683) (xy 100.589857 -249.358612)
			(xy 100.631528 -249.325381) (xy 100.677686 -249.298732) (xy 100.7273 -249.27926) (xy 100.779262 -249.2674)
			(xy 100.832412 -249.263417) (xy 100.885562 -249.2674) (xy 100.937524 -249.27926) (xy 100.987138 -249.298732)
			(xy 101.033296 -249.325381) (xy 101.074967 -249.358612) (xy 101.111219 -249.397683) (xy 101.141243 -249.44172)
			(xy 101.164369 -249.489741) (xy 101.180079 -249.540671) (xy 101.188022 -249.593375) (xy 101.18852 -249.620024)
			(xy 101.188022 -249.646673) (xy 101.416602 -249.646673) (xy 101.416602 -249.593375) (xy 101.424545 -249.540671)
			(xy 101.440255 -249.489741) (xy 101.463381 -249.44172) (xy 101.493405 -249.397683) (xy 101.529657 -249.358612)
			(xy 101.571328 -249.325381) (xy 101.617486 -249.298732) (xy 101.6671 -249.27926) (xy 101.719062 -249.2674)
			(xy 101.772212 -249.263417) (xy 101.825362 -249.2674) (xy 101.877324 -249.27926) (xy 101.926938 -249.298732)
			(xy 101.973096 -249.325381) (xy 102.014767 -249.358612) (xy 102.051019 -249.397683) (xy 102.081043 -249.44172)
			(xy 102.104169 -249.489741) (xy 102.119879 -249.540671) (xy 102.127822 -249.593375) (xy 102.12832 -249.620024)
			(xy 102.127822 -249.646673) (xy 102.119879 -249.699377) (xy 102.104169 -249.750307) (xy 102.081043 -249.798328)
			(xy 102.051019 -249.842365) (xy 102.014767 -249.881436) (xy 101.973096 -249.914667) (xy 101.926938 -249.941316)
			(xy 101.877324 -249.960788) (xy 101.825362 -249.972648) (xy 101.772212 -249.976632) (xy 101.719062 -249.972648)
			(xy 101.6671 -249.960788) (xy 101.617486 -249.941316) (xy 101.571328 -249.914667) (xy 101.529657 -249.881436)
			(xy 101.493405 -249.842365) (xy 101.463381 -249.798328) (xy 101.440255 -249.750307) (xy 101.424545 -249.699377)
			(xy 101.416602 -249.646673) (xy 101.188022 -249.646673) (xy 101.180079 -249.699377) (xy 101.164369 -249.750307)
			(xy 101.141243 -249.798328) (xy 101.111219 -249.842365) (xy 101.074967 -249.881436) (xy 101.033296 -249.914667)
			(xy 100.987138 -249.941316) (xy 100.937524 -249.960788) (xy 100.885562 -249.972648) (xy 100.832412 -249.976632)
			(xy 100.779262 -249.972648) (xy 100.7273 -249.960788) (xy 100.677686 -249.941316) (xy 100.631528 -249.914667)
			(xy 100.589857 -249.881436) (xy 100.553605 -249.842365) (xy 100.523581 -249.798328) (xy 100.500455 -249.750307)
			(xy 100.484745 -249.699377) (xy 100.476802 -249.646673) (xy 100.247194 -249.646673) (xy 100.245391 -249.671504)
			(xy 100.234253 -249.721918) (xy 100.215951 -249.770194) (xy 100.190868 -249.81532) (xy 100.159531 -249.856351)
			(xy 100.122596 -249.892425) (xy 100.080839 -249.922787) (xy 100.05822 -249.935238) (xy 100.05822 -251.135134)
			(xy 102.478586 -251.135134) (xy 102.479001 -251.110464) (xy 102.485803 -251.061597) (xy 102.499296 -251.014138)
			(xy 102.519219 -250.969001) (xy 102.545191 -250.927052) (xy 102.560628 -250.907804) (xy 102.569223 -250.896651)
			(xy 102.580575 -250.870899) (xy 102.584462 -250.843026) (xy 102.580589 -250.815151) (xy 102.56925 -250.789393)
			(xy 102.560628 -250.778264) (xy 102.545193 -250.759017) (xy 102.519235 -250.71706) (xy 102.499318 -250.671922)
			(xy 102.485823 -250.624467) (xy 102.479008 -250.575602) (xy 102.478586 -250.550934) (xy 102.479084 -250.524285)
			(xy 102.487027 -250.471581) (xy 102.502737 -250.420651) (xy 102.525863 -250.37263) (xy 102.555887 -250.328593)
			(xy 102.592139 -250.289522) (xy 102.63381 -250.256291) (xy 102.679968 -250.229642) (xy 102.729582 -250.21017)
			(xy 102.781544 -250.19831) (xy 102.834694 -250.194327) (xy 102.887844 -250.19831) (xy 102.939806 -250.21017)
			(xy 102.98942 -250.229642) (xy 103.035578 -250.256291) (xy 103.077249 -250.289522) (xy 103.113501 -250.328593)
			(xy 103.143525 -250.37263) (xy 103.166651 -250.420651) (xy 103.182361 -250.471581) (xy 103.190304 -250.524285)
			(xy 103.190802 -250.550934) (xy 103.190349 -250.575602) (xy 103.183553 -250.624467) (xy 103.170068 -250.671924)
			(xy 103.150154 -250.717062) (xy 103.124191 -250.759014) (xy 103.10876 -250.778264) (xy 103.100101 -250.789371)
			(xy 103.088759 -250.81514) (xy 103.084885 -250.843026) (xy 103.088773 -250.870911) (xy 103.100129 -250.896674)
			(xy 103.10876 -250.907804) (xy 103.124179 -250.927064) (xy 103.150139 -250.969017) (xy 103.170059 -251.014152)
			(xy 103.183559 -251.061605) (xy 103.190378 -251.110466) (xy 103.190802 -251.135134) (xy 103.190304 -251.161783)
			(xy 103.182361 -251.214487) (xy 103.166651 -251.265417) (xy 103.143525 -251.313438) (xy 103.113501 -251.357475)
			(xy 103.077249 -251.396546) (xy 103.035578 -251.429777) (xy 102.98942 -251.456426) (xy 102.939806 -251.475898)
			(xy 102.887844 -251.487758) (xy 102.834694 -251.491742) (xy 102.781544 -251.487758) (xy 102.729582 -251.475898)
			(xy 102.679968 -251.456426) (xy 102.63381 -251.429777) (xy 102.592139 -251.396546) (xy 102.555887 -251.357475)
			(xy 102.525863 -251.313438) (xy 102.502737 -251.265417) (xy 102.487027 -251.214487) (xy 102.479084 -251.161783)
			(xy 102.478586 -251.135134) (xy 100.05822 -251.135134) (xy 100.05822 -252.798834) (xy 102.539546 -252.798834)
			(xy 102.53997 -252.774165) (xy 102.546771 -252.725298) (xy 102.560262 -252.67784) (xy 102.580184 -252.632703)
			(xy 102.606153 -252.590752) (xy 102.621588 -252.571504) (xy 102.630186 -252.560353) (xy 102.641542 -252.534601)
			(xy 102.645431 -252.506726) (xy 102.641557 -252.47885) (xy 102.630213 -252.453092) (xy 102.621588 -252.441964)
			(xy 102.606162 -252.42271) (xy 102.580201 -252.380756) (xy 102.560282 -252.33562) (xy 102.546785 -252.288165)
			(xy 102.539968 -252.239302) (xy 102.539546 -252.214634) (xy 102.540044 -252.187985) (xy 102.547987 -252.135281)
			(xy 102.563697 -252.084351) (xy 102.586823 -252.03633) (xy 102.616847 -251.992293) (xy 102.653099 -251.953222)
			(xy 102.69477 -251.919991) (xy 102.740928 -251.893342) (xy 102.790542 -251.87387) (xy 102.842504 -251.86201)
			(xy 102.895654 -251.858027) (xy 102.948804 -251.86201) (xy 103.000766 -251.87387) (xy 103.05038 -251.893342)
			(xy 103.096538 -251.919991) (xy 103.138209 -251.953222) (xy 103.174461 -251.992293) (xy 103.204485 -252.03633)
			(xy 103.227611 -252.084351) (xy 103.243321 -252.135281) (xy 103.251264 -252.187985) (xy 103.251762 -252.214634)
			(xy 103.251318 -252.239302) (xy 103.244521 -252.288169) (xy 103.231035 -252.335626) (xy 103.211118 -252.380764)
			(xy 103.185153 -252.422715) (xy 103.16972 -252.441964) (xy 103.161064 -252.453072) (xy 103.149727 -252.478841)
			(xy 103.145854 -252.506726) (xy 103.149741 -252.53461) (xy 103.161092 -252.560373) (xy 103.16972 -252.571504)
			(xy 103.185133 -252.590769) (xy 103.211095 -252.63272) (xy 103.231017 -252.677854) (xy 103.244517 -252.725305)
			(xy 103.251337 -252.774167) (xy 103.251762 -252.798834) (xy 103.251264 -252.825483) (xy 103.243321 -252.878187)
			(xy 103.227611 -252.929117) (xy 103.204485 -252.977138) (xy 103.174461 -253.021175) (xy 103.138209 -253.060246)
			(xy 103.096538 -253.093477) (xy 103.05038 -253.120126) (xy 103.000766 -253.139598) (xy 102.948804 -253.151458)
			(xy 102.895654 -253.155442) (xy 102.842504 -253.151458) (xy 102.790542 -253.139598) (xy 102.740928 -253.120126)
			(xy 102.69477 -253.093477) (xy 102.653099 -253.060246) (xy 102.616847 -253.021175) (xy 102.586823 -252.977138)
			(xy 102.563697 -252.929117) (xy 102.547987 -252.878187) (xy 102.540044 -252.825483) (xy 102.539546 -252.798834)
			(xy 100.05822 -252.798834) (xy 100.05822 -253.585726) (xy 100.058711 -253.600512) (xy 100.067161 -253.62885)
			(xy 100.083372 -253.65358) (xy 100.105989 -253.672631) (xy 100.133114 -253.684406) (xy 100.162475 -253.687918)
			(xy 100.191612 -253.682874) (xy 100.218084 -253.669695) (xy 100.229162 -253.659894) (xy 100.249082 -253.641908)
			(xy 100.293313 -253.611514) (xy 100.341601 -253.588094) (xy 100.392854 -253.572178) (xy 100.445914 -253.564125)
			(xy 100.472748 -253.563628) (xy 100.499392 -253.564129) (xy 100.552085 -253.572078) (xy 100.603004 -253.587791)
			(xy 100.651013 -253.610916) (xy 100.69504 -253.640939) (xy 100.734101 -253.677187) (xy 100.767323 -253.718852)
			(xy 100.793965 -253.765002) (xy 100.813432 -253.814608) (xy 100.825289 -253.86656) (xy 100.829271 -253.9197)
			(xy 100.827271 -253.946385) (xy 101.056938 -253.946385) (xy 101.056938 -253.893087) (xy 101.064881 -253.840383)
			(xy 101.080591 -253.789453) (xy 101.103717 -253.741432) (xy 101.133741 -253.697395) (xy 101.169993 -253.658324)
			(xy 101.211664 -253.625093) (xy 101.257822 -253.598444) (xy 101.307436 -253.578972) (xy 101.359398 -253.567112)
			(xy 101.412548 -253.563129) (xy 101.465698 -253.567112) (xy 101.51766 -253.578972) (xy 101.567274 -253.598444)
			(xy 101.613432 -253.625093) (xy 101.655103 -253.658324) (xy 101.691355 -253.697395) (xy 101.721379 -253.741432)
			(xy 101.744505 -253.789453) (xy 101.760215 -253.840383) (xy 101.768158 -253.893087) (xy 101.768656 -253.919736)
			(xy 101.768158 -253.946385) (xy 101.996738 -253.946385) (xy 101.996738 -253.893087) (xy 102.004681 -253.840383)
			(xy 102.020391 -253.789453) (xy 102.043517 -253.741432) (xy 102.073541 -253.697395) (xy 102.109793 -253.658324)
			(xy 102.151464 -253.625093) (xy 102.197622 -253.598444) (xy 102.247236 -253.578972) (xy 102.299198 -253.567112)
			(xy 102.352348 -253.563129) (xy 102.405498 -253.567112) (xy 102.45746 -253.578972) (xy 102.507074 -253.598444)
			(xy 102.553232 -253.625093) (xy 102.594903 -253.658324) (xy 102.631155 -253.697395) (xy 102.661179 -253.741432)
			(xy 102.684305 -253.789453) (xy 102.700015 -253.840383) (xy 102.707958 -253.893087) (xy 102.708456 -253.919736)
			(xy 102.707958 -253.946385) (xy 102.700015 -253.999089) (xy 102.684305 -254.050019) (xy 102.661179 -254.09804)
			(xy 102.631155 -254.142077) (xy 102.594903 -254.181148) (xy 102.553232 -254.214379) (xy 102.507074 -254.241028)
			(xy 102.45746 -254.2605) (xy 102.405498 -254.27236) (xy 102.352348 -254.276344) (xy 102.299198 -254.27236)
			(xy 102.247236 -254.2605) (xy 102.197622 -254.241028) (xy 102.151464 -254.214379) (xy 102.109793 -254.181148)
			(xy 102.073541 -254.142077) (xy 102.043517 -254.09804) (xy 102.020391 -254.050019) (xy 102.004681 -253.999089)
			(xy 101.996738 -253.946385) (xy 101.768158 -253.946385) (xy 101.760215 -253.999089) (xy 101.744505 -254.050019)
			(xy 101.721379 -254.09804) (xy 101.691355 -254.142077) (xy 101.655103 -254.181148) (xy 101.613432 -254.214379)
			(xy 101.567274 -254.241028) (xy 101.51766 -254.2605) (xy 101.465698 -254.27236) (xy 101.412548 -254.276344)
			(xy 101.359398 -254.27236) (xy 101.307436 -254.2605) (xy 101.257822 -254.241028) (xy 101.211664 -254.214379)
			(xy 101.169993 -254.181148) (xy 101.133741 -254.142077) (xy 101.103717 -254.09804) (xy 101.080591 -254.050019)
			(xy 101.064881 -253.999089) (xy 101.056938 -253.946385) (xy 100.827271 -253.946385) (xy 100.825289 -253.97284)
			(xy 100.813432 -254.024792) (xy 100.793965 -254.074398) (xy 100.767323 -254.120548) (xy 100.734101 -254.162213)
			(xy 100.69504 -254.198461) (xy 100.651013 -254.228484) (xy 100.603004 -254.251609) (xy 100.552085 -254.267322)
			(xy 100.499392 -254.275271) (xy 100.472748 -254.275844) (xy 100.445912 -254.275361) (xy 100.392848 -254.267317)
			(xy 100.34159 -254.251404) (xy 100.2933 -254.227981) (xy 100.249069 -254.19758) (xy 100.229162 -254.179578)
			(xy 100.218027 -254.169857) (xy 100.19157 -254.156705) (xy 100.162455 -254.151674) (xy 100.133118 -254.155185)
			(xy 100.106013 -254.166945) (xy 100.083407 -254.185969) (xy 100.067191 -254.210667) (xy 100.058721 -254.238973)
			(xy 100.05822 -254.253746) (xy 100.05822 -254.37973) (xy 100.095812 -254.38989) (xy 100.122099 -254.397538)
			(xy 100.172121 -254.419785) (xy 100.218149 -254.449424) (xy 100.259099 -254.485758) (xy 100.294007 -254.527931)
			(xy 100.322049 -254.57495) (xy 100.342565 -254.625706) (xy 100.355072 -254.679003) (xy 100.359276 -254.733587)
			(xy 100.357228 -254.760201) (xy 100.586784 -254.760201) (xy 100.586784 -254.706903) (xy 100.594727 -254.654199)
			(xy 100.610437 -254.603269) (xy 100.633563 -254.555248) (xy 100.663587 -254.511211) (xy 100.699839 -254.47214)
			(xy 100.74151 -254.438909) (xy 100.787668 -254.41226) (xy 100.837282 -254.392788) (xy 100.889244 -254.380928)
			(xy 100.942394 -254.376945) (xy 100.995544 -254.380928) (xy 101.047506 -254.392788) (xy 101.09712 -254.41226)
			(xy 101.143278 -254.438909) (xy 101.184949 -254.47214) (xy 101.221201 -254.511211) (xy 101.251225 -254.555248)
			(xy 101.274351 -254.603269) (xy 101.290061 -254.654199) (xy 101.298004 -254.706903) (xy 101.298502 -254.733552)
			(xy 101.298004 -254.760201) (xy 101.526584 -254.760201) (xy 101.526584 -254.706903) (xy 101.534527 -254.654199)
			(xy 101.550237 -254.603269) (xy 101.573363 -254.555248) (xy 101.603387 -254.511211) (xy 101.639639 -254.47214)
			(xy 101.68131 -254.438909) (xy 101.727468 -254.41226) (xy 101.777082 -254.392788) (xy 101.829044 -254.380928)
			(xy 101.882194 -254.376945) (xy 101.935344 -254.380928) (xy 101.987306 -254.392788) (xy 102.03692 -254.41226)
			(xy 102.083078 -254.438909) (xy 102.124749 -254.47214) (xy 102.161001 -254.511211) (xy 102.191025 -254.555248)
			(xy 102.214151 -254.603269) (xy 102.229861 -254.654199) (xy 102.237804 -254.706903) (xy 102.238302 -254.733552)
			(xy 102.237804 -254.760201) (xy 102.229861 -254.812905) (xy 102.214151 -254.863835) (xy 102.191025 -254.911856)
			(xy 102.161001 -254.955893) (xy 102.124749 -254.994964) (xy 102.083078 -255.028195) (xy 102.03692 -255.054844)
			(xy 101.987306 -255.074316) (xy 101.935344 -255.086176) (xy 101.882194 -255.09016) (xy 101.829044 -255.086176)
			(xy 101.777082 -255.074316) (xy 101.727468 -255.054844) (xy 101.68131 -255.028195) (xy 101.639639 -254.994964)
			(xy 101.603387 -254.955893) (xy 101.573363 -254.911856) (xy 101.550237 -254.863835) (xy 101.534527 -254.812905)
			(xy 101.526584 -254.760201) (xy 101.298004 -254.760201) (xy 101.290061 -254.812905) (xy 101.274351 -254.863835)
			(xy 101.251225 -254.911856) (xy 101.221201 -254.955893) (xy 101.184949 -254.994964) (xy 101.143278 -255.028195)
			(xy 101.09712 -255.054844) (xy 101.047506 -255.074316) (xy 100.995544 -255.086176) (xy 100.942394 -255.09016)
			(xy 100.889244 -255.086176) (xy 100.837282 -255.074316) (xy 100.787668 -255.054844) (xy 100.74151 -255.028195)
			(xy 100.699839 -254.994964) (xy 100.663587 -254.955893) (xy 100.633563 -254.911856) (xy 100.610437 -254.863835)
			(xy 100.594727 -254.812905) (xy 100.586784 -254.760201) (xy 100.357228 -254.760201) (xy 100.355076 -254.788172)
			(xy 100.342573 -254.84147) (xy 100.32206 -254.892228) (xy 100.294021 -254.939248) (xy 100.259117 -254.981424)
			(xy 100.218169 -255.017761) (xy 100.172143 -255.047403) (xy 100.122123 -255.069653) (xy 100.095812 -255.077214)
			(xy 100.05822 -255.087374) (xy 100.05822 -255.213612) (xy 100.058723 -255.228388) (xy 100.067186 -255.256703)
			(xy 100.0834 -255.281411) (xy 100.106008 -255.300443) (xy 100.133118 -255.312207) (xy 100.162462 -255.315719)
			(xy 100.191582 -255.310684) (xy 100.218043 -255.297523) (xy 100.229162 -255.28778) (xy 100.249082 -255.269794)
			(xy 100.293314 -255.239402) (xy 100.341602 -255.215983) (xy 100.392855 -255.200068) (xy 100.445914 -255.192015)
			(xy 100.472748 -255.191514) (xy 100.499393 -255.192016) (xy 100.552088 -255.199964) (xy 100.603009 -255.215678)
			(xy 100.65102 -255.238804) (xy 100.695049 -255.268828) (xy 100.734111 -255.305077) (xy 100.767335 -255.346744)
			(xy 100.793978 -255.392896) (xy 100.813446 -255.442503) (xy 100.825303 -255.494458) (xy 100.829285 -255.5476)
			(xy 100.827287 -255.574271) (xy 101.056938 -255.574271) (xy 101.056938 -255.520973) (xy 101.064881 -255.468269)
			(xy 101.080591 -255.417339) (xy 101.103717 -255.369318) (xy 101.133741 -255.325281) (xy 101.169993 -255.28621)
			(xy 101.211664 -255.252979) (xy 101.257822 -255.22633) (xy 101.307436 -255.206858) (xy 101.359398 -255.194998)
			(xy 101.412548 -255.191015) (xy 101.465698 -255.194998) (xy 101.51766 -255.206858) (xy 101.567274 -255.22633)
			(xy 101.613432 -255.252979) (xy 101.655103 -255.28621) (xy 101.691355 -255.325281) (xy 101.721379 -255.369318)
			(xy 101.744505 -255.417339) (xy 101.760215 -255.468269) (xy 101.768158 -255.520973) (xy 101.768656 -255.5476)
			(xy 101.99569 -255.5476) (xy 101.999674 -255.494446) (xy 102.011536 -255.442479) (xy 102.031011 -255.39286)
			(xy 102.057665 -255.346699) (xy 102.090902 -255.305027) (xy 102.129979 -255.268774) (xy 102.174023 -255.238751)
			(xy 102.22205 -255.215628) (xy 102.272987 -255.199922) (xy 102.325696 -255.191984) (xy 102.352348 -255.191514)
			(xy 102.378978 -255.192014) (xy 102.431649 -255.199915) (xy 102.45725 -255.207262) (xy 102.47036 -255.210901)
			(xy 102.497542 -255.211829) (xy 102.524001 -255.205537) (xy 102.547856 -255.192472) (xy 102.567406 -255.173565)
			(xy 102.581261 -255.150161) (xy 102.585266 -255.137158) (xy 102.592545 -255.112413) (xy 102.613226 -255.065163)
			(xy 102.640508 -255.021391) (xy 102.673819 -254.982013) (xy 102.712462 -254.947852) (xy 102.755629 -254.919623)
			(xy 102.802417 -254.897917) (xy 102.851847 -254.883188) (xy 102.902885 -254.875743) (xy 102.928674 -254.875284)
			(xy 102.956658 -254.875836) (xy 103.011938 -254.884588) (xy 103.065168 -254.90188) (xy 103.115038 -254.927286)
			(xy 103.160319 -254.960181) (xy 103.199897 -254.999755) (xy 103.232796 -255.045033) (xy 103.258207 -255.0949)
			(xy 103.275504 -255.148129) (xy 103.284261 -255.203408) (xy 103.284782 -255.231392) (xy 103.284355 -255.256224)
			(xy 103.277454 -255.305406) (xy 103.263786 -255.353152) (xy 103.243616 -255.398536) (xy 103.217335 -255.440676)
			(xy 103.201724 -255.459992) (xy 103.193061 -255.471166) (xy 103.1816 -255.496996) (xy 103.177638 -255.524976)
			(xy 103.181477 -255.552973) (xy 103.192826 -255.578854) (xy 103.20147 -255.59004) (xy 103.216946 -255.6093)
			(xy 103.24299 -255.651286) (xy 103.262973 -255.696472) (xy 103.276511 -255.743988) (xy 103.283344 -255.79292)
			(xy 103.283766 -255.817624) (xy 103.28331 -255.845612) (xy 103.274549 -255.900899) (xy 103.257248 -255.954134)
			(xy 103.231831 -256.004007) (xy 103.198925 -256.04929) (xy 103.15934 -256.088868) (xy 103.114051 -256.121765)
			(xy 103.064173 -256.147173) (xy 103.010934 -256.164465) (xy 102.955646 -256.173215) (xy 102.927658 -256.173732)
			(xy 102.900794 -256.173287) (xy 102.847675 -256.165223) (xy 102.79637 -256.149271) (xy 102.748045 -256.125792)
			(xy 102.703795 -256.095318) (xy 102.664626 -256.058543) (xy 102.631427 -256.0163) (xy 102.604951 -255.969549)
			(xy 102.594918 -255.944624) (xy 102.588792 -255.930233) (xy 102.569326 -255.905773) (xy 102.543386 -255.888328)
			(xy 102.51339 -255.879525) (xy 102.482137 -255.880185) (xy 102.467156 -255.88468) (xy 102.439286 -255.893555)
			(xy 102.381591 -255.903137) (xy 102.352348 -255.90373) (xy 102.325696 -255.903216) (xy 102.272987 -255.895278)
			(xy 102.22205 -255.879572) (xy 102.174023 -255.856449) (xy 102.129979 -255.826426) (xy 102.090902 -255.790173)
			(xy 102.057665 -255.748501) (xy 102.031011 -255.70234) (xy 102.011536 -255.652721) (xy 101.999674 -255.600754)
			(xy 101.99569 -255.5476) (xy 101.768656 -255.5476) (xy 101.768656 -255.547622) (xy 101.768158 -255.574271)
			(xy 101.760215 -255.626975) (xy 101.744505 -255.677905) (xy 101.721379 -255.725926) (xy 101.691355 -255.769963)
			(xy 101.655103 -255.809034) (xy 101.613432 -255.842265) (xy 101.567274 -255.868914) (xy 101.51766 -255.888386)
			(xy 101.465698 -255.900246) (xy 101.412548 -255.90423) (xy 101.359398 -255.900246) (xy 101.307436 -255.888386)
			(xy 101.257822 -255.868914) (xy 101.211664 -255.842265) (xy 101.169993 -255.809034) (xy 101.133741 -255.769963)
			(xy 101.103717 -255.725926) (xy 101.080591 -255.677905) (xy 101.064881 -255.626975) (xy 101.056938 -255.574271)
			(xy 100.827287 -255.574271) (xy 100.825303 -255.600742) (xy 100.813446 -255.652697) (xy 100.793978 -255.702304)
			(xy 100.767335 -255.748456) (xy 100.734111 -255.790123) (xy 100.695049 -255.826372) (xy 100.65102 -255.856396)
			(xy 100.603009 -255.879522) (xy 100.552088 -255.895236) (xy 100.499393 -255.903184) (xy 100.472748 -255.90373)
			(xy 100.445913 -255.903247) (xy 100.392848 -255.895203) (xy 100.341591 -255.879289) (xy 100.293301 -255.855866)
			(xy 100.249071 -255.825463) (xy 100.229162 -255.807464) (xy 100.218026 -255.797743) (xy 100.191568 -255.784593)
			(xy 100.162453 -255.779563) (xy 100.133116 -255.783074) (xy 100.106011 -255.794834) (xy 100.083404 -255.813857)
			(xy 100.067185 -255.838554) (xy 100.058712 -255.866859) (xy 100.05822 -255.881632) (xy 100.05822 -256.007616)
			(xy 100.095812 -256.017776) (xy 100.122093 -256.025424) (xy 100.172102 -256.047668) (xy 100.218117 -256.077304)
			(xy 100.259055 -256.113632) (xy 100.293952 -256.155798) (xy 100.321984 -256.202807) (xy 100.342493 -256.253552)
			(xy 100.354994 -256.306838) (xy 100.359193 -256.36141) (xy 100.357139 -256.388087) (xy 100.587038 -256.388087)
			(xy 100.587038 -256.334789) (xy 100.594981 -256.282085) (xy 100.610691 -256.231155) (xy 100.633817 -256.183134)
			(xy 100.663841 -256.139097) (xy 100.700093 -256.100026) (xy 100.741764 -256.066795) (xy 100.787922 -256.040146)
			(xy 100.837536 -256.020674) (xy 100.889498 -256.008814) (xy 100.942648 -256.004831) (xy 100.995798 -256.008814)
			(xy 101.04776 -256.020674) (xy 101.097374 -256.040146) (xy 101.143532 -256.066795) (xy 101.185203 -256.100026)
			(xy 101.221455 -256.139097) (xy 101.251479 -256.183134) (xy 101.274605 -256.231155) (xy 101.290315 -256.282085)
			(xy 101.298258 -256.334789) (xy 101.298756 -256.361438) (xy 101.298258 -256.388087) (xy 101.526584 -256.388087)
			(xy 101.526584 -256.334789) (xy 101.534527 -256.282085) (xy 101.550237 -256.231155) (xy 101.573363 -256.183134)
			(xy 101.603387 -256.139097) (xy 101.639639 -256.100026) (xy 101.68131 -256.066795) (xy 101.727468 -256.040146)
			(xy 101.777082 -256.020674) (xy 101.829044 -256.008814) (xy 101.882194 -256.004831) (xy 101.935344 -256.008814)
			(xy 101.987306 -256.020674) (xy 102.03692 -256.040146) (xy 102.083078 -256.066795) (xy 102.124749 -256.100026)
			(xy 102.161001 -256.139097) (xy 102.191025 -256.183134) (xy 102.214151 -256.231155) (xy 102.229861 -256.282085)
			(xy 102.237804 -256.334789) (xy 102.238302 -256.361438) (xy 102.237804 -256.388087) (xy 102.229861 -256.440791)
			(xy 102.214151 -256.491721) (xy 102.191025 -256.539742) (xy 102.161001 -256.583779) (xy 102.124749 -256.62285)
			(xy 102.083078 -256.656081) (xy 102.03692 -256.68273) (xy 101.987306 -256.702202) (xy 101.935344 -256.714062)
			(xy 101.882194 -256.718046) (xy 101.829044 -256.714062) (xy 101.777082 -256.702202) (xy 101.727468 -256.68273)
			(xy 101.68131 -256.656081) (xy 101.639639 -256.62285) (xy 101.603387 -256.583779) (xy 101.573363 -256.539742)
			(xy 101.550237 -256.491721) (xy 101.534527 -256.440791) (xy 101.526584 -256.388087) (xy 101.298258 -256.388087)
			(xy 101.290315 -256.440791) (xy 101.274605 -256.491721) (xy 101.251479 -256.539742) (xy 101.221455 -256.583779)
			(xy 101.185203 -256.62285) (xy 101.143532 -256.656081) (xy 101.097374 -256.68273) (xy 101.04776 -256.702202)
			(xy 100.995798 -256.714062) (xy 100.942648 -256.718046) (xy 100.889498 -256.714062) (xy 100.837536 -256.702202)
			(xy 100.787922 -256.68273) (xy 100.741764 -256.656081) (xy 100.700093 -256.62285) (xy 100.663841 -256.583779)
			(xy 100.633817 -256.539742) (xy 100.610691 -256.491721) (xy 100.594981 -256.440791) (xy 100.587038 -256.388087)
			(xy 100.357139 -256.388087) (xy 100.354991 -256.415981) (xy 100.342487 -256.469267) (xy 100.321976 -256.520011)
			(xy 100.29394 -256.567019) (xy 100.259042 -256.609182) (xy 100.218101 -256.645508) (xy 100.172084 -256.675141)
			(xy 100.122074 -256.697382) (xy 100.095812 -256.7051) (xy 100.05822 -256.71526) (xy 100.05822 -256.841244)
			(xy 100.058714 -256.856028) (xy 100.067166 -256.884361) (xy 100.083378 -256.909087) (xy 100.105993 -256.928134)
			(xy 100.133115 -256.939906) (xy 100.162472 -256.943419) (xy 100.191606 -256.938376) (xy 100.218075 -256.925201)
			(xy 100.229162 -256.915412) (xy 100.249081 -256.897425) (xy 100.293312 -256.86703) (xy 100.3416 -256.843609)
			(xy 100.392854 -256.827692) (xy 100.445914 -256.819638) (xy 100.472748 -256.819146) (xy 100.499398 -256.819647)
			(xy 100.552103 -256.827598) (xy 100.603034 -256.843314) (xy 100.651055 -256.866445) (xy 100.695091 -256.896474)
			(xy 100.734161 -256.932731) (xy 100.767391 -256.974405) (xy 100.79404 -257.020566) (xy 100.813511 -257.070183)
			(xy 100.825371 -257.122148) (xy 100.829354 -257.1753) (xy 100.82736 -257.201903) (xy 101.056938 -257.201903)
			(xy 101.056938 -257.148605) (xy 101.064881 -257.095901) (xy 101.080591 -257.044971) (xy 101.103717 -256.99695)
			(xy 101.133741 -256.952913) (xy 101.169993 -256.913842) (xy 101.211664 -256.880611) (xy 101.257822 -256.853962)
			(xy 101.307436 -256.83449) (xy 101.359398 -256.82263) (xy 101.412548 -256.818647) (xy 101.465698 -256.82263)
			(xy 101.51766 -256.83449) (xy 101.567274 -256.853962) (xy 101.613432 -256.880611) (xy 101.655103 -256.913842)
			(xy 101.691355 -256.952913) (xy 101.721379 -256.99695) (xy 101.744505 -257.044971) (xy 101.760215 -257.095901)
			(xy 101.768158 -257.148605) (xy 101.768656 -257.175254) (xy 101.768158 -257.201903) (xy 101.996738 -257.201903)
			(xy 101.996738 -257.148605) (xy 102.004681 -257.095901) (xy 102.020391 -257.044971) (xy 102.043517 -256.99695)
			(xy 102.073541 -256.952913) (xy 102.109793 -256.913842) (xy 102.151464 -256.880611) (xy 102.197622 -256.853962)
			(xy 102.247236 -256.83449) (xy 102.299198 -256.82263) (xy 102.352348 -256.818647) (xy 102.405498 -256.82263)
			(xy 102.45746 -256.83449) (xy 102.507074 -256.853962) (xy 102.553232 -256.880611) (xy 102.594903 -256.913842)
			(xy 102.631155 -256.952913) (xy 102.661179 -256.99695) (xy 102.684305 -257.044971) (xy 102.700015 -257.095901)
			(xy 102.707958 -257.148605) (xy 102.708456 -257.175254) (xy 102.707958 -257.201903) (xy 102.700015 -257.254607)
			(xy 102.684305 -257.305537) (xy 102.661179 -257.353558) (xy 102.631155 -257.397595) (xy 102.594903 -257.436666)
			(xy 102.553232 -257.469897) (xy 102.507074 -257.496546) (xy 102.45746 -257.516018) (xy 102.405498 -257.527878)
			(xy 102.352348 -257.531862) (xy 102.299198 -257.527878) (xy 102.247236 -257.516018) (xy 102.197622 -257.496546)
			(xy 102.151464 -257.469897) (xy 102.109793 -257.436666) (xy 102.073541 -257.397595) (xy 102.043517 -257.353558)
			(xy 102.020391 -257.305537) (xy 102.004681 -257.254607) (xy 101.996738 -257.201903) (xy 101.768158 -257.201903)
			(xy 101.760215 -257.254607) (xy 101.744505 -257.305537) (xy 101.721379 -257.353558) (xy 101.691355 -257.397595)
			(xy 101.655103 -257.436666) (xy 101.613432 -257.469897) (xy 101.567274 -257.496546) (xy 101.51766 -257.516018)
			(xy 101.465698 -257.527878) (xy 101.412548 -257.531862) (xy 101.359398 -257.527878) (xy 101.307436 -257.516018)
			(xy 101.257822 -257.496546) (xy 101.211664 -257.469897) (xy 101.169993 -257.436666) (xy 101.133741 -257.397595)
			(xy 101.103717 -257.353558) (xy 101.080591 -257.305537) (xy 101.064881 -257.254607) (xy 101.056938 -257.201903)
			(xy 100.82736 -257.201903) (xy 100.825371 -257.228452) (xy 100.813511 -257.280417) (xy 100.79404 -257.330034)
			(xy 100.767391 -257.376195) (xy 100.734161 -257.417869) (xy 100.695091 -257.454126) (xy 100.651055 -257.484155)
			(xy 100.603034 -257.507286) (xy 100.552103 -257.523002) (xy 100.499398 -257.530953) (xy 100.472748 -257.531362)
			(xy 100.445912 -257.530879) (xy 100.392847 -257.522835) (xy 100.341589 -257.506923) (xy 100.293298 -257.483501)
			(xy 100.249067 -257.453101) (xy 100.229162 -257.435096) (xy 100.218028 -257.425374) (xy 100.191572 -257.412219)
			(xy 100.162458 -257.407187) (xy 100.133121 -257.410698) (xy 100.106016 -257.422458) (xy 100.083412 -257.441484)
			(xy 100.067198 -257.466184) (xy 100.058731 -257.494491) (xy 100.05822 -257.509264) (xy 100.05822 -257.635248)
			(xy 100.095812 -257.645408) (xy 100.122098 -257.653056) (xy 100.172117 -257.675302) (xy 100.218143 -257.704941)
			(xy 100.25909 -257.741274) (xy 100.293995 -257.783445) (xy 100.322035 -257.830462) (xy 100.34255 -257.881215)
			(xy 100.355056 -257.934511) (xy 100.359258 -257.989092) (xy 100.357209 -258.015719) (xy 100.586784 -258.015719)
			(xy 100.586784 -257.962421) (xy 100.594727 -257.909717) (xy 100.610437 -257.858787) (xy 100.633563 -257.810766)
			(xy 100.663587 -257.766729) (xy 100.699839 -257.727658) (xy 100.74151 -257.694427) (xy 100.787668 -257.667778)
			(xy 100.837282 -257.648306) (xy 100.889244 -257.636446) (xy 100.942394 -257.632463) (xy 100.995544 -257.636446)
			(xy 101.047506 -257.648306) (xy 101.09712 -257.667778) (xy 101.143278 -257.694427) (xy 101.184949 -257.727658)
			(xy 101.221201 -257.766729) (xy 101.251225 -257.810766) (xy 101.274351 -257.858787) (xy 101.290061 -257.909717)
			(xy 101.298004 -257.962421) (xy 101.298502 -257.98907) (xy 101.298004 -258.015719) (xy 101.526584 -258.015719)
			(xy 101.526584 -257.962421) (xy 101.534527 -257.909717) (xy 101.550237 -257.858787) (xy 101.573363 -257.810766)
			(xy 101.603387 -257.766729) (xy 101.639639 -257.727658) (xy 101.68131 -257.694427) (xy 101.727468 -257.667778)
			(xy 101.777082 -257.648306) (xy 101.829044 -257.636446) (xy 101.882194 -257.632463) (xy 101.935344 -257.636446)
			(xy 101.987306 -257.648306) (xy 102.03692 -257.667778) (xy 102.083078 -257.694427) (xy 102.124749 -257.727658)
			(xy 102.161001 -257.766729) (xy 102.191025 -257.810766) (xy 102.214151 -257.858787) (xy 102.229861 -257.909717)
			(xy 102.237804 -257.962421) (xy 102.238302 -257.98907) (xy 102.237804 -258.015719) (xy 102.229861 -258.068423)
			(xy 102.214151 -258.119353) (xy 102.191025 -258.167374) (xy 102.161001 -258.211411) (xy 102.124749 -258.250482)
			(xy 102.083078 -258.283713) (xy 102.03692 -258.310362) (xy 101.987306 -258.329834) (xy 101.935344 -258.341694)
			(xy 101.882194 -258.345678) (xy 101.829044 -258.341694) (xy 101.777082 -258.329834) (xy 101.727468 -258.310362)
			(xy 101.68131 -258.283713) (xy 101.639639 -258.250482) (xy 101.603387 -258.211411) (xy 101.573363 -258.167374)
			(xy 101.550237 -258.119353) (xy 101.534527 -258.068423) (xy 101.526584 -258.015719) (xy 101.298004 -258.015719)
			(xy 101.290061 -258.068423) (xy 101.274351 -258.119353) (xy 101.251225 -258.167374) (xy 101.221201 -258.211411)
			(xy 101.184949 -258.250482) (xy 101.143278 -258.283713) (xy 101.09712 -258.310362) (xy 101.047506 -258.329834)
			(xy 100.995544 -258.341694) (xy 100.942394 -258.345678) (xy 100.889244 -258.341694) (xy 100.837282 -258.329834)
			(xy 100.787668 -258.310362) (xy 100.74151 -258.283713) (xy 100.699839 -258.250482) (xy 100.663587 -258.211411)
			(xy 100.633563 -258.167374) (xy 100.610437 -258.119353) (xy 100.594727 -258.068423) (xy 100.586784 -258.015719)
			(xy 100.357209 -258.015719) (xy 100.355058 -258.043674) (xy 100.342555 -258.09697) (xy 100.322042 -258.147724)
			(xy 100.294004 -258.194742) (xy 100.259101 -258.236915) (xy 100.218155 -258.27325) (xy 100.172131 -258.30289)
			(xy 100.122113 -258.325138) (xy 100.095812 -258.332732) (xy 100.05822 -258.342892) (xy 100.05822 -258.46913)
			(xy 100.058712 -258.483915) (xy 100.067162 -258.512252) (xy 100.083374 -258.536982) (xy 100.105989 -258.556032)
			(xy 100.133114 -258.567806) (xy 100.162474 -258.571319) (xy 100.191611 -258.566274) (xy 100.218082 -258.553096)
			(xy 100.229162 -258.543298) (xy 100.249081 -258.525312) (xy 100.293313 -258.494918) (xy 100.341601 -258.471498)
			(xy 100.392854 -258.455581) (xy 100.445914 -258.447528) (xy 100.472748 -258.447032) (xy 100.499392 -258.447533)
			(xy 100.552084 -258.455482) (xy 100.603003 -258.471195) (xy 100.651011 -258.49432) (xy 100.695037 -258.524342)
			(xy 100.734098 -258.56059) (xy 100.76732 -258.602254) (xy 100.793962 -258.648404) (xy 100.813428 -258.698009)
			(xy 100.825285 -258.749961) (xy 100.829267 -258.8031) (xy 100.827267 -258.829789) (xy 101.056684 -258.829789)
			(xy 101.056684 -258.776491) (xy 101.064627 -258.723787) (xy 101.080337 -258.672857) (xy 101.103463 -258.624836)
			(xy 101.133487 -258.580799) (xy 101.169739 -258.541728) (xy 101.21141 -258.508497) (xy 101.257568 -258.481848)
			(xy 101.307182 -258.462376) (xy 101.359144 -258.450516) (xy 101.412294 -258.446533) (xy 101.465444 -258.450516)
			(xy 101.517406 -258.462376) (xy 101.56702 -258.481848) (xy 101.613178 -258.508497) (xy 101.654849 -258.541728)
			(xy 101.691101 -258.580799) (xy 101.721125 -258.624836) (xy 101.744251 -258.672857) (xy 101.759961 -258.723787)
			(xy 101.767904 -258.776491) (xy 101.768402 -258.80314) (xy 101.767904 -258.829789) (xy 101.759961 -258.882493)
			(xy 101.744251 -258.933423) (xy 101.721125 -258.981444) (xy 101.691101 -259.025481) (xy 101.654849 -259.064552)
			(xy 101.613178 -259.097783) (xy 101.56702 -259.124432) (xy 101.517406 -259.143904) (xy 101.465444 -259.155764)
			(xy 101.412294 -259.159748) (xy 101.359144 -259.155764) (xy 101.307182 -259.143904) (xy 101.257568 -259.124432)
			(xy 101.21141 -259.097783) (xy 101.169739 -259.064552) (xy 101.133487 -259.025481) (xy 101.103463 -258.981444)
			(xy 101.080337 -258.933423) (xy 101.064627 -258.882493) (xy 101.056684 -258.829789) (xy 100.827267 -258.829789)
			(xy 100.825285 -258.856239) (xy 100.813428 -258.908191) (xy 100.793962 -258.957796) (xy 100.76732 -259.003946)
			(xy 100.734098 -259.04561) (xy 100.695037 -259.081858) (xy 100.651011 -259.11188) (xy 100.603003 -259.135005)
			(xy 100.552084 -259.150718) (xy 100.499392 -259.158667) (xy 100.472748 -259.159248) (xy 100.445912 -259.158765)
			(xy 100.392848 -259.150721) (xy 100.34159 -259.134808) (xy 100.293299 -259.111386) (xy 100.249069 -259.080984)
			(xy 100.229162 -259.062982) (xy 100.218027 -259.05326) (xy 100.19157 -259.040108) (xy 100.162456 -259.035077)
			(xy 100.133119 -259.038588) (xy 100.106014 -259.050348) (xy 100.083408 -259.069373) (xy 100.067193 -259.094071)
			(xy 100.058723 -259.122377) (xy 100.05822 -259.13715) (xy 100.05822 -259.263134) (xy 100.095812 -259.273294)
			(xy 100.122099 -259.280942) (xy 100.17212 -259.303189) (xy 100.218148 -259.332828) (xy 100.259097 -259.369162)
			(xy 100.294004 -259.411334) (xy 100.322046 -259.458352) (xy 100.342562 -259.509108) (xy 100.355069 -259.562405)
			(xy 100.359272 -259.616988) (xy 100.357224 -259.643605) (xy 100.586784 -259.643605) (xy 100.586784 -259.590307)
			(xy 100.594727 -259.537603) (xy 100.610437 -259.486673) (xy 100.633563 -259.438652) (xy 100.663587 -259.394615)
			(xy 100.699839 -259.355544) (xy 100.74151 -259.322313) (xy 100.787668 -259.295664) (xy 100.837282 -259.276192)
			(xy 100.889244 -259.264332) (xy 100.942394 -259.260349) (xy 100.995544 -259.264332) (xy 101.047506 -259.276192)
			(xy 101.09712 -259.295664) (xy 101.143278 -259.322313) (xy 101.184949 -259.355544) (xy 101.221201 -259.394615)
			(xy 101.251225 -259.438652) (xy 101.274351 -259.486673) (xy 101.290061 -259.537603) (xy 101.298004 -259.590307)
			(xy 101.298502 -259.616956) (xy 101.298004 -259.643605) (xy 101.290061 -259.696309) (xy 101.281795 -259.723107)
			(xy 102.510834 -259.723107) (xy 102.510834 -259.669809) (xy 102.518777 -259.617105) (xy 102.534487 -259.566175)
			(xy 102.557613 -259.518154) (xy 102.587637 -259.474117) (xy 102.623889 -259.435046) (xy 102.66556 -259.401815)
			(xy 102.711718 -259.375166) (xy 102.761332 -259.355694) (xy 102.813294 -259.343834) (xy 102.866444 -259.339851)
			(xy 102.919594 -259.343834) (xy 102.971556 -259.355694) (xy 103.02117 -259.375166) (xy 103.067328 -259.401815)
			(xy 103.108999 -259.435046) (xy 103.145251 -259.474117) (xy 103.175275 -259.518154) (xy 103.198401 -259.566175)
			(xy 103.214111 -259.617105) (xy 103.222054 -259.669809) (xy 103.222552 -259.696458) (xy 103.222054 -259.723107)
			(xy 103.214111 -259.775811) (xy 103.198401 -259.826741) (xy 103.175275 -259.874762) (xy 103.145251 -259.918799)
			(xy 103.108999 -259.95787) (xy 103.067328 -259.991101) (xy 103.02117 -260.01775) (xy 102.971556 -260.037222)
			(xy 102.919594 -260.049082) (xy 102.866444 -260.053066) (xy 102.813294 -260.049082) (xy 102.761332 -260.037222)
			(xy 102.711718 -260.01775) (xy 102.66556 -259.991101) (xy 102.623889 -259.95787) (xy 102.587637 -259.918799)
			(xy 102.557613 -259.874762) (xy 102.534487 -259.826741) (xy 102.518777 -259.775811) (xy 102.510834 -259.723107)
			(xy 101.281795 -259.723107) (xy 101.274351 -259.747239) (xy 101.251225 -259.79526) (xy 101.221201 -259.839297)
			(xy 101.184949 -259.878368) (xy 101.143278 -259.911599) (xy 101.09712 -259.938248) (xy 101.047506 -259.95772)
			(xy 100.995544 -259.96958) (xy 100.942394 -259.973564) (xy 100.889244 -259.96958) (xy 100.837282 -259.95772)
			(xy 100.787668 -259.938248) (xy 100.74151 -259.911599) (xy 100.699839 -259.878368) (xy 100.663587 -259.839297)
			(xy 100.633563 -259.79526) (xy 100.610437 -259.747239) (xy 100.594727 -259.696309) (xy 100.586784 -259.643605)
			(xy 100.357224 -259.643605) (xy 100.355072 -259.671572) (xy 100.342569 -259.72487) (xy 100.322056 -259.775627)
			(xy 100.294017 -259.822647) (xy 100.259113 -259.864822) (xy 100.218166 -259.901158) (xy 100.172141 -259.9308)
			(xy 100.122121 -259.95305) (xy 100.095812 -259.960618) (xy 100.05822 -259.970778) (xy 100.05822 -260.096762)
			(xy 100.058716 -260.111544) (xy 100.067171 -260.139872) (xy 100.083384 -260.164593) (xy 100.105997 -260.183636)
			(xy 100.133116 -260.195407) (xy 100.162469 -260.198919) (xy 100.1916 -260.193878) (xy 100.218067 -260.180707)
			(xy 100.229162 -260.17093) (xy 100.249081 -260.152942) (xy 100.293311 -260.122545) (xy 100.341599 -260.099123)
			(xy 100.392853 -260.083206) (xy 100.445914 -260.075152) (xy 100.472748 -260.074664) (xy 100.500729 -260.075217)
			(xy 100.556002 -260.083977) (xy 100.609225 -260.101276) (xy 100.659086 -260.126686) (xy 100.70436 -260.159582)
			(xy 100.743931 -260.199155) (xy 100.776825 -260.244431) (xy 100.802232 -260.294294) (xy 100.819527 -260.347517)
			(xy 100.828285 -260.402791) (xy 100.828856 -260.430772) (xy 100.82829 -260.459362) (xy 100.819159 -260.515807)
			(xy 100.801127 -260.570068) (xy 100.774658 -260.620752) (xy 100.740431 -260.666555) (xy 100.699325 -260.706302)
			(xy 100.676202 -260.723126) (xy 100.664332 -260.732017) (xy 100.645894 -260.75523) (xy 100.634884 -260.782754)
			(xy 100.632224 -260.812279) (xy 100.638139 -260.841327) (xy 100.652132 -260.867461) (xy 100.662232 -260.87832)
			(xy 100.737416 -260.953504) (xy 100.760063 -260.938234) (xy 100.809024 -260.914027) (xy 100.861104 -260.897572)
			(xy 100.915085 -260.889254) (xy 100.942394 -260.888734) (xy 100.967908 -260.889165) (xy 101.018414 -260.896438)
			(xy 101.067363 -260.91085) (xy 101.113752 -260.932106) (xy 101.15663 -260.95977) (xy 101.195117 -260.993275)
			(xy 101.228423 -261.031932) (xy 101.255867 -261.074951) (xy 101.266752 -261.09803) (xy 101.280214 -261.127748)
			(xy 101.544374 -261.127748) (xy 101.557836 -261.09803) (xy 101.569526 -261.073455) (xy 101.599248 -261.02787)
			(xy 101.635561 -260.98734) (xy 101.677619 -260.952808) (xy 101.724442 -260.925078) (xy 101.774939 -260.904796)
			(xy 101.827935 -260.892435) (xy 101.882194 -260.888282) (xy 101.936453 -260.892435) (xy 101.989449 -260.904796)
			(xy 102.039946 -260.925078) (xy 102.086769 -260.952808) (xy 102.128827 -260.98734) (xy 102.16514 -261.02787)
			(xy 102.194862 -261.073455) (xy 102.206552 -261.09803) (xy 102.220014 -261.127748) (xy 102.464616 -261.127748)
			(xy 102.479575 -261.127219) (xy 102.508211 -261.118552) (xy 102.53311 -261.101966) (xy 102.552141 -261.078881)
			(xy 102.563674 -261.051275) (xy 102.566719 -261.021512) (xy 102.561017 -260.992142) (xy 102.554532 -260.97865)
			(xy 102.541574 -260.952899) (xy 102.523242 -260.898248) (xy 102.51396 -260.841356) (xy 102.513384 -260.812534)
			(xy 102.513882 -260.785885) (xy 102.521825 -260.733181) (xy 102.537535 -260.682251) (xy 102.560661 -260.63423)
			(xy 102.590685 -260.590193) (xy 102.626937 -260.551122) (xy 102.668608 -260.517891) (xy 102.714766 -260.491242)
			(xy 102.76438 -260.47177) (xy 102.816342 -260.45991) (xy 102.869492 -260.455927) (xy 102.922642 -260.45991)
			(xy 102.974604 -260.47177) (xy 103.024218 -260.491242) (xy 103.070376 -260.517891) (xy 103.112047 -260.551122)
			(xy 103.148299 -260.590193) (xy 103.178323 -260.63423) (xy 103.201449 -260.682251) (xy 103.217159 -260.733181)
			(xy 103.225102 -260.785885) (xy 103.2256 -260.812534) (xy 103.22504 -260.841356) (xy 103.215745 -260.898246)
			(xy 103.197402 -260.952895) (xy 103.184452 -260.97865) (xy 103.177915 -260.992133) (xy 103.172178 -261.021529)
			(xy 103.175207 -261.051326) (xy 103.186742 -261.078966) (xy 103.205792 -261.102077) (xy 103.230722 -261.118675)
			(xy 103.259393 -261.127336) (xy 103.274368 -261.127748) (xy 104.00538 -261.127748) (xy 104.85882 -260.274308)
			(xy 104.85882 -258.109974) (xy 104.858315 -258.095459) (xy 104.850161 -258.067599) (xy 104.834492 -258.043162)
			(xy 104.812576 -258.024126) (xy 104.786187 -258.012032) (xy 104.757459 -258.007858) (xy 104.728719 -258.011942)
			(xy 104.71531 -258.017518) (xy 104.692066 -258.027568) (xy 104.643447 -258.041726) (xy 104.59331 -258.048841)
			(xy 104.56799 -258.049268) (xy 104.543321 -258.048847) (xy 104.494456 -258.042034) (xy 104.447 -258.02854)
			(xy 104.401861 -258.008623) (xy 104.359904 -257.982665) (xy 104.34066 -257.967226) (xy 104.32953 -257.958599)
			(xy 104.30377 -257.947252) (xy 104.27589 -257.943371) (xy 104.24801 -257.947252) (xy 104.22225 -257.958599)
			(xy 104.21112 -257.967226) (xy 104.189704 -257.984349) (xy 104.142647 -258.012488) (xy 104.09183 -258.033077)
			(xy 104.038457 -258.045629) (xy 103.98379 -258.049846) (xy 103.929123 -258.045629) (xy 103.87575 -258.033077)
			(xy 103.824933 -258.012488) (xy 103.777876 -257.984349) (xy 103.75646 -257.967226) (xy 103.74533 -257.958599)
			(xy 103.71957 -257.947252) (xy 103.69169 -257.943371) (xy 103.66381 -257.947252) (xy 103.63805 -257.958599)
			(xy 103.62692 -257.967226) (xy 103.607672 -257.982662) (xy 103.565722 -258.008633) (xy 103.520585 -258.028557)
			(xy 103.473127 -258.042051) (xy 103.42426 -258.048855) (xy 103.39959 -258.049268) (xy 103.372944 -258.048769)
			(xy 103.320248 -258.040825) (xy 103.269324 -258.025116) (xy 103.221311 -258.001993) (xy 103.17728 -257.971972)
			(xy 103.138215 -257.935724) (xy 103.104988 -257.894058) (xy 103.078343 -257.847906) (xy 103.058874 -257.798298)
			(xy 103.047015 -257.746343) (xy 103.043033 -257.6932) (xy 103.047015 -257.640057) (xy 103.058874 -257.588102)
			(xy 103.078343 -257.538494) (xy 103.104988 -257.492342) (xy 103.138215 -257.450676) (xy 103.17728 -257.414428)
			(xy 103.221311 -257.384407) (xy 103.269324 -257.361284) (xy 103.320248 -257.345575) (xy 103.372944 -257.337631)
			(xy 103.39959 -257.337052) (xy 103.424257 -257.337478) (xy 103.473116 -257.344301) (xy 103.520566 -257.357805)
			(xy 103.565697 -257.37773) (xy 103.607645 -257.403695) (xy 103.62692 -257.419094) (xy 103.63805 -257.427721)
			(xy 103.66381 -257.439068) (xy 103.69169 -257.442949) (xy 103.71957 -257.439068) (xy 103.74533 -257.427721)
			(xy 103.75646 -257.419094) (xy 103.777876 -257.401971) (xy 103.824933 -257.373832) (xy 103.87575 -257.353243)
			(xy 103.929123 -257.340691) (xy 103.98379 -257.336474) (xy 104.038457 -257.340691) (xy 104.09183 -257.353243)
			(xy 104.142647 -257.373832) (xy 104.189704 -257.401971) (xy 104.21112 -257.419094) (xy 104.22225 -257.427721)
			(xy 104.24801 -257.439068) (xy 104.27589 -257.442949) (xy 104.30377 -257.439068) (xy 104.32953 -257.427721)
			(xy 104.34066 -257.419094) (xy 104.359907 -257.403656) (xy 104.401857 -257.377681) (xy 104.446994 -257.357754)
			(xy 104.494452 -257.344257) (xy 104.54332 -257.337449) (xy 104.56799 -257.337052) (xy 104.593309 -257.337479)
			(xy 104.643444 -257.344608) (xy 104.692066 -257.358753) (xy 104.71531 -257.368802) (xy 104.728734 -257.374313)
			(xy 104.757456 -257.378358) (xy 104.786157 -257.374169) (xy 104.812523 -257.362082) (xy 104.83443 -257.343072)
			(xy 104.850111 -257.318672) (xy 104.858303 -257.290848) (xy 104.85882 -257.276346) (xy 104.85882 -254.477774)
			(xy 104.858357 -254.464267) (xy 104.851187 -254.438219) (xy 104.837436 -254.414963) (xy 104.818066 -254.396129)
			(xy 104.794435 -254.383034) (xy 104.768197 -254.376596) (xy 104.75468 -254.376428) (xy 104.74579 -254.376428)
			(xy 104.721121 -254.376008) (xy 104.672255 -254.369196) (xy 104.624797 -254.355704) (xy 104.579657 -254.335789)
			(xy 104.537697 -254.309835) (xy 104.51846 -254.294386) (xy 104.50733 -254.285759) (xy 104.48157 -254.274412)
			(xy 104.45369 -254.270531) (xy 104.42581 -254.274412) (xy 104.40005 -254.285759) (xy 104.38892 -254.294386)
			(xy 104.369673 -254.309823) (xy 104.327723 -254.335797) (xy 104.282586 -254.355723) (xy 104.235128 -254.369218)
			(xy 104.18626 -254.376024) (xy 104.16159 -254.376428) (xy 104.13494 -254.37593) (xy 104.082235 -254.367984)
			(xy 104.031302 -254.352272) (xy 103.98328 -254.329145) (xy 103.939242 -254.299119) (xy 103.90017 -254.262865)
			(xy 103.866938 -254.221192) (xy 103.840288 -254.175032) (xy 103.820816 -254.125416) (xy 103.808956 -254.073452)
			(xy 103.804972 -254.0203) (xy 103.808956 -253.967148) (xy 103.820816 -253.915184) (xy 103.840288 -253.865568)
			(xy 103.866938 -253.819408) (xy 103.90017 -253.777735) (xy 103.939242 -253.741481) (xy 103.98328 -253.711455)
			(xy 104.031302 -253.688328) (xy 104.082235 -253.672616) (xy 104.13494 -253.66467) (xy 104.16159 -253.664212)
			(xy 104.186257 -253.664638) (xy 104.235117 -253.67146) (xy 104.282568 -253.684962) (xy 104.3277 -253.704886)
			(xy 104.36965 -253.730848) (xy 104.38892 -253.746254) (xy 104.40005 -253.754881) (xy 104.42581 -253.766228)
			(xy 104.45369 -253.770109) (xy 104.48157 -253.766228) (xy 104.50733 -253.754881) (xy 104.51846 -253.746254)
			(xy 104.537708 -253.730817) (xy 104.579658 -253.704845) (xy 104.624795 -253.68492) (xy 104.672253 -253.671425)
			(xy 104.72112 -253.664618) (xy 104.74579 -253.664212) (xy 104.75468 -253.664212) (xy 104.768198 -253.664126)
			(xy 104.794442 -253.65768) (xy 104.818072 -253.644571) (xy 104.837432 -253.625716) (xy 104.851162 -253.602441)
			(xy 104.8583 -253.576377) (xy 104.85882 -253.562866) (xy 104.85882 -250.802394) (xy 104.858385 -250.78877)
			(xy 104.851183 -250.76249) (xy 104.837293 -250.739047) (xy 104.817701 -250.720108) (xy 104.793802 -250.70702)
			(xy 104.767293 -250.700712) (xy 104.753664 -250.700794) (xy 104.74071 -250.701048) (xy 104.716043 -250.700622)
			(xy 104.667184 -250.693799) (xy 104.619734 -250.680295) (xy 104.574603 -250.66037) (xy 104.532655 -250.634405)
			(xy 104.51338 -250.619006) (xy 104.50225 -250.610379) (xy 104.47649 -250.599032) (xy 104.44861 -250.595151)
			(xy 104.42073 -250.599032) (xy 104.39497 -250.610379) (xy 104.38384 -250.619006) (xy 104.364593 -250.634444)
			(xy 104.322643 -250.660419) (xy 104.277506 -250.680346) (xy 104.230048 -250.693843) (xy 104.18118 -250.700651)
			(xy 104.15651 -250.701048) (xy 104.129855 -250.700575) (xy 104.077141 -250.692631) (xy 104.0262 -250.676919)
			(xy 103.97817 -250.65379) (xy 103.934123 -250.623761) (xy 103.895044 -250.587502) (xy 103.861806 -250.545824)
			(xy 103.835151 -250.499657) (xy 103.815674 -250.450033) (xy 103.803812 -250.39806) (xy 103.799828 -250.3449)
			(xy 103.803812 -250.29174) (xy 103.815674 -250.239767) (xy 103.835151 -250.190143) (xy 103.861806 -250.143976)
			(xy 103.895044 -250.102298) (xy 103.934123 -250.066039) (xy 103.97817 -250.03601) (xy 104.0262 -250.012881)
			(xy 104.077141 -249.997169) (xy 104.129855 -249.989225) (xy 104.15651 -249.988832) (xy 104.181179 -249.989253)
			(xy 104.230044 -249.996066) (xy 104.2775 -250.00956) (xy 104.322639 -250.029477) (xy 104.364596 -250.055435)
			(xy 104.38384 -250.070874) (xy 104.39497 -250.079501) (xy 104.42073 -250.090848) (xy 104.44861 -250.094729)
			(xy 104.47649 -250.090848) (xy 104.50225 -250.079501) (xy 104.51338 -250.070874) (xy 104.532628 -250.055438)
			(xy 104.574578 -250.029467) (xy 104.619715 -250.009543) (xy 104.667173 -249.996049) (xy 104.71604 -249.989245)
			(xy 104.74071 -249.988832) (xy 104.753664 -249.989086) (xy 104.7673 -249.989137) (xy 104.793826 -249.982866)
			(xy 104.817745 -249.969796) (xy 104.83735 -249.95086) (xy 104.851242 -249.927408) (xy 104.85843 -249.901115)
			(xy 104.85882 -249.887486) (xy 104.85882 -244.757448) (xy 103.34752 -243.246148) (xy 103.34752 -241.236246)
			(xy 103.347056 -241.222667) (xy 103.33983 -241.196486) (xy 103.325956 -241.173136) (xy 103.306417 -241.154271)
			(xy 103.282595 -241.141225) (xy 103.256177 -241.134921) (xy 103.229031 -241.135805) (xy 103.203079 -241.143816)
			(xy 103.180157 -241.158386) (xy 103.170736 -241.168174) (xy 103.153773 -241.186235) (xy 103.115716 -241.217963)
			(xy 103.073629 -241.244111) (xy 103.028324 -241.264174) (xy 102.980676 -241.277765) (xy 102.931604 -241.284622)
			(xy 102.90683 -241.285014) (xy 102.878843 -241.284496) (xy 102.823557 -241.275744) (xy 102.770322 -241.258451)
			(xy 102.720447 -241.233043) (xy 102.675161 -241.200144) (xy 102.635579 -241.160567) (xy 102.602676 -241.115284)
			(xy 102.577263 -241.065412) (xy 102.559964 -241.012178) (xy 102.551207 -240.956893) (xy 102.550722 -240.928906)
			(xy 102.551141 -240.904237) (xy 102.557952 -240.855371) (xy 102.571444 -240.807913) (xy 102.591359 -240.762772)
			(xy 102.617315 -240.720813) (xy 102.632764 -240.701576) (xy 102.64139 -240.690445) (xy 102.652735 -240.664684)
			(xy 102.656616 -240.636805) (xy 102.652737 -240.608925) (xy 102.641394 -240.583163) (xy 102.632764 -240.572036)
			(xy 102.617327 -240.552788) (xy 102.591355 -240.510838) (xy 102.57143 -240.465701) (xy 102.557934 -240.418243)
			(xy 102.551128 -240.369376) (xy 102.550722 -240.344706) (xy 102.551242 -240.316721) (xy 102.559997 -240.261441)
			(xy 102.577293 -240.20821) (xy 102.602703 -240.158342) (xy 102.635603 -240.113062) (xy 102.67518 -240.073487)
			(xy 102.720462 -240.040591) (xy 102.770333 -240.015184) (xy 102.823564 -239.997892) (xy 102.878845 -239.98914)
			(xy 102.90683 -239.988598) (xy 102.931602 -239.989025) (xy 102.98067 -239.995888) (xy 103.028315 -240.009477)
			(xy 103.07362 -240.029531) (xy 103.115712 -240.055663) (xy 103.153782 -240.087371) (xy 103.170736 -240.105438)
			(xy 103.180185 -240.115193) (xy 103.203098 -240.129755) (xy 103.22904 -240.137761) (xy 103.256174 -240.138645)
			(xy 103.282582 -240.132344) (xy 103.306394 -240.119304) (xy 103.325925 -240.100447) (xy 103.339795 -240.077109)
			(xy 103.347021 -240.050939) (xy 103.34752 -240.037366) (xy 103.34752 -239.616996) (xy 103.335134 -239.609525)
			(xy 103.311483 -239.592867) (xy 103.300276 -239.583722) (xy 103.289146 -239.575095) (xy 103.263386 -239.563748)
			(xy 103.235506 -239.559867) (xy 103.207626 -239.563748) (xy 103.181866 -239.575095) (xy 103.170736 -239.583722)
			(xy 103.151488 -239.599159) (xy 103.109539 -239.625133) (xy 103.064402 -239.645059) (xy 103.016944 -239.658554)
			(xy 102.968076 -239.665361) (xy 102.943406 -239.665764) (xy 102.917059 -239.66529) (xy 102.864941 -239.657527)
			(xy 102.814535 -239.64217) (xy 102.766942 -239.619554) (xy 102.723201 -239.590173) (xy 102.684265 -239.554667)
			(xy 102.650986 -239.513813) (xy 102.62409 -239.468501) (xy 102.604162 -239.419721) (xy 102.597458 -239.394238)
			(xy 102.593664 -239.380787) (xy 102.579836 -239.35651) (xy 102.559956 -239.33688) (xy 102.535506 -239.323362)
			(xy 102.50831 -239.316963) (xy 102.480397 -239.318161) (xy 102.453849 -239.326868) (xy 102.44201 -239.334294)
			(xy 102.41979 -239.348751) (xy 102.371975 -239.371635) (xy 102.321295 -239.387176) (xy 102.268871 -239.395031)
			(xy 102.242366 -239.395508) (xy 102.215718 -239.395008) (xy 102.163019 -239.38706) (xy 102.112093 -239.371347)
			(xy 102.064077 -239.34822) (xy 102.020044 -239.318195) (xy 101.980977 -239.281943) (xy 101.94775 -239.240273)
			(xy 101.921104 -239.194117) (xy 101.901634 -239.144506) (xy 101.889775 -239.092546) (xy 101.885792 -239.0394)
			(xy 101.889775 -238.986254) (xy 101.901634 -238.934294) (xy 101.921104 -238.884683) (xy 101.94775 -238.838527)
			(xy 101.980977 -238.796857) (xy 102.020044 -238.760605) (xy 102.064077 -238.73058) (xy 102.112093 -238.707453)
			(xy 102.163019 -238.69174) (xy 102.215718 -238.683792) (xy 102.242366 -238.683292) (xy 102.26871 -238.683772)
			(xy 102.320823 -238.691543) (xy 102.371223 -238.706905) (xy 102.418809 -238.729525) (xy 102.462545 -238.758907)
			(xy 102.501475 -238.794411) (xy 102.534751 -238.835263) (xy 102.561646 -238.880571) (xy 102.581573 -238.929346)
			(xy 102.588314 -238.954818) (xy 102.592103 -238.968277) (xy 102.605926 -238.99257) (xy 102.625809 -239.012215)
			(xy 102.650266 -239.025746) (xy 102.677472 -239.032153) (xy 102.705397 -239.030957) (xy 102.731956 -239.022249)
			(xy 102.743762 -239.014762) (xy 102.765982 -239.000305) (xy 102.813798 -238.97742) (xy 102.864477 -238.961877)
			(xy 102.916901 -238.954019) (xy 102.943406 -238.953548) (xy 102.968075 -238.953968) (xy 103.01694 -238.960781)
			(xy 103.064396 -238.974275) (xy 103.109535 -238.994193) (xy 103.151491 -239.020151) (xy 103.170736 -239.03559)
			(xy 103.181866 -239.044217) (xy 103.207626 -239.055564) (xy 103.235506 -239.059445) (xy 103.263386 -239.055564)
			(xy 103.289146 -239.044217) (xy 103.300276 -239.03559) (xy 103.311478 -239.026439) (xy 103.33513 -239.009781)
			(xy 103.34752 -239.002316) (xy 103.34752 -238.681768) (xy 105.355644 -236.673644) (xy 108.83392 -236.673644)
			(xy 108.849356 -236.673115) (xy 108.878823 -236.663909) (xy 108.90419 -236.646315) (xy 108.923137 -236.621941)
			(xy 108.933931 -236.593018) (xy 108.935266 -236.577632) (xy 108.937284 -236.55072) (xy 108.948418 -236.497914)
			(xy 108.967391 -236.447393) (xy 108.993769 -236.400313) (xy 109.026948 -236.35775) (xy 109.066168 -236.320681)
			(xy 109.110532 -236.289953) (xy 109.159024 -236.266269) (xy 109.210534 -236.250172) (xy 109.263883 -236.24203)
			(xy 109.317849 -236.24203) (xy 109.371198 -236.250172) (xy 109.422708 -236.266269) (xy 109.4712 -236.289953)
			(xy 109.515564 -236.320681) (xy 109.554784 -236.35775) (xy 109.587963 -236.400313) (xy 109.614341 -236.447393)
			(xy 109.633314 -236.497914) (xy 109.644448 -236.55072) (xy 109.646466 -236.577632) (xy 109.647855 -236.593007)
			(xy 109.658671 -236.621905) (xy 109.677609 -236.646266) (xy 109.702949 -236.663873) (xy 109.732385 -236.673126)
			(xy 109.747812 -236.673644) (xy 109.773974 -236.673644) (xy 109.789405 -236.673107) (xy 109.818858 -236.663892)
			(xy 109.844211 -236.646295) (xy 109.863146 -236.621925) (xy 109.873933 -236.59301) (xy 109.87532 -236.577632)
			(xy 109.877338 -236.55072) (xy 109.888472 -236.497914) (xy 109.907445 -236.447393) (xy 109.933823 -236.400313)
			(xy 109.967002 -236.35775) (xy 110.006222 -236.320681) (xy 110.050586 -236.289953) (xy 110.099078 -236.266269)
			(xy 110.150588 -236.250172) (xy 110.203937 -236.24203) (xy 110.257903 -236.24203) (xy 110.311252 -236.250172)
			(xy 110.362762 -236.266269) (xy 110.411254 -236.289953) (xy 110.455618 -236.320681) (xy 110.494838 -236.35775)
			(xy 110.528017 -236.400313) (xy 110.554395 -236.447393) (xy 110.573368 -236.497914) (xy 110.584502 -236.55072)
			(xy 110.58652 -236.577632) (xy 110.58791 -236.593003) (xy 110.598727 -236.621895) (xy 110.617668 -236.646246)
			(xy 110.643008 -236.663841) (xy 110.672442 -236.673079) (xy 110.687866 -236.673644) (xy 110.71352 -236.673644)
			(xy 110.728956 -236.673115) (xy 110.758423 -236.663909) (xy 110.78379 -236.646315) (xy 110.802737 -236.621941)
			(xy 110.813531 -236.593018) (xy 110.814866 -236.577632) (xy 110.816884 -236.55072) (xy 110.828018 -236.497914)
			(xy 110.846991 -236.447393) (xy 110.873369 -236.400313) (xy 110.906548 -236.35775) (xy 110.945768 -236.320681)
			(xy 110.990132 -236.289953) (xy 111.038624 -236.266269) (xy 111.090134 -236.250172) (xy 111.143483 -236.24203)
			(xy 111.197449 -236.24203) (xy 111.250798 -236.250172) (xy 111.302308 -236.266269) (xy 111.3508 -236.289953)
			(xy 111.395164 -236.320681) (xy 111.434384 -236.35775) (xy 111.467563 -236.400313) (xy 111.493941 -236.447393)
			(xy 111.512914 -236.497914) (xy 111.524048 -236.55072) (xy 111.526066 -236.577632) (xy 111.527455 -236.593007)
			(xy 111.538271 -236.621905) (xy 111.557209 -236.646266) (xy 111.582549 -236.663873) (xy 111.611985 -236.673126)
			(xy 111.627412 -236.673644) (xy 111.65332 -236.673644) (xy 111.668756 -236.673115) (xy 111.698223 -236.663909)
			(xy 111.72359 -236.646315) (xy 111.742537 -236.621941) (xy 111.753331 -236.593018) (xy 111.754666 -236.577632)
			(xy 111.756684 -236.55072) (xy 111.767818 -236.497914) (xy 111.786791 -236.447393) (xy 111.813169 -236.400313)
			(xy 111.846348 -236.35775) (xy 111.885568 -236.320681) (xy 111.929932 -236.289953) (xy 111.978424 -236.266269)
			(xy 112.029934 -236.250172) (xy 112.083283 -236.24203) (xy 112.137249 -236.24203) (xy 112.190598 -236.250172)
			(xy 112.242108 -236.266269) (xy 112.2906 -236.289953) (xy 112.334964 -236.320681) (xy 112.374184 -236.35775)
			(xy 112.407363 -236.400313) (xy 112.433741 -236.447393) (xy 112.452714 -236.497914) (xy 112.463848 -236.55072)
			(xy 112.465866 -236.577632) (xy 112.467255 -236.593007) (xy 112.478071 -236.621905) (xy 112.497009 -236.646266)
			(xy 112.522349 -236.663873) (xy 112.551785 -236.673126) (xy 112.567212 -236.673644) (xy 112.59312 -236.673644)
			(xy 112.608556 -236.673115) (xy 112.638023 -236.663909) (xy 112.66339 -236.646315) (xy 112.682337 -236.621941)
			(xy 112.693131 -236.593018) (xy 112.694466 -236.577632) (xy 112.696484 -236.55072) (xy 112.707618 -236.497914)
			(xy 112.726591 -236.447393) (xy 112.752969 -236.400313) (xy 112.786148 -236.35775) (xy 112.825368 -236.320681)
			(xy 112.869732 -236.289953) (xy 112.918224 -236.266269) (xy 112.969734 -236.250172) (xy 113.023083 -236.24203)
			(xy 113.077049 -236.24203) (xy 113.130398 -236.250172) (xy 113.181908 -236.266269) (xy 113.2304 -236.289953)
			(xy 113.274764 -236.320681) (xy 113.313984 -236.35775) (xy 113.347163 -236.400313) (xy 113.373541 -236.447393)
			(xy 113.392514 -236.497914) (xy 113.403648 -236.55072) (xy 113.405666 -236.577632) (xy 113.407055 -236.593007)
			(xy 113.417871 -236.621905) (xy 113.436809 -236.646266) (xy 113.462149 -236.663873) (xy 113.491585 -236.673126)
			(xy 113.507012 -236.673644) (xy 113.533174 -236.673644) (xy 113.548605 -236.673107) (xy 113.578058 -236.663892)
			(xy 113.603411 -236.646295) (xy 113.622346 -236.621925) (xy 113.633133 -236.59301) (xy 113.63452 -236.577632)
			(xy 113.636538 -236.55072) (xy 113.647672 -236.497914) (xy 113.666645 -236.447393) (xy 113.693023 -236.400313)
			(xy 113.726202 -236.35775) (xy 113.765422 -236.320681) (xy 113.809786 -236.289953) (xy 113.858278 -236.266269)
			(xy 113.909788 -236.250172) (xy 113.963137 -236.24203) (xy 114.017103 -236.24203) (xy 114.070452 -236.250172)
			(xy 114.121962 -236.266269) (xy 114.170454 -236.289953) (xy 114.214818 -236.320681) (xy 114.254038 -236.35775)
			(xy 114.287217 -236.400313) (xy 114.313595 -236.447393) (xy 114.332568 -236.497914) (xy 114.343702 -236.55072)
			(xy 114.34572 -236.577632) (xy 114.34711 -236.593003) (xy 114.357927 -236.621895) (xy 114.376868 -236.646246)
			(xy 114.402208 -236.663841) (xy 114.431642 -236.673079) (xy 114.447066 -236.673644) (xy 114.884454 -236.673644)
			(xy 114.897902 -236.673226) (xy 114.923861 -236.66619) (xy 114.947083 -236.652621) (xy 114.965957 -236.63346)
			(xy 114.979175 -236.610035) (xy 114.985818 -236.583973) (xy 114.986054 -236.57052) (xy 114.986054 -236.565186)
			(xy 114.986552 -236.538537) (xy 114.994495 -236.485833) (xy 115.010205 -236.434903) (xy 115.033331 -236.386882)
			(xy 115.063355 -236.342845) (xy 115.099607 -236.303774) (xy 115.141278 -236.270543) (xy 115.187436 -236.243894)
			(xy 115.23705 -236.224422) (xy 115.289012 -236.212562) (xy 115.342162 -236.208579) (xy 115.395312 -236.212562)
			(xy 115.447274 -236.224422) (xy 115.496888 -236.243894) (xy 115.510928 -236.252) (xy 120.619796 -236.252)
			(xy 120.623779 -236.198852) (xy 120.635639 -236.146891) (xy 120.65511 -236.097278) (xy 120.681758 -236.051121)
			(xy 120.714988 -236.009452) (xy 120.754057 -235.9732) (xy 120.798092 -235.943176) (xy 120.846111 -235.92005)
			(xy 120.89704 -235.904339) (xy 120.949741 -235.896394) (xy 120.97639 -235.895896) (xy 121.002974 -235.896332)
			(xy 121.055553 -235.904222) (xy 121.106374 -235.919842) (xy 121.154308 -235.942846) (xy 121.198288 -235.972723)
			(xy 121.237336 -236.008807) (xy 121.270584 -236.050296) (xy 121.297293 -236.096268) (xy 121.316869 -236.1457)
			(xy 121.323354 -236.171486) (xy 121.327434 -236.186528) (xy 121.343276 -236.213348) (xy 121.366478 -236.234133)
			(xy 121.394872 -236.246941) (xy 121.425808 -236.250577) (xy 121.44121 -236.248194) (xy 121.457753 -236.245242)
			(xy 121.491209 -236.242059) (xy 121.508012 -236.241844) (xy 121.534657 -236.242439) (xy 121.587352 -236.250383)
			(xy 121.638274 -236.266092) (xy 121.686286 -236.289215) (xy 121.730316 -236.319235) (xy 121.76938 -236.355482)
			(xy 121.802605 -236.397147) (xy 121.82925 -236.443298) (xy 121.848719 -236.492905) (xy 121.860577 -236.544859)
			(xy 121.864559 -236.598) (xy 121.862566 -236.624601) (xy 122.092456 -236.624601) (xy 122.092456 -236.571303)
			(xy 122.100399 -236.518599) (xy 122.116109 -236.467669) (xy 122.139235 -236.419648) (xy 122.169259 -236.375611)
			(xy 122.205511 -236.33654) (xy 122.247182 -236.303309) (xy 122.29334 -236.27666) (xy 122.342954 -236.257188)
			(xy 122.394916 -236.245328) (xy 122.448066 -236.241345) (xy 122.501216 -236.245328) (xy 122.553178 -236.257188)
			(xy 122.602792 -236.27666) (xy 122.64895 -236.303309) (xy 122.690621 -236.33654) (xy 122.726873 -236.375611)
			(xy 122.756897 -236.419648) (xy 122.780023 -236.467669) (xy 122.795733 -236.518599) (xy 122.803676 -236.571303)
			(xy 122.804174 -236.597952) (xy 122.803676 -236.624601) (xy 123.032002 -236.624601) (xy 123.032002 -236.571303)
			(xy 123.039945 -236.518599) (xy 123.055655 -236.467669) (xy 123.078781 -236.419648) (xy 123.108805 -236.375611)
			(xy 123.145057 -236.33654) (xy 123.186728 -236.303309) (xy 123.232886 -236.27666) (xy 123.2825 -236.257188)
			(xy 123.334462 -236.245328) (xy 123.387612 -236.241345) (xy 123.440762 -236.245328) (xy 123.492724 -236.257188)
			(xy 123.542338 -236.27666) (xy 123.588496 -236.303309) (xy 123.630167 -236.33654) (xy 123.666419 -236.375611)
			(xy 123.696443 -236.419648) (xy 123.719569 -236.467669) (xy 123.735279 -236.518599) (xy 123.743222 -236.571303)
			(xy 123.74372 -236.597952) (xy 123.743222 -236.624601) (xy 123.971802 -236.624601) (xy 123.971802 -236.571303)
			(xy 123.979745 -236.518599) (xy 123.995455 -236.467669) (xy 124.018581 -236.419648) (xy 124.048605 -236.375611)
			(xy 124.084857 -236.33654) (xy 124.126528 -236.303309) (xy 124.172686 -236.27666) (xy 124.2223 -236.257188)
			(xy 124.274262 -236.245328) (xy 124.327412 -236.241345) (xy 124.380562 -236.245328) (xy 124.432524 -236.257188)
			(xy 124.482138 -236.27666) (xy 124.528296 -236.303309) (xy 124.569967 -236.33654) (xy 124.606219 -236.375611)
			(xy 124.636243 -236.419648) (xy 124.659369 -236.467669) (xy 124.675079 -236.518599) (xy 124.683022 -236.571303)
			(xy 124.68352 -236.597952) (xy 124.683022 -236.624601) (xy 124.911602 -236.624601) (xy 124.911602 -236.571303)
			(xy 124.919545 -236.518599) (xy 124.935255 -236.467669) (xy 124.958381 -236.419648) (xy 124.988405 -236.375611)
			(xy 125.024657 -236.33654) (xy 125.066328 -236.303309) (xy 125.112486 -236.27666) (xy 125.1621 -236.257188)
			(xy 125.214062 -236.245328) (xy 125.267212 -236.241345) (xy 125.320362 -236.245328) (xy 125.372324 -236.257188)
			(xy 125.421938 -236.27666) (xy 125.468096 -236.303309) (xy 125.509767 -236.33654) (xy 125.546019 -236.375611)
			(xy 125.576043 -236.419648) (xy 125.599169 -236.467669) (xy 125.614879 -236.518599) (xy 125.622822 -236.571303)
			(xy 125.62332 -236.597952) (xy 125.622822 -236.624601) (xy 125.851402 -236.624601) (xy 125.851402 -236.571303)
			(xy 125.859345 -236.518599) (xy 125.875055 -236.467669) (xy 125.898181 -236.419648) (xy 125.928205 -236.375611)
			(xy 125.964457 -236.33654) (xy 126.006128 -236.303309) (xy 126.052286 -236.27666) (xy 126.1019 -236.257188)
			(xy 126.153862 -236.245328) (xy 126.207012 -236.241345) (xy 126.260162 -236.245328) (xy 126.312124 -236.257188)
			(xy 126.361738 -236.27666) (xy 126.407896 -236.303309) (xy 126.449567 -236.33654) (xy 126.485819 -236.375611)
			(xy 126.515843 -236.419648) (xy 126.538969 -236.467669) (xy 126.554679 -236.518599) (xy 126.562622 -236.571303)
			(xy 126.56312 -236.597952) (xy 126.562622 -236.624601) (xy 126.791202 -236.624601) (xy 126.791202 -236.571303)
			(xy 126.799145 -236.518599) (xy 126.814855 -236.467669) (xy 126.837981 -236.419648) (xy 126.868005 -236.375611)
			(xy 126.904257 -236.33654) (xy 126.945928 -236.303309) (xy 126.992086 -236.27666) (xy 127.0417 -236.257188)
			(xy 127.093662 -236.245328) (xy 127.146812 -236.241345) (xy 127.199962 -236.245328) (xy 127.251924 -236.257188)
			(xy 127.301538 -236.27666) (xy 127.347696 -236.303309) (xy 127.389367 -236.33654) (xy 127.425619 -236.375611)
			(xy 127.455643 -236.419648) (xy 127.478769 -236.467669) (xy 127.494479 -236.518599) (xy 127.502422 -236.571303)
			(xy 127.50292 -236.597952) (xy 127.502422 -236.624601) (xy 127.731002 -236.624601) (xy 127.731002 -236.571303)
			(xy 127.738945 -236.518599) (xy 127.754655 -236.467669) (xy 127.777781 -236.419648) (xy 127.807805 -236.375611)
			(xy 127.844057 -236.33654) (xy 127.885728 -236.303309) (xy 127.931886 -236.27666) (xy 127.9815 -236.257188)
			(xy 128.033462 -236.245328) (xy 128.086612 -236.241345) (xy 128.139762 -236.245328) (xy 128.191724 -236.257188)
			(xy 128.241338 -236.27666) (xy 128.287496 -236.303309) (xy 128.329167 -236.33654) (xy 128.365419 -236.375611)
			(xy 128.395443 -236.419648) (xy 128.418569 -236.467669) (xy 128.434279 -236.518599) (xy 128.442222 -236.571303)
			(xy 128.44272 -236.597952) (xy 128.442222 -236.624601) (xy 128.671056 -236.624601) (xy 128.671056 -236.571303)
			(xy 128.678999 -236.518599) (xy 128.694709 -236.467669) (xy 128.717835 -236.419648) (xy 128.747859 -236.375611)
			(xy 128.784111 -236.33654) (xy 128.825782 -236.303309) (xy 128.87194 -236.27666) (xy 128.921554 -236.257188)
			(xy 128.973516 -236.245328) (xy 129.026666 -236.241345) (xy 129.079816 -236.245328) (xy 129.131778 -236.257188)
			(xy 129.181392 -236.27666) (xy 129.22755 -236.303309) (xy 129.269221 -236.33654) (xy 129.305473 -236.375611)
			(xy 129.335497 -236.419648) (xy 129.358623 -236.467669) (xy 129.374333 -236.518599) (xy 129.382276 -236.571303)
			(xy 129.382774 -236.597952) (xy 129.382276 -236.624601) (xy 129.610602 -236.624601) (xy 129.610602 -236.571303)
			(xy 129.618545 -236.518599) (xy 129.634255 -236.467669) (xy 129.657381 -236.419648) (xy 129.687405 -236.375611)
			(xy 129.723657 -236.33654) (xy 129.765328 -236.303309) (xy 129.811486 -236.27666) (xy 129.8611 -236.257188)
			(xy 129.913062 -236.245328) (xy 129.966212 -236.241345) (xy 130.019362 -236.245328) (xy 130.071324 -236.257188)
			(xy 130.120938 -236.27666) (xy 130.167096 -236.303309) (xy 130.208767 -236.33654) (xy 130.245019 -236.375611)
			(xy 130.275043 -236.419648) (xy 130.298169 -236.467669) (xy 130.313879 -236.518599) (xy 130.321822 -236.571303)
			(xy 130.32232 -236.597952) (xy 130.321822 -236.624601) (xy 130.550402 -236.624601) (xy 130.550402 -236.571303)
			(xy 130.558345 -236.518599) (xy 130.574055 -236.467669) (xy 130.597181 -236.419648) (xy 130.627205 -236.375611)
			(xy 130.663457 -236.33654) (xy 130.705128 -236.303309) (xy 130.751286 -236.27666) (xy 130.8009 -236.257188)
			(xy 130.852862 -236.245328) (xy 130.906012 -236.241345) (xy 130.959162 -236.245328) (xy 131.011124 -236.257188)
			(xy 131.060738 -236.27666) (xy 131.106896 -236.303309) (xy 131.148567 -236.33654) (xy 131.184819 -236.375611)
			(xy 131.214843 -236.419648) (xy 131.237969 -236.467669) (xy 131.253679 -236.518599) (xy 131.261622 -236.571303)
			(xy 131.26212 -236.597952) (xy 131.261622 -236.624601) (xy 131.490202 -236.624601) (xy 131.490202 -236.571303)
			(xy 131.498145 -236.518599) (xy 131.513855 -236.467669) (xy 131.536981 -236.419648) (xy 131.567005 -236.375611)
			(xy 131.603257 -236.33654) (xy 131.644928 -236.303309) (xy 131.691086 -236.27666) (xy 131.7407 -236.257188)
			(xy 131.792662 -236.245328) (xy 131.845812 -236.241345) (xy 131.898962 -236.245328) (xy 131.950924 -236.257188)
			(xy 132.000538 -236.27666) (xy 132.046696 -236.303309) (xy 132.088367 -236.33654) (xy 132.124619 -236.375611)
			(xy 132.154643 -236.419648) (xy 132.177769 -236.467669) (xy 132.193479 -236.518599) (xy 132.201422 -236.571303)
			(xy 132.20192 -236.597952) (xy 132.201422 -236.624601) (xy 132.430002 -236.624601) (xy 132.430002 -236.571303)
			(xy 132.437945 -236.518599) (xy 132.453655 -236.467669) (xy 132.476781 -236.419648) (xy 132.506805 -236.375611)
			(xy 132.543057 -236.33654) (xy 132.584728 -236.303309) (xy 132.630886 -236.27666) (xy 132.6805 -236.257188)
			(xy 132.732462 -236.245328) (xy 132.785612 -236.241345) (xy 132.838762 -236.245328) (xy 132.890724 -236.257188)
			(xy 132.940338 -236.27666) (xy 132.986496 -236.303309) (xy 133.028167 -236.33654) (xy 133.064419 -236.375611)
			(xy 133.094443 -236.419648) (xy 133.117569 -236.467669) (xy 133.133279 -236.518599) (xy 133.141222 -236.571303)
			(xy 133.14172 -236.597952) (xy 133.141222 -236.624601) (xy 133.370056 -236.624601) (xy 133.370056 -236.571303)
			(xy 133.377999 -236.518599) (xy 133.393709 -236.467669) (xy 133.416835 -236.419648) (xy 133.446859 -236.375611)
			(xy 133.483111 -236.33654) (xy 133.524782 -236.303309) (xy 133.57094 -236.27666) (xy 133.620554 -236.257188)
			(xy 133.672516 -236.245328) (xy 133.725666 -236.241345) (xy 133.778816 -236.245328) (xy 133.830778 -236.257188)
			(xy 133.880392 -236.27666) (xy 133.92655 -236.303309) (xy 133.968221 -236.33654) (xy 134.004473 -236.375611)
			(xy 134.034497 -236.419648) (xy 134.057623 -236.467669) (xy 134.073333 -236.518599) (xy 134.081276 -236.571303)
			(xy 134.081774 -236.597952) (xy 134.081276 -236.624601) (xy 134.309856 -236.624601) (xy 134.309856 -236.571303)
			(xy 134.317799 -236.518599) (xy 134.333509 -236.467669) (xy 134.356635 -236.419648) (xy 134.386659 -236.375611)
			(xy 134.422911 -236.33654) (xy 134.464582 -236.303309) (xy 134.51074 -236.27666) (xy 134.560354 -236.257188)
			(xy 134.612316 -236.245328) (xy 134.665466 -236.241345) (xy 134.718616 -236.245328) (xy 134.770578 -236.257188)
			(xy 134.820192 -236.27666) (xy 134.86635 -236.303309) (xy 134.908021 -236.33654) (xy 134.944273 -236.375611)
			(xy 134.974297 -236.419648) (xy 134.997423 -236.467669) (xy 135.013133 -236.518599) (xy 135.021076 -236.571303)
			(xy 135.021574 -236.597952) (xy 135.021076 -236.624601) (xy 135.013133 -236.677305) (xy 134.997423 -236.728235)
			(xy 134.974297 -236.776256) (xy 134.944273 -236.820293) (xy 134.908021 -236.859364) (xy 134.86635 -236.892595)
			(xy 134.820192 -236.919244) (xy 134.770578 -236.938716) (xy 134.718616 -236.950576) (xy 134.665466 -236.95456)
			(xy 134.612316 -236.950576) (xy 134.560354 -236.938716) (xy 134.51074 -236.919244) (xy 134.464582 -236.892595)
			(xy 134.422911 -236.859364) (xy 134.386659 -236.820293) (xy 134.356635 -236.776256) (xy 134.333509 -236.728235)
			(xy 134.317799 -236.677305) (xy 134.309856 -236.624601) (xy 134.081276 -236.624601) (xy 134.073333 -236.677305)
			(xy 134.057623 -236.728235) (xy 134.034497 -236.776256) (xy 134.004473 -236.820293) (xy 133.968221 -236.859364)
			(xy 133.92655 -236.892595) (xy 133.880392 -236.919244) (xy 133.830778 -236.938716) (xy 133.778816 -236.950576)
			(xy 133.725666 -236.95456) (xy 133.672516 -236.950576) (xy 133.620554 -236.938716) (xy 133.57094 -236.919244)
			(xy 133.524782 -236.892595) (xy 133.483111 -236.859364) (xy 133.446859 -236.820293) (xy 133.416835 -236.776256)
			(xy 133.393709 -236.728235) (xy 133.377999 -236.677305) (xy 133.370056 -236.624601) (xy 133.141222 -236.624601)
			(xy 133.133279 -236.677305) (xy 133.117569 -236.728235) (xy 133.094443 -236.776256) (xy 133.064419 -236.820293)
			(xy 133.028167 -236.859364) (xy 132.986496 -236.892595) (xy 132.940338 -236.919244) (xy 132.890724 -236.938716)
			(xy 132.838762 -236.950576) (xy 132.785612 -236.95456) (xy 132.732462 -236.950576) (xy 132.6805 -236.938716)
			(xy 132.630886 -236.919244) (xy 132.584728 -236.892595) (xy 132.543057 -236.859364) (xy 132.506805 -236.820293)
			(xy 132.476781 -236.776256) (xy 132.453655 -236.728235) (xy 132.437945 -236.677305) (xy 132.430002 -236.624601)
			(xy 132.201422 -236.624601) (xy 132.193479 -236.677305) (xy 132.177769 -236.728235) (xy 132.154643 -236.776256)
			(xy 132.124619 -236.820293) (xy 132.088367 -236.859364) (xy 132.046696 -236.892595) (xy 132.000538 -236.919244)
			(xy 131.950924 -236.938716) (xy 131.898962 -236.950576) (xy 131.845812 -236.95456) (xy 131.792662 -236.950576)
			(xy 131.7407 -236.938716) (xy 131.691086 -236.919244) (xy 131.644928 -236.892595) (xy 131.603257 -236.859364)
			(xy 131.567005 -236.820293) (xy 131.536981 -236.776256) (xy 131.513855 -236.728235) (xy 131.498145 -236.677305)
			(xy 131.490202 -236.624601) (xy 131.261622 -236.624601) (xy 131.253679 -236.677305) (xy 131.237969 -236.728235)
			(xy 131.214843 -236.776256) (xy 131.184819 -236.820293) (xy 131.148567 -236.859364) (xy 131.106896 -236.892595)
			(xy 131.060738 -236.919244) (xy 131.011124 -236.938716) (xy 130.959162 -236.950576) (xy 130.906012 -236.95456)
			(xy 130.852862 -236.950576) (xy 130.8009 -236.938716) (xy 130.751286 -236.919244) (xy 130.705128 -236.892595)
			(xy 130.663457 -236.859364) (xy 130.627205 -236.820293) (xy 130.597181 -236.776256) (xy 130.574055 -236.728235)
			(xy 130.558345 -236.677305) (xy 130.550402 -236.624601) (xy 130.321822 -236.624601) (xy 130.313879 -236.677305)
			(xy 130.298169 -236.728235) (xy 130.275043 -236.776256) (xy 130.245019 -236.820293) (xy 130.208767 -236.859364)
			(xy 130.167096 -236.892595) (xy 130.120938 -236.919244) (xy 130.071324 -236.938716) (xy 130.019362 -236.950576)
			(xy 129.966212 -236.95456) (xy 129.913062 -236.950576) (xy 129.8611 -236.938716) (xy 129.811486 -236.919244)
			(xy 129.765328 -236.892595) (xy 129.723657 -236.859364) (xy 129.687405 -236.820293) (xy 129.657381 -236.776256)
			(xy 129.634255 -236.728235) (xy 129.618545 -236.677305) (xy 129.610602 -236.624601) (xy 129.382276 -236.624601)
			(xy 129.374333 -236.677305) (xy 129.358623 -236.728235) (xy 129.335497 -236.776256) (xy 129.305473 -236.820293)
			(xy 129.269221 -236.859364) (xy 129.22755 -236.892595) (xy 129.181392 -236.919244) (xy 129.131778 -236.938716)
			(xy 129.079816 -236.950576) (xy 129.026666 -236.95456) (xy 128.973516 -236.950576) (xy 128.921554 -236.938716)
			(xy 128.87194 -236.919244) (xy 128.825782 -236.892595) (xy 128.784111 -236.859364) (xy 128.747859 -236.820293)
			(xy 128.717835 -236.776256) (xy 128.694709 -236.728235) (xy 128.678999 -236.677305) (xy 128.671056 -236.624601)
			(xy 128.442222 -236.624601) (xy 128.434279 -236.677305) (xy 128.418569 -236.728235) (xy 128.395443 -236.776256)
			(xy 128.365419 -236.820293) (xy 128.329167 -236.859364) (xy 128.287496 -236.892595) (xy 128.241338 -236.919244)
			(xy 128.191724 -236.938716) (xy 128.139762 -236.950576) (xy 128.086612 -236.95456) (xy 128.033462 -236.950576)
			(xy 127.9815 -236.938716) (xy 127.931886 -236.919244) (xy 127.885728 -236.892595) (xy 127.844057 -236.859364)
			(xy 127.807805 -236.820293) (xy 127.777781 -236.776256) (xy 127.754655 -236.728235) (xy 127.738945 -236.677305)
			(xy 127.731002 -236.624601) (xy 127.502422 -236.624601) (xy 127.494479 -236.677305) (xy 127.478769 -236.728235)
			(xy 127.455643 -236.776256) (xy 127.425619 -236.820293) (xy 127.389367 -236.859364) (xy 127.347696 -236.892595)
			(xy 127.301538 -236.919244) (xy 127.251924 -236.938716) (xy 127.199962 -236.950576) (xy 127.146812 -236.95456)
			(xy 127.093662 -236.950576) (xy 127.0417 -236.938716) (xy 126.992086 -236.919244) (xy 126.945928 -236.892595)
			(xy 126.904257 -236.859364) (xy 126.868005 -236.820293) (xy 126.837981 -236.776256) (xy 126.814855 -236.728235)
			(xy 126.799145 -236.677305) (xy 126.791202 -236.624601) (xy 126.562622 -236.624601) (xy 126.554679 -236.677305)
			(xy 126.538969 -236.728235) (xy 126.515843 -236.776256) (xy 126.485819 -236.820293) (xy 126.449567 -236.859364)
			(xy 126.407896 -236.892595) (xy 126.361738 -236.919244) (xy 126.312124 -236.938716) (xy 126.260162 -236.950576)
			(xy 126.207012 -236.95456) (xy 126.153862 -236.950576) (xy 126.1019 -236.938716) (xy 126.052286 -236.919244)
			(xy 126.006128 -236.892595) (xy 125.964457 -236.859364) (xy 125.928205 -236.820293) (xy 125.898181 -236.776256)
			(xy 125.875055 -236.728235) (xy 125.859345 -236.677305) (xy 125.851402 -236.624601) (xy 125.622822 -236.624601)
			(xy 125.614879 -236.677305) (xy 125.599169 -236.728235) (xy 125.576043 -236.776256) (xy 125.546019 -236.820293)
			(xy 125.509767 -236.859364) (xy 125.468096 -236.892595) (xy 125.421938 -236.919244) (xy 125.372324 -236.938716)
			(xy 125.320362 -236.950576) (xy 125.267212 -236.95456) (xy 125.214062 -236.950576) (xy 125.1621 -236.938716)
			(xy 125.112486 -236.919244) (xy 125.066328 -236.892595) (xy 125.024657 -236.859364) (xy 124.988405 -236.820293)
			(xy 124.958381 -236.776256) (xy 124.935255 -236.728235) (xy 124.919545 -236.677305) (xy 124.911602 -236.624601)
			(xy 124.683022 -236.624601) (xy 124.675079 -236.677305) (xy 124.659369 -236.728235) (xy 124.636243 -236.776256)
			(xy 124.606219 -236.820293) (xy 124.569967 -236.859364) (xy 124.528296 -236.892595) (xy 124.482138 -236.919244)
			(xy 124.432524 -236.938716) (xy 124.380562 -236.950576) (xy 124.327412 -236.95456) (xy 124.274262 -236.950576)
			(xy 124.2223 -236.938716) (xy 124.172686 -236.919244) (xy 124.126528 -236.892595) (xy 124.084857 -236.859364)
			(xy 124.048605 -236.820293) (xy 124.018581 -236.776256) (xy 123.995455 -236.728235) (xy 123.979745 -236.677305)
			(xy 123.971802 -236.624601) (xy 123.743222 -236.624601) (xy 123.735279 -236.677305) (xy 123.719569 -236.728235)
			(xy 123.696443 -236.776256) (xy 123.666419 -236.820293) (xy 123.630167 -236.859364) (xy 123.588496 -236.892595)
			(xy 123.542338 -236.919244) (xy 123.492724 -236.938716) (xy 123.440762 -236.950576) (xy 123.387612 -236.95456)
			(xy 123.334462 -236.950576) (xy 123.2825 -236.938716) (xy 123.232886 -236.919244) (xy 123.186728 -236.892595)
			(xy 123.145057 -236.859364) (xy 123.108805 -236.820293) (xy 123.078781 -236.776256) (xy 123.055655 -236.728235)
			(xy 123.039945 -236.677305) (xy 123.032002 -236.624601) (xy 122.803676 -236.624601) (xy 122.795733 -236.677305)
			(xy 122.780023 -236.728235) (xy 122.756897 -236.776256) (xy 122.726873 -236.820293) (xy 122.690621 -236.859364)
			(xy 122.64895 -236.892595) (xy 122.602792 -236.919244) (xy 122.553178 -236.938716) (xy 122.501216 -236.950576)
			(xy 122.448066 -236.95456) (xy 122.394916 -236.950576) (xy 122.342954 -236.938716) (xy 122.29334 -236.919244)
			(xy 122.247182 -236.892595) (xy 122.205511 -236.859364) (xy 122.169259 -236.820293) (xy 122.139235 -236.776256)
			(xy 122.116109 -236.728235) (xy 122.100399 -236.677305) (xy 122.092456 -236.624601) (xy 121.862566 -236.624601)
			(xy 121.860577 -236.651141) (xy 121.848719 -236.703095) (xy 121.82925 -236.752702) (xy 121.802605 -236.798853)
			(xy 121.76938 -236.840518) (xy 121.730316 -236.876765) (xy 121.686286 -236.906785) (xy 121.638274 -236.929908)
			(xy 121.587352 -236.945617) (xy 121.534657 -236.953561) (xy 121.508012 -236.95406) (xy 121.481426 -236.953656)
			(xy 121.428844 -236.945766) (xy 121.37802 -236.930143) (xy 121.330085 -236.907136) (xy 121.286104 -236.877255)
			(xy 121.247056 -236.841167) (xy 121.213809 -236.799673) (xy 121.187102 -236.753695) (xy 121.16753 -236.704258)
			(xy 121.161048 -236.67847) (xy 121.156992 -236.663421) (xy 121.14114 -236.636604) (xy 121.117932 -236.615823)
			(xy 121.089534 -236.603017) (xy 121.058595 -236.59938) (xy 121.043192 -236.601762) (xy 121.026649 -236.604714)
			(xy 120.993193 -236.607897) (xy 120.97639 -236.608112) (xy 120.949741 -236.607606) (xy 120.89704 -236.599661)
			(xy 120.846111 -236.58395) (xy 120.798092 -236.560824) (xy 120.754057 -236.5308) (xy 120.714988 -236.494548)
			(xy 120.681758 -236.452879) (xy 120.65511 -236.406722) (xy 120.635639 -236.357109) (xy 120.623779 -236.305148)
			(xy 120.619796 -236.252) (xy 115.510928 -236.252) (xy 115.543046 -236.270543) (xy 115.584717 -236.303774)
			(xy 115.620969 -236.342845) (xy 115.650993 -236.386882) (xy 115.674119 -236.434903) (xy 115.689829 -236.485833)
			(xy 115.697772 -236.538537) (xy 115.69827 -236.565186) (xy 115.69827 -236.57052) (xy 115.698473 -236.583983)
			(xy 115.705101 -236.61007) (xy 115.718315 -236.63352) (xy 115.737196 -236.652702) (xy 115.760433 -236.666286)
			(xy 115.786412 -236.673326) (xy 115.79987 -236.673644) (xy 118.636034 -236.673644) (xy 119.409443 -237.447053)
			(xy 120.62078 -237.447053) (xy 120.62078 -237.393755) (xy 120.628723 -237.341051) (xy 120.644433 -237.290121)
			(xy 120.667559 -237.2421) (xy 120.697583 -237.198063) (xy 120.733835 -237.158992) (xy 120.775506 -237.125761)
			(xy 120.821664 -237.099112) (xy 120.871278 -237.07964) (xy 120.92324 -237.06778) (xy 120.97639 -237.063797)
			(xy 121.02954 -237.06778) (xy 121.081502 -237.07964) (xy 121.131116 -237.099112) (xy 121.177274 -237.125761)
			(xy 121.218945 -237.158992) (xy 121.255197 -237.198063) (xy 121.285221 -237.2421) (xy 121.308347 -237.290121)
			(xy 121.324057 -237.341051) (xy 121.332 -237.393755) (xy 121.332498 -237.420404) (xy 121.332166 -237.438163)
			(xy 121.622556 -237.438163) (xy 121.622556 -237.384865) (xy 121.630499 -237.332161) (xy 121.646209 -237.281231)
			(xy 121.669335 -237.23321) (xy 121.699359 -237.189173) (xy 121.735611 -237.150102) (xy 121.777282 -237.116871)
			(xy 121.82344 -237.090222) (xy 121.873054 -237.07075) (xy 121.925016 -237.05889) (xy 121.978166 -237.054907)
			(xy 122.031316 -237.05889) (xy 122.083278 -237.07075) (xy 122.132892 -237.090222) (xy 122.17905 -237.116871)
			(xy 122.220721 -237.150102) (xy 122.256973 -237.189173) (xy 122.286997 -237.23321) (xy 122.310123 -237.281231)
			(xy 122.325833 -237.332161) (xy 122.333776 -237.384865) (xy 122.334274 -237.411514) (xy 122.333776 -237.438163)
			(xy 122.562356 -237.438163) (xy 122.562356 -237.384865) (xy 122.570299 -237.332161) (xy 122.586009 -237.281231)
			(xy 122.609135 -237.23321) (xy 122.639159 -237.189173) (xy 122.675411 -237.150102) (xy 122.717082 -237.116871)
			(xy 122.76324 -237.090222) (xy 122.812854 -237.07075) (xy 122.864816 -237.05889) (xy 122.917966 -237.054907)
			(xy 122.971116 -237.05889) (xy 123.023078 -237.07075) (xy 123.072692 -237.090222) (xy 123.11885 -237.116871)
			(xy 123.160521 -237.150102) (xy 123.196773 -237.189173) (xy 123.226797 -237.23321) (xy 123.249923 -237.281231)
			(xy 123.265633 -237.332161) (xy 123.273576 -237.384865) (xy 123.274074 -237.411514) (xy 123.273576 -237.438163)
			(xy 123.502156 -237.438163) (xy 123.502156 -237.384865) (xy 123.510099 -237.332161) (xy 123.525809 -237.281231)
			(xy 123.548935 -237.23321) (xy 123.578959 -237.189173) (xy 123.615211 -237.150102) (xy 123.656882 -237.116871)
			(xy 123.70304 -237.090222) (xy 123.752654 -237.07075) (xy 123.804616 -237.05889) (xy 123.857766 -237.054907)
			(xy 123.910916 -237.05889) (xy 123.962878 -237.07075) (xy 124.012492 -237.090222) (xy 124.05865 -237.116871)
			(xy 124.100321 -237.150102) (xy 124.136573 -237.189173) (xy 124.166597 -237.23321) (xy 124.189723 -237.281231)
			(xy 124.205433 -237.332161) (xy 124.213376 -237.384865) (xy 124.213874 -237.411514) (xy 124.213376 -237.438163)
			(xy 124.441956 -237.438163) (xy 124.441956 -237.384865) (xy 124.449899 -237.332161) (xy 124.465609 -237.281231)
			(xy 124.488735 -237.23321) (xy 124.518759 -237.189173) (xy 124.555011 -237.150102) (xy 124.596682 -237.116871)
			(xy 124.64284 -237.090222) (xy 124.692454 -237.07075) (xy 124.744416 -237.05889) (xy 124.797566 -237.054907)
			(xy 124.850716 -237.05889) (xy 124.902678 -237.07075) (xy 124.952292 -237.090222) (xy 124.99845 -237.116871)
			(xy 125.040121 -237.150102) (xy 125.076373 -237.189173) (xy 125.106397 -237.23321) (xy 125.129523 -237.281231)
			(xy 125.145233 -237.332161) (xy 125.153176 -237.384865) (xy 125.153674 -237.411514) (xy 125.153176 -237.438163)
			(xy 125.381756 -237.438163) (xy 125.381756 -237.384865) (xy 125.389699 -237.332161) (xy 125.405409 -237.281231)
			(xy 125.428535 -237.23321) (xy 125.458559 -237.189173) (xy 125.494811 -237.150102) (xy 125.536482 -237.116871)
			(xy 125.58264 -237.090222) (xy 125.632254 -237.07075) (xy 125.684216 -237.05889) (xy 125.737366 -237.054907)
			(xy 125.790516 -237.05889) (xy 125.842478 -237.07075) (xy 125.892092 -237.090222) (xy 125.93825 -237.116871)
			(xy 125.979921 -237.150102) (xy 126.016173 -237.189173) (xy 126.046197 -237.23321) (xy 126.069323 -237.281231)
			(xy 126.085033 -237.332161) (xy 126.092976 -237.384865) (xy 126.093474 -237.411514) (xy 126.092976 -237.438163)
			(xy 126.321556 -237.438163) (xy 126.321556 -237.384865) (xy 126.329499 -237.332161) (xy 126.345209 -237.281231)
			(xy 126.368335 -237.23321) (xy 126.398359 -237.189173) (xy 126.434611 -237.150102) (xy 126.476282 -237.116871)
			(xy 126.52244 -237.090222) (xy 126.572054 -237.07075) (xy 126.624016 -237.05889) (xy 126.677166 -237.054907)
			(xy 126.730316 -237.05889) (xy 126.782278 -237.07075) (xy 126.831892 -237.090222) (xy 126.87805 -237.116871)
			(xy 126.919721 -237.150102) (xy 126.955973 -237.189173) (xy 126.985997 -237.23321) (xy 127.009123 -237.281231)
			(xy 127.024833 -237.332161) (xy 127.032776 -237.384865) (xy 127.033274 -237.411514) (xy 127.032776 -237.438163)
			(xy 127.261356 -237.438163) (xy 127.261356 -237.384865) (xy 127.269299 -237.332161) (xy 127.285009 -237.281231)
			(xy 127.308135 -237.23321) (xy 127.338159 -237.189173) (xy 127.374411 -237.150102) (xy 127.416082 -237.116871)
			(xy 127.46224 -237.090222) (xy 127.511854 -237.07075) (xy 127.563816 -237.05889) (xy 127.616966 -237.054907)
			(xy 127.670116 -237.05889) (xy 127.722078 -237.07075) (xy 127.771692 -237.090222) (xy 127.81785 -237.116871)
			(xy 127.859521 -237.150102) (xy 127.895773 -237.189173) (xy 127.925797 -237.23321) (xy 127.948923 -237.281231)
			(xy 127.964633 -237.332161) (xy 127.972576 -237.384865) (xy 127.973074 -237.411514) (xy 127.972576 -237.438163)
			(xy 128.201156 -237.438163) (xy 128.201156 -237.384865) (xy 128.209099 -237.332161) (xy 128.224809 -237.281231)
			(xy 128.247935 -237.23321) (xy 128.277959 -237.189173) (xy 128.314211 -237.150102) (xy 128.355882 -237.116871)
			(xy 128.40204 -237.090222) (xy 128.451654 -237.07075) (xy 128.503616 -237.05889) (xy 128.556766 -237.054907)
			(xy 128.609916 -237.05889) (xy 128.661878 -237.07075) (xy 128.711492 -237.090222) (xy 128.75765 -237.116871)
			(xy 128.799321 -237.150102) (xy 128.835573 -237.189173) (xy 128.865597 -237.23321) (xy 128.888723 -237.281231)
			(xy 128.904433 -237.332161) (xy 128.912376 -237.384865) (xy 128.912874 -237.411514) (xy 128.912376 -237.438163)
			(xy 129.140956 -237.438163) (xy 129.140956 -237.384865) (xy 129.148899 -237.332161) (xy 129.164609 -237.281231)
			(xy 129.187735 -237.23321) (xy 129.217759 -237.189173) (xy 129.254011 -237.150102) (xy 129.295682 -237.116871)
			(xy 129.34184 -237.090222) (xy 129.391454 -237.07075) (xy 129.443416 -237.05889) (xy 129.496566 -237.054907)
			(xy 129.549716 -237.05889) (xy 129.601678 -237.07075) (xy 129.651292 -237.090222) (xy 129.69745 -237.116871)
			(xy 129.739121 -237.150102) (xy 129.775373 -237.189173) (xy 129.805397 -237.23321) (xy 129.828523 -237.281231)
			(xy 129.844233 -237.332161) (xy 129.852176 -237.384865) (xy 129.852674 -237.411514) (xy 129.852176 -237.438163)
			(xy 130.080756 -237.438163) (xy 130.080756 -237.384865) (xy 130.088699 -237.332161) (xy 130.104409 -237.281231)
			(xy 130.127535 -237.23321) (xy 130.157559 -237.189173) (xy 130.193811 -237.150102) (xy 130.235482 -237.116871)
			(xy 130.28164 -237.090222) (xy 130.331254 -237.07075) (xy 130.383216 -237.05889) (xy 130.436366 -237.054907)
			(xy 130.489516 -237.05889) (xy 130.541478 -237.07075) (xy 130.591092 -237.090222) (xy 130.63725 -237.116871)
			(xy 130.678921 -237.150102) (xy 130.715173 -237.189173) (xy 130.745197 -237.23321) (xy 130.768323 -237.281231)
			(xy 130.784033 -237.332161) (xy 130.791976 -237.384865) (xy 130.792474 -237.411514) (xy 130.791976 -237.438163)
			(xy 131.020556 -237.438163) (xy 131.020556 -237.384865) (xy 131.028499 -237.332161) (xy 131.044209 -237.281231)
			(xy 131.067335 -237.23321) (xy 131.097359 -237.189173) (xy 131.133611 -237.150102) (xy 131.175282 -237.116871)
			(xy 131.22144 -237.090222) (xy 131.271054 -237.07075) (xy 131.323016 -237.05889) (xy 131.376166 -237.054907)
			(xy 131.429316 -237.05889) (xy 131.481278 -237.07075) (xy 131.530892 -237.090222) (xy 131.57705 -237.116871)
			(xy 131.618721 -237.150102) (xy 131.654973 -237.189173) (xy 131.684997 -237.23321) (xy 131.708123 -237.281231)
			(xy 131.723833 -237.332161) (xy 131.731776 -237.384865) (xy 131.732274 -237.411514) (xy 131.731776 -237.438163)
			(xy 131.960356 -237.438163) (xy 131.960356 -237.384865) (xy 131.968299 -237.332161) (xy 131.984009 -237.281231)
			(xy 132.007135 -237.23321) (xy 132.037159 -237.189173) (xy 132.073411 -237.150102) (xy 132.115082 -237.116871)
			(xy 132.16124 -237.090222) (xy 132.210854 -237.07075) (xy 132.262816 -237.05889) (xy 132.315966 -237.054907)
			(xy 132.369116 -237.05889) (xy 132.421078 -237.07075) (xy 132.470692 -237.090222) (xy 132.51685 -237.116871)
			(xy 132.558521 -237.150102) (xy 132.594773 -237.189173) (xy 132.624797 -237.23321) (xy 132.647923 -237.281231)
			(xy 132.663633 -237.332161) (xy 132.671576 -237.384865) (xy 132.672074 -237.411514) (xy 132.671576 -237.438163)
			(xy 132.899902 -237.438163) (xy 132.899902 -237.384865) (xy 132.907845 -237.332161) (xy 132.923555 -237.281231)
			(xy 132.946681 -237.23321) (xy 132.976705 -237.189173) (xy 133.012957 -237.150102) (xy 133.054628 -237.116871)
			(xy 133.100786 -237.090222) (xy 133.1504 -237.07075) (xy 133.202362 -237.05889) (xy 133.255512 -237.054907)
			(xy 133.308662 -237.05889) (xy 133.360624 -237.07075) (xy 133.410238 -237.090222) (xy 133.456396 -237.116871)
			(xy 133.498067 -237.150102) (xy 133.534319 -237.189173) (xy 133.564343 -237.23321) (xy 133.587469 -237.281231)
			(xy 133.603179 -237.332161) (xy 133.611122 -237.384865) (xy 133.61162 -237.411514) (xy 133.611122 -237.438163)
			(xy 133.839956 -237.438163) (xy 133.839956 -237.384865) (xy 133.847899 -237.332161) (xy 133.863609 -237.281231)
			(xy 133.886735 -237.23321) (xy 133.916759 -237.189173) (xy 133.953011 -237.150102) (xy 133.994682 -237.116871)
			(xy 134.04084 -237.090222) (xy 134.090454 -237.07075) (xy 134.142416 -237.05889) (xy 134.195566 -237.054907)
			(xy 134.248716 -237.05889) (xy 134.300678 -237.07075) (xy 134.350292 -237.090222) (xy 134.39645 -237.116871)
			(xy 134.438121 -237.150102) (xy 134.474373 -237.189173) (xy 134.504397 -237.23321) (xy 134.527523 -237.281231)
			(xy 134.543233 -237.332161) (xy 134.551176 -237.384865) (xy 134.551674 -237.411514) (xy 134.551176 -237.438163)
			(xy 134.543233 -237.490867) (xy 134.527523 -237.541797) (xy 134.504397 -237.589818) (xy 134.474373 -237.633855)
			(xy 134.438121 -237.672926) (xy 134.39645 -237.706157) (xy 134.350292 -237.732806) (xy 134.300678 -237.752278)
			(xy 134.248716 -237.764138) (xy 134.195566 -237.768122) (xy 134.142416 -237.764138) (xy 134.090454 -237.752278)
			(xy 134.04084 -237.732806) (xy 133.994682 -237.706157) (xy 133.953011 -237.672926) (xy 133.916759 -237.633855)
			(xy 133.886735 -237.589818) (xy 133.863609 -237.541797) (xy 133.847899 -237.490867) (xy 133.839956 -237.438163)
			(xy 133.611122 -237.438163) (xy 133.603179 -237.490867) (xy 133.587469 -237.541797) (xy 133.564343 -237.589818)
			(xy 133.534319 -237.633855) (xy 133.498067 -237.672926) (xy 133.456396 -237.706157) (xy 133.410238 -237.732806)
			(xy 133.360624 -237.752278) (xy 133.308662 -237.764138) (xy 133.255512 -237.768122) (xy 133.202362 -237.764138)
			(xy 133.1504 -237.752278) (xy 133.100786 -237.732806) (xy 133.054628 -237.706157) (xy 133.012957 -237.672926)
			(xy 132.976705 -237.633855) (xy 132.946681 -237.589818) (xy 132.923555 -237.541797) (xy 132.907845 -237.490867)
			(xy 132.899902 -237.438163) (xy 132.671576 -237.438163) (xy 132.663633 -237.490867) (xy 132.647923 -237.541797)
			(xy 132.624797 -237.589818) (xy 132.594773 -237.633855) (xy 132.558521 -237.672926) (xy 132.51685 -237.706157)
			(xy 132.470692 -237.732806) (xy 132.421078 -237.752278) (xy 132.369116 -237.764138) (xy 132.315966 -237.768122)
			(xy 132.262816 -237.764138) (xy 132.210854 -237.752278) (xy 132.16124 -237.732806) (xy 132.115082 -237.706157)
			(xy 132.073411 -237.672926) (xy 132.037159 -237.633855) (xy 132.007135 -237.589818) (xy 131.984009 -237.541797)
			(xy 131.968299 -237.490867) (xy 131.960356 -237.438163) (xy 131.731776 -237.438163) (xy 131.723833 -237.490867)
			(xy 131.708123 -237.541797) (xy 131.684997 -237.589818) (xy 131.654973 -237.633855) (xy 131.618721 -237.672926)
			(xy 131.57705 -237.706157) (xy 131.530892 -237.732806) (xy 131.481278 -237.752278) (xy 131.429316 -237.764138)
			(xy 131.376166 -237.768122) (xy 131.323016 -237.764138) (xy 131.271054 -237.752278) (xy 131.22144 -237.732806)
			(xy 131.175282 -237.706157) (xy 131.133611 -237.672926) (xy 131.097359 -237.633855) (xy 131.067335 -237.589818)
			(xy 131.044209 -237.541797) (xy 131.028499 -237.490867) (xy 131.020556 -237.438163) (xy 130.791976 -237.438163)
			(xy 130.784033 -237.490867) (xy 130.768323 -237.541797) (xy 130.745197 -237.589818) (xy 130.715173 -237.633855)
			(xy 130.678921 -237.672926) (xy 130.63725 -237.706157) (xy 130.591092 -237.732806) (xy 130.541478 -237.752278)
			(xy 130.489516 -237.764138) (xy 130.436366 -237.768122) (xy 130.383216 -237.764138) (xy 130.331254 -237.752278)
			(xy 130.28164 -237.732806) (xy 130.235482 -237.706157) (xy 130.193811 -237.672926) (xy 130.157559 -237.633855)
			(xy 130.127535 -237.589818) (xy 130.104409 -237.541797) (xy 130.088699 -237.490867) (xy 130.080756 -237.438163)
			(xy 129.852176 -237.438163) (xy 129.844233 -237.490867) (xy 129.828523 -237.541797) (xy 129.805397 -237.589818)
			(xy 129.775373 -237.633855) (xy 129.739121 -237.672926) (xy 129.69745 -237.706157) (xy 129.651292 -237.732806)
			(xy 129.601678 -237.752278) (xy 129.549716 -237.764138) (xy 129.496566 -237.768122) (xy 129.443416 -237.764138)
			(xy 129.391454 -237.752278) (xy 129.34184 -237.732806) (xy 129.295682 -237.706157) (xy 129.254011 -237.672926)
			(xy 129.217759 -237.633855) (xy 129.187735 -237.589818) (xy 129.164609 -237.541797) (xy 129.148899 -237.490867)
			(xy 129.140956 -237.438163) (xy 128.912376 -237.438163) (xy 128.904433 -237.490867) (xy 128.888723 -237.541797)
			(xy 128.865597 -237.589818) (xy 128.835573 -237.633855) (xy 128.799321 -237.672926) (xy 128.75765 -237.706157)
			(xy 128.711492 -237.732806) (xy 128.661878 -237.752278) (xy 128.609916 -237.764138) (xy 128.556766 -237.768122)
			(xy 128.503616 -237.764138) (xy 128.451654 -237.752278) (xy 128.40204 -237.732806) (xy 128.355882 -237.706157)
			(xy 128.314211 -237.672926) (xy 128.277959 -237.633855) (xy 128.247935 -237.589818) (xy 128.224809 -237.541797)
			(xy 128.209099 -237.490867) (xy 128.201156 -237.438163) (xy 127.972576 -237.438163) (xy 127.964633 -237.490867)
			(xy 127.948923 -237.541797) (xy 127.925797 -237.589818) (xy 127.895773 -237.633855) (xy 127.859521 -237.672926)
			(xy 127.81785 -237.706157) (xy 127.771692 -237.732806) (xy 127.722078 -237.752278) (xy 127.670116 -237.764138)
			(xy 127.616966 -237.768122) (xy 127.563816 -237.764138) (xy 127.511854 -237.752278) (xy 127.46224 -237.732806)
			(xy 127.416082 -237.706157) (xy 127.374411 -237.672926) (xy 127.338159 -237.633855) (xy 127.308135 -237.589818)
			(xy 127.285009 -237.541797) (xy 127.269299 -237.490867) (xy 127.261356 -237.438163) (xy 127.032776 -237.438163)
			(xy 127.024833 -237.490867) (xy 127.009123 -237.541797) (xy 126.985997 -237.589818) (xy 126.955973 -237.633855)
			(xy 126.919721 -237.672926) (xy 126.87805 -237.706157) (xy 126.831892 -237.732806) (xy 126.782278 -237.752278)
			(xy 126.730316 -237.764138) (xy 126.677166 -237.768122) (xy 126.624016 -237.764138) (xy 126.572054 -237.752278)
			(xy 126.52244 -237.732806) (xy 126.476282 -237.706157) (xy 126.434611 -237.672926) (xy 126.398359 -237.633855)
			(xy 126.368335 -237.589818) (xy 126.345209 -237.541797) (xy 126.329499 -237.490867) (xy 126.321556 -237.438163)
			(xy 126.092976 -237.438163) (xy 126.085033 -237.490867) (xy 126.069323 -237.541797) (xy 126.046197 -237.589818)
			(xy 126.016173 -237.633855) (xy 125.979921 -237.672926) (xy 125.93825 -237.706157) (xy 125.892092 -237.732806)
			(xy 125.842478 -237.752278) (xy 125.790516 -237.764138) (xy 125.737366 -237.768122) (xy 125.684216 -237.764138)
			(xy 125.632254 -237.752278) (xy 125.58264 -237.732806) (xy 125.536482 -237.706157) (xy 125.494811 -237.672926)
			(xy 125.458559 -237.633855) (xy 125.428535 -237.589818) (xy 125.405409 -237.541797) (xy 125.389699 -237.490867)
			(xy 125.381756 -237.438163) (xy 125.153176 -237.438163) (xy 125.145233 -237.490867) (xy 125.129523 -237.541797)
			(xy 125.106397 -237.589818) (xy 125.076373 -237.633855) (xy 125.040121 -237.672926) (xy 124.99845 -237.706157)
			(xy 124.952292 -237.732806) (xy 124.902678 -237.752278) (xy 124.850716 -237.764138) (xy 124.797566 -237.768122)
			(xy 124.744416 -237.764138) (xy 124.692454 -237.752278) (xy 124.64284 -237.732806) (xy 124.596682 -237.706157)
			(xy 124.555011 -237.672926) (xy 124.518759 -237.633855) (xy 124.488735 -237.589818) (xy 124.465609 -237.541797)
			(xy 124.449899 -237.490867) (xy 124.441956 -237.438163) (xy 124.213376 -237.438163) (xy 124.205433 -237.490867)
			(xy 124.189723 -237.541797) (xy 124.166597 -237.589818) (xy 124.136573 -237.633855) (xy 124.100321 -237.672926)
			(xy 124.05865 -237.706157) (xy 124.012492 -237.732806) (xy 123.962878 -237.752278) (xy 123.910916 -237.764138)
			(xy 123.857766 -237.768122) (xy 123.804616 -237.764138) (xy 123.752654 -237.752278) (xy 123.70304 -237.732806)
			(xy 123.656882 -237.706157) (xy 123.615211 -237.672926) (xy 123.578959 -237.633855) (xy 123.548935 -237.589818)
			(xy 123.525809 -237.541797) (xy 123.510099 -237.490867) (xy 123.502156 -237.438163) (xy 123.273576 -237.438163)
			(xy 123.265633 -237.490867) (xy 123.249923 -237.541797) (xy 123.226797 -237.589818) (xy 123.196773 -237.633855)
			(xy 123.160521 -237.672926) (xy 123.11885 -237.706157) (xy 123.072692 -237.732806) (xy 123.023078 -237.752278)
			(xy 122.971116 -237.764138) (xy 122.917966 -237.768122) (xy 122.864816 -237.764138) (xy 122.812854 -237.752278)
			(xy 122.76324 -237.732806) (xy 122.717082 -237.706157) (xy 122.675411 -237.672926) (xy 122.639159 -237.633855)
			(xy 122.609135 -237.589818) (xy 122.586009 -237.541797) (xy 122.570299 -237.490867) (xy 122.562356 -237.438163)
			(xy 122.333776 -237.438163) (xy 122.325833 -237.490867) (xy 122.310123 -237.541797) (xy 122.286997 -237.589818)
			(xy 122.256973 -237.633855) (xy 122.220721 -237.672926) (xy 122.17905 -237.706157) (xy 122.132892 -237.732806)
			(xy 122.083278 -237.752278) (xy 122.031316 -237.764138) (xy 121.978166 -237.768122) (xy 121.925016 -237.764138)
			(xy 121.873054 -237.752278) (xy 121.82344 -237.732806) (xy 121.777282 -237.706157) (xy 121.735611 -237.672926)
			(xy 121.699359 -237.633855) (xy 121.669335 -237.589818) (xy 121.646209 -237.541797) (xy 121.630499 -237.490867)
			(xy 121.622556 -237.438163) (xy 121.332166 -237.438163) (xy 121.332 -237.447053) (xy 121.324057 -237.499757)
			(xy 121.308347 -237.550687) (xy 121.285221 -237.598708) (xy 121.255197 -237.642745) (xy 121.218945 -237.681816)
			(xy 121.177274 -237.715047) (xy 121.131116 -237.741696) (xy 121.081502 -237.761168) (xy 121.02954 -237.773028)
			(xy 120.97639 -237.777012) (xy 120.92324 -237.773028) (xy 120.871278 -237.761168) (xy 120.821664 -237.741696)
			(xy 120.775506 -237.715047) (xy 120.733835 -237.681816) (xy 120.697583 -237.642745) (xy 120.667559 -237.598708)
			(xy 120.644433 -237.550687) (xy 120.628723 -237.499757) (xy 120.62078 -237.447053) (xy 119.409443 -237.447053)
			(xy 120.214623 -238.252233) (xy 121.152402 -238.252233) (xy 121.152402 -238.198935) (xy 121.160345 -238.146231)
			(xy 121.176055 -238.095301) (xy 121.199181 -238.04728) (xy 121.229205 -238.003243) (xy 121.265457 -237.964172)
			(xy 121.307128 -237.930941) (xy 121.353286 -237.904292) (xy 121.4029 -237.88482) (xy 121.454862 -237.87296)
			(xy 121.508012 -237.868977) (xy 121.561162 -237.87296) (xy 121.613124 -237.88482) (xy 121.662738 -237.904292)
			(xy 121.708896 -237.930941) (xy 121.750567 -237.964172) (xy 121.786819 -238.003243) (xy 121.816843 -238.04728)
			(xy 121.839969 -238.095301) (xy 121.855679 -238.146231) (xy 121.863622 -238.198935) (xy 121.86412 -238.225584)
			(xy 121.863622 -238.252233) (xy 122.092202 -238.252233) (xy 122.092202 -238.198935) (xy 122.100145 -238.146231)
			(xy 122.115855 -238.095301) (xy 122.138981 -238.04728) (xy 122.169005 -238.003243) (xy 122.205257 -237.964172)
			(xy 122.246928 -237.930941) (xy 122.293086 -237.904292) (xy 122.3427 -237.88482) (xy 122.394662 -237.87296)
			(xy 122.447812 -237.868977) (xy 122.500962 -237.87296) (xy 122.552924 -237.88482) (xy 122.602538 -237.904292)
			(xy 122.648696 -237.930941) (xy 122.690367 -237.964172) (xy 122.726619 -238.003243) (xy 122.756643 -238.04728)
			(xy 122.779769 -238.095301) (xy 122.795479 -238.146231) (xy 122.803422 -238.198935) (xy 122.80392 -238.225584)
			(xy 122.803422 -238.252233) (xy 123.032002 -238.252233) (xy 123.032002 -238.198935) (xy 123.039945 -238.146231)
			(xy 123.055655 -238.095301) (xy 123.078781 -238.04728) (xy 123.108805 -238.003243) (xy 123.145057 -237.964172)
			(xy 123.186728 -237.930941) (xy 123.232886 -237.904292) (xy 123.2825 -237.88482) (xy 123.334462 -237.87296)
			(xy 123.387612 -237.868977) (xy 123.440762 -237.87296) (xy 123.492724 -237.88482) (xy 123.542338 -237.904292)
			(xy 123.588496 -237.930941) (xy 123.630167 -237.964172) (xy 123.666419 -238.003243) (xy 123.696443 -238.04728)
			(xy 123.719569 -238.095301) (xy 123.735279 -238.146231) (xy 123.743222 -238.198935) (xy 123.74372 -238.225584)
			(xy 123.743222 -238.252233) (xy 123.971802 -238.252233) (xy 123.971802 -238.198935) (xy 123.979745 -238.146231)
			(xy 123.995455 -238.095301) (xy 124.018581 -238.04728) (xy 124.048605 -238.003243) (xy 124.084857 -237.964172)
			(xy 124.126528 -237.930941) (xy 124.172686 -237.904292) (xy 124.2223 -237.88482) (xy 124.274262 -237.87296)
			(xy 124.327412 -237.868977) (xy 124.380562 -237.87296) (xy 124.432524 -237.88482) (xy 124.482138 -237.904292)
			(xy 124.528296 -237.930941) (xy 124.569967 -237.964172) (xy 124.606219 -238.003243) (xy 124.636243 -238.04728)
			(xy 124.659369 -238.095301) (xy 124.675079 -238.146231) (xy 124.683022 -238.198935) (xy 124.68352 -238.225584)
			(xy 124.683022 -238.252233) (xy 124.911602 -238.252233) (xy 124.911602 -238.198935) (xy 124.919545 -238.146231)
			(xy 124.935255 -238.095301) (xy 124.958381 -238.04728) (xy 124.988405 -238.003243) (xy 125.024657 -237.964172)
			(xy 125.066328 -237.930941) (xy 125.112486 -237.904292) (xy 125.1621 -237.88482) (xy 125.214062 -237.87296)
			(xy 125.267212 -237.868977) (xy 125.320362 -237.87296) (xy 125.372324 -237.88482) (xy 125.421938 -237.904292)
			(xy 125.468096 -237.930941) (xy 125.509767 -237.964172) (xy 125.546019 -238.003243) (xy 125.576043 -238.04728)
			(xy 125.599169 -238.095301) (xy 125.614879 -238.146231) (xy 125.622822 -238.198935) (xy 125.62332 -238.225584)
			(xy 125.622822 -238.252233) (xy 125.851656 -238.252233) (xy 125.851656 -238.198935) (xy 125.859599 -238.146231)
			(xy 125.875309 -238.095301) (xy 125.898435 -238.04728) (xy 125.928459 -238.003243) (xy 125.964711 -237.964172)
			(xy 126.006382 -237.930941) (xy 126.05254 -237.904292) (xy 126.102154 -237.88482) (xy 126.154116 -237.87296)
			(xy 126.207266 -237.868977) (xy 126.260416 -237.87296) (xy 126.312378 -237.88482) (xy 126.361992 -237.904292)
			(xy 126.40815 -237.930941) (xy 126.449821 -237.964172) (xy 126.486073 -238.003243) (xy 126.516097 -238.04728)
			(xy 126.539223 -238.095301) (xy 126.554933 -238.146231) (xy 126.562876 -238.198935) (xy 126.563374 -238.225584)
			(xy 126.562876 -238.252233) (xy 126.791202 -238.252233) (xy 126.791202 -238.198935) (xy 126.799145 -238.146231)
			(xy 126.814855 -238.095301) (xy 126.837981 -238.04728) (xy 126.868005 -238.003243) (xy 126.904257 -237.964172)
			(xy 126.945928 -237.930941) (xy 126.992086 -237.904292) (xy 127.0417 -237.88482) (xy 127.093662 -237.87296)
			(xy 127.146812 -237.868977) (xy 127.199962 -237.87296) (xy 127.251924 -237.88482) (xy 127.301538 -237.904292)
			(xy 127.347696 -237.930941) (xy 127.389367 -237.964172) (xy 127.425619 -238.003243) (xy 127.455643 -238.04728)
			(xy 127.478769 -238.095301) (xy 127.494479 -238.146231) (xy 127.502422 -238.198935) (xy 127.50292 -238.225584)
			(xy 127.502422 -238.252233) (xy 127.731002 -238.252233) (xy 127.731002 -238.198935) (xy 127.738945 -238.146231)
			(xy 127.754655 -238.095301) (xy 127.777781 -238.04728) (xy 127.807805 -238.003243) (xy 127.844057 -237.964172)
			(xy 127.885728 -237.930941) (xy 127.931886 -237.904292) (xy 127.9815 -237.88482) (xy 128.033462 -237.87296)
			(xy 128.086612 -237.868977) (xy 128.139762 -237.87296) (xy 128.191724 -237.88482) (xy 128.241338 -237.904292)
			(xy 128.287496 -237.930941) (xy 128.329167 -237.964172) (xy 128.365419 -238.003243) (xy 128.395443 -238.04728)
			(xy 128.418569 -238.095301) (xy 128.434279 -238.146231) (xy 128.442222 -238.198935) (xy 128.44272 -238.225584)
			(xy 128.442222 -238.252233) (xy 128.670802 -238.252233) (xy 128.670802 -238.198935) (xy 128.678745 -238.146231)
			(xy 128.694455 -238.095301) (xy 128.717581 -238.04728) (xy 128.747605 -238.003243) (xy 128.783857 -237.964172)
			(xy 128.825528 -237.930941) (xy 128.871686 -237.904292) (xy 128.9213 -237.88482) (xy 128.973262 -237.87296)
			(xy 129.026412 -237.868977) (xy 129.079562 -237.87296) (xy 129.131524 -237.88482) (xy 129.181138 -237.904292)
			(xy 129.227296 -237.930941) (xy 129.268967 -237.964172) (xy 129.305219 -238.003243) (xy 129.335243 -238.04728)
			(xy 129.358369 -238.095301) (xy 129.374079 -238.146231) (xy 129.382022 -238.198935) (xy 129.38252 -238.225584)
			(xy 129.382022 -238.252233) (xy 129.610602 -238.252233) (xy 129.610602 -238.198935) (xy 129.618545 -238.146231)
			(xy 129.634255 -238.095301) (xy 129.657381 -238.04728) (xy 129.687405 -238.003243) (xy 129.723657 -237.964172)
			(xy 129.765328 -237.930941) (xy 129.811486 -237.904292) (xy 129.8611 -237.88482) (xy 129.913062 -237.87296)
			(xy 129.966212 -237.868977) (xy 130.019362 -237.87296) (xy 130.071324 -237.88482) (xy 130.120938 -237.904292)
			(xy 130.167096 -237.930941) (xy 130.208767 -237.964172) (xy 130.245019 -238.003243) (xy 130.275043 -238.04728)
			(xy 130.298169 -238.095301) (xy 130.313879 -238.146231) (xy 130.321822 -238.198935) (xy 130.32232 -238.225584)
			(xy 130.321822 -238.252233) (xy 130.550402 -238.252233) (xy 130.550402 -238.198935) (xy 130.558345 -238.146231)
			(xy 130.574055 -238.095301) (xy 130.597181 -238.04728) (xy 130.627205 -238.003243) (xy 130.663457 -237.964172)
			(xy 130.705128 -237.930941) (xy 130.751286 -237.904292) (xy 130.8009 -237.88482) (xy 130.852862 -237.87296)
			(xy 130.906012 -237.868977) (xy 130.959162 -237.87296) (xy 131.011124 -237.88482) (xy 131.060738 -237.904292)
			(xy 131.106896 -237.930941) (xy 131.148567 -237.964172) (xy 131.184819 -238.003243) (xy 131.214843 -238.04728)
			(xy 131.237969 -238.095301) (xy 131.253679 -238.146231) (xy 131.261622 -238.198935) (xy 131.26212 -238.225584)
			(xy 131.261622 -238.252233) (xy 131.490202 -238.252233) (xy 131.490202 -238.198935) (xy 131.498145 -238.146231)
			(xy 131.513855 -238.095301) (xy 131.536981 -238.04728) (xy 131.567005 -238.003243) (xy 131.603257 -237.964172)
			(xy 131.644928 -237.930941) (xy 131.691086 -237.904292) (xy 131.7407 -237.88482) (xy 131.792662 -237.87296)
			(xy 131.845812 -237.868977) (xy 131.898962 -237.87296) (xy 131.950924 -237.88482) (xy 132.000538 -237.904292)
			(xy 132.046696 -237.930941) (xy 132.088367 -237.964172) (xy 132.124619 -238.003243) (xy 132.154643 -238.04728)
			(xy 132.177769 -238.095301) (xy 132.193479 -238.146231) (xy 132.201422 -238.198935) (xy 132.20192 -238.225584)
			(xy 132.201422 -238.252233) (xy 132.430256 -238.252233) (xy 132.430256 -238.198935) (xy 132.438199 -238.146231)
			(xy 132.453909 -238.095301) (xy 132.477035 -238.04728) (xy 132.507059 -238.003243) (xy 132.543311 -237.964172)
			(xy 132.584982 -237.930941) (xy 132.63114 -237.904292) (xy 132.680754 -237.88482) (xy 132.732716 -237.87296)
			(xy 132.785866 -237.868977) (xy 132.839016 -237.87296) (xy 132.890978 -237.88482) (xy 132.940592 -237.904292)
			(xy 132.98675 -237.930941) (xy 133.028421 -237.964172) (xy 133.064673 -238.003243) (xy 133.094697 -238.04728)
			(xy 133.117823 -238.095301) (xy 133.133533 -238.146231) (xy 133.141476 -238.198935) (xy 133.141974 -238.225584)
			(xy 133.141476 -238.252233) (xy 133.370056 -238.252233) (xy 133.370056 -238.198935) (xy 133.377999 -238.146231)
			(xy 133.393709 -238.095301) (xy 133.416835 -238.04728) (xy 133.446859 -238.003243) (xy 133.483111 -237.964172)
			(xy 133.524782 -237.930941) (xy 133.57094 -237.904292) (xy 133.620554 -237.88482) (xy 133.672516 -237.87296)
			(xy 133.725666 -237.868977) (xy 133.778816 -237.87296) (xy 133.830778 -237.88482) (xy 133.880392 -237.904292)
			(xy 133.92655 -237.930941) (xy 133.968221 -237.964172) (xy 134.004473 -238.003243) (xy 134.034497 -238.04728)
			(xy 134.057623 -238.095301) (xy 134.073333 -238.146231) (xy 134.081276 -238.198935) (xy 134.081774 -238.225584)
			(xy 134.081276 -238.252233) (xy 134.309856 -238.252233) (xy 134.309856 -238.198935) (xy 134.317799 -238.146231)
			(xy 134.333509 -238.095301) (xy 134.356635 -238.04728) (xy 134.386659 -238.003243) (xy 134.422911 -237.964172)
			(xy 134.464582 -237.930941) (xy 134.51074 -237.904292) (xy 134.560354 -237.88482) (xy 134.612316 -237.87296)
			(xy 134.665466 -237.868977) (xy 134.718616 -237.87296) (xy 134.770578 -237.88482) (xy 134.820192 -237.904292)
			(xy 134.86635 -237.930941) (xy 134.908021 -237.964172) (xy 134.944273 -238.003243) (xy 134.974297 -238.04728)
			(xy 134.997423 -238.095301) (xy 135.013133 -238.146231) (xy 135.021076 -238.198935) (xy 135.021574 -238.225584)
			(xy 135.021076 -238.252233) (xy 135.013133 -238.304937) (xy 134.997423 -238.355867) (xy 134.974297 -238.403888)
			(xy 134.944273 -238.447925) (xy 134.908021 -238.486996) (xy 134.86635 -238.520227) (xy 134.820192 -238.546876)
			(xy 134.770578 -238.566348) (xy 134.718616 -238.578208) (xy 134.665466 -238.582192) (xy 134.612316 -238.578208)
			(xy 134.560354 -238.566348) (xy 134.51074 -238.546876) (xy 134.464582 -238.520227) (xy 134.422911 -238.486996)
			(xy 134.386659 -238.447925) (xy 134.356635 -238.403888) (xy 134.333509 -238.355867) (xy 134.317799 -238.304937)
			(xy 134.309856 -238.252233) (xy 134.081276 -238.252233) (xy 134.073333 -238.304937) (xy 134.057623 -238.355867)
			(xy 134.034497 -238.403888) (xy 134.004473 -238.447925) (xy 133.968221 -238.486996) (xy 133.92655 -238.520227)
			(xy 133.880392 -238.546876) (xy 133.830778 -238.566348) (xy 133.778816 -238.578208) (xy 133.725666 -238.582192)
			(xy 133.672516 -238.578208) (xy 133.620554 -238.566348) (xy 133.57094 -238.546876) (xy 133.524782 -238.520227)
			(xy 133.483111 -238.486996) (xy 133.446859 -238.447925) (xy 133.416835 -238.403888) (xy 133.393709 -238.355867)
			(xy 133.377999 -238.304937) (xy 133.370056 -238.252233) (xy 133.141476 -238.252233) (xy 133.133533 -238.304937)
			(xy 133.117823 -238.355867) (xy 133.094697 -238.403888) (xy 133.064673 -238.447925) (xy 133.028421 -238.486996)
			(xy 132.98675 -238.520227) (xy 132.940592 -238.546876) (xy 132.890978 -238.566348) (xy 132.839016 -238.578208)
			(xy 132.785866 -238.582192) (xy 132.732716 -238.578208) (xy 132.680754 -238.566348) (xy 132.63114 -238.546876)
			(xy 132.584982 -238.520227) (xy 132.543311 -238.486996) (xy 132.507059 -238.447925) (xy 132.477035 -238.403888)
			(xy 132.453909 -238.355867) (xy 132.438199 -238.304937) (xy 132.430256 -238.252233) (xy 132.201422 -238.252233)
			(xy 132.193479 -238.304937) (xy 132.177769 -238.355867) (xy 132.154643 -238.403888) (xy 132.124619 -238.447925)
			(xy 132.088367 -238.486996) (xy 132.046696 -238.520227) (xy 132.000538 -238.546876) (xy 131.950924 -238.566348)
			(xy 131.898962 -238.578208) (xy 131.845812 -238.582192) (xy 131.792662 -238.578208) (xy 131.7407 -238.566348)
			(xy 131.691086 -238.546876) (xy 131.644928 -238.520227) (xy 131.603257 -238.486996) (xy 131.567005 -238.447925)
			(xy 131.536981 -238.403888) (xy 131.513855 -238.355867) (xy 131.498145 -238.304937) (xy 131.490202 -238.252233)
			(xy 131.261622 -238.252233) (xy 131.253679 -238.304937) (xy 131.237969 -238.355867) (xy 131.214843 -238.403888)
			(xy 131.184819 -238.447925) (xy 131.148567 -238.486996) (xy 131.106896 -238.520227) (xy 131.060738 -238.546876)
			(xy 131.011124 -238.566348) (xy 130.959162 -238.578208) (xy 130.906012 -238.582192) (xy 130.852862 -238.578208)
			(xy 130.8009 -238.566348) (xy 130.751286 -238.546876) (xy 130.705128 -238.520227) (xy 130.663457 -238.486996)
			(xy 130.627205 -238.447925) (xy 130.597181 -238.403888) (xy 130.574055 -238.355867) (xy 130.558345 -238.304937)
			(xy 130.550402 -238.252233) (xy 130.321822 -238.252233) (xy 130.313879 -238.304937) (xy 130.298169 -238.355867)
			(xy 130.275043 -238.403888) (xy 130.245019 -238.447925) (xy 130.208767 -238.486996) (xy 130.167096 -238.520227)
			(xy 130.120938 -238.546876) (xy 130.071324 -238.566348) (xy 130.019362 -238.578208) (xy 129.966212 -238.582192)
			(xy 129.913062 -238.578208) (xy 129.8611 -238.566348) (xy 129.811486 -238.546876) (xy 129.765328 -238.520227)
			(xy 129.723657 -238.486996) (xy 129.687405 -238.447925) (xy 129.657381 -238.403888) (xy 129.634255 -238.355867)
			(xy 129.618545 -238.304937) (xy 129.610602 -238.252233) (xy 129.382022 -238.252233) (xy 129.374079 -238.304937)
			(xy 129.358369 -238.355867) (xy 129.335243 -238.403888) (xy 129.305219 -238.447925) (xy 129.268967 -238.486996)
			(xy 129.227296 -238.520227) (xy 129.181138 -238.546876) (xy 129.131524 -238.566348) (xy 129.079562 -238.578208)
			(xy 129.026412 -238.582192) (xy 128.973262 -238.578208) (xy 128.9213 -238.566348) (xy 128.871686 -238.546876)
			(xy 128.825528 -238.520227) (xy 128.783857 -238.486996) (xy 128.747605 -238.447925) (xy 128.717581 -238.403888)
			(xy 128.694455 -238.355867) (xy 128.678745 -238.304937) (xy 128.670802 -238.252233) (xy 128.442222 -238.252233)
			(xy 128.434279 -238.304937) (xy 128.418569 -238.355867) (xy 128.395443 -238.403888) (xy 128.365419 -238.447925)
			(xy 128.329167 -238.486996) (xy 128.287496 -238.520227) (xy 128.241338 -238.546876) (xy 128.191724 -238.566348)
			(xy 128.139762 -238.578208) (xy 128.086612 -238.582192) (xy 128.033462 -238.578208) (xy 127.9815 -238.566348)
			(xy 127.931886 -238.546876) (xy 127.885728 -238.520227) (xy 127.844057 -238.486996) (xy 127.807805 -238.447925)
			(xy 127.777781 -238.403888) (xy 127.754655 -238.355867) (xy 127.738945 -238.304937) (xy 127.731002 -238.252233)
			(xy 127.502422 -238.252233) (xy 127.494479 -238.304937) (xy 127.478769 -238.355867) (xy 127.455643 -238.403888)
			(xy 127.425619 -238.447925) (xy 127.389367 -238.486996) (xy 127.347696 -238.520227) (xy 127.301538 -238.546876)
			(xy 127.251924 -238.566348) (xy 127.199962 -238.578208) (xy 127.146812 -238.582192) (xy 127.093662 -238.578208)
			(xy 127.0417 -238.566348) (xy 126.992086 -238.546876) (xy 126.945928 -238.520227) (xy 126.904257 -238.486996)
			(xy 126.868005 -238.447925) (xy 126.837981 -238.403888) (xy 126.814855 -238.355867) (xy 126.799145 -238.304937)
			(xy 126.791202 -238.252233) (xy 126.562876 -238.252233) (xy 126.554933 -238.304937) (xy 126.539223 -238.355867)
			(xy 126.516097 -238.403888) (xy 126.486073 -238.447925) (xy 126.449821 -238.486996) (xy 126.40815 -238.520227)
			(xy 126.361992 -238.546876) (xy 126.312378 -238.566348) (xy 126.260416 -238.578208) (xy 126.207266 -238.582192)
			(xy 126.154116 -238.578208) (xy 126.102154 -238.566348) (xy 126.05254 -238.546876) (xy 126.006382 -238.520227)
			(xy 125.964711 -238.486996) (xy 125.928459 -238.447925) (xy 125.898435 -238.403888) (xy 125.875309 -238.355867)
			(xy 125.859599 -238.304937) (xy 125.851656 -238.252233) (xy 125.622822 -238.252233) (xy 125.614879 -238.304937)
			(xy 125.599169 -238.355867) (xy 125.576043 -238.403888) (xy 125.546019 -238.447925) (xy 125.509767 -238.486996)
			(xy 125.468096 -238.520227) (xy 125.421938 -238.546876) (xy 125.372324 -238.566348) (xy 125.320362 -238.578208)
			(xy 125.267212 -238.582192) (xy 125.214062 -238.578208) (xy 125.1621 -238.566348) (xy 125.112486 -238.546876)
			(xy 125.066328 -238.520227) (xy 125.024657 -238.486996) (xy 124.988405 -238.447925) (xy 124.958381 -238.403888)
			(xy 124.935255 -238.355867) (xy 124.919545 -238.304937) (xy 124.911602 -238.252233) (xy 124.683022 -238.252233)
			(xy 124.675079 -238.304937) (xy 124.659369 -238.355867) (xy 124.636243 -238.403888) (xy 124.606219 -238.447925)
			(xy 124.569967 -238.486996) (xy 124.528296 -238.520227) (xy 124.482138 -238.546876) (xy 124.432524 -238.566348)
			(xy 124.380562 -238.578208) (xy 124.327412 -238.582192) (xy 124.274262 -238.578208) (xy 124.2223 -238.566348)
			(xy 124.172686 -238.546876) (xy 124.126528 -238.520227) (xy 124.084857 -238.486996) (xy 124.048605 -238.447925)
			(xy 124.018581 -238.403888) (xy 123.995455 -238.355867) (xy 123.979745 -238.304937) (xy 123.971802 -238.252233)
			(xy 123.743222 -238.252233) (xy 123.735279 -238.304937) (xy 123.719569 -238.355867) (xy 123.696443 -238.403888)
			(xy 123.666419 -238.447925) (xy 123.630167 -238.486996) (xy 123.588496 -238.520227) (xy 123.542338 -238.546876)
			(xy 123.492724 -238.566348) (xy 123.440762 -238.578208) (xy 123.387612 -238.582192) (xy 123.334462 -238.578208)
			(xy 123.2825 -238.566348) (xy 123.232886 -238.546876) (xy 123.186728 -238.520227) (xy 123.145057 -238.486996)
			(xy 123.108805 -238.447925) (xy 123.078781 -238.403888) (xy 123.055655 -238.355867) (xy 123.039945 -238.304937)
			(xy 123.032002 -238.252233) (xy 122.803422 -238.252233) (xy 122.795479 -238.304937) (xy 122.779769 -238.355867)
			(xy 122.756643 -238.403888) (xy 122.726619 -238.447925) (xy 122.690367 -238.486996) (xy 122.648696 -238.520227)
			(xy 122.602538 -238.546876) (xy 122.552924 -238.566348) (xy 122.500962 -238.578208) (xy 122.447812 -238.582192)
			(xy 122.394662 -238.578208) (xy 122.3427 -238.566348) (xy 122.293086 -238.546876) (xy 122.246928 -238.520227)
			(xy 122.205257 -238.486996) (xy 122.169005 -238.447925) (xy 122.138981 -238.403888) (xy 122.115855 -238.355867)
			(xy 122.100145 -238.304937) (xy 122.092202 -238.252233) (xy 121.863622 -238.252233) (xy 121.855679 -238.304937)
			(xy 121.839969 -238.355867) (xy 121.816843 -238.403888) (xy 121.786819 -238.447925) (xy 121.750567 -238.486996)
			(xy 121.708896 -238.520227) (xy 121.662738 -238.546876) (xy 121.613124 -238.566348) (xy 121.561162 -238.578208)
			(xy 121.508012 -238.582192) (xy 121.454862 -238.578208) (xy 121.4029 -238.566348) (xy 121.353286 -238.546876)
			(xy 121.307128 -238.520227) (xy 121.265457 -238.486996) (xy 121.229205 -238.447925) (xy 121.199181 -238.403888)
			(xy 121.176055 -238.355867) (xy 121.160345 -238.304937) (xy 121.152402 -238.252233) (xy 120.214623 -238.252233)
			(xy 120.62968 -238.66729) (xy 120.62968 -239.066049) (xy 121.622556 -239.066049) (xy 121.622556 -239.012751)
			(xy 121.630499 -238.960047) (xy 121.646209 -238.909117) (xy 121.669335 -238.861096) (xy 121.699359 -238.817059)
			(xy 121.735611 -238.777988) (xy 121.777282 -238.744757) (xy 121.82344 -238.718108) (xy 121.873054 -238.698636)
			(xy 121.925016 -238.686776) (xy 121.978166 -238.682793) (xy 122.031316 -238.686776) (xy 122.083278 -238.698636)
			(xy 122.132892 -238.718108) (xy 122.17905 -238.744757) (xy 122.220721 -238.777988) (xy 122.256973 -238.817059)
			(xy 122.286997 -238.861096) (xy 122.310123 -238.909117) (xy 122.325833 -238.960047) (xy 122.333776 -239.012751)
			(xy 122.334274 -239.0394) (xy 122.333776 -239.066049) (xy 122.562102 -239.066049) (xy 122.562102 -239.012751)
			(xy 122.570045 -238.960047) (xy 122.585755 -238.909117) (xy 122.608881 -238.861096) (xy 122.638905 -238.817059)
			(xy 122.675157 -238.777988) (xy 122.716828 -238.744757) (xy 122.762986 -238.718108) (xy 122.8126 -238.698636)
			(xy 122.864562 -238.686776) (xy 122.917712 -238.682793) (xy 122.970862 -238.686776) (xy 123.022824 -238.698636)
			(xy 123.072438 -238.718108) (xy 123.118596 -238.744757) (xy 123.160267 -238.777988) (xy 123.196519 -238.817059)
			(xy 123.226543 -238.861096) (xy 123.249669 -238.909117) (xy 123.265379 -238.960047) (xy 123.273322 -239.012751)
			(xy 123.27382 -239.0394) (xy 123.273322 -239.066049) (xy 123.502156 -239.066049) (xy 123.502156 -239.012751)
			(xy 123.510099 -238.960047) (xy 123.525809 -238.909117) (xy 123.548935 -238.861096) (xy 123.578959 -238.817059)
			(xy 123.615211 -238.777988) (xy 123.656882 -238.744757) (xy 123.70304 -238.718108) (xy 123.752654 -238.698636)
			(xy 123.804616 -238.686776) (xy 123.857766 -238.682793) (xy 123.910916 -238.686776) (xy 123.962878 -238.698636)
			(xy 124.012492 -238.718108) (xy 124.05865 -238.744757) (xy 124.100321 -238.777988) (xy 124.136573 -238.817059)
			(xy 124.166597 -238.861096) (xy 124.189723 -238.909117) (xy 124.205433 -238.960047) (xy 124.213376 -239.012751)
			(xy 124.213874 -239.0394) (xy 124.213376 -239.066049) (xy 124.441956 -239.066049) (xy 124.441956 -239.012751)
			(xy 124.449899 -238.960047) (xy 124.465609 -238.909117) (xy 124.488735 -238.861096) (xy 124.518759 -238.817059)
			(xy 124.555011 -238.777988) (xy 124.596682 -238.744757) (xy 124.64284 -238.718108) (xy 124.692454 -238.698636)
			(xy 124.744416 -238.686776) (xy 124.797566 -238.682793) (xy 124.850716 -238.686776) (xy 124.902678 -238.698636)
			(xy 124.952292 -238.718108) (xy 124.99845 -238.744757) (xy 125.040121 -238.777988) (xy 125.076373 -238.817059)
			(xy 125.106397 -238.861096) (xy 125.129523 -238.909117) (xy 125.145233 -238.960047) (xy 125.153176 -239.012751)
			(xy 125.153674 -239.0394) (xy 125.153176 -239.066049) (xy 125.381756 -239.066049) (xy 125.381756 -239.012751)
			(xy 125.389699 -238.960047) (xy 125.405409 -238.909117) (xy 125.428535 -238.861096) (xy 125.458559 -238.817059)
			(xy 125.494811 -238.777988) (xy 125.536482 -238.744757) (xy 125.58264 -238.718108) (xy 125.632254 -238.698636)
			(xy 125.684216 -238.686776) (xy 125.737366 -238.682793) (xy 125.790516 -238.686776) (xy 125.842478 -238.698636)
			(xy 125.892092 -238.718108) (xy 125.93825 -238.744757) (xy 125.979921 -238.777988) (xy 126.016173 -238.817059)
			(xy 126.046197 -238.861096) (xy 126.069323 -238.909117) (xy 126.085033 -238.960047) (xy 126.092976 -239.012751)
			(xy 126.093474 -239.0394) (xy 126.092976 -239.066049) (xy 126.321556 -239.066049) (xy 126.321556 -239.012751)
			(xy 126.329499 -238.960047) (xy 126.345209 -238.909117) (xy 126.368335 -238.861096) (xy 126.398359 -238.817059)
			(xy 126.434611 -238.777988) (xy 126.476282 -238.744757) (xy 126.52244 -238.718108) (xy 126.572054 -238.698636)
			(xy 126.624016 -238.686776) (xy 126.677166 -238.682793) (xy 126.730316 -238.686776) (xy 126.782278 -238.698636)
			(xy 126.831892 -238.718108) (xy 126.87805 -238.744757) (xy 126.919721 -238.777988) (xy 126.955973 -238.817059)
			(xy 126.985997 -238.861096) (xy 127.009123 -238.909117) (xy 127.024833 -238.960047) (xy 127.032776 -239.012751)
			(xy 127.033274 -239.0394) (xy 127.032776 -239.066049) (xy 127.261356 -239.066049) (xy 127.261356 -239.012751)
			(xy 127.269299 -238.960047) (xy 127.285009 -238.909117) (xy 127.308135 -238.861096) (xy 127.338159 -238.817059)
			(xy 127.374411 -238.777988) (xy 127.416082 -238.744757) (xy 127.46224 -238.718108) (xy 127.511854 -238.698636)
			(xy 127.563816 -238.686776) (xy 127.616966 -238.682793) (xy 127.670116 -238.686776) (xy 127.722078 -238.698636)
			(xy 127.771692 -238.718108) (xy 127.81785 -238.744757) (xy 127.859521 -238.777988) (xy 127.895773 -238.817059)
			(xy 127.925797 -238.861096) (xy 127.948923 -238.909117) (xy 127.964633 -238.960047) (xy 127.972576 -239.012751)
			(xy 127.973074 -239.0394) (xy 127.972576 -239.066049) (xy 128.201156 -239.066049) (xy 128.201156 -239.012751)
			(xy 128.209099 -238.960047) (xy 128.224809 -238.909117) (xy 128.247935 -238.861096) (xy 128.277959 -238.817059)
			(xy 128.314211 -238.777988) (xy 128.355882 -238.744757) (xy 128.40204 -238.718108) (xy 128.451654 -238.698636)
			(xy 128.503616 -238.686776) (xy 128.556766 -238.682793) (xy 128.609916 -238.686776) (xy 128.661878 -238.698636)
			(xy 128.711492 -238.718108) (xy 128.75765 -238.744757) (xy 128.799321 -238.777988) (xy 128.835573 -238.817059)
			(xy 128.865597 -238.861096) (xy 128.888723 -238.909117) (xy 128.904433 -238.960047) (xy 128.912376 -239.012751)
			(xy 128.912874 -239.0394) (xy 128.912376 -239.066049) (xy 129.140702 -239.066049) (xy 129.140702 -239.012751)
			(xy 129.148645 -238.960047) (xy 129.164355 -238.909117) (xy 129.187481 -238.861096) (xy 129.217505 -238.817059)
			(xy 129.253757 -238.777988) (xy 129.295428 -238.744757) (xy 129.341586 -238.718108) (xy 129.3912 -238.698636)
			(xy 129.443162 -238.686776) (xy 129.496312 -238.682793) (xy 129.549462 -238.686776) (xy 129.601424 -238.698636)
			(xy 129.651038 -238.718108) (xy 129.697196 -238.744757) (xy 129.738867 -238.777988) (xy 129.775119 -238.817059)
			(xy 129.805143 -238.861096) (xy 129.828269 -238.909117) (xy 129.843979 -238.960047) (xy 129.851922 -239.012751)
			(xy 129.85242 -239.0394) (xy 129.851922 -239.066049) (xy 130.080756 -239.066049) (xy 130.080756 -239.012751)
			(xy 130.088699 -238.960047) (xy 130.104409 -238.909117) (xy 130.127535 -238.861096) (xy 130.157559 -238.817059)
			(xy 130.193811 -238.777988) (xy 130.235482 -238.744757) (xy 130.28164 -238.718108) (xy 130.331254 -238.698636)
			(xy 130.383216 -238.686776) (xy 130.436366 -238.682793) (xy 130.489516 -238.686776) (xy 130.541478 -238.698636)
			(xy 130.591092 -238.718108) (xy 130.63725 -238.744757) (xy 130.678921 -238.777988) (xy 130.715173 -238.817059)
			(xy 130.745197 -238.861096) (xy 130.768323 -238.909117) (xy 130.784033 -238.960047) (xy 130.791976 -239.012751)
			(xy 130.792474 -239.0394) (xy 130.791976 -239.066049) (xy 131.020556 -239.066049) (xy 131.020556 -239.012751)
			(xy 131.028499 -238.960047) (xy 131.044209 -238.909117) (xy 131.067335 -238.861096) (xy 131.097359 -238.817059)
			(xy 131.133611 -238.777988) (xy 131.175282 -238.744757) (xy 131.22144 -238.718108) (xy 131.271054 -238.698636)
			(xy 131.323016 -238.686776) (xy 131.376166 -238.682793) (xy 131.429316 -238.686776) (xy 131.481278 -238.698636)
			(xy 131.530892 -238.718108) (xy 131.57705 -238.744757) (xy 131.618721 -238.777988) (xy 131.654973 -238.817059)
			(xy 131.684997 -238.861096) (xy 131.708123 -238.909117) (xy 131.723833 -238.960047) (xy 131.731776 -239.012751)
			(xy 131.732274 -239.0394) (xy 131.731776 -239.066049) (xy 131.960356 -239.066049) (xy 131.960356 -239.012751)
			(xy 131.968299 -238.960047) (xy 131.984009 -238.909117) (xy 132.007135 -238.861096) (xy 132.037159 -238.817059)
			(xy 132.073411 -238.777988) (xy 132.115082 -238.744757) (xy 132.16124 -238.718108) (xy 132.210854 -238.698636)
			(xy 132.262816 -238.686776) (xy 132.315966 -238.682793) (xy 132.369116 -238.686776) (xy 132.421078 -238.698636)
			(xy 132.470692 -238.718108) (xy 132.51685 -238.744757) (xy 132.558521 -238.777988) (xy 132.594773 -238.817059)
			(xy 132.624797 -238.861096) (xy 132.647923 -238.909117) (xy 132.663633 -238.960047) (xy 132.671576 -239.012751)
			(xy 132.672074 -239.0394) (xy 132.671576 -239.066049) (xy 132.900156 -239.066049) (xy 132.900156 -239.012751)
			(xy 132.908099 -238.960047) (xy 132.923809 -238.909117) (xy 132.946935 -238.861096) (xy 132.976959 -238.817059)
			(xy 133.013211 -238.777988) (xy 133.054882 -238.744757) (xy 133.10104 -238.718108) (xy 133.150654 -238.698636)
			(xy 133.202616 -238.686776) (xy 133.255766 -238.682793) (xy 133.308916 -238.686776) (xy 133.360878 -238.698636)
			(xy 133.410492 -238.718108) (xy 133.45665 -238.744757) (xy 133.498321 -238.777988) (xy 133.534573 -238.817059)
			(xy 133.564597 -238.861096) (xy 133.587723 -238.909117) (xy 133.603433 -238.960047) (xy 133.611376 -239.012751)
			(xy 133.611874 -239.0394) (xy 133.611376 -239.066049) (xy 133.839956 -239.066049) (xy 133.839956 -239.012751)
			(xy 133.847899 -238.960047) (xy 133.863609 -238.909117) (xy 133.886735 -238.861096) (xy 133.916759 -238.817059)
			(xy 133.953011 -238.777988) (xy 133.994682 -238.744757) (xy 134.04084 -238.718108) (xy 134.090454 -238.698636)
			(xy 134.142416 -238.686776) (xy 134.195566 -238.682793) (xy 134.248716 -238.686776) (xy 134.300678 -238.698636)
			(xy 134.350292 -238.718108) (xy 134.39645 -238.744757) (xy 134.438121 -238.777988) (xy 134.474373 -238.817059)
			(xy 134.504397 -238.861096) (xy 134.527523 -238.909117) (xy 134.543233 -238.960047) (xy 134.551176 -239.012751)
			(xy 134.551674 -239.0394) (xy 134.551176 -239.066049) (xy 134.543233 -239.118753) (xy 134.527523 -239.169683)
			(xy 134.504397 -239.217704) (xy 134.474373 -239.261741) (xy 134.438121 -239.300812) (xy 134.39645 -239.334043)
			(xy 134.350292 -239.360692) (xy 134.300678 -239.380164) (xy 134.248716 -239.392024) (xy 134.195566 -239.396008)
			(xy 134.142416 -239.392024) (xy 134.090454 -239.380164) (xy 134.04084 -239.360692) (xy 133.994682 -239.334043)
			(xy 133.953011 -239.300812) (xy 133.916759 -239.261741) (xy 133.886735 -239.217704) (xy 133.863609 -239.169683)
			(xy 133.847899 -239.118753) (xy 133.839956 -239.066049) (xy 133.611376 -239.066049) (xy 133.603433 -239.118753)
			(xy 133.587723 -239.169683) (xy 133.564597 -239.217704) (xy 133.534573 -239.261741) (xy 133.498321 -239.300812)
			(xy 133.45665 -239.334043) (xy 133.410492 -239.360692) (xy 133.360878 -239.380164) (xy 133.308916 -239.392024)
			(xy 133.255766 -239.396008) (xy 133.202616 -239.392024) (xy 133.150654 -239.380164) (xy 133.10104 -239.360692)
			(xy 133.054882 -239.334043) (xy 133.013211 -239.300812) (xy 132.976959 -239.261741) (xy 132.946935 -239.217704)
			(xy 132.923809 -239.169683) (xy 132.908099 -239.118753) (xy 132.900156 -239.066049) (xy 132.671576 -239.066049)
			(xy 132.663633 -239.118753) (xy 132.647923 -239.169683) (xy 132.624797 -239.217704) (xy 132.594773 -239.261741)
			(xy 132.558521 -239.300812) (xy 132.51685 -239.334043) (xy 132.470692 -239.360692) (xy 132.421078 -239.380164)
			(xy 132.369116 -239.392024) (xy 132.315966 -239.396008) (xy 132.262816 -239.392024) (xy 132.210854 -239.380164)
			(xy 132.16124 -239.360692) (xy 132.115082 -239.334043) (xy 132.073411 -239.300812) (xy 132.037159 -239.261741)
			(xy 132.007135 -239.217704) (xy 131.984009 -239.169683) (xy 131.968299 -239.118753) (xy 131.960356 -239.066049)
			(xy 131.731776 -239.066049) (xy 131.723833 -239.118753) (xy 131.708123 -239.169683) (xy 131.684997 -239.217704)
			(xy 131.654973 -239.261741) (xy 131.618721 -239.300812) (xy 131.57705 -239.334043) (xy 131.530892 -239.360692)
			(xy 131.481278 -239.380164) (xy 131.429316 -239.392024) (xy 131.376166 -239.396008) (xy 131.323016 -239.392024)
			(xy 131.271054 -239.380164) (xy 131.22144 -239.360692) (xy 131.175282 -239.334043) (xy 131.133611 -239.300812)
			(xy 131.097359 -239.261741) (xy 131.067335 -239.217704) (xy 131.044209 -239.169683) (xy 131.028499 -239.118753)
			(xy 131.020556 -239.066049) (xy 130.791976 -239.066049) (xy 130.784033 -239.118753) (xy 130.768323 -239.169683)
			(xy 130.745197 -239.217704) (xy 130.715173 -239.261741) (xy 130.678921 -239.300812) (xy 130.63725 -239.334043)
			(xy 130.591092 -239.360692) (xy 130.541478 -239.380164) (xy 130.489516 -239.392024) (xy 130.436366 -239.396008)
			(xy 130.383216 -239.392024) (xy 130.331254 -239.380164) (xy 130.28164 -239.360692) (xy 130.235482 -239.334043)
			(xy 130.193811 -239.300812) (xy 130.157559 -239.261741) (xy 130.127535 -239.217704) (xy 130.104409 -239.169683)
			(xy 130.088699 -239.118753) (xy 130.080756 -239.066049) (xy 129.851922 -239.066049) (xy 129.843979 -239.118753)
			(xy 129.828269 -239.169683) (xy 129.805143 -239.217704) (xy 129.775119 -239.261741) (xy 129.738867 -239.300812)
			(xy 129.697196 -239.334043) (xy 129.651038 -239.360692) (xy 129.601424 -239.380164) (xy 129.549462 -239.392024)
			(xy 129.496312 -239.396008) (xy 129.443162 -239.392024) (xy 129.3912 -239.380164) (xy 129.341586 -239.360692)
			(xy 129.295428 -239.334043) (xy 129.253757 -239.300812) (xy 129.217505 -239.261741) (xy 129.187481 -239.217704)
			(xy 129.164355 -239.169683) (xy 129.148645 -239.118753) (xy 129.140702 -239.066049) (xy 128.912376 -239.066049)
			(xy 128.904433 -239.118753) (xy 128.888723 -239.169683) (xy 128.865597 -239.217704) (xy 128.835573 -239.261741)
			(xy 128.799321 -239.300812) (xy 128.75765 -239.334043) (xy 128.711492 -239.360692) (xy 128.661878 -239.380164)
			(xy 128.609916 -239.392024) (xy 128.556766 -239.396008) (xy 128.503616 -239.392024) (xy 128.451654 -239.380164)
			(xy 128.40204 -239.360692) (xy 128.355882 -239.334043) (xy 128.314211 -239.300812) (xy 128.277959 -239.261741)
			(xy 128.247935 -239.217704) (xy 128.224809 -239.169683) (xy 128.209099 -239.118753) (xy 128.201156 -239.066049)
			(xy 127.972576 -239.066049) (xy 127.964633 -239.118753) (xy 127.948923 -239.169683) (xy 127.925797 -239.217704)
			(xy 127.895773 -239.261741) (xy 127.859521 -239.300812) (xy 127.81785 -239.334043) (xy 127.771692 -239.360692)
			(xy 127.722078 -239.380164) (xy 127.670116 -239.392024) (xy 127.616966 -239.396008) (xy 127.563816 -239.392024)
			(xy 127.511854 -239.380164) (xy 127.46224 -239.360692) (xy 127.416082 -239.334043) (xy 127.374411 -239.300812)
			(xy 127.338159 -239.261741) (xy 127.308135 -239.217704) (xy 127.285009 -239.169683) (xy 127.269299 -239.118753)
			(xy 127.261356 -239.066049) (xy 127.032776 -239.066049) (xy 127.024833 -239.118753) (xy 127.009123 -239.169683)
			(xy 126.985997 -239.217704) (xy 126.955973 -239.261741) (xy 126.919721 -239.300812) (xy 126.87805 -239.334043)
			(xy 126.831892 -239.360692) (xy 126.782278 -239.380164) (xy 126.730316 -239.392024) (xy 126.677166 -239.396008)
			(xy 126.624016 -239.392024) (xy 126.572054 -239.380164) (xy 126.52244 -239.360692) (xy 126.476282 -239.334043)
			(xy 126.434611 -239.300812) (xy 126.398359 -239.261741) (xy 126.368335 -239.217704) (xy 126.345209 -239.169683)
			(xy 126.329499 -239.118753) (xy 126.321556 -239.066049) (xy 126.092976 -239.066049) (xy 126.085033 -239.118753)
			(xy 126.069323 -239.169683) (xy 126.046197 -239.217704) (xy 126.016173 -239.261741) (xy 125.979921 -239.300812)
			(xy 125.93825 -239.334043) (xy 125.892092 -239.360692) (xy 125.842478 -239.380164) (xy 125.790516 -239.392024)
			(xy 125.737366 -239.396008) (xy 125.684216 -239.392024) (xy 125.632254 -239.380164) (xy 125.58264 -239.360692)
			(xy 125.536482 -239.334043) (xy 125.494811 -239.300812) (xy 125.458559 -239.261741) (xy 125.428535 -239.217704)
			(xy 125.405409 -239.169683) (xy 125.389699 -239.118753) (xy 125.381756 -239.066049) (xy 125.153176 -239.066049)
			(xy 125.145233 -239.118753) (xy 125.129523 -239.169683) (xy 125.106397 -239.217704) (xy 125.076373 -239.261741)
			(xy 125.040121 -239.300812) (xy 124.99845 -239.334043) (xy 124.952292 -239.360692) (xy 124.902678 -239.380164)
			(xy 124.850716 -239.392024) (xy 124.797566 -239.396008) (xy 124.744416 -239.392024) (xy 124.692454 -239.380164)
			(xy 124.64284 -239.360692) (xy 124.596682 -239.334043) (xy 124.555011 -239.300812) (xy 124.518759 -239.261741)
			(xy 124.488735 -239.217704) (xy 124.465609 -239.169683) (xy 124.449899 -239.118753) (xy 124.441956 -239.066049)
			(xy 124.213376 -239.066049) (xy 124.205433 -239.118753) (xy 124.189723 -239.169683) (xy 124.166597 -239.217704)
			(xy 124.136573 -239.261741) (xy 124.100321 -239.300812) (xy 124.05865 -239.334043) (xy 124.012492 -239.360692)
			(xy 123.962878 -239.380164) (xy 123.910916 -239.392024) (xy 123.857766 -239.396008) (xy 123.804616 -239.392024)
			(xy 123.752654 -239.380164) (xy 123.70304 -239.360692) (xy 123.656882 -239.334043) (xy 123.615211 -239.300812)
			(xy 123.578959 -239.261741) (xy 123.548935 -239.217704) (xy 123.525809 -239.169683) (xy 123.510099 -239.118753)
			(xy 123.502156 -239.066049) (xy 123.273322 -239.066049) (xy 123.265379 -239.118753) (xy 123.249669 -239.169683)
			(xy 123.226543 -239.217704) (xy 123.196519 -239.261741) (xy 123.160267 -239.300812) (xy 123.118596 -239.334043)
			(xy 123.072438 -239.360692) (xy 123.022824 -239.380164) (xy 122.970862 -239.392024) (xy 122.917712 -239.396008)
			(xy 122.864562 -239.392024) (xy 122.8126 -239.380164) (xy 122.762986 -239.360692) (xy 122.716828 -239.334043)
			(xy 122.675157 -239.300812) (xy 122.638905 -239.261741) (xy 122.608881 -239.217704) (xy 122.585755 -239.169683)
			(xy 122.570045 -239.118753) (xy 122.562102 -239.066049) (xy 122.333776 -239.066049) (xy 122.325833 -239.118753)
			(xy 122.310123 -239.169683) (xy 122.286997 -239.217704) (xy 122.256973 -239.261741) (xy 122.220721 -239.300812)
			(xy 122.17905 -239.334043) (xy 122.132892 -239.360692) (xy 122.083278 -239.380164) (xy 122.031316 -239.392024)
			(xy 121.978166 -239.396008) (xy 121.925016 -239.392024) (xy 121.873054 -239.380164) (xy 121.82344 -239.360692)
			(xy 121.777282 -239.334043) (xy 121.735611 -239.300812) (xy 121.699359 -239.261741) (xy 121.669335 -239.217704)
			(xy 121.646209 -239.169683) (xy 121.630499 -239.118753) (xy 121.622556 -239.066049) (xy 120.62968 -239.066049)
			(xy 120.62968 -239.100106) (xy 120.647292 -239.121692) (xy 120.676284 -239.169262) (xy 120.697514 -239.220767)
			(xy 120.710463 -239.27495) (xy 120.714816 -239.330488) (xy 120.710467 -239.386026) (xy 120.697521 -239.44021)
			(xy 120.676295 -239.491716) (xy 120.647307 -239.539288) (xy 120.62968 -239.560862) (xy 120.62968 -239.718088)
			(xy 120.630219 -239.733128) (xy 120.638982 -239.761905) (xy 120.65575 -239.786878) (xy 120.679069 -239.80588)
			(xy 120.706913 -239.817263) (xy 120.736866 -239.820036) (xy 120.766326 -239.81396) (xy 120.779794 -239.807242)
			(xy 120.806031 -239.793644) (xy 120.861896 -239.774389) (xy 120.920175 -239.764629) (xy 120.94972 -239.764062)
			(xy 120.976087 -239.764541) (xy 121.028245 -239.772325) (xy 121.053606 -239.779556) (xy 121.068217 -239.783447)
			(xy 121.098438 -239.783439) (xy 121.127334 -239.77459) (xy 121.152377 -239.757675) (xy 121.171376 -239.734174)
			(xy 121.177558 -239.720374) (xy 121.187877 -239.695993) (xy 121.21467 -239.650334) (xy 121.247931 -239.609146)
			(xy 121.286923 -239.573338) (xy 121.330789 -239.543699) (xy 121.37856 -239.520882) (xy 121.429183 -239.505392)
			(xy 121.481542 -239.497568) (xy 121.508012 -239.497108) (xy 121.534659 -239.497607) (xy 121.587359 -239.505552)
			(xy 121.638286 -239.521262) (xy 121.686302 -239.544387) (xy 121.730336 -239.57441) (xy 121.769404 -239.610661)
			(xy 121.802632 -239.652329) (xy 121.829279 -239.698484) (xy 121.848749 -239.748095) (xy 121.860608 -239.800054)
			(xy 121.864591 -239.8532) (xy 121.862593 -239.879865) (xy 122.092456 -239.879865) (xy 122.092456 -239.826567)
			(xy 122.100399 -239.773863) (xy 122.116109 -239.722933) (xy 122.139235 -239.674912) (xy 122.169259 -239.630875)
			(xy 122.205511 -239.591804) (xy 122.247182 -239.558573) (xy 122.29334 -239.531924) (xy 122.342954 -239.512452)
			(xy 122.394916 -239.500592) (xy 122.448066 -239.496609) (xy 122.501216 -239.500592) (xy 122.553178 -239.512452)
			(xy 122.602792 -239.531924) (xy 122.64895 -239.558573) (xy 122.690621 -239.591804) (xy 122.726873 -239.630875)
			(xy 122.756897 -239.674912) (xy 122.780023 -239.722933) (xy 122.795733 -239.773863) (xy 122.803676 -239.826567)
			(xy 122.804174 -239.853216) (xy 122.803676 -239.879865) (xy 123.032002 -239.879865) (xy 123.032002 -239.826567)
			(xy 123.039945 -239.773863) (xy 123.055655 -239.722933) (xy 123.078781 -239.674912) (xy 123.108805 -239.630875)
			(xy 123.145057 -239.591804) (xy 123.186728 -239.558573) (xy 123.232886 -239.531924) (xy 123.2825 -239.512452)
			(xy 123.334462 -239.500592) (xy 123.387612 -239.496609) (xy 123.440762 -239.500592) (xy 123.492724 -239.512452)
			(xy 123.542338 -239.531924) (xy 123.588496 -239.558573) (xy 123.630167 -239.591804) (xy 123.666419 -239.630875)
			(xy 123.696443 -239.674912) (xy 123.719569 -239.722933) (xy 123.735279 -239.773863) (xy 123.743222 -239.826567)
			(xy 123.74372 -239.853216) (xy 123.743222 -239.879865) (xy 123.971802 -239.879865) (xy 123.971802 -239.826567)
			(xy 123.979745 -239.773863) (xy 123.995455 -239.722933) (xy 124.018581 -239.674912) (xy 124.048605 -239.630875)
			(xy 124.084857 -239.591804) (xy 124.126528 -239.558573) (xy 124.172686 -239.531924) (xy 124.2223 -239.512452)
			(xy 124.274262 -239.500592) (xy 124.327412 -239.496609) (xy 124.380562 -239.500592) (xy 124.432524 -239.512452)
			(xy 124.482138 -239.531924) (xy 124.528296 -239.558573) (xy 124.569967 -239.591804) (xy 124.606219 -239.630875)
			(xy 124.636243 -239.674912) (xy 124.659369 -239.722933) (xy 124.675079 -239.773863) (xy 124.683022 -239.826567)
			(xy 124.68352 -239.853216) (xy 124.683022 -239.879865) (xy 124.911856 -239.879865) (xy 124.911856 -239.826567)
			(xy 124.919799 -239.773863) (xy 124.935509 -239.722933) (xy 124.958635 -239.674912) (xy 124.988659 -239.630875)
			(xy 125.024911 -239.591804) (xy 125.066582 -239.558573) (xy 125.11274 -239.531924) (xy 125.162354 -239.512452)
			(xy 125.214316 -239.500592) (xy 125.267466 -239.496609) (xy 125.320616 -239.500592) (xy 125.372578 -239.512452)
			(xy 125.422192 -239.531924) (xy 125.46835 -239.558573) (xy 125.510021 -239.591804) (xy 125.546273 -239.630875)
			(xy 125.576297 -239.674912) (xy 125.599423 -239.722933) (xy 125.615133 -239.773863) (xy 125.623076 -239.826567)
			(xy 125.623574 -239.853216) (xy 125.623076 -239.879865) (xy 125.851402 -239.879865) (xy 125.851402 -239.826567)
			(xy 125.859345 -239.773863) (xy 125.875055 -239.722933) (xy 125.898181 -239.674912) (xy 125.928205 -239.630875)
			(xy 125.964457 -239.591804) (xy 126.006128 -239.558573) (xy 126.052286 -239.531924) (xy 126.1019 -239.512452)
			(xy 126.153862 -239.500592) (xy 126.207012 -239.496609) (xy 126.260162 -239.500592) (xy 126.312124 -239.512452)
			(xy 126.361738 -239.531924) (xy 126.407896 -239.558573) (xy 126.449567 -239.591804) (xy 126.485819 -239.630875)
			(xy 126.515843 -239.674912) (xy 126.538969 -239.722933) (xy 126.554679 -239.773863) (xy 126.562622 -239.826567)
			(xy 126.56312 -239.853216) (xy 126.562622 -239.879865) (xy 126.791202 -239.879865) (xy 126.791202 -239.826567)
			(xy 126.799145 -239.773863) (xy 126.814855 -239.722933) (xy 126.837981 -239.674912) (xy 126.868005 -239.630875)
			(xy 126.904257 -239.591804) (xy 126.945928 -239.558573) (xy 126.992086 -239.531924) (xy 127.0417 -239.512452)
			(xy 127.093662 -239.500592) (xy 127.146812 -239.496609) (xy 127.199962 -239.500592) (xy 127.251924 -239.512452)
			(xy 127.301538 -239.531924) (xy 127.347696 -239.558573) (xy 127.389367 -239.591804) (xy 127.425619 -239.630875)
			(xy 127.455643 -239.674912) (xy 127.478769 -239.722933) (xy 127.494479 -239.773863) (xy 127.502422 -239.826567)
			(xy 127.50292 -239.853216) (xy 127.502422 -239.879865) (xy 127.731002 -239.879865) (xy 127.731002 -239.826567)
			(xy 127.738945 -239.773863) (xy 127.754655 -239.722933) (xy 127.777781 -239.674912) (xy 127.807805 -239.630875)
			(xy 127.844057 -239.591804) (xy 127.885728 -239.558573) (xy 127.931886 -239.531924) (xy 127.9815 -239.512452)
			(xy 128.033462 -239.500592) (xy 128.086612 -239.496609) (xy 128.139762 -239.500592) (xy 128.191724 -239.512452)
			(xy 128.241338 -239.531924) (xy 128.287496 -239.558573) (xy 128.329167 -239.591804) (xy 128.365419 -239.630875)
			(xy 128.395443 -239.674912) (xy 128.418569 -239.722933) (xy 128.434279 -239.773863) (xy 128.442222 -239.826567)
			(xy 128.44272 -239.853216) (xy 128.442222 -239.879865) (xy 128.670802 -239.879865) (xy 128.670802 -239.826567)
			(xy 128.678745 -239.773863) (xy 128.694455 -239.722933) (xy 128.717581 -239.674912) (xy 128.747605 -239.630875)
			(xy 128.783857 -239.591804) (xy 128.825528 -239.558573) (xy 128.871686 -239.531924) (xy 128.9213 -239.512452)
			(xy 128.973262 -239.500592) (xy 129.026412 -239.496609) (xy 129.079562 -239.500592) (xy 129.131524 -239.512452)
			(xy 129.181138 -239.531924) (xy 129.227296 -239.558573) (xy 129.268967 -239.591804) (xy 129.305219 -239.630875)
			(xy 129.335243 -239.674912) (xy 129.358369 -239.722933) (xy 129.374079 -239.773863) (xy 129.382022 -239.826567)
			(xy 129.38252 -239.853216) (xy 129.382022 -239.879865) (xy 129.610602 -239.879865) (xy 129.610602 -239.826567)
			(xy 129.618545 -239.773863) (xy 129.634255 -239.722933) (xy 129.657381 -239.674912) (xy 129.687405 -239.630875)
			(xy 129.723657 -239.591804) (xy 129.765328 -239.558573) (xy 129.811486 -239.531924) (xy 129.8611 -239.512452)
			(xy 129.913062 -239.500592) (xy 129.966212 -239.496609) (xy 130.019362 -239.500592) (xy 130.071324 -239.512452)
			(xy 130.120938 -239.531924) (xy 130.167096 -239.558573) (xy 130.208767 -239.591804) (xy 130.245019 -239.630875)
			(xy 130.275043 -239.674912) (xy 130.298169 -239.722933) (xy 130.313879 -239.773863) (xy 130.321822 -239.826567)
			(xy 130.32232 -239.853216) (xy 130.321822 -239.879865) (xy 130.550402 -239.879865) (xy 130.550402 -239.826567)
			(xy 130.558345 -239.773863) (xy 130.574055 -239.722933) (xy 130.597181 -239.674912) (xy 130.627205 -239.630875)
			(xy 130.663457 -239.591804) (xy 130.705128 -239.558573) (xy 130.751286 -239.531924) (xy 130.8009 -239.512452)
			(xy 130.852862 -239.500592) (xy 130.906012 -239.496609) (xy 130.959162 -239.500592) (xy 131.011124 -239.512452)
			(xy 131.060738 -239.531924) (xy 131.106896 -239.558573) (xy 131.148567 -239.591804) (xy 131.184819 -239.630875)
			(xy 131.214843 -239.674912) (xy 131.237969 -239.722933) (xy 131.253679 -239.773863) (xy 131.261622 -239.826567)
			(xy 131.26212 -239.853216) (xy 131.261622 -239.879865) (xy 131.490456 -239.879865) (xy 131.490456 -239.826567)
			(xy 131.498399 -239.773863) (xy 131.514109 -239.722933) (xy 131.537235 -239.674912) (xy 131.567259 -239.630875)
			(xy 131.603511 -239.591804) (xy 131.645182 -239.558573) (xy 131.69134 -239.531924) (xy 131.740954 -239.512452)
			(xy 131.792916 -239.500592) (xy 131.846066 -239.496609) (xy 131.899216 -239.500592) (xy 131.951178 -239.512452)
			(xy 132.000792 -239.531924) (xy 132.04695 -239.558573) (xy 132.088621 -239.591804) (xy 132.124873 -239.630875)
			(xy 132.154897 -239.674912) (xy 132.178023 -239.722933) (xy 132.193733 -239.773863) (xy 132.201676 -239.826567)
			(xy 132.202174 -239.853216) (xy 132.201676 -239.879865) (xy 132.430002 -239.879865) (xy 132.430002 -239.826567)
			(xy 132.437945 -239.773863) (xy 132.453655 -239.722933) (xy 132.476781 -239.674912) (xy 132.506805 -239.630875)
			(xy 132.543057 -239.591804) (xy 132.584728 -239.558573) (xy 132.630886 -239.531924) (xy 132.6805 -239.512452)
			(xy 132.732462 -239.500592) (xy 132.785612 -239.496609) (xy 132.838762 -239.500592) (xy 132.890724 -239.512452)
			(xy 132.940338 -239.531924) (xy 132.986496 -239.558573) (xy 133.028167 -239.591804) (xy 133.064419 -239.630875)
			(xy 133.094443 -239.674912) (xy 133.117569 -239.722933) (xy 133.133279 -239.773863) (xy 133.141222 -239.826567)
			(xy 133.14172 -239.853216) (xy 133.141222 -239.879865) (xy 133.370056 -239.879865) (xy 133.370056 -239.826567)
			(xy 133.377999 -239.773863) (xy 133.393709 -239.722933) (xy 133.416835 -239.674912) (xy 133.446859 -239.630875)
			(xy 133.483111 -239.591804) (xy 133.524782 -239.558573) (xy 133.57094 -239.531924) (xy 133.620554 -239.512452)
			(xy 133.672516 -239.500592) (xy 133.725666 -239.496609) (xy 133.778816 -239.500592) (xy 133.830778 -239.512452)
			(xy 133.880392 -239.531924) (xy 133.92655 -239.558573) (xy 133.968221 -239.591804) (xy 134.004473 -239.630875)
			(xy 134.034497 -239.674912) (xy 134.057623 -239.722933) (xy 134.073333 -239.773863) (xy 134.081276 -239.826567)
			(xy 134.081774 -239.853216) (xy 134.081276 -239.879865) (xy 134.309602 -239.879865) (xy 134.309602 -239.826567)
			(xy 134.317545 -239.773863) (xy 134.333255 -239.722933) (xy 134.356381 -239.674912) (xy 134.386405 -239.630875)
			(xy 134.422657 -239.591804) (xy 134.464328 -239.558573) (xy 134.510486 -239.531924) (xy 134.5601 -239.512452)
			(xy 134.612062 -239.500592) (xy 134.665212 -239.496609) (xy 134.718362 -239.500592) (xy 134.770324 -239.512452)
			(xy 134.819938 -239.531924) (xy 134.866096 -239.558573) (xy 134.907767 -239.591804) (xy 134.944019 -239.630875)
			(xy 134.974043 -239.674912) (xy 134.997169 -239.722933) (xy 135.012879 -239.773863) (xy 135.020822 -239.826567)
			(xy 135.02132 -239.853216) (xy 135.020822 -239.879865) (xy 135.012879 -239.932569) (xy 134.997169 -239.983499)
			(xy 134.974043 -240.03152) (xy 134.944019 -240.075557) (xy 134.907767 -240.114628) (xy 134.866096 -240.147859)
			(xy 134.819938 -240.174508) (xy 134.770324 -240.19398) (xy 134.718362 -240.20584) (xy 134.665212 -240.209824)
			(xy 134.612062 -240.20584) (xy 134.5601 -240.19398) (xy 134.510486 -240.174508) (xy 134.464328 -240.147859)
			(xy 134.422657 -240.114628) (xy 134.386405 -240.075557) (xy 134.356381 -240.03152) (xy 134.333255 -239.983499)
			(xy 134.317545 -239.932569) (xy 134.309602 -239.879865) (xy 134.081276 -239.879865) (xy 134.073333 -239.932569)
			(xy 134.057623 -239.983499) (xy 134.034497 -240.03152) (xy 134.004473 -240.075557) (xy 133.968221 -240.114628)
			(xy 133.92655 -240.147859) (xy 133.880392 -240.174508) (xy 133.830778 -240.19398) (xy 133.778816 -240.20584)
			(xy 133.725666 -240.209824) (xy 133.672516 -240.20584) (xy 133.620554 -240.19398) (xy 133.57094 -240.174508)
			(xy 133.524782 -240.147859) (xy 133.483111 -240.114628) (xy 133.446859 -240.075557) (xy 133.416835 -240.03152)
			(xy 133.393709 -239.983499) (xy 133.377999 -239.932569) (xy 133.370056 -239.879865) (xy 133.141222 -239.879865)
			(xy 133.133279 -239.932569) (xy 133.117569 -239.983499) (xy 133.094443 -240.03152) (xy 133.064419 -240.075557)
			(xy 133.028167 -240.114628) (xy 132.986496 -240.147859) (xy 132.940338 -240.174508) (xy 132.890724 -240.19398)
			(xy 132.838762 -240.20584) (xy 132.785612 -240.209824) (xy 132.732462 -240.20584) (xy 132.6805 -240.19398)
			(xy 132.630886 -240.174508) (xy 132.584728 -240.147859) (xy 132.543057 -240.114628) (xy 132.506805 -240.075557)
			(xy 132.476781 -240.03152) (xy 132.453655 -239.983499) (xy 132.437945 -239.932569) (xy 132.430002 -239.879865)
			(xy 132.201676 -239.879865) (xy 132.193733 -239.932569) (xy 132.178023 -239.983499) (xy 132.154897 -240.03152)
			(xy 132.124873 -240.075557) (xy 132.088621 -240.114628) (xy 132.04695 -240.147859) (xy 132.000792 -240.174508)
			(xy 131.951178 -240.19398) (xy 131.899216 -240.20584) (xy 131.846066 -240.209824) (xy 131.792916 -240.20584)
			(xy 131.740954 -240.19398) (xy 131.69134 -240.174508) (xy 131.645182 -240.147859) (xy 131.603511 -240.114628)
			(xy 131.567259 -240.075557) (xy 131.537235 -240.03152) (xy 131.514109 -239.983499) (xy 131.498399 -239.932569)
			(xy 131.490456 -239.879865) (xy 131.261622 -239.879865) (xy 131.253679 -239.932569) (xy 131.237969 -239.983499)
			(xy 131.214843 -240.03152) (xy 131.184819 -240.075557) (xy 131.148567 -240.114628) (xy 131.106896 -240.147859)
			(xy 131.060738 -240.174508) (xy 131.011124 -240.19398) (xy 130.959162 -240.20584) (xy 130.906012 -240.209824)
			(xy 130.852862 -240.20584) (xy 130.8009 -240.19398) (xy 130.751286 -240.174508) (xy 130.705128 -240.147859)
			(xy 130.663457 -240.114628) (xy 130.627205 -240.075557) (xy 130.597181 -240.03152) (xy 130.574055 -239.983499)
			(xy 130.558345 -239.932569) (xy 130.550402 -239.879865) (xy 130.321822 -239.879865) (xy 130.313879 -239.932569)
			(xy 130.298169 -239.983499) (xy 130.275043 -240.03152) (xy 130.245019 -240.075557) (xy 130.208767 -240.114628)
			(xy 130.167096 -240.147859) (xy 130.120938 -240.174508) (xy 130.071324 -240.19398) (xy 130.019362 -240.20584)
			(xy 129.966212 -240.209824) (xy 129.913062 -240.20584) (xy 129.8611 -240.19398) (xy 129.811486 -240.174508)
			(xy 129.765328 -240.147859) (xy 129.723657 -240.114628) (xy 129.687405 -240.075557) (xy 129.657381 -240.03152)
			(xy 129.634255 -239.983499) (xy 129.618545 -239.932569) (xy 129.610602 -239.879865) (xy 129.382022 -239.879865)
			(xy 129.374079 -239.932569) (xy 129.358369 -239.983499) (xy 129.335243 -240.03152) (xy 129.305219 -240.075557)
			(xy 129.268967 -240.114628) (xy 129.227296 -240.147859) (xy 129.181138 -240.174508) (xy 129.131524 -240.19398)
			(xy 129.079562 -240.20584) (xy 129.026412 -240.209824) (xy 128.973262 -240.20584) (xy 128.9213 -240.19398)
			(xy 128.871686 -240.174508) (xy 128.825528 -240.147859) (xy 128.783857 -240.114628) (xy 128.747605 -240.075557)
			(xy 128.717581 -240.03152) (xy 128.694455 -239.983499) (xy 128.678745 -239.932569) (xy 128.670802 -239.879865)
			(xy 128.442222 -239.879865) (xy 128.434279 -239.932569) (xy 128.418569 -239.983499) (xy 128.395443 -240.03152)
			(xy 128.365419 -240.075557) (xy 128.329167 -240.114628) (xy 128.287496 -240.147859) (xy 128.241338 -240.174508)
			(xy 128.191724 -240.19398) (xy 128.139762 -240.20584) (xy 128.086612 -240.209824) (xy 128.033462 -240.20584)
			(xy 127.9815 -240.19398) (xy 127.931886 -240.174508) (xy 127.885728 -240.147859) (xy 127.844057 -240.114628)
			(xy 127.807805 -240.075557) (xy 127.777781 -240.03152) (xy 127.754655 -239.983499) (xy 127.738945 -239.932569)
			(xy 127.731002 -239.879865) (xy 127.502422 -239.879865) (xy 127.494479 -239.932569) (xy 127.478769 -239.983499)
			(xy 127.455643 -240.03152) (xy 127.425619 -240.075557) (xy 127.389367 -240.114628) (xy 127.347696 -240.147859)
			(xy 127.301538 -240.174508) (xy 127.251924 -240.19398) (xy 127.199962 -240.20584) (xy 127.146812 -240.209824)
			(xy 127.093662 -240.20584) (xy 127.0417 -240.19398) (xy 126.992086 -240.174508) (xy 126.945928 -240.147859)
			(xy 126.904257 -240.114628) (xy 126.868005 -240.075557) (xy 126.837981 -240.03152) (xy 126.814855 -239.983499)
			(xy 126.799145 -239.932569) (xy 126.791202 -239.879865) (xy 126.562622 -239.879865) (xy 126.554679 -239.932569)
			(xy 126.538969 -239.983499) (xy 126.515843 -240.03152) (xy 126.485819 -240.075557) (xy 126.449567 -240.114628)
			(xy 126.407896 -240.147859) (xy 126.361738 -240.174508) (xy 126.312124 -240.19398) (xy 126.260162 -240.20584)
			(xy 126.207012 -240.209824) (xy 126.153862 -240.20584) (xy 126.1019 -240.19398) (xy 126.052286 -240.174508)
			(xy 126.006128 -240.147859) (xy 125.964457 -240.114628) (xy 125.928205 -240.075557) (xy 125.898181 -240.03152)
			(xy 125.875055 -239.983499) (xy 125.859345 -239.932569) (xy 125.851402 -239.879865) (xy 125.623076 -239.879865)
			(xy 125.615133 -239.932569) (xy 125.599423 -239.983499) (xy 125.576297 -240.03152) (xy 125.546273 -240.075557)
			(xy 125.510021 -240.114628) (xy 125.46835 -240.147859) (xy 125.422192 -240.174508) (xy 125.372578 -240.19398)
			(xy 125.320616 -240.20584) (xy 125.267466 -240.209824) (xy 125.214316 -240.20584) (xy 125.162354 -240.19398)
			(xy 125.11274 -240.174508) (xy 125.066582 -240.147859) (xy 125.024911 -240.114628) (xy 124.988659 -240.075557)
			(xy 124.958635 -240.03152) (xy 124.935509 -239.983499) (xy 124.919799 -239.932569) (xy 124.911856 -239.879865)
			(xy 124.683022 -239.879865) (xy 124.675079 -239.932569) (xy 124.659369 -239.983499) (xy 124.636243 -240.03152)
			(xy 124.606219 -240.075557) (xy 124.569967 -240.114628) (xy 124.528296 -240.147859) (xy 124.482138 -240.174508)
			(xy 124.432524 -240.19398) (xy 124.380562 -240.20584) (xy 124.327412 -240.209824) (xy 124.274262 -240.20584)
			(xy 124.2223 -240.19398) (xy 124.172686 -240.174508) (xy 124.126528 -240.147859) (xy 124.084857 -240.114628)
			(xy 124.048605 -240.075557) (xy 124.018581 -240.03152) (xy 123.995455 -239.983499) (xy 123.979745 -239.932569)
			(xy 123.971802 -239.879865) (xy 123.743222 -239.879865) (xy 123.735279 -239.932569) (xy 123.719569 -239.983499)
			(xy 123.696443 -240.03152) (xy 123.666419 -240.075557) (xy 123.630167 -240.114628) (xy 123.588496 -240.147859)
			(xy 123.542338 -240.174508) (xy 123.492724 -240.19398) (xy 123.440762 -240.20584) (xy 123.387612 -240.209824)
			(xy 123.334462 -240.20584) (xy 123.2825 -240.19398) (xy 123.232886 -240.174508) (xy 123.186728 -240.147859)
			(xy 123.145057 -240.114628) (xy 123.108805 -240.075557) (xy 123.078781 -240.03152) (xy 123.055655 -239.983499)
			(xy 123.039945 -239.932569) (xy 123.032002 -239.879865) (xy 122.803676 -239.879865) (xy 122.795733 -239.932569)
			(xy 122.780023 -239.983499) (xy 122.756897 -240.03152) (xy 122.726873 -240.075557) (xy 122.690621 -240.114628)
			(xy 122.64895 -240.147859) (xy 122.602792 -240.174508) (xy 122.553178 -240.19398) (xy 122.501216 -240.20584)
			(xy 122.448066 -240.209824) (xy 122.394916 -240.20584) (xy 122.342954 -240.19398) (xy 122.29334 -240.174508)
			(xy 122.247182 -240.147859) (xy 122.205511 -240.114628) (xy 122.169259 -240.075557) (xy 122.139235 -240.03152)
			(xy 122.116109 -239.983499) (xy 122.100399 -239.932569) (xy 122.092456 -239.879865) (xy 121.862593 -239.879865)
			(xy 121.860608 -239.906346) (xy 121.848749 -239.958305) (xy 121.829279 -240.007916) (xy 121.802632 -240.054071)
			(xy 121.769404 -240.095739) (xy 121.730336 -240.13199) (xy 121.686302 -240.162013) (xy 121.638286 -240.185138)
			(xy 121.587359 -240.200848) (xy 121.534659 -240.208793) (xy 121.508012 -240.209324) (xy 121.481644 -240.208847)
			(xy 121.429486 -240.201068) (xy 121.404126 -240.19383) (xy 121.389513 -240.189934) (xy 121.359285 -240.189935)
			(xy 121.33038 -240.198778) (xy 121.305327 -240.215691) (xy 121.286317 -240.239193) (xy 121.280174 -240.253012)
			(xy 121.269361 -240.278448) (xy 121.241047 -240.325914) (xy 121.223786 -240.3475) (xy 121.215154 -240.358629)
			(xy 121.203797 -240.384392) (xy 121.199908 -240.412277) (xy 121.203784 -240.440163) (xy 121.215129 -240.465931)
			(xy 121.223786 -240.47704) (xy 121.239226 -240.496287) (xy 121.265204 -240.538235) (xy 121.285135 -240.583372)
			(xy 121.298636 -240.63083) (xy 121.305447 -240.679699) (xy 121.305667 -240.693935) (xy 122.562102 -240.693935)
			(xy 122.562102 -240.640637) (xy 122.570045 -240.587933) (xy 122.585755 -240.537003) (xy 122.608881 -240.488982)
			(xy 122.638905 -240.444945) (xy 122.675157 -240.405874) (xy 122.716828 -240.372643) (xy 122.762986 -240.345994)
			(xy 122.8126 -240.326522) (xy 122.864562 -240.314662) (xy 122.917712 -240.310679) (xy 122.970862 -240.314662)
			(xy 123.022824 -240.326522) (xy 123.072438 -240.345994) (xy 123.118596 -240.372643) (xy 123.160267 -240.405874)
			(xy 123.196519 -240.444945) (xy 123.226543 -240.488982) (xy 123.249669 -240.537003) (xy 123.265379 -240.587933)
			(xy 123.273322 -240.640637) (xy 123.27382 -240.667286) (xy 123.273322 -240.693935) (xy 123.502156 -240.693935)
			(xy 123.502156 -240.640637) (xy 123.510099 -240.587933) (xy 123.525809 -240.537003) (xy 123.548935 -240.488982)
			(xy 123.578959 -240.444945) (xy 123.615211 -240.405874) (xy 123.656882 -240.372643) (xy 123.70304 -240.345994)
			(xy 123.752654 -240.326522) (xy 123.804616 -240.314662) (xy 123.857766 -240.310679) (xy 123.910916 -240.314662)
			(xy 123.962878 -240.326522) (xy 124.012492 -240.345994) (xy 124.05865 -240.372643) (xy 124.100321 -240.405874)
			(xy 124.136573 -240.444945) (xy 124.166597 -240.488982) (xy 124.189723 -240.537003) (xy 124.205433 -240.587933)
			(xy 124.213376 -240.640637) (xy 124.213874 -240.667286) (xy 124.213376 -240.693935) (xy 124.441956 -240.693935)
			(xy 124.441956 -240.640637) (xy 124.449899 -240.587933) (xy 124.465609 -240.537003) (xy 124.488735 -240.488982)
			(xy 124.518759 -240.444945) (xy 124.555011 -240.405874) (xy 124.596682 -240.372643) (xy 124.64284 -240.345994)
			(xy 124.692454 -240.326522) (xy 124.744416 -240.314662) (xy 124.797566 -240.310679) (xy 124.850716 -240.314662)
			(xy 124.902678 -240.326522) (xy 124.952292 -240.345994) (xy 124.99845 -240.372643) (xy 125.040121 -240.405874)
			(xy 125.076373 -240.444945) (xy 125.106397 -240.488982) (xy 125.129523 -240.537003) (xy 125.145233 -240.587933)
			(xy 125.153176 -240.640637) (xy 125.153674 -240.667286) (xy 125.153176 -240.693935) (xy 125.381502 -240.693935)
			(xy 125.381502 -240.640637) (xy 125.389445 -240.587933) (xy 125.405155 -240.537003) (xy 125.428281 -240.488982)
			(xy 125.458305 -240.444945) (xy 125.494557 -240.405874) (xy 125.536228 -240.372643) (xy 125.582386 -240.345994)
			(xy 125.632 -240.326522) (xy 125.683962 -240.314662) (xy 125.737112 -240.310679) (xy 125.790262 -240.314662)
			(xy 125.842224 -240.326522) (xy 125.891838 -240.345994) (xy 125.937996 -240.372643) (xy 125.979667 -240.405874)
			(xy 126.015919 -240.444945) (xy 126.045943 -240.488982) (xy 126.069069 -240.537003) (xy 126.084779 -240.587933)
			(xy 126.092722 -240.640637) (xy 126.09322 -240.667286) (xy 126.092722 -240.693935) (xy 126.321556 -240.693935)
			(xy 126.321556 -240.640637) (xy 126.329499 -240.587933) (xy 126.345209 -240.537003) (xy 126.368335 -240.488982)
			(xy 126.398359 -240.444945) (xy 126.434611 -240.405874) (xy 126.476282 -240.372643) (xy 126.52244 -240.345994)
			(xy 126.572054 -240.326522) (xy 126.624016 -240.314662) (xy 126.677166 -240.310679) (xy 126.730316 -240.314662)
			(xy 126.782278 -240.326522) (xy 126.831892 -240.345994) (xy 126.87805 -240.372643) (xy 126.919721 -240.405874)
			(xy 126.955973 -240.444945) (xy 126.985997 -240.488982) (xy 127.009123 -240.537003) (xy 127.024833 -240.587933)
			(xy 127.032776 -240.640637) (xy 127.033274 -240.667286) (xy 127.032776 -240.693935) (xy 127.261356 -240.693935)
			(xy 127.261356 -240.640637) (xy 127.269299 -240.587933) (xy 127.285009 -240.537003) (xy 127.308135 -240.488982)
			(xy 127.338159 -240.444945) (xy 127.374411 -240.405874) (xy 127.416082 -240.372643) (xy 127.46224 -240.345994)
			(xy 127.511854 -240.326522) (xy 127.563816 -240.314662) (xy 127.616966 -240.310679) (xy 127.670116 -240.314662)
			(xy 127.722078 -240.326522) (xy 127.771692 -240.345994) (xy 127.81785 -240.372643) (xy 127.859521 -240.405874)
			(xy 127.895773 -240.444945) (xy 127.925797 -240.488982) (xy 127.948923 -240.537003) (xy 127.964633 -240.587933)
			(xy 127.972576 -240.640637) (xy 127.973074 -240.667286) (xy 127.972576 -240.693935) (xy 128.201156 -240.693935)
			(xy 128.201156 -240.640637) (xy 128.209099 -240.587933) (xy 128.224809 -240.537003) (xy 128.247935 -240.488982)
			(xy 128.277959 -240.444945) (xy 128.314211 -240.405874) (xy 128.355882 -240.372643) (xy 128.40204 -240.345994)
			(xy 128.451654 -240.326522) (xy 128.503616 -240.314662) (xy 128.556766 -240.310679) (xy 128.609916 -240.314662)
			(xy 128.661878 -240.326522) (xy 128.711492 -240.345994) (xy 128.75765 -240.372643) (xy 128.799321 -240.405874)
			(xy 128.835573 -240.444945) (xy 128.865597 -240.488982) (xy 128.888723 -240.537003) (xy 128.904433 -240.587933)
			(xy 128.912376 -240.640637) (xy 128.912874 -240.667286) (xy 128.912376 -240.693935) (xy 129.140956 -240.693935)
			(xy 129.140956 -240.640637) (xy 129.148899 -240.587933) (xy 129.164609 -240.537003) (xy 129.187735 -240.488982)
			(xy 129.217759 -240.444945) (xy 129.254011 -240.405874) (xy 129.295682 -240.372643) (xy 129.34184 -240.345994)
			(xy 129.391454 -240.326522) (xy 129.443416 -240.314662) (xy 129.496566 -240.310679) (xy 129.549716 -240.314662)
			(xy 129.601678 -240.326522) (xy 129.651292 -240.345994) (xy 129.69745 -240.372643) (xy 129.739121 -240.405874)
			(xy 129.775373 -240.444945) (xy 129.805397 -240.488982) (xy 129.828523 -240.537003) (xy 129.844233 -240.587933)
			(xy 129.852176 -240.640637) (xy 129.852674 -240.667286) (xy 129.852176 -240.693935) (xy 130.080756 -240.693935)
			(xy 130.080756 -240.640637) (xy 130.088699 -240.587933) (xy 130.104409 -240.537003) (xy 130.127535 -240.488982)
			(xy 130.157559 -240.444945) (xy 130.193811 -240.405874) (xy 130.235482 -240.372643) (xy 130.28164 -240.345994)
			(xy 130.331254 -240.326522) (xy 130.383216 -240.314662) (xy 130.436366 -240.310679) (xy 130.489516 -240.314662)
			(xy 130.541478 -240.326522) (xy 130.591092 -240.345994) (xy 130.63725 -240.372643) (xy 130.678921 -240.405874)
			(xy 130.715173 -240.444945) (xy 130.745197 -240.488982) (xy 130.768323 -240.537003) (xy 130.784033 -240.587933)
			(xy 130.791976 -240.640637) (xy 130.792474 -240.667286) (xy 130.791976 -240.693935) (xy 131.020556 -240.693935)
			(xy 131.020556 -240.640637) (xy 131.028499 -240.587933) (xy 131.044209 -240.537003) (xy 131.067335 -240.488982)
			(xy 131.097359 -240.444945) (xy 131.133611 -240.405874) (xy 131.175282 -240.372643) (xy 131.22144 -240.345994)
			(xy 131.271054 -240.326522) (xy 131.323016 -240.314662) (xy 131.376166 -240.310679) (xy 131.429316 -240.314662)
			(xy 131.481278 -240.326522) (xy 131.530892 -240.345994) (xy 131.57705 -240.372643) (xy 131.618721 -240.405874)
			(xy 131.654973 -240.444945) (xy 131.684997 -240.488982) (xy 131.708123 -240.537003) (xy 131.723833 -240.587933)
			(xy 131.731776 -240.640637) (xy 131.732274 -240.667286) (xy 131.731776 -240.693935) (xy 131.960102 -240.693935)
			(xy 131.960102 -240.640637) (xy 131.968045 -240.587933) (xy 131.983755 -240.537003) (xy 132.006881 -240.488982)
			(xy 132.036905 -240.444945) (xy 132.073157 -240.405874) (xy 132.114828 -240.372643) (xy 132.160986 -240.345994)
			(xy 132.2106 -240.326522) (xy 132.262562 -240.314662) (xy 132.315712 -240.310679) (xy 132.368862 -240.314662)
			(xy 132.420824 -240.326522) (xy 132.470438 -240.345994) (xy 132.516596 -240.372643) (xy 132.558267 -240.405874)
			(xy 132.594519 -240.444945) (xy 132.624543 -240.488982) (xy 132.647669 -240.537003) (xy 132.663379 -240.587933)
			(xy 132.671322 -240.640637) (xy 132.67182 -240.667286) (xy 132.671322 -240.693935) (xy 132.900156 -240.693935)
			(xy 132.900156 -240.640637) (xy 132.908099 -240.587933) (xy 132.923809 -240.537003) (xy 132.946935 -240.488982)
			(xy 132.976959 -240.444945) (xy 133.013211 -240.405874) (xy 133.054882 -240.372643) (xy 133.10104 -240.345994)
			(xy 133.150654 -240.326522) (xy 133.202616 -240.314662) (xy 133.255766 -240.310679) (xy 133.308916 -240.314662)
			(xy 133.360878 -240.326522) (xy 133.410492 -240.345994) (xy 133.45665 -240.372643) (xy 133.498321 -240.405874)
			(xy 133.534573 -240.444945) (xy 133.564597 -240.488982) (xy 133.587723 -240.537003) (xy 133.603433 -240.587933)
			(xy 133.611376 -240.640637) (xy 133.611874 -240.667286) (xy 133.611376 -240.693935) (xy 133.839956 -240.693935)
			(xy 133.839956 -240.640637) (xy 133.847899 -240.587933) (xy 133.863609 -240.537003) (xy 133.886735 -240.488982)
			(xy 133.916759 -240.444945) (xy 133.953011 -240.405874) (xy 133.994682 -240.372643) (xy 134.04084 -240.345994)
			(xy 134.090454 -240.326522) (xy 134.142416 -240.314662) (xy 134.195566 -240.310679) (xy 134.248716 -240.314662)
			(xy 134.300678 -240.326522) (xy 134.350292 -240.345994) (xy 134.39645 -240.372643) (xy 134.438121 -240.405874)
			(xy 134.474373 -240.444945) (xy 134.504397 -240.488982) (xy 134.527523 -240.537003) (xy 134.543233 -240.587933)
			(xy 134.551176 -240.640637) (xy 134.551674 -240.667286) (xy 134.551176 -240.693935) (xy 134.543233 -240.746639)
			(xy 134.527523 -240.797569) (xy 134.504397 -240.84559) (xy 134.474373 -240.889627) (xy 134.438121 -240.928698)
			(xy 134.39645 -240.961929) (xy 134.350292 -240.988578) (xy 134.300678 -241.00805) (xy 134.248716 -241.01991)
			(xy 134.195566 -241.023894) (xy 134.142416 -241.01991) (xy 134.090454 -241.00805) (xy 134.04084 -240.988578)
			(xy 133.994682 -240.961929) (xy 133.953011 -240.928698) (xy 133.916759 -240.889627) (xy 133.886735 -240.84559)
			(xy 133.863609 -240.797569) (xy 133.847899 -240.746639) (xy 133.839956 -240.693935) (xy 133.611376 -240.693935)
			(xy 133.603433 -240.746639) (xy 133.587723 -240.797569) (xy 133.564597 -240.84559) (xy 133.534573 -240.889627)
			(xy 133.498321 -240.928698) (xy 133.45665 -240.961929) (xy 133.410492 -240.988578) (xy 133.360878 -241.00805)
			(xy 133.308916 -241.01991) (xy 133.255766 -241.023894) (xy 133.202616 -241.01991) (xy 133.150654 -241.00805)
			(xy 133.10104 -240.988578) (xy 133.054882 -240.961929) (xy 133.013211 -240.928698) (xy 132.976959 -240.889627)
			(xy 132.946935 -240.84559) (xy 132.923809 -240.797569) (xy 132.908099 -240.746639) (xy 132.900156 -240.693935)
			(xy 132.671322 -240.693935) (xy 132.663379 -240.746639) (xy 132.647669 -240.797569) (xy 132.624543 -240.84559)
			(xy 132.594519 -240.889627) (xy 132.558267 -240.928698) (xy 132.516596 -240.961929) (xy 132.470438 -240.988578)
			(xy 132.420824 -241.00805) (xy 132.368862 -241.01991) (xy 132.315712 -241.023894) (xy 132.262562 -241.01991)
			(xy 132.2106 -241.00805) (xy 132.160986 -240.988578) (xy 132.114828 -240.961929) (xy 132.073157 -240.928698)
			(xy 132.036905 -240.889627) (xy 132.006881 -240.84559) (xy 131.983755 -240.797569) (xy 131.968045 -240.746639)
			(xy 131.960102 -240.693935) (xy 131.731776 -240.693935) (xy 131.723833 -240.746639) (xy 131.708123 -240.797569)
			(xy 131.684997 -240.84559) (xy 131.654973 -240.889627) (xy 131.618721 -240.928698) (xy 131.57705 -240.961929)
			(xy 131.530892 -240.988578) (xy 131.481278 -241.00805) (xy 131.429316 -241.01991) (xy 131.376166 -241.023894)
			(xy 131.323016 -241.01991) (xy 131.271054 -241.00805) (xy 131.22144 -240.988578) (xy 131.175282 -240.961929)
			(xy 131.133611 -240.928698) (xy 131.097359 -240.889627) (xy 131.067335 -240.84559) (xy 131.044209 -240.797569)
			(xy 131.028499 -240.746639) (xy 131.020556 -240.693935) (xy 130.791976 -240.693935) (xy 130.784033 -240.746639)
			(xy 130.768323 -240.797569) (xy 130.745197 -240.84559) (xy 130.715173 -240.889627) (xy 130.678921 -240.928698)
			(xy 130.63725 -240.961929) (xy 130.591092 -240.988578) (xy 130.541478 -241.00805) (xy 130.489516 -241.01991)
			(xy 130.436366 -241.023894) (xy 130.383216 -241.01991) (xy 130.331254 -241.00805) (xy 130.28164 -240.988578)
			(xy 130.235482 -240.961929) (xy 130.193811 -240.928698) (xy 130.157559 -240.889627) (xy 130.127535 -240.84559)
			(xy 130.104409 -240.797569) (xy 130.088699 -240.746639) (xy 130.080756 -240.693935) (xy 129.852176 -240.693935)
			(xy 129.844233 -240.746639) (xy 129.828523 -240.797569) (xy 129.805397 -240.84559) (xy 129.775373 -240.889627)
			(xy 129.739121 -240.928698) (xy 129.69745 -240.961929) (xy 129.651292 -240.988578) (xy 129.601678 -241.00805)
			(xy 129.549716 -241.01991) (xy 129.496566 -241.023894) (xy 129.443416 -241.01991) (xy 129.391454 -241.00805)
			(xy 129.34184 -240.988578) (xy 129.295682 -240.961929) (xy 129.254011 -240.928698) (xy 129.217759 -240.889627)
			(xy 129.187735 -240.84559) (xy 129.164609 -240.797569) (xy 129.148899 -240.746639) (xy 129.140956 -240.693935)
			(xy 128.912376 -240.693935) (xy 128.904433 -240.746639) (xy 128.888723 -240.797569) (xy 128.865597 -240.84559)
			(xy 128.835573 -240.889627) (xy 128.799321 -240.928698) (xy 128.75765 -240.961929) (xy 128.711492 -240.988578)
			(xy 128.661878 -241.00805) (xy 128.609916 -241.01991) (xy 128.556766 -241.023894) (xy 128.503616 -241.01991)
			(xy 128.451654 -241.00805) (xy 128.40204 -240.988578) (xy 128.355882 -240.961929) (xy 128.314211 -240.928698)
			(xy 128.277959 -240.889627) (xy 128.247935 -240.84559) (xy 128.224809 -240.797569) (xy 128.209099 -240.746639)
			(xy 128.201156 -240.693935) (xy 127.972576 -240.693935) (xy 127.964633 -240.746639) (xy 127.948923 -240.797569)
			(xy 127.925797 -240.84559) (xy 127.895773 -240.889627) (xy 127.859521 -240.928698) (xy 127.81785 -240.961929)
			(xy 127.771692 -240.988578) (xy 127.722078 -241.00805) (xy 127.670116 -241.01991) (xy 127.616966 -241.023894)
			(xy 127.563816 -241.01991) (xy 127.511854 -241.00805) (xy 127.46224 -240.988578) (xy 127.416082 -240.961929)
			(xy 127.374411 -240.928698) (xy 127.338159 -240.889627) (xy 127.308135 -240.84559) (xy 127.285009 -240.797569)
			(xy 127.269299 -240.746639) (xy 127.261356 -240.693935) (xy 127.032776 -240.693935) (xy 127.024833 -240.746639)
			(xy 127.009123 -240.797569) (xy 126.985997 -240.84559) (xy 126.955973 -240.889627) (xy 126.919721 -240.928698)
			(xy 126.87805 -240.961929) (xy 126.831892 -240.988578) (xy 126.782278 -241.00805) (xy 126.730316 -241.01991)
			(xy 126.677166 -241.023894) (xy 126.624016 -241.01991) (xy 126.572054 -241.00805) (xy 126.52244 -240.988578)
			(xy 126.476282 -240.961929) (xy 126.434611 -240.928698) (xy 126.398359 -240.889627) (xy 126.368335 -240.84559)
			(xy 126.345209 -240.797569) (xy 126.329499 -240.746639) (xy 126.321556 -240.693935) (xy 126.092722 -240.693935)
			(xy 126.084779 -240.746639) (xy 126.069069 -240.797569) (xy 126.045943 -240.84559) (xy 126.015919 -240.889627)
			(xy 125.979667 -240.928698) (xy 125.937996 -240.961929) (xy 125.891838 -240.988578) (xy 125.842224 -241.00805)
			(xy 125.790262 -241.01991) (xy 125.737112 -241.023894) (xy 125.683962 -241.01991) (xy 125.632 -241.00805)
			(xy 125.582386 -240.988578) (xy 125.536228 -240.961929) (xy 125.494557 -240.928698) (xy 125.458305 -240.889627)
			(xy 125.428281 -240.84559) (xy 125.405155 -240.797569) (xy 125.389445 -240.746639) (xy 125.381502 -240.693935)
			(xy 125.153176 -240.693935) (xy 125.145233 -240.746639) (xy 125.129523 -240.797569) (xy 125.106397 -240.84559)
			(xy 125.076373 -240.889627) (xy 125.040121 -240.928698) (xy 124.99845 -240.961929) (xy 124.952292 -240.988578)
			(xy 124.902678 -241.00805) (xy 124.850716 -241.01991) (xy 124.797566 -241.023894) (xy 124.744416 -241.01991)
			(xy 124.692454 -241.00805) (xy 124.64284 -240.988578) (xy 124.596682 -240.961929) (xy 124.555011 -240.928698)
			(xy 124.518759 -240.889627) (xy 124.488735 -240.84559) (xy 124.465609 -240.797569) (xy 124.449899 -240.746639)
			(xy 124.441956 -240.693935) (xy 124.213376 -240.693935) (xy 124.205433 -240.746639) (xy 124.189723 -240.797569)
			(xy 124.166597 -240.84559) (xy 124.136573 -240.889627) (xy 124.100321 -240.928698) (xy 124.05865 -240.961929)
			(xy 124.012492 -240.988578) (xy 123.962878 -241.00805) (xy 123.910916 -241.01991) (xy 123.857766 -241.023894)
			(xy 123.804616 -241.01991) (xy 123.752654 -241.00805) (xy 123.70304 -240.988578) (xy 123.656882 -240.961929)
			(xy 123.615211 -240.928698) (xy 123.578959 -240.889627) (xy 123.548935 -240.84559) (xy 123.525809 -240.797569)
			(xy 123.510099 -240.746639) (xy 123.502156 -240.693935) (xy 123.273322 -240.693935) (xy 123.265379 -240.746639)
			(xy 123.249669 -240.797569) (xy 123.226543 -240.84559) (xy 123.196519 -240.889627) (xy 123.160267 -240.928698)
			(xy 123.118596 -240.961929) (xy 123.072438 -240.988578) (xy 123.022824 -241.00805) (xy 122.970862 -241.01991)
			(xy 122.917712 -241.023894) (xy 122.864562 -241.01991) (xy 122.8126 -241.00805) (xy 122.762986 -240.988578)
			(xy 122.716828 -240.961929) (xy 122.675157 -240.928698) (xy 122.638905 -240.889627) (xy 122.608881 -240.84559)
			(xy 122.585755 -240.797569) (xy 122.570045 -240.746639) (xy 122.562102 -240.693935) (xy 121.305667 -240.693935)
			(xy 121.305828 -240.70437) (xy 121.30531 -240.732357) (xy 121.296558 -240.787644) (xy 121.279265 -240.840881)
			(xy 121.253857 -240.890757) (xy 121.220959 -240.936044) (xy 121.181382 -240.975627) (xy 121.136099 -241.008531)
			(xy 121.086227 -241.033946) (xy 121.032993 -241.051247) (xy 120.977707 -241.060006) (xy 120.94972 -241.060478)
			(xy 120.920175 -241.059897) (xy 120.861896 -241.050143) (xy 120.806028 -241.0309) (xy 120.779794 -241.017298)
			(xy 120.766327 -241.010597) (xy 120.736876 -241.004559) (xy 120.706942 -241.007352) (xy 120.679116 -241.018735)
			(xy 120.655806 -241.037722) (xy 120.63903 -241.06267) (xy 120.63024 -241.091421) (xy 120.62968 -241.106452)
			(xy 120.62968 -241.507751) (xy 122.092456 -241.507751) (xy 122.092456 -241.454453) (xy 122.100399 -241.401749)
			(xy 122.116109 -241.350819) (xy 122.139235 -241.302798) (xy 122.169259 -241.258761) (xy 122.205511 -241.21969)
			(xy 122.247182 -241.186459) (xy 122.29334 -241.15981) (xy 122.342954 -241.140338) (xy 122.394916 -241.128478)
			(xy 122.448066 -241.124495) (xy 122.501216 -241.128478) (xy 122.553178 -241.140338) (xy 122.602792 -241.15981)
			(xy 122.64895 -241.186459) (xy 122.690621 -241.21969) (xy 122.726873 -241.258761) (xy 122.756897 -241.302798)
			(xy 122.780023 -241.350819) (xy 122.795733 -241.401749) (xy 122.803676 -241.454453) (xy 122.804174 -241.481102)
			(xy 122.803676 -241.507751) (xy 123.032002 -241.507751) (xy 123.032002 -241.454453) (xy 123.039945 -241.401749)
			(xy 123.055655 -241.350819) (xy 123.078781 -241.302798) (xy 123.108805 -241.258761) (xy 123.145057 -241.21969)
			(xy 123.186728 -241.186459) (xy 123.232886 -241.15981) (xy 123.2825 -241.140338) (xy 123.334462 -241.128478)
			(xy 123.387612 -241.124495) (xy 123.440762 -241.128478) (xy 123.492724 -241.140338) (xy 123.542338 -241.15981)
			(xy 123.588496 -241.186459) (xy 123.630167 -241.21969) (xy 123.666419 -241.258761) (xy 123.696443 -241.302798)
			(xy 123.719569 -241.350819) (xy 123.735279 -241.401749) (xy 123.743222 -241.454453) (xy 123.74372 -241.481102)
			(xy 123.743222 -241.507751) (xy 123.971802 -241.507751) (xy 123.971802 -241.454453) (xy 123.979745 -241.401749)
			(xy 123.995455 -241.350819) (xy 124.018581 -241.302798) (xy 124.048605 -241.258761) (xy 124.084857 -241.21969)
			(xy 124.126528 -241.186459) (xy 124.172686 -241.15981) (xy 124.2223 -241.140338) (xy 124.274262 -241.128478)
			(xy 124.327412 -241.124495) (xy 124.380562 -241.128478) (xy 124.432524 -241.140338) (xy 124.482138 -241.15981)
			(xy 124.528296 -241.186459) (xy 124.569967 -241.21969) (xy 124.606219 -241.258761) (xy 124.636243 -241.302798)
			(xy 124.659369 -241.350819) (xy 124.675079 -241.401749) (xy 124.683022 -241.454453) (xy 124.68352 -241.481102)
			(xy 124.683022 -241.507751) (xy 124.911602 -241.507751) (xy 124.911602 -241.454453) (xy 124.919545 -241.401749)
			(xy 124.935255 -241.350819) (xy 124.958381 -241.302798) (xy 124.988405 -241.258761) (xy 125.024657 -241.21969)
			(xy 125.066328 -241.186459) (xy 125.112486 -241.15981) (xy 125.1621 -241.140338) (xy 125.214062 -241.128478)
			(xy 125.267212 -241.124495) (xy 125.320362 -241.128478) (xy 125.372324 -241.140338) (xy 125.421938 -241.15981)
			(xy 125.468096 -241.186459) (xy 125.509767 -241.21969) (xy 125.546019 -241.258761) (xy 125.576043 -241.302798)
			(xy 125.599169 -241.350819) (xy 125.614879 -241.401749) (xy 125.622822 -241.454453) (xy 125.62332 -241.481102)
			(xy 125.622822 -241.507751) (xy 125.851402 -241.507751) (xy 125.851402 -241.454453) (xy 125.859345 -241.401749)
			(xy 125.875055 -241.350819) (xy 125.898181 -241.302798) (xy 125.928205 -241.258761) (xy 125.964457 -241.21969)
			(xy 126.006128 -241.186459) (xy 126.052286 -241.15981) (xy 126.1019 -241.140338) (xy 126.153862 -241.128478)
			(xy 126.207012 -241.124495) (xy 126.260162 -241.128478) (xy 126.312124 -241.140338) (xy 126.361738 -241.15981)
			(xy 126.407896 -241.186459) (xy 126.449567 -241.21969) (xy 126.485819 -241.258761) (xy 126.515843 -241.302798)
			(xy 126.538969 -241.350819) (xy 126.554679 -241.401749) (xy 126.562622 -241.454453) (xy 126.56312 -241.481102)
			(xy 126.562622 -241.507751) (xy 126.791202 -241.507751) (xy 126.791202 -241.454453) (xy 126.799145 -241.401749)
			(xy 126.814855 -241.350819) (xy 126.837981 -241.302798) (xy 126.868005 -241.258761) (xy 126.904257 -241.21969)
			(xy 126.945928 -241.186459) (xy 126.992086 -241.15981) (xy 127.0417 -241.140338) (xy 127.093662 -241.128478)
			(xy 127.146812 -241.124495) (xy 127.199962 -241.128478) (xy 127.251924 -241.140338) (xy 127.301538 -241.15981)
			(xy 127.347696 -241.186459) (xy 127.389367 -241.21969) (xy 127.425619 -241.258761) (xy 127.455643 -241.302798)
			(xy 127.478769 -241.350819) (xy 127.494479 -241.401749) (xy 127.502422 -241.454453) (xy 127.50292 -241.481102)
			(xy 127.502422 -241.507751) (xy 127.731002 -241.507751) (xy 127.731002 -241.454453) (xy 127.738945 -241.401749)
			(xy 127.754655 -241.350819) (xy 127.777781 -241.302798) (xy 127.807805 -241.258761) (xy 127.844057 -241.21969)
			(xy 127.885728 -241.186459) (xy 127.931886 -241.15981) (xy 127.9815 -241.140338) (xy 128.033462 -241.128478)
			(xy 128.086612 -241.124495) (xy 128.139762 -241.128478) (xy 128.191724 -241.140338) (xy 128.241338 -241.15981)
			(xy 128.287496 -241.186459) (xy 128.329167 -241.21969) (xy 128.365419 -241.258761) (xy 128.395443 -241.302798)
			(xy 128.418569 -241.350819) (xy 128.434279 -241.401749) (xy 128.442222 -241.454453) (xy 128.44272 -241.481102)
			(xy 128.442222 -241.507751) (xy 128.671056 -241.507751) (xy 128.671056 -241.454453) (xy 128.678999 -241.401749)
			(xy 128.694709 -241.350819) (xy 128.717835 -241.302798) (xy 128.747859 -241.258761) (xy 128.784111 -241.21969)
			(xy 128.825782 -241.186459) (xy 128.87194 -241.15981) (xy 128.921554 -241.140338) (xy 128.973516 -241.128478)
			(xy 129.026666 -241.124495) (xy 129.079816 -241.128478) (xy 129.131778 -241.140338) (xy 129.181392 -241.15981)
			(xy 129.22755 -241.186459) (xy 129.269221 -241.21969) (xy 129.305473 -241.258761) (xy 129.335497 -241.302798)
			(xy 129.358623 -241.350819) (xy 129.374333 -241.401749) (xy 129.382276 -241.454453) (xy 129.382774 -241.481102)
			(xy 129.382276 -241.507751) (xy 129.610602 -241.507751) (xy 129.610602 -241.454453) (xy 129.618545 -241.401749)
			(xy 129.634255 -241.350819) (xy 129.657381 -241.302798) (xy 129.687405 -241.258761) (xy 129.723657 -241.21969)
			(xy 129.765328 -241.186459) (xy 129.811486 -241.15981) (xy 129.8611 -241.140338) (xy 129.913062 -241.128478)
			(xy 129.966212 -241.124495) (xy 130.019362 -241.128478) (xy 130.071324 -241.140338) (xy 130.120938 -241.15981)
			(xy 130.167096 -241.186459) (xy 130.208767 -241.21969) (xy 130.245019 -241.258761) (xy 130.275043 -241.302798)
			(xy 130.298169 -241.350819) (xy 130.313879 -241.401749) (xy 130.321822 -241.454453) (xy 130.32232 -241.481102)
			(xy 130.321822 -241.507751) (xy 130.550402 -241.507751) (xy 130.550402 -241.454453) (xy 130.558345 -241.401749)
			(xy 130.574055 -241.350819) (xy 130.597181 -241.302798) (xy 130.627205 -241.258761) (xy 130.663457 -241.21969)
			(xy 130.705128 -241.186459) (xy 130.751286 -241.15981) (xy 130.8009 -241.140338) (xy 130.852862 -241.128478)
			(xy 130.906012 -241.124495) (xy 130.959162 -241.128478) (xy 131.011124 -241.140338) (xy 131.060738 -241.15981)
			(xy 131.106896 -241.186459) (xy 131.148567 -241.21969) (xy 131.184819 -241.258761) (xy 131.214843 -241.302798)
			(xy 131.237969 -241.350819) (xy 131.253679 -241.401749) (xy 131.261622 -241.454453) (xy 131.26212 -241.481102)
			(xy 131.261622 -241.507751) (xy 131.490202 -241.507751) (xy 131.490202 -241.454453) (xy 131.498145 -241.401749)
			(xy 131.513855 -241.350819) (xy 131.536981 -241.302798) (xy 131.567005 -241.258761) (xy 131.603257 -241.21969)
			(xy 131.644928 -241.186459) (xy 131.691086 -241.15981) (xy 131.7407 -241.140338) (xy 131.792662 -241.128478)
			(xy 131.845812 -241.124495) (xy 131.898962 -241.128478) (xy 131.950924 -241.140338) (xy 132.000538 -241.15981)
			(xy 132.046696 -241.186459) (xy 132.088367 -241.21969) (xy 132.124619 -241.258761) (xy 132.154643 -241.302798)
			(xy 132.177769 -241.350819) (xy 132.193479 -241.401749) (xy 132.201422 -241.454453) (xy 132.20192 -241.481102)
			(xy 132.201422 -241.507751) (xy 132.430002 -241.507751) (xy 132.430002 -241.454453) (xy 132.437945 -241.401749)
			(xy 132.453655 -241.350819) (xy 132.476781 -241.302798) (xy 132.506805 -241.258761) (xy 132.543057 -241.21969)
			(xy 132.584728 -241.186459) (xy 132.630886 -241.15981) (xy 132.6805 -241.140338) (xy 132.732462 -241.128478)
			(xy 132.785612 -241.124495) (xy 132.838762 -241.128478) (xy 132.890724 -241.140338) (xy 132.940338 -241.15981)
			(xy 132.986496 -241.186459) (xy 133.028167 -241.21969) (xy 133.064419 -241.258761) (xy 133.094443 -241.302798)
			(xy 133.117569 -241.350819) (xy 133.133279 -241.401749) (xy 133.141222 -241.454453) (xy 133.14172 -241.481102)
			(xy 133.141222 -241.507751) (xy 133.370056 -241.507751) (xy 133.370056 -241.454453) (xy 133.377999 -241.401749)
			(xy 133.393709 -241.350819) (xy 133.416835 -241.302798) (xy 133.446859 -241.258761) (xy 133.483111 -241.21969)
			(xy 133.524782 -241.186459) (xy 133.57094 -241.15981) (xy 133.620554 -241.140338) (xy 133.672516 -241.128478)
			(xy 133.725666 -241.124495) (xy 133.778816 -241.128478) (xy 133.830778 -241.140338) (xy 133.880392 -241.15981)
			(xy 133.92655 -241.186459) (xy 133.968221 -241.21969) (xy 134.004473 -241.258761) (xy 134.034497 -241.302798)
			(xy 134.057623 -241.350819) (xy 134.073333 -241.401749) (xy 134.081276 -241.454453) (xy 134.081774 -241.481102)
			(xy 134.081276 -241.507751) (xy 134.309602 -241.507751) (xy 134.309602 -241.454453) (xy 134.317545 -241.401749)
			(xy 134.333255 -241.350819) (xy 134.356381 -241.302798) (xy 134.386405 -241.258761) (xy 134.422657 -241.21969)
			(xy 134.464328 -241.186459) (xy 134.510486 -241.15981) (xy 134.5601 -241.140338) (xy 134.612062 -241.128478)
			(xy 134.665212 -241.124495) (xy 134.718362 -241.128478) (xy 134.770324 -241.140338) (xy 134.819938 -241.15981)
			(xy 134.866096 -241.186459) (xy 134.907767 -241.21969) (xy 134.944019 -241.258761) (xy 134.974043 -241.302798)
			(xy 134.997169 -241.350819) (xy 135.012879 -241.401749) (xy 135.020822 -241.454453) (xy 135.02132 -241.481102)
			(xy 135.020822 -241.507751) (xy 135.012879 -241.560455) (xy 134.997169 -241.611385) (xy 134.974043 -241.659406)
			(xy 134.944019 -241.703443) (xy 134.907767 -241.742514) (xy 134.866096 -241.775745) (xy 134.819938 -241.802394)
			(xy 134.770324 -241.821866) (xy 134.718362 -241.833726) (xy 134.665212 -241.83771) (xy 134.612062 -241.833726)
			(xy 134.5601 -241.821866) (xy 134.510486 -241.802394) (xy 134.464328 -241.775745) (xy 134.422657 -241.742514)
			(xy 134.386405 -241.703443) (xy 134.356381 -241.659406) (xy 134.333255 -241.611385) (xy 134.317545 -241.560455)
			(xy 134.309602 -241.507751) (xy 134.081276 -241.507751) (xy 134.073333 -241.560455) (xy 134.057623 -241.611385)
			(xy 134.034497 -241.659406) (xy 134.004473 -241.703443) (xy 133.968221 -241.742514) (xy 133.92655 -241.775745)
			(xy 133.880392 -241.802394) (xy 133.830778 -241.821866) (xy 133.778816 -241.833726) (xy 133.725666 -241.83771)
			(xy 133.672516 -241.833726) (xy 133.620554 -241.821866) (xy 133.57094 -241.802394) (xy 133.524782 -241.775745)
			(xy 133.483111 -241.742514) (xy 133.446859 -241.703443) (xy 133.416835 -241.659406) (xy 133.393709 -241.611385)
			(xy 133.377999 -241.560455) (xy 133.370056 -241.507751) (xy 133.141222 -241.507751) (xy 133.133279 -241.560455)
			(xy 133.117569 -241.611385) (xy 133.094443 -241.659406) (xy 133.064419 -241.703443) (xy 133.028167 -241.742514)
			(xy 132.986496 -241.775745) (xy 132.940338 -241.802394) (xy 132.890724 -241.821866) (xy 132.838762 -241.833726)
			(xy 132.785612 -241.83771) (xy 132.732462 -241.833726) (xy 132.6805 -241.821866) (xy 132.630886 -241.802394)
			(xy 132.584728 -241.775745) (xy 132.543057 -241.742514) (xy 132.506805 -241.703443) (xy 132.476781 -241.659406)
			(xy 132.453655 -241.611385) (xy 132.437945 -241.560455) (xy 132.430002 -241.507751) (xy 132.201422 -241.507751)
			(xy 132.193479 -241.560455) (xy 132.177769 -241.611385) (xy 132.154643 -241.659406) (xy 132.124619 -241.703443)
			(xy 132.088367 -241.742514) (xy 132.046696 -241.775745) (xy 132.000538 -241.802394) (xy 131.950924 -241.821866)
			(xy 131.898962 -241.833726) (xy 131.845812 -241.83771) (xy 131.792662 -241.833726) (xy 131.7407 -241.821866)
			(xy 131.691086 -241.802394) (xy 131.644928 -241.775745) (xy 131.603257 -241.742514) (xy 131.567005 -241.703443)
			(xy 131.536981 -241.659406) (xy 131.513855 -241.611385) (xy 131.498145 -241.560455) (xy 131.490202 -241.507751)
			(xy 131.261622 -241.507751) (xy 131.253679 -241.560455) (xy 131.237969 -241.611385) (xy 131.214843 -241.659406)
			(xy 131.184819 -241.703443) (xy 131.148567 -241.742514) (xy 131.106896 -241.775745) (xy 131.060738 -241.802394)
			(xy 131.011124 -241.821866) (xy 130.959162 -241.833726) (xy 130.906012 -241.83771) (xy 130.852862 -241.833726)
			(xy 130.8009 -241.821866) (xy 130.751286 -241.802394) (xy 130.705128 -241.775745) (xy 130.663457 -241.742514)
			(xy 130.627205 -241.703443) (xy 130.597181 -241.659406) (xy 130.574055 -241.611385) (xy 130.558345 -241.560455)
			(xy 130.550402 -241.507751) (xy 130.321822 -241.507751) (xy 130.313879 -241.560455) (xy 130.298169 -241.611385)
			(xy 130.275043 -241.659406) (xy 130.245019 -241.703443) (xy 130.208767 -241.742514) (xy 130.167096 -241.775745)
			(xy 130.120938 -241.802394) (xy 130.071324 -241.821866) (xy 130.019362 -241.833726) (xy 129.966212 -241.83771)
			(xy 129.913062 -241.833726) (xy 129.8611 -241.821866) (xy 129.811486 -241.802394) (xy 129.765328 -241.775745)
			(xy 129.723657 -241.742514) (xy 129.687405 -241.703443) (xy 129.657381 -241.659406) (xy 129.634255 -241.611385)
			(xy 129.618545 -241.560455) (xy 129.610602 -241.507751) (xy 129.382276 -241.507751) (xy 129.374333 -241.560455)
			(xy 129.358623 -241.611385) (xy 129.335497 -241.659406) (xy 129.305473 -241.703443) (xy 129.269221 -241.742514)
			(xy 129.22755 -241.775745) (xy 129.181392 -241.802394) (xy 129.131778 -241.821866) (xy 129.079816 -241.833726)
			(xy 129.026666 -241.83771) (xy 128.973516 -241.833726) (xy 128.921554 -241.821866) (xy 128.87194 -241.802394)
			(xy 128.825782 -241.775745) (xy 128.784111 -241.742514) (xy 128.747859 -241.703443) (xy 128.717835 -241.659406)
			(xy 128.694709 -241.611385) (xy 128.678999 -241.560455) (xy 128.671056 -241.507751) (xy 128.442222 -241.507751)
			(xy 128.434279 -241.560455) (xy 128.418569 -241.611385) (xy 128.395443 -241.659406) (xy 128.365419 -241.703443)
			(xy 128.329167 -241.742514) (xy 128.287496 -241.775745) (xy 128.241338 -241.802394) (xy 128.191724 -241.821866)
			(xy 128.139762 -241.833726) (xy 128.086612 -241.83771) (xy 128.033462 -241.833726) (xy 127.9815 -241.821866)
			(xy 127.931886 -241.802394) (xy 127.885728 -241.775745) (xy 127.844057 -241.742514) (xy 127.807805 -241.703443)
			(xy 127.777781 -241.659406) (xy 127.754655 -241.611385) (xy 127.738945 -241.560455) (xy 127.731002 -241.507751)
			(xy 127.502422 -241.507751) (xy 127.494479 -241.560455) (xy 127.478769 -241.611385) (xy 127.455643 -241.659406)
			(xy 127.425619 -241.703443) (xy 127.389367 -241.742514) (xy 127.347696 -241.775745) (xy 127.301538 -241.802394)
			(xy 127.251924 -241.821866) (xy 127.199962 -241.833726) (xy 127.146812 -241.83771) (xy 127.093662 -241.833726)
			(xy 127.0417 -241.821866) (xy 126.992086 -241.802394) (xy 126.945928 -241.775745) (xy 126.904257 -241.742514)
			(xy 126.868005 -241.703443) (xy 126.837981 -241.659406) (xy 126.814855 -241.611385) (xy 126.799145 -241.560455)
			(xy 126.791202 -241.507751) (xy 126.562622 -241.507751) (xy 126.554679 -241.560455) (xy 126.538969 -241.611385)
			(xy 126.515843 -241.659406) (xy 126.485819 -241.703443) (xy 126.449567 -241.742514) (xy 126.407896 -241.775745)
			(xy 126.361738 -241.802394) (xy 126.312124 -241.821866) (xy 126.260162 -241.833726) (xy 126.207012 -241.83771)
			(xy 126.153862 -241.833726) (xy 126.1019 -241.821866) (xy 126.052286 -241.802394) (xy 126.006128 -241.775745)
			(xy 125.964457 -241.742514) (xy 125.928205 -241.703443) (xy 125.898181 -241.659406) (xy 125.875055 -241.611385)
			(xy 125.859345 -241.560455) (xy 125.851402 -241.507751) (xy 125.622822 -241.507751) (xy 125.614879 -241.560455)
			(xy 125.599169 -241.611385) (xy 125.576043 -241.659406) (xy 125.546019 -241.703443) (xy 125.509767 -241.742514)
			(xy 125.468096 -241.775745) (xy 125.421938 -241.802394) (xy 125.372324 -241.821866) (xy 125.320362 -241.833726)
			(xy 125.267212 -241.83771) (xy 125.214062 -241.833726) (xy 125.1621 -241.821866) (xy 125.112486 -241.802394)
			(xy 125.066328 -241.775745) (xy 125.024657 -241.742514) (xy 124.988405 -241.703443) (xy 124.958381 -241.659406)
			(xy 124.935255 -241.611385) (xy 124.919545 -241.560455) (xy 124.911602 -241.507751) (xy 124.683022 -241.507751)
			(xy 124.675079 -241.560455) (xy 124.659369 -241.611385) (xy 124.636243 -241.659406) (xy 124.606219 -241.703443)
			(xy 124.569967 -241.742514) (xy 124.528296 -241.775745) (xy 124.482138 -241.802394) (xy 124.432524 -241.821866)
			(xy 124.380562 -241.833726) (xy 124.327412 -241.83771) (xy 124.274262 -241.833726) (xy 124.2223 -241.821866)
			(xy 124.172686 -241.802394) (xy 124.126528 -241.775745) (xy 124.084857 -241.742514) (xy 124.048605 -241.703443)
			(xy 124.018581 -241.659406) (xy 123.995455 -241.611385) (xy 123.979745 -241.560455) (xy 123.971802 -241.507751)
			(xy 123.743222 -241.507751) (xy 123.735279 -241.560455) (xy 123.719569 -241.611385) (xy 123.696443 -241.659406)
			(xy 123.666419 -241.703443) (xy 123.630167 -241.742514) (xy 123.588496 -241.775745) (xy 123.542338 -241.802394)
			(xy 123.492724 -241.821866) (xy 123.440762 -241.833726) (xy 123.387612 -241.83771) (xy 123.334462 -241.833726)
			(xy 123.2825 -241.821866) (xy 123.232886 -241.802394) (xy 123.186728 -241.775745) (xy 123.145057 -241.742514)
			(xy 123.108805 -241.703443) (xy 123.078781 -241.659406) (xy 123.055655 -241.611385) (xy 123.039945 -241.560455)
			(xy 123.032002 -241.507751) (xy 122.803676 -241.507751) (xy 122.795733 -241.560455) (xy 122.780023 -241.611385)
			(xy 122.756897 -241.659406) (xy 122.726873 -241.703443) (xy 122.690621 -241.742514) (xy 122.64895 -241.775745)
			(xy 122.602792 -241.802394) (xy 122.553178 -241.821866) (xy 122.501216 -241.833726) (xy 122.448066 -241.83771)
			(xy 122.394916 -241.833726) (xy 122.342954 -241.821866) (xy 122.29334 -241.802394) (xy 122.247182 -241.775745)
			(xy 122.205511 -241.742514) (xy 122.169259 -241.703443) (xy 122.139235 -241.659406) (xy 122.116109 -241.611385)
			(xy 122.100399 -241.560455) (xy 122.092456 -241.507751) (xy 120.62968 -241.507751) (xy 120.62968 -242.321567)
			(xy 122.562356 -242.321567) (xy 122.562356 -242.268269) (xy 122.570299 -242.215565) (xy 122.586009 -242.164635)
			(xy 122.609135 -242.116614) (xy 122.639159 -242.072577) (xy 122.675411 -242.033506) (xy 122.717082 -242.000275)
			(xy 122.76324 -241.973626) (xy 122.812854 -241.954154) (xy 122.864816 -241.942294) (xy 122.917966 -241.938311)
			(xy 122.971116 -241.942294) (xy 123.023078 -241.954154) (xy 123.072692 -241.973626) (xy 123.11885 -242.000275)
			(xy 123.160521 -242.033506) (xy 123.196773 -242.072577) (xy 123.226797 -242.116614) (xy 123.249923 -242.164635)
			(xy 123.265633 -242.215565) (xy 123.273576 -242.268269) (xy 123.274074 -242.294918) (xy 123.273576 -242.321567)
			(xy 123.502156 -242.321567) (xy 123.502156 -242.268269) (xy 123.510099 -242.215565) (xy 123.525809 -242.164635)
			(xy 123.548935 -242.116614) (xy 123.578959 -242.072577) (xy 123.615211 -242.033506) (xy 123.656882 -242.000275)
			(xy 123.70304 -241.973626) (xy 123.752654 -241.954154) (xy 123.804616 -241.942294) (xy 123.857766 -241.938311)
			(xy 123.910916 -241.942294) (xy 123.962878 -241.954154) (xy 124.012492 -241.973626) (xy 124.05865 -242.000275)
			(xy 124.100321 -242.033506) (xy 124.136573 -242.072577) (xy 124.166597 -242.116614) (xy 124.189723 -242.164635)
			(xy 124.205433 -242.215565) (xy 124.213376 -242.268269) (xy 124.213874 -242.294918) (xy 124.213376 -242.321567)
			(xy 124.441956 -242.321567) (xy 124.441956 -242.268269) (xy 124.449899 -242.215565) (xy 124.465609 -242.164635)
			(xy 124.488735 -242.116614) (xy 124.518759 -242.072577) (xy 124.555011 -242.033506) (xy 124.596682 -242.000275)
			(xy 124.64284 -241.973626) (xy 124.692454 -241.954154) (xy 124.744416 -241.942294) (xy 124.797566 -241.938311)
			(xy 124.850716 -241.942294) (xy 124.902678 -241.954154) (xy 124.952292 -241.973626) (xy 124.99845 -242.000275)
			(xy 125.040121 -242.033506) (xy 125.076373 -242.072577) (xy 125.106397 -242.116614) (xy 125.129523 -242.164635)
			(xy 125.145233 -242.215565) (xy 125.153176 -242.268269) (xy 125.153674 -242.294918) (xy 125.153176 -242.321567)
			(xy 125.381756 -242.321567) (xy 125.381756 -242.268269) (xy 125.389699 -242.215565) (xy 125.405409 -242.164635)
			(xy 125.428535 -242.116614) (xy 125.458559 -242.072577) (xy 125.494811 -242.033506) (xy 125.536482 -242.000275)
			(xy 125.58264 -241.973626) (xy 125.632254 -241.954154) (xy 125.684216 -241.942294) (xy 125.737366 -241.938311)
			(xy 125.790516 -241.942294) (xy 125.842478 -241.954154) (xy 125.892092 -241.973626) (xy 125.93825 -242.000275)
			(xy 125.979921 -242.033506) (xy 126.016173 -242.072577) (xy 126.046197 -242.116614) (xy 126.069323 -242.164635)
			(xy 126.085033 -242.215565) (xy 126.092976 -242.268269) (xy 126.093474 -242.294918) (xy 126.092976 -242.321567)
			(xy 126.321556 -242.321567) (xy 126.321556 -242.268269) (xy 126.329499 -242.215565) (xy 126.345209 -242.164635)
			(xy 126.368335 -242.116614) (xy 126.398359 -242.072577) (xy 126.434611 -242.033506) (xy 126.476282 -242.000275)
			(xy 126.52244 -241.973626) (xy 126.572054 -241.954154) (xy 126.624016 -241.942294) (xy 126.677166 -241.938311)
			(xy 126.730316 -241.942294) (xy 126.782278 -241.954154) (xy 126.831892 -241.973626) (xy 126.87805 -242.000275)
			(xy 126.919721 -242.033506) (xy 126.955973 -242.072577) (xy 126.985997 -242.116614) (xy 127.009123 -242.164635)
			(xy 127.024833 -242.215565) (xy 127.032776 -242.268269) (xy 127.033274 -242.294918) (xy 127.032776 -242.321567)
			(xy 127.261356 -242.321567) (xy 127.261356 -242.268269) (xy 127.269299 -242.215565) (xy 127.285009 -242.164635)
			(xy 127.308135 -242.116614) (xy 127.338159 -242.072577) (xy 127.374411 -242.033506) (xy 127.416082 -242.000275)
			(xy 127.46224 -241.973626) (xy 127.511854 -241.954154) (xy 127.563816 -241.942294) (xy 127.616966 -241.938311)
			(xy 127.670116 -241.942294) (xy 127.722078 -241.954154) (xy 127.771692 -241.973626) (xy 127.81785 -242.000275)
			(xy 127.859521 -242.033506) (xy 127.895773 -242.072577) (xy 127.925797 -242.116614) (xy 127.948923 -242.164635)
			(xy 127.964633 -242.215565) (xy 127.972576 -242.268269) (xy 127.973074 -242.294918) (xy 127.972576 -242.321567)
			(xy 128.201156 -242.321567) (xy 128.201156 -242.268269) (xy 128.209099 -242.215565) (xy 128.224809 -242.164635)
			(xy 128.247935 -242.116614) (xy 128.277959 -242.072577) (xy 128.314211 -242.033506) (xy 128.355882 -242.000275)
			(xy 128.40204 -241.973626) (xy 128.451654 -241.954154) (xy 128.503616 -241.942294) (xy 128.556766 -241.938311)
			(xy 128.609916 -241.942294) (xy 128.661878 -241.954154) (xy 128.711492 -241.973626) (xy 128.75765 -242.000275)
			(xy 128.799321 -242.033506) (xy 128.835573 -242.072577) (xy 128.865597 -242.116614) (xy 128.888723 -242.164635)
			(xy 128.904433 -242.215565) (xy 128.912376 -242.268269) (xy 128.912874 -242.294918) (xy 128.912376 -242.321567)
			(xy 129.140956 -242.321567) (xy 129.140956 -242.268269) (xy 129.148899 -242.215565) (xy 129.164609 -242.164635)
			(xy 129.187735 -242.116614) (xy 129.217759 -242.072577) (xy 129.254011 -242.033506) (xy 129.295682 -242.000275)
			(xy 129.34184 -241.973626) (xy 129.391454 -241.954154) (xy 129.443416 -241.942294) (xy 129.496566 -241.938311)
			(xy 129.549716 -241.942294) (xy 129.601678 -241.954154) (xy 129.651292 -241.973626) (xy 129.69745 -242.000275)
			(xy 129.739121 -242.033506) (xy 129.775373 -242.072577) (xy 129.805397 -242.116614) (xy 129.828523 -242.164635)
			(xy 129.844233 -242.215565) (xy 129.852176 -242.268269) (xy 129.852674 -242.294918) (xy 129.852176 -242.321567)
			(xy 130.080756 -242.321567) (xy 130.080756 -242.268269) (xy 130.088699 -242.215565) (xy 130.104409 -242.164635)
			(xy 130.127535 -242.116614) (xy 130.157559 -242.072577) (xy 130.193811 -242.033506) (xy 130.235482 -242.000275)
			(xy 130.28164 -241.973626) (xy 130.331254 -241.954154) (xy 130.383216 -241.942294) (xy 130.436366 -241.938311)
			(xy 130.489516 -241.942294) (xy 130.541478 -241.954154) (xy 130.591092 -241.973626) (xy 130.63725 -242.000275)
			(xy 130.678921 -242.033506) (xy 130.715173 -242.072577) (xy 130.745197 -242.116614) (xy 130.768323 -242.164635)
			(xy 130.784033 -242.215565) (xy 130.791976 -242.268269) (xy 130.792474 -242.294918) (xy 130.791976 -242.321567)
			(xy 131.020556 -242.321567) (xy 131.020556 -242.268269) (xy 131.028499 -242.215565) (xy 131.044209 -242.164635)
			(xy 131.067335 -242.116614) (xy 131.097359 -242.072577) (xy 131.133611 -242.033506) (xy 131.175282 -242.000275)
			(xy 131.22144 -241.973626) (xy 131.271054 -241.954154) (xy 131.323016 -241.942294) (xy 131.376166 -241.938311)
			(xy 131.429316 -241.942294) (xy 131.481278 -241.954154) (xy 131.530892 -241.973626) (xy 131.57705 -242.000275)
			(xy 131.618721 -242.033506) (xy 131.654973 -242.072577) (xy 131.684997 -242.116614) (xy 131.708123 -242.164635)
			(xy 131.723833 -242.215565) (xy 131.731776 -242.268269) (xy 131.732274 -242.294918) (xy 131.731776 -242.321567)
			(xy 131.960356 -242.321567) (xy 131.960356 -242.268269) (xy 131.968299 -242.215565) (xy 131.984009 -242.164635)
			(xy 132.007135 -242.116614) (xy 132.037159 -242.072577) (xy 132.073411 -242.033506) (xy 132.115082 -242.000275)
			(xy 132.16124 -241.973626) (xy 132.210854 -241.954154) (xy 132.262816 -241.942294) (xy 132.315966 -241.938311)
			(xy 132.369116 -241.942294) (xy 132.421078 -241.954154) (xy 132.470692 -241.973626) (xy 132.51685 -242.000275)
			(xy 132.558521 -242.033506) (xy 132.594773 -242.072577) (xy 132.624797 -242.116614) (xy 132.647923 -242.164635)
			(xy 132.663633 -242.215565) (xy 132.671576 -242.268269) (xy 132.672074 -242.294918) (xy 132.671576 -242.321567)
			(xy 132.900156 -242.321567) (xy 132.900156 -242.268269) (xy 132.908099 -242.215565) (xy 132.923809 -242.164635)
			(xy 132.946935 -242.116614) (xy 132.976959 -242.072577) (xy 133.013211 -242.033506) (xy 133.054882 -242.000275)
			(xy 133.10104 -241.973626) (xy 133.150654 -241.954154) (xy 133.202616 -241.942294) (xy 133.255766 -241.938311)
			(xy 133.308916 -241.942294) (xy 133.360878 -241.954154) (xy 133.410492 -241.973626) (xy 133.45665 -242.000275)
			(xy 133.498321 -242.033506) (xy 133.534573 -242.072577) (xy 133.564597 -242.116614) (xy 133.587723 -242.164635)
			(xy 133.603433 -242.215565) (xy 133.611376 -242.268269) (xy 133.611874 -242.294918) (xy 133.611376 -242.321567)
			(xy 133.839956 -242.321567) (xy 133.839956 -242.268269) (xy 133.847899 -242.215565) (xy 133.863609 -242.164635)
			(xy 133.886735 -242.116614) (xy 133.916759 -242.072577) (xy 133.953011 -242.033506) (xy 133.994682 -242.000275)
			(xy 134.04084 -241.973626) (xy 134.090454 -241.954154) (xy 134.142416 -241.942294) (xy 134.195566 -241.938311)
			(xy 134.248716 -241.942294) (xy 134.300678 -241.954154) (xy 134.350292 -241.973626) (xy 134.39645 -242.000275)
			(xy 134.438121 -242.033506) (xy 134.474373 -242.072577) (xy 134.504397 -242.116614) (xy 134.527523 -242.164635)
			(xy 134.543233 -242.215565) (xy 134.551176 -242.268269) (xy 134.551674 -242.294918) (xy 134.551176 -242.321567)
			(xy 134.543233 -242.374271) (xy 134.527523 -242.425201) (xy 134.504397 -242.473222) (xy 134.474373 -242.517259)
			(xy 134.438121 -242.55633) (xy 134.39645 -242.589561) (xy 134.350292 -242.61621) (xy 134.300678 -242.635682)
			(xy 134.248716 -242.647542) (xy 134.195566 -242.651526) (xy 134.142416 -242.647542) (xy 134.090454 -242.635682)
			(xy 134.04084 -242.61621) (xy 133.994682 -242.589561) (xy 133.953011 -242.55633) (xy 133.916759 -242.517259)
			(xy 133.886735 -242.473222) (xy 133.863609 -242.425201) (xy 133.847899 -242.374271) (xy 133.839956 -242.321567)
			(xy 133.611376 -242.321567) (xy 133.603433 -242.374271) (xy 133.587723 -242.425201) (xy 133.564597 -242.473222)
			(xy 133.534573 -242.517259) (xy 133.498321 -242.55633) (xy 133.45665 -242.589561) (xy 133.410492 -242.61621)
			(xy 133.360878 -242.635682) (xy 133.308916 -242.647542) (xy 133.255766 -242.651526) (xy 133.202616 -242.647542)
			(xy 133.150654 -242.635682) (xy 133.10104 -242.61621) (xy 133.054882 -242.589561) (xy 133.013211 -242.55633)
			(xy 132.976959 -242.517259) (xy 132.946935 -242.473222) (xy 132.923809 -242.425201) (xy 132.908099 -242.374271)
			(xy 132.900156 -242.321567) (xy 132.671576 -242.321567) (xy 132.663633 -242.374271) (xy 132.647923 -242.425201)
			(xy 132.624797 -242.473222) (xy 132.594773 -242.517259) (xy 132.558521 -242.55633) (xy 132.51685 -242.589561)
			(xy 132.470692 -242.61621) (xy 132.421078 -242.635682) (xy 132.369116 -242.647542) (xy 132.315966 -242.651526)
			(xy 132.262816 -242.647542) (xy 132.210854 -242.635682) (xy 132.16124 -242.61621) (xy 132.115082 -242.589561)
			(xy 132.073411 -242.55633) (xy 132.037159 -242.517259) (xy 132.007135 -242.473222) (xy 131.984009 -242.425201)
			(xy 131.968299 -242.374271) (xy 131.960356 -242.321567) (xy 131.731776 -242.321567) (xy 131.723833 -242.374271)
			(xy 131.708123 -242.425201) (xy 131.684997 -242.473222) (xy 131.654973 -242.517259) (xy 131.618721 -242.55633)
			(xy 131.57705 -242.589561) (xy 131.530892 -242.61621) (xy 131.481278 -242.635682) (xy 131.429316 -242.647542)
			(xy 131.376166 -242.651526) (xy 131.323016 -242.647542) (xy 131.271054 -242.635682) (xy 131.22144 -242.61621)
			(xy 131.175282 -242.589561) (xy 131.133611 -242.55633) (xy 131.097359 -242.517259) (xy 131.067335 -242.473222)
			(xy 131.044209 -242.425201) (xy 131.028499 -242.374271) (xy 131.020556 -242.321567) (xy 130.791976 -242.321567)
			(xy 130.784033 -242.374271) (xy 130.768323 -242.425201) (xy 130.745197 -242.473222) (xy 130.715173 -242.517259)
			(xy 130.678921 -242.55633) (xy 130.63725 -242.589561) (xy 130.591092 -242.61621) (xy 130.541478 -242.635682)
			(xy 130.489516 -242.647542) (xy 130.436366 -242.651526) (xy 130.383216 -242.647542) (xy 130.331254 -242.635682)
			(xy 130.28164 -242.61621) (xy 130.235482 -242.589561) (xy 130.193811 -242.55633) (xy 130.157559 -242.517259)
			(xy 130.127535 -242.473222) (xy 130.104409 -242.425201) (xy 130.088699 -242.374271) (xy 130.080756 -242.321567)
			(xy 129.852176 -242.321567) (xy 129.844233 -242.374271) (xy 129.828523 -242.425201) (xy 129.805397 -242.473222)
			(xy 129.775373 -242.517259) (xy 129.739121 -242.55633) (xy 129.69745 -242.589561) (xy 129.651292 -242.61621)
			(xy 129.601678 -242.635682) (xy 129.549716 -242.647542) (xy 129.496566 -242.651526) (xy 129.443416 -242.647542)
			(xy 129.391454 -242.635682) (xy 129.34184 -242.61621) (xy 129.295682 -242.589561) (xy 129.254011 -242.55633)
			(xy 129.217759 -242.517259) (xy 129.187735 -242.473222) (xy 129.164609 -242.425201) (xy 129.148899 -242.374271)
			(xy 129.140956 -242.321567) (xy 128.912376 -242.321567) (xy 128.904433 -242.374271) (xy 128.888723 -242.425201)
			(xy 128.865597 -242.473222) (xy 128.835573 -242.517259) (xy 128.799321 -242.55633) (xy 128.75765 -242.589561)
			(xy 128.711492 -242.61621) (xy 128.661878 -242.635682) (xy 128.609916 -242.647542) (xy 128.556766 -242.651526)
			(xy 128.503616 -242.647542) (xy 128.451654 -242.635682) (xy 128.40204 -242.61621) (xy 128.355882 -242.589561)
			(xy 128.314211 -242.55633) (xy 128.277959 -242.517259) (xy 128.247935 -242.473222) (xy 128.224809 -242.425201)
			(xy 128.209099 -242.374271) (xy 128.201156 -242.321567) (xy 127.972576 -242.321567) (xy 127.964633 -242.374271)
			(xy 127.948923 -242.425201) (xy 127.925797 -242.473222) (xy 127.895773 -242.517259) (xy 127.859521 -242.55633)
			(xy 127.81785 -242.589561) (xy 127.771692 -242.61621) (xy 127.722078 -242.635682) (xy 127.670116 -242.647542)
			(xy 127.616966 -242.651526) (xy 127.563816 -242.647542) (xy 127.511854 -242.635682) (xy 127.46224 -242.61621)
			(xy 127.416082 -242.589561) (xy 127.374411 -242.55633) (xy 127.338159 -242.517259) (xy 127.308135 -242.473222)
			(xy 127.285009 -242.425201) (xy 127.269299 -242.374271) (xy 127.261356 -242.321567) (xy 127.032776 -242.321567)
			(xy 127.024833 -242.374271) (xy 127.009123 -242.425201) (xy 126.985997 -242.473222) (xy 126.955973 -242.517259)
			(xy 126.919721 -242.55633) (xy 126.87805 -242.589561) (xy 126.831892 -242.61621) (xy 126.782278 -242.635682)
			(xy 126.730316 -242.647542) (xy 126.677166 -242.651526) (xy 126.624016 -242.647542) (xy 126.572054 -242.635682)
			(xy 126.52244 -242.61621) (xy 126.476282 -242.589561) (xy 126.434611 -242.55633) (xy 126.398359 -242.517259)
			(xy 126.368335 -242.473222) (xy 126.345209 -242.425201) (xy 126.329499 -242.374271) (xy 126.321556 -242.321567)
			(xy 126.092976 -242.321567) (xy 126.085033 -242.374271) (xy 126.069323 -242.425201) (xy 126.046197 -242.473222)
			(xy 126.016173 -242.517259) (xy 125.979921 -242.55633) (xy 125.93825 -242.589561) (xy 125.892092 -242.61621)
			(xy 125.842478 -242.635682) (xy 125.790516 -242.647542) (xy 125.737366 -242.651526) (xy 125.684216 -242.647542)
			(xy 125.632254 -242.635682) (xy 125.58264 -242.61621) (xy 125.536482 -242.589561) (xy 125.494811 -242.55633)
			(xy 125.458559 -242.517259) (xy 125.428535 -242.473222) (xy 125.405409 -242.425201) (xy 125.389699 -242.374271)
			(xy 125.381756 -242.321567) (xy 125.153176 -242.321567) (xy 125.145233 -242.374271) (xy 125.129523 -242.425201)
			(xy 125.106397 -242.473222) (xy 125.076373 -242.517259) (xy 125.040121 -242.55633) (xy 124.99845 -242.589561)
			(xy 124.952292 -242.61621) (xy 124.902678 -242.635682) (xy 124.850716 -242.647542) (xy 124.797566 -242.651526)
			(xy 124.744416 -242.647542) (xy 124.692454 -242.635682) (xy 124.64284 -242.61621) (xy 124.596682 -242.589561)
			(xy 124.555011 -242.55633) (xy 124.518759 -242.517259) (xy 124.488735 -242.473222) (xy 124.465609 -242.425201)
			(xy 124.449899 -242.374271) (xy 124.441956 -242.321567) (xy 124.213376 -242.321567) (xy 124.205433 -242.374271)
			(xy 124.189723 -242.425201) (xy 124.166597 -242.473222) (xy 124.136573 -242.517259) (xy 124.100321 -242.55633)
			(xy 124.05865 -242.589561) (xy 124.012492 -242.61621) (xy 123.962878 -242.635682) (xy 123.910916 -242.647542)
			(xy 123.857766 -242.651526) (xy 123.804616 -242.647542) (xy 123.752654 -242.635682) (xy 123.70304 -242.61621)
			(xy 123.656882 -242.589561) (xy 123.615211 -242.55633) (xy 123.578959 -242.517259) (xy 123.548935 -242.473222)
			(xy 123.525809 -242.425201) (xy 123.510099 -242.374271) (xy 123.502156 -242.321567) (xy 123.273576 -242.321567)
			(xy 123.265633 -242.374271) (xy 123.249923 -242.425201) (xy 123.226797 -242.473222) (xy 123.196773 -242.517259)
			(xy 123.160521 -242.55633) (xy 123.11885 -242.589561) (xy 123.072692 -242.61621) (xy 123.023078 -242.635682)
			(xy 122.971116 -242.647542) (xy 122.917966 -242.651526) (xy 122.864816 -242.647542) (xy 122.812854 -242.635682)
			(xy 122.76324 -242.61621) (xy 122.717082 -242.589561) (xy 122.675411 -242.55633) (xy 122.639159 -242.517259)
			(xy 122.609135 -242.473222) (xy 122.586009 -242.425201) (xy 122.570299 -242.374271) (xy 122.562356 -242.321567)
			(xy 120.62968 -242.321567) (xy 120.62968 -242.915948) (xy 120.409991 -243.135637) (xy 122.092202 -243.135637)
			(xy 122.092202 -243.082339) (xy 122.100145 -243.029635) (xy 122.115855 -242.978705) (xy 122.138981 -242.930684)
			(xy 122.169005 -242.886647) (xy 122.205257 -242.847576) (xy 122.246928 -242.814345) (xy 122.293086 -242.787696)
			(xy 122.3427 -242.768224) (xy 122.394662 -242.756364) (xy 122.447812 -242.752381) (xy 122.500962 -242.756364)
			(xy 122.552924 -242.768224) (xy 122.602538 -242.787696) (xy 122.648696 -242.814345) (xy 122.690367 -242.847576)
			(xy 122.726619 -242.886647) (xy 122.756643 -242.930684) (xy 122.779769 -242.978705) (xy 122.795479 -243.029635)
			(xy 122.803422 -243.082339) (xy 122.80392 -243.108988) (xy 122.803422 -243.135637) (xy 123.032002 -243.135637)
			(xy 123.032002 -243.082339) (xy 123.039945 -243.029635) (xy 123.055655 -242.978705) (xy 123.078781 -242.930684)
			(xy 123.108805 -242.886647) (xy 123.145057 -242.847576) (xy 123.186728 -242.814345) (xy 123.232886 -242.787696)
			(xy 123.2825 -242.768224) (xy 123.334462 -242.756364) (xy 123.387612 -242.752381) (xy 123.440762 -242.756364)
			(xy 123.492724 -242.768224) (xy 123.542338 -242.787696) (xy 123.588496 -242.814345) (xy 123.630167 -242.847576)
			(xy 123.666419 -242.886647) (xy 123.696443 -242.930684) (xy 123.719569 -242.978705) (xy 123.735279 -243.029635)
			(xy 123.743222 -243.082339) (xy 123.74372 -243.108988) (xy 123.743222 -243.135637) (xy 123.971802 -243.135637)
			(xy 123.971802 -243.082339) (xy 123.979745 -243.029635) (xy 123.995455 -242.978705) (xy 124.018581 -242.930684)
			(xy 124.048605 -242.886647) (xy 124.084857 -242.847576) (xy 124.126528 -242.814345) (xy 124.172686 -242.787696)
			(xy 124.2223 -242.768224) (xy 124.274262 -242.756364) (xy 124.327412 -242.752381) (xy 124.380562 -242.756364)
			(xy 124.432524 -242.768224) (xy 124.482138 -242.787696) (xy 124.528296 -242.814345) (xy 124.569967 -242.847576)
			(xy 124.606219 -242.886647) (xy 124.636243 -242.930684) (xy 124.659369 -242.978705) (xy 124.675079 -243.029635)
			(xy 124.683022 -243.082339) (xy 124.68352 -243.108988) (xy 124.683022 -243.135637) (xy 124.911602 -243.135637)
			(xy 124.911602 -243.082339) (xy 124.919545 -243.029635) (xy 124.935255 -242.978705) (xy 124.958381 -242.930684)
			(xy 124.988405 -242.886647) (xy 125.024657 -242.847576) (xy 125.066328 -242.814345) (xy 125.112486 -242.787696)
			(xy 125.1621 -242.768224) (xy 125.214062 -242.756364) (xy 125.267212 -242.752381) (xy 125.320362 -242.756364)
			(xy 125.372324 -242.768224) (xy 125.421938 -242.787696) (xy 125.468096 -242.814345) (xy 125.509767 -242.847576)
			(xy 125.546019 -242.886647) (xy 125.576043 -242.930684) (xy 125.599169 -242.978705) (xy 125.614879 -243.029635)
			(xy 125.622822 -243.082339) (xy 125.62332 -243.108988) (xy 125.622822 -243.135637) (xy 125.851656 -243.135637)
			(xy 125.851656 -243.082339) (xy 125.859599 -243.029635) (xy 125.875309 -242.978705) (xy 125.898435 -242.930684)
			(xy 125.928459 -242.886647) (xy 125.964711 -242.847576) (xy 126.006382 -242.814345) (xy 126.05254 -242.787696)
			(xy 126.102154 -242.768224) (xy 126.154116 -242.756364) (xy 126.207266 -242.752381) (xy 126.260416 -242.756364)
			(xy 126.312378 -242.768224) (xy 126.361992 -242.787696) (xy 126.40815 -242.814345) (xy 126.449821 -242.847576)
			(xy 126.486073 -242.886647) (xy 126.516097 -242.930684) (xy 126.539223 -242.978705) (xy 126.554933 -243.029635)
			(xy 126.562876 -243.082339) (xy 126.563374 -243.108988) (xy 126.562876 -243.135637) (xy 126.791202 -243.135637)
			(xy 126.791202 -243.082339) (xy 126.799145 -243.029635) (xy 126.814855 -242.978705) (xy 126.837981 -242.930684)
			(xy 126.868005 -242.886647) (xy 126.904257 -242.847576) (xy 126.945928 -242.814345) (xy 126.992086 -242.787696)
			(xy 127.0417 -242.768224) (xy 127.093662 -242.756364) (xy 127.146812 -242.752381) (xy 127.199962 -242.756364)
			(xy 127.251924 -242.768224) (xy 127.301538 -242.787696) (xy 127.347696 -242.814345) (xy 127.389367 -242.847576)
			(xy 127.425619 -242.886647) (xy 127.455643 -242.930684) (xy 127.478769 -242.978705) (xy 127.494479 -243.029635)
			(xy 127.502422 -243.082339) (xy 127.50292 -243.108988) (xy 127.502422 -243.135637) (xy 127.731002 -243.135637)
			(xy 127.731002 -243.082339) (xy 127.738945 -243.029635) (xy 127.754655 -242.978705) (xy 127.777781 -242.930684)
			(xy 127.807805 -242.886647) (xy 127.844057 -242.847576) (xy 127.885728 -242.814345) (xy 127.931886 -242.787696)
			(xy 127.9815 -242.768224) (xy 128.033462 -242.756364) (xy 128.086612 -242.752381) (xy 128.139762 -242.756364)
			(xy 128.191724 -242.768224) (xy 128.241338 -242.787696) (xy 128.287496 -242.814345) (xy 128.329167 -242.847576)
			(xy 128.365419 -242.886647) (xy 128.395443 -242.930684) (xy 128.418569 -242.978705) (xy 128.434279 -243.029635)
			(xy 128.442222 -243.082339) (xy 128.44272 -243.108988) (xy 128.442222 -243.135637) (xy 128.670802 -243.135637)
			(xy 128.670802 -243.082339) (xy 128.678745 -243.029635) (xy 128.694455 -242.978705) (xy 128.717581 -242.930684)
			(xy 128.747605 -242.886647) (xy 128.783857 -242.847576) (xy 128.825528 -242.814345) (xy 128.871686 -242.787696)
			(xy 128.9213 -242.768224) (xy 128.973262 -242.756364) (xy 129.026412 -242.752381) (xy 129.079562 -242.756364)
			(xy 129.131524 -242.768224) (xy 129.181138 -242.787696) (xy 129.227296 -242.814345) (xy 129.268967 -242.847576)
			(xy 129.305219 -242.886647) (xy 129.335243 -242.930684) (xy 129.358369 -242.978705) (xy 129.374079 -243.029635)
			(xy 129.382022 -243.082339) (xy 129.38252 -243.108988) (xy 129.382022 -243.135637) (xy 129.610602 -243.135637)
			(xy 129.610602 -243.082339) (xy 129.618545 -243.029635) (xy 129.634255 -242.978705) (xy 129.657381 -242.930684)
			(xy 129.687405 -242.886647) (xy 129.723657 -242.847576) (xy 129.765328 -242.814345) (xy 129.811486 -242.787696)
			(xy 129.8611 -242.768224) (xy 129.913062 -242.756364) (xy 129.966212 -242.752381) (xy 130.019362 -242.756364)
			(xy 130.071324 -242.768224) (xy 130.120938 -242.787696) (xy 130.167096 -242.814345) (xy 130.208767 -242.847576)
			(xy 130.245019 -242.886647) (xy 130.275043 -242.930684) (xy 130.298169 -242.978705) (xy 130.313879 -243.029635)
			(xy 130.321822 -243.082339) (xy 130.32232 -243.108988) (xy 130.321822 -243.135637) (xy 130.550402 -243.135637)
			(xy 130.550402 -243.082339) (xy 130.558345 -243.029635) (xy 130.574055 -242.978705) (xy 130.597181 -242.930684)
			(xy 130.627205 -242.886647) (xy 130.663457 -242.847576) (xy 130.705128 -242.814345) (xy 130.751286 -242.787696)
			(xy 130.8009 -242.768224) (xy 130.852862 -242.756364) (xy 130.906012 -242.752381) (xy 130.959162 -242.756364)
			(xy 131.011124 -242.768224) (xy 131.060738 -242.787696) (xy 131.106896 -242.814345) (xy 131.148567 -242.847576)
			(xy 131.184819 -242.886647) (xy 131.214843 -242.930684) (xy 131.237969 -242.978705) (xy 131.253679 -243.029635)
			(xy 131.261622 -243.082339) (xy 131.26212 -243.108988) (xy 131.261622 -243.135637) (xy 131.490202 -243.135637)
			(xy 131.490202 -243.082339) (xy 131.498145 -243.029635) (xy 131.513855 -242.978705) (xy 131.536981 -242.930684)
			(xy 131.567005 -242.886647) (xy 131.603257 -242.847576) (xy 131.644928 -242.814345) (xy 131.691086 -242.787696)
			(xy 131.7407 -242.768224) (xy 131.792662 -242.756364) (xy 131.845812 -242.752381) (xy 131.898962 -242.756364)
			(xy 131.950924 -242.768224) (xy 132.000538 -242.787696) (xy 132.046696 -242.814345) (xy 132.088367 -242.847576)
			(xy 132.124619 -242.886647) (xy 132.154643 -242.930684) (xy 132.177769 -242.978705) (xy 132.193479 -243.029635)
			(xy 132.201422 -243.082339) (xy 132.20192 -243.108988) (xy 132.201422 -243.135637) (xy 132.430256 -243.135637)
			(xy 132.430256 -243.082339) (xy 132.438199 -243.029635) (xy 132.453909 -242.978705) (xy 132.477035 -242.930684)
			(xy 132.507059 -242.886647) (xy 132.543311 -242.847576) (xy 132.584982 -242.814345) (xy 132.63114 -242.787696)
			(xy 132.680754 -242.768224) (xy 132.732716 -242.756364) (xy 132.785866 -242.752381) (xy 132.839016 -242.756364)
			(xy 132.890978 -242.768224) (xy 132.940592 -242.787696) (xy 132.98675 -242.814345) (xy 133.028421 -242.847576)
			(xy 133.064673 -242.886647) (xy 133.094697 -242.930684) (xy 133.117823 -242.978705) (xy 133.133533 -243.029635)
			(xy 133.141476 -243.082339) (xy 133.141974 -243.108988) (xy 133.141476 -243.135637) (xy 133.370056 -243.135637)
			(xy 133.370056 -243.082339) (xy 133.377999 -243.029635) (xy 133.393709 -242.978705) (xy 133.416835 -242.930684)
			(xy 133.446859 -242.886647) (xy 133.483111 -242.847576) (xy 133.524782 -242.814345) (xy 133.57094 -242.787696)
			(xy 133.620554 -242.768224) (xy 133.672516 -242.756364) (xy 133.725666 -242.752381) (xy 133.778816 -242.756364)
			(xy 133.830778 -242.768224) (xy 133.880392 -242.787696) (xy 133.92655 -242.814345) (xy 133.968221 -242.847576)
			(xy 134.004473 -242.886647) (xy 134.034497 -242.930684) (xy 134.057623 -242.978705) (xy 134.073333 -243.029635)
			(xy 134.081276 -243.082339) (xy 134.081774 -243.108988) (xy 134.081276 -243.135637) (xy 134.309602 -243.135637)
			(xy 134.309602 -243.082339) (xy 134.317545 -243.029635) (xy 134.333255 -242.978705) (xy 134.356381 -242.930684)
			(xy 134.386405 -242.886647) (xy 134.422657 -242.847576) (xy 134.464328 -242.814345) (xy 134.510486 -242.787696)
			(xy 134.5601 -242.768224) (xy 134.612062 -242.756364) (xy 134.665212 -242.752381) (xy 134.718362 -242.756364)
			(xy 134.770324 -242.768224) (xy 134.819938 -242.787696) (xy 134.866096 -242.814345) (xy 134.907767 -242.847576)
			(xy 134.944019 -242.886647) (xy 134.974043 -242.930684) (xy 134.997169 -242.978705) (xy 135.012879 -243.029635)
			(xy 135.020822 -243.082339) (xy 135.02132 -243.108988) (xy 135.020822 -243.135637) (xy 135.012879 -243.188341)
			(xy 134.997169 -243.239271) (xy 134.974043 -243.287292) (xy 134.944019 -243.331329) (xy 134.907767 -243.3704)
			(xy 134.866096 -243.403631) (xy 134.819938 -243.43028) (xy 134.770324 -243.449752) (xy 134.718362 -243.461612)
			(xy 134.665212 -243.465596) (xy 134.612062 -243.461612) (xy 134.5601 -243.449752) (xy 134.510486 -243.43028)
			(xy 134.464328 -243.403631) (xy 134.422657 -243.3704) (xy 134.386405 -243.331329) (xy 134.356381 -243.287292)
			(xy 134.333255 -243.239271) (xy 134.317545 -243.188341) (xy 134.309602 -243.135637) (xy 134.081276 -243.135637)
			(xy 134.073333 -243.188341) (xy 134.057623 -243.239271) (xy 134.034497 -243.287292) (xy 134.004473 -243.331329)
			(xy 133.968221 -243.3704) (xy 133.92655 -243.403631) (xy 133.880392 -243.43028) (xy 133.830778 -243.449752)
			(xy 133.778816 -243.461612) (xy 133.725666 -243.465596) (xy 133.672516 -243.461612) (xy 133.620554 -243.449752)
			(xy 133.57094 -243.43028) (xy 133.524782 -243.403631) (xy 133.483111 -243.3704) (xy 133.446859 -243.331329)
			(xy 133.416835 -243.287292) (xy 133.393709 -243.239271) (xy 133.377999 -243.188341) (xy 133.370056 -243.135637)
			(xy 133.141476 -243.135637) (xy 133.133533 -243.188341) (xy 133.117823 -243.239271) (xy 133.094697 -243.287292)
			(xy 133.064673 -243.331329) (xy 133.028421 -243.3704) (xy 132.98675 -243.403631) (xy 132.940592 -243.43028)
			(xy 132.890978 -243.449752) (xy 132.839016 -243.461612) (xy 132.785866 -243.465596) (xy 132.732716 -243.461612)
			(xy 132.680754 -243.449752) (xy 132.63114 -243.43028) (xy 132.584982 -243.403631) (xy 132.543311 -243.3704)
			(xy 132.507059 -243.331329) (xy 132.477035 -243.287292) (xy 132.453909 -243.239271) (xy 132.438199 -243.188341)
			(xy 132.430256 -243.135637) (xy 132.201422 -243.135637) (xy 132.193479 -243.188341) (xy 132.177769 -243.239271)
			(xy 132.154643 -243.287292) (xy 132.124619 -243.331329) (xy 132.088367 -243.3704) (xy 132.046696 -243.403631)
			(xy 132.000538 -243.43028) (xy 131.950924 -243.449752) (xy 131.898962 -243.461612) (xy 131.845812 -243.465596)
			(xy 131.792662 -243.461612) (xy 131.7407 -243.449752) (xy 131.691086 -243.43028) (xy 131.644928 -243.403631)
			(xy 131.603257 -243.3704) (xy 131.567005 -243.331329) (xy 131.536981 -243.287292) (xy 131.513855 -243.239271)
			(xy 131.498145 -243.188341) (xy 131.490202 -243.135637) (xy 131.261622 -243.135637) (xy 131.253679 -243.188341)
			(xy 131.237969 -243.239271) (xy 131.214843 -243.287292) (xy 131.184819 -243.331329) (xy 131.148567 -243.3704)
			(xy 131.106896 -243.403631) (xy 131.060738 -243.43028) (xy 131.011124 -243.449752) (xy 130.959162 -243.461612)
			(xy 130.906012 -243.465596) (xy 130.852862 -243.461612) (xy 130.8009 -243.449752) (xy 130.751286 -243.43028)
			(xy 130.705128 -243.403631) (xy 130.663457 -243.3704) (xy 130.627205 -243.331329) (xy 130.597181 -243.287292)
			(xy 130.574055 -243.239271) (xy 130.558345 -243.188341) (xy 130.550402 -243.135637) (xy 130.321822 -243.135637)
			(xy 130.313879 -243.188341) (xy 130.298169 -243.239271) (xy 130.275043 -243.287292) (xy 130.245019 -243.331329)
			(xy 130.208767 -243.3704) (xy 130.167096 -243.403631) (xy 130.120938 -243.43028) (xy 130.071324 -243.449752)
			(xy 130.019362 -243.461612) (xy 129.966212 -243.465596) (xy 129.913062 -243.461612) (xy 129.8611 -243.449752)
			(xy 129.811486 -243.43028) (xy 129.765328 -243.403631) (xy 129.723657 -243.3704) (xy 129.687405 -243.331329)
			(xy 129.657381 -243.287292) (xy 129.634255 -243.239271) (xy 129.618545 -243.188341) (xy 129.610602 -243.135637)
			(xy 129.382022 -243.135637) (xy 129.374079 -243.188341) (xy 129.358369 -243.239271) (xy 129.335243 -243.287292)
			(xy 129.305219 -243.331329) (xy 129.268967 -243.3704) (xy 129.227296 -243.403631) (xy 129.181138 -243.43028)
			(xy 129.131524 -243.449752) (xy 129.079562 -243.461612) (xy 129.026412 -243.465596) (xy 128.973262 -243.461612)
			(xy 128.9213 -243.449752) (xy 128.871686 -243.43028) (xy 128.825528 -243.403631) (xy 128.783857 -243.3704)
			(xy 128.747605 -243.331329) (xy 128.717581 -243.287292) (xy 128.694455 -243.239271) (xy 128.678745 -243.188341)
			(xy 128.670802 -243.135637) (xy 128.442222 -243.135637) (xy 128.434279 -243.188341) (xy 128.418569 -243.239271)
			(xy 128.395443 -243.287292) (xy 128.365419 -243.331329) (xy 128.329167 -243.3704) (xy 128.287496 -243.403631)
			(xy 128.241338 -243.43028) (xy 128.191724 -243.449752) (xy 128.139762 -243.461612) (xy 128.086612 -243.465596)
			(xy 128.033462 -243.461612) (xy 127.9815 -243.449752) (xy 127.931886 -243.43028) (xy 127.885728 -243.403631)
			(xy 127.844057 -243.3704) (xy 127.807805 -243.331329) (xy 127.777781 -243.287292) (xy 127.754655 -243.239271)
			(xy 127.738945 -243.188341) (xy 127.731002 -243.135637) (xy 127.502422 -243.135637) (xy 127.494479 -243.188341)
			(xy 127.478769 -243.239271) (xy 127.455643 -243.287292) (xy 127.425619 -243.331329) (xy 127.389367 -243.3704)
			(xy 127.347696 -243.403631) (xy 127.301538 -243.43028) (xy 127.251924 -243.449752) (xy 127.199962 -243.461612)
			(xy 127.146812 -243.465596) (xy 127.093662 -243.461612) (xy 127.0417 -243.449752) (xy 126.992086 -243.43028)
			(xy 126.945928 -243.403631) (xy 126.904257 -243.3704) (xy 126.868005 -243.331329) (xy 126.837981 -243.287292)
			(xy 126.814855 -243.239271) (xy 126.799145 -243.188341) (xy 126.791202 -243.135637) (xy 126.562876 -243.135637)
			(xy 126.554933 -243.188341) (xy 126.539223 -243.239271) (xy 126.516097 -243.287292) (xy 126.486073 -243.331329)
			(xy 126.449821 -243.3704) (xy 126.40815 -243.403631) (xy 126.361992 -243.43028) (xy 126.312378 -243.449752)
			(xy 126.260416 -243.461612) (xy 126.207266 -243.465596) (xy 126.154116 -243.461612) (xy 126.102154 -243.449752)
			(xy 126.05254 -243.43028) (xy 126.006382 -243.403631) (xy 125.964711 -243.3704) (xy 125.928459 -243.331329)
			(xy 125.898435 -243.287292) (xy 125.875309 -243.239271) (xy 125.859599 -243.188341) (xy 125.851656 -243.135637)
			(xy 125.622822 -243.135637) (xy 125.614879 -243.188341) (xy 125.599169 -243.239271) (xy 125.576043 -243.287292)
			(xy 125.546019 -243.331329) (xy 125.509767 -243.3704) (xy 125.468096 -243.403631) (xy 125.421938 -243.43028)
			(xy 125.372324 -243.449752) (xy 125.320362 -243.461612) (xy 125.267212 -243.465596) (xy 125.214062 -243.461612)
			(xy 125.1621 -243.449752) (xy 125.112486 -243.43028) (xy 125.066328 -243.403631) (xy 125.024657 -243.3704)
			(xy 124.988405 -243.331329) (xy 124.958381 -243.287292) (xy 124.935255 -243.239271) (xy 124.919545 -243.188341)
			(xy 124.911602 -243.135637) (xy 124.683022 -243.135637) (xy 124.675079 -243.188341) (xy 124.659369 -243.239271)
			(xy 124.636243 -243.287292) (xy 124.606219 -243.331329) (xy 124.569967 -243.3704) (xy 124.528296 -243.403631)
			(xy 124.482138 -243.43028) (xy 124.432524 -243.449752) (xy 124.380562 -243.461612) (xy 124.327412 -243.465596)
			(xy 124.274262 -243.461612) (xy 124.2223 -243.449752) (xy 124.172686 -243.43028) (xy 124.126528 -243.403631)
			(xy 124.084857 -243.3704) (xy 124.048605 -243.331329) (xy 124.018581 -243.287292) (xy 123.995455 -243.239271)
			(xy 123.979745 -243.188341) (xy 123.971802 -243.135637) (xy 123.743222 -243.135637) (xy 123.735279 -243.188341)
			(xy 123.719569 -243.239271) (xy 123.696443 -243.287292) (xy 123.666419 -243.331329) (xy 123.630167 -243.3704)
			(xy 123.588496 -243.403631) (xy 123.542338 -243.43028) (xy 123.492724 -243.449752) (xy 123.440762 -243.461612)
			(xy 123.387612 -243.465596) (xy 123.334462 -243.461612) (xy 123.2825 -243.449752) (xy 123.232886 -243.43028)
			(xy 123.186728 -243.403631) (xy 123.145057 -243.3704) (xy 123.108805 -243.331329) (xy 123.078781 -243.287292)
			(xy 123.055655 -243.239271) (xy 123.039945 -243.188341) (xy 123.032002 -243.135637) (xy 122.803422 -243.135637)
			(xy 122.795479 -243.188341) (xy 122.779769 -243.239271) (xy 122.756643 -243.287292) (xy 122.726619 -243.331329)
			(xy 122.690367 -243.3704) (xy 122.648696 -243.403631) (xy 122.602538 -243.43028) (xy 122.552924 -243.449752)
			(xy 122.500962 -243.461612) (xy 122.447812 -243.465596) (xy 122.394662 -243.461612) (xy 122.3427 -243.449752)
			(xy 122.293086 -243.43028) (xy 122.246928 -243.403631) (xy 122.205257 -243.3704) (xy 122.169005 -243.331329)
			(xy 122.138981 -243.287292) (xy 122.115855 -243.239271) (xy 122.100145 -243.188341) (xy 122.092202 -243.135637)
			(xy 120.409991 -243.135637) (xy 118.87708 -244.668548) (xy 118.87708 -245.015003) (xy 120.619698 -245.015003)
			(xy 120.623915 -244.960336) (xy 120.636468 -244.906962) (xy 120.657058 -244.856146) (xy 120.6852 -244.809089)
			(xy 120.702324 -244.787674) (xy 120.710948 -244.776542) (xy 120.722296 -244.750783) (xy 120.726178 -244.722903)
			(xy 120.722298 -244.695023) (xy 120.710951 -244.669264) (xy 120.702324 -244.658134) (xy 120.685204 -244.636716)
			(xy 120.657061 -244.58966) (xy 120.63647 -244.538844) (xy 120.623916 -244.48547) (xy 120.619698 -244.430803)
			(xy 120.623915 -244.376136) (xy 120.636468 -244.322762) (xy 120.657058 -244.271946) (xy 120.6852 -244.224889)
			(xy 120.702324 -244.203474) (xy 120.710948 -244.192342) (xy 120.722296 -244.166583) (xy 120.726178 -244.138703)
			(xy 120.722298 -244.110823) (xy 120.710951 -244.085064) (xy 120.702324 -244.073934) (xy 120.686874 -244.054698)
			(xy 120.660919 -244.012738) (xy 120.641005 -243.967597) (xy 120.627513 -243.920139) (xy 120.620702 -243.871273)
			(xy 120.620282 -243.846604) (xy 120.62078 -243.819955) (xy 120.628723 -243.767251) (xy 120.644433 -243.716321)
			(xy 120.667559 -243.6683) (xy 120.697583 -243.624263) (xy 120.733835 -243.585192) (xy 120.775506 -243.551961)
			(xy 120.821664 -243.525312) (xy 120.871278 -243.50584) (xy 120.92324 -243.49398) (xy 120.97639 -243.489997)
			(xy 121.02954 -243.49398) (xy 121.081502 -243.50584) (xy 121.131116 -243.525312) (xy 121.177274 -243.551961)
			(xy 121.218945 -243.585192) (xy 121.255197 -243.624263) (xy 121.285221 -243.6683) (xy 121.308347 -243.716321)
			(xy 121.324057 -243.767251) (xy 121.332 -243.819955) (xy 121.332498 -243.846604) (xy 121.332086 -243.871274)
			(xy 121.32528 -243.920141) (xy 121.316945 -243.949453) (xy 121.622302 -243.949453) (xy 121.622302 -243.896155)
			(xy 121.630245 -243.843451) (xy 121.645955 -243.792521) (xy 121.669081 -243.7445) (xy 121.699105 -243.700463)
			(xy 121.735357 -243.661392) (xy 121.777028 -243.628161) (xy 121.823186 -243.601512) (xy 121.8728 -243.58204)
			(xy 121.924762 -243.57018) (xy 121.977912 -243.566197) (xy 122.031062 -243.57018) (xy 122.083024 -243.58204)
			(xy 122.132638 -243.601512) (xy 122.178796 -243.628161) (xy 122.220467 -243.661392) (xy 122.256719 -243.700463)
			(xy 122.286743 -243.7445) (xy 122.309869 -243.792521) (xy 122.325579 -243.843451) (xy 122.333522 -243.896155)
			(xy 122.33402 -243.922804) (xy 122.333522 -243.949453) (xy 122.562102 -243.949453) (xy 122.562102 -243.896155)
			(xy 122.570045 -243.843451) (xy 122.585755 -243.792521) (xy 122.608881 -243.7445) (xy 122.638905 -243.700463)
			(xy 122.675157 -243.661392) (xy 122.716828 -243.628161) (xy 122.762986 -243.601512) (xy 122.8126 -243.58204)
			(xy 122.864562 -243.57018) (xy 122.917712 -243.566197) (xy 122.970862 -243.57018) (xy 123.022824 -243.58204)
			(xy 123.072438 -243.601512) (xy 123.118596 -243.628161) (xy 123.160267 -243.661392) (xy 123.196519 -243.700463)
			(xy 123.226543 -243.7445) (xy 123.249669 -243.792521) (xy 123.265379 -243.843451) (xy 123.273322 -243.896155)
			(xy 123.27382 -243.922804) (xy 123.273322 -243.949453) (xy 123.502156 -243.949453) (xy 123.502156 -243.896155)
			(xy 123.510099 -243.843451) (xy 123.525809 -243.792521) (xy 123.548935 -243.7445) (xy 123.578959 -243.700463)
			(xy 123.615211 -243.661392) (xy 123.656882 -243.628161) (xy 123.70304 -243.601512) (xy 123.752654 -243.58204)
			(xy 123.804616 -243.57018) (xy 123.857766 -243.566197) (xy 123.910916 -243.57018) (xy 123.962878 -243.58204)
			(xy 124.012492 -243.601512) (xy 124.05865 -243.628161) (xy 124.100321 -243.661392) (xy 124.136573 -243.700463)
			(xy 124.166597 -243.7445) (xy 124.189723 -243.792521) (xy 124.205433 -243.843451) (xy 124.213376 -243.896155)
			(xy 124.213874 -243.922804) (xy 124.213376 -243.949453) (xy 124.441956 -243.949453) (xy 124.441956 -243.896155)
			(xy 124.449899 -243.843451) (xy 124.465609 -243.792521) (xy 124.488735 -243.7445) (xy 124.518759 -243.700463)
			(xy 124.555011 -243.661392) (xy 124.596682 -243.628161) (xy 124.64284 -243.601512) (xy 124.692454 -243.58204)
			(xy 124.744416 -243.57018) (xy 124.797566 -243.566197) (xy 124.850716 -243.57018) (xy 124.902678 -243.58204)
			(xy 124.952292 -243.601512) (xy 124.99845 -243.628161) (xy 125.040121 -243.661392) (xy 125.076373 -243.700463)
			(xy 125.106397 -243.7445) (xy 125.129523 -243.792521) (xy 125.145233 -243.843451) (xy 125.153176 -243.896155)
			(xy 125.153674 -243.922804) (xy 125.153176 -243.949453) (xy 125.381756 -243.949453) (xy 125.381756 -243.896155)
			(xy 125.389699 -243.843451) (xy 125.405409 -243.792521) (xy 125.428535 -243.7445) (xy 125.458559 -243.700463)
			(xy 125.494811 -243.661392) (xy 125.536482 -243.628161) (xy 125.58264 -243.601512) (xy 125.632254 -243.58204)
			(xy 125.684216 -243.57018) (xy 125.737366 -243.566197) (xy 125.790516 -243.57018) (xy 125.842478 -243.58204)
			(xy 125.892092 -243.601512) (xy 125.93825 -243.628161) (xy 125.979921 -243.661392) (xy 126.016173 -243.700463)
			(xy 126.046197 -243.7445) (xy 126.069323 -243.792521) (xy 126.085033 -243.843451) (xy 126.092976 -243.896155)
			(xy 126.093474 -243.922804) (xy 126.092976 -243.949453) (xy 126.321556 -243.949453) (xy 126.321556 -243.896155)
			(xy 126.329499 -243.843451) (xy 126.345209 -243.792521) (xy 126.368335 -243.7445) (xy 126.398359 -243.700463)
			(xy 126.434611 -243.661392) (xy 126.476282 -243.628161) (xy 126.52244 -243.601512) (xy 126.572054 -243.58204)
			(xy 126.624016 -243.57018) (xy 126.677166 -243.566197) (xy 126.730316 -243.57018) (xy 126.782278 -243.58204)
			(xy 126.831892 -243.601512) (xy 126.87805 -243.628161) (xy 126.919721 -243.661392) (xy 126.955973 -243.700463)
			(xy 126.985997 -243.7445) (xy 127.009123 -243.792521) (xy 127.024833 -243.843451) (xy 127.032776 -243.896155)
			(xy 127.033274 -243.922804) (xy 127.032776 -243.949453) (xy 127.261356 -243.949453) (xy 127.261356 -243.896155)
			(xy 127.269299 -243.843451) (xy 127.285009 -243.792521) (xy 127.308135 -243.7445) (xy 127.338159 -243.700463)
			(xy 127.374411 -243.661392) (xy 127.416082 -243.628161) (xy 127.46224 -243.601512) (xy 127.511854 -243.58204)
			(xy 127.563816 -243.57018) (xy 127.616966 -243.566197) (xy 127.670116 -243.57018) (xy 127.722078 -243.58204)
			(xy 127.771692 -243.601512) (xy 127.81785 -243.628161) (xy 127.859521 -243.661392) (xy 127.895773 -243.700463)
			(xy 127.925797 -243.7445) (xy 127.948923 -243.792521) (xy 127.964633 -243.843451) (xy 127.972576 -243.896155)
			(xy 127.973074 -243.922804) (xy 127.972576 -243.949453) (xy 128.201156 -243.949453) (xy 128.201156 -243.896155)
			(xy 128.209099 -243.843451) (xy 128.224809 -243.792521) (xy 128.247935 -243.7445) (xy 128.277959 -243.700463)
			(xy 128.314211 -243.661392) (xy 128.355882 -243.628161) (xy 128.40204 -243.601512) (xy 128.451654 -243.58204)
			(xy 128.503616 -243.57018) (xy 128.556766 -243.566197) (xy 128.609916 -243.57018) (xy 128.661878 -243.58204)
			(xy 128.711492 -243.601512) (xy 128.75765 -243.628161) (xy 128.799321 -243.661392) (xy 128.835573 -243.700463)
			(xy 128.865597 -243.7445) (xy 128.888723 -243.792521) (xy 128.904433 -243.843451) (xy 128.912376 -243.896155)
			(xy 128.912874 -243.922804) (xy 128.912376 -243.949453) (xy 129.140702 -243.949453) (xy 129.140702 -243.896155)
			(xy 129.148645 -243.843451) (xy 129.164355 -243.792521) (xy 129.187481 -243.7445) (xy 129.217505 -243.700463)
			(xy 129.253757 -243.661392) (xy 129.295428 -243.628161) (xy 129.341586 -243.601512) (xy 129.3912 -243.58204)
			(xy 129.443162 -243.57018) (xy 129.496312 -243.566197) (xy 129.549462 -243.57018) (xy 129.601424 -243.58204)
			(xy 129.651038 -243.601512) (xy 129.697196 -243.628161) (xy 129.738867 -243.661392) (xy 129.775119 -243.700463)
			(xy 129.805143 -243.7445) (xy 129.828269 -243.792521) (xy 129.843979 -243.843451) (xy 129.851922 -243.896155)
			(xy 129.85242 -243.922804) (xy 129.851922 -243.949453) (xy 130.080756 -243.949453) (xy 130.080756 -243.896155)
			(xy 130.088699 -243.843451) (xy 130.104409 -243.792521) (xy 130.127535 -243.7445) (xy 130.157559 -243.700463)
			(xy 130.193811 -243.661392) (xy 130.235482 -243.628161) (xy 130.28164 -243.601512) (xy 130.331254 -243.58204)
			(xy 130.383216 -243.57018) (xy 130.436366 -243.566197) (xy 130.489516 -243.57018) (xy 130.541478 -243.58204)
			(xy 130.591092 -243.601512) (xy 130.63725 -243.628161) (xy 130.678921 -243.661392) (xy 130.715173 -243.700463)
			(xy 130.745197 -243.7445) (xy 130.768323 -243.792521) (xy 130.784033 -243.843451) (xy 130.791976 -243.896155)
			(xy 130.792474 -243.922804) (xy 130.791976 -243.949453) (xy 131.020556 -243.949453) (xy 131.020556 -243.896155)
			(xy 131.028499 -243.843451) (xy 131.044209 -243.792521) (xy 131.067335 -243.7445) (xy 131.097359 -243.700463)
			(xy 131.133611 -243.661392) (xy 131.175282 -243.628161) (xy 131.22144 -243.601512) (xy 131.271054 -243.58204)
			(xy 131.323016 -243.57018) (xy 131.376166 -243.566197) (xy 131.429316 -243.57018) (xy 131.481278 -243.58204)
			(xy 131.530892 -243.601512) (xy 131.57705 -243.628161) (xy 131.618721 -243.661392) (xy 131.654973 -243.700463)
			(xy 131.684997 -243.7445) (xy 131.708123 -243.792521) (xy 131.723833 -243.843451) (xy 131.731776 -243.896155)
			(xy 131.732274 -243.922804) (xy 131.731776 -243.949453) (xy 131.960356 -243.949453) (xy 131.960356 -243.896155)
			(xy 131.968299 -243.843451) (xy 131.984009 -243.792521) (xy 132.007135 -243.7445) (xy 132.037159 -243.700463)
			(xy 132.073411 -243.661392) (xy 132.115082 -243.628161) (xy 132.16124 -243.601512) (xy 132.210854 -243.58204)
			(xy 132.262816 -243.57018) (xy 132.315966 -243.566197) (xy 132.369116 -243.57018) (xy 132.421078 -243.58204)
			(xy 132.470692 -243.601512) (xy 132.51685 -243.628161) (xy 132.558521 -243.661392) (xy 132.594773 -243.700463)
			(xy 132.624797 -243.7445) (xy 132.647923 -243.792521) (xy 132.663633 -243.843451) (xy 132.671576 -243.896155)
			(xy 132.672074 -243.922804) (xy 132.671576 -243.949453) (xy 132.900156 -243.949453) (xy 132.900156 -243.896155)
			(xy 132.908099 -243.843451) (xy 132.923809 -243.792521) (xy 132.946935 -243.7445) (xy 132.976959 -243.700463)
			(xy 133.013211 -243.661392) (xy 133.054882 -243.628161) (xy 133.10104 -243.601512) (xy 133.150654 -243.58204)
			(xy 133.202616 -243.57018) (xy 133.255766 -243.566197) (xy 133.308916 -243.57018) (xy 133.360878 -243.58204)
			(xy 133.410492 -243.601512) (xy 133.45665 -243.628161) (xy 133.498321 -243.661392) (xy 133.534573 -243.700463)
			(xy 133.564597 -243.7445) (xy 133.587723 -243.792521) (xy 133.603433 -243.843451) (xy 133.611376 -243.896155)
			(xy 133.611874 -243.922804) (xy 133.611376 -243.949453) (xy 133.839956 -243.949453) (xy 133.839956 -243.896155)
			(xy 133.847899 -243.843451) (xy 133.863609 -243.792521) (xy 133.886735 -243.7445) (xy 133.916759 -243.700463)
			(xy 133.953011 -243.661392) (xy 133.994682 -243.628161) (xy 134.04084 -243.601512) (xy 134.090454 -243.58204)
			(xy 134.142416 -243.57018) (xy 134.195566 -243.566197) (xy 134.248716 -243.57018) (xy 134.300678 -243.58204)
			(xy 134.350292 -243.601512) (xy 134.39645 -243.628161) (xy 134.438121 -243.661392) (xy 134.474373 -243.700463)
			(xy 134.504397 -243.7445) (xy 134.527523 -243.792521) (xy 134.543233 -243.843451) (xy 134.551176 -243.896155)
			(xy 134.551674 -243.922804) (xy 134.551176 -243.949453) (xy 134.543233 -244.002157) (xy 134.527523 -244.053087)
			(xy 134.504397 -244.101108) (xy 134.474373 -244.145145) (xy 134.438121 -244.184216) (xy 134.39645 -244.217447)
			(xy 134.350292 -244.244096) (xy 134.300678 -244.263568) (xy 134.248716 -244.275428) (xy 134.195566 -244.279412)
			(xy 134.142416 -244.275428) (xy 134.090454 -244.263568) (xy 134.04084 -244.244096) (xy 133.994682 -244.217447)
			(xy 133.953011 -244.184216) (xy 133.916759 -244.145145) (xy 133.886735 -244.101108) (xy 133.863609 -244.053087)
			(xy 133.847899 -244.002157) (xy 133.839956 -243.949453) (xy 133.611376 -243.949453) (xy 133.603433 -244.002157)
			(xy 133.587723 -244.053087) (xy 133.564597 -244.101108) (xy 133.534573 -244.145145) (xy 133.498321 -244.184216)
			(xy 133.45665 -244.217447) (xy 133.410492 -244.244096) (xy 133.360878 -244.263568) (xy 133.308916 -244.275428)
			(xy 133.255766 -244.279412) (xy 133.202616 -244.275428) (xy 133.150654 -244.263568) (xy 133.10104 -244.244096)
			(xy 133.054882 -244.217447) (xy 133.013211 -244.184216) (xy 132.976959 -244.145145) (xy 132.946935 -244.101108)
			(xy 132.923809 -244.053087) (xy 132.908099 -244.002157) (xy 132.900156 -243.949453) (xy 132.671576 -243.949453)
			(xy 132.663633 -244.002157) (xy 132.647923 -244.053087) (xy 132.624797 -244.101108) (xy 132.594773 -244.145145)
			(xy 132.558521 -244.184216) (xy 132.51685 -244.217447) (xy 132.470692 -244.244096) (xy 132.421078 -244.263568)
			(xy 132.369116 -244.275428) (xy 132.315966 -244.279412) (xy 132.262816 -244.275428) (xy 132.210854 -244.263568)
			(xy 132.16124 -244.244096) (xy 132.115082 -244.217447) (xy 132.073411 -244.184216) (xy 132.037159 -244.145145)
			(xy 132.007135 -244.101108) (xy 131.984009 -244.053087) (xy 131.968299 -244.002157) (xy 131.960356 -243.949453)
			(xy 131.731776 -243.949453) (xy 131.723833 -244.002157) (xy 131.708123 -244.053087) (xy 131.684997 -244.101108)
			(xy 131.654973 -244.145145) (xy 131.618721 -244.184216) (xy 131.57705 -244.217447) (xy 131.530892 -244.244096)
			(xy 131.481278 -244.263568) (xy 131.429316 -244.275428) (xy 131.376166 -244.279412) (xy 131.323016 -244.275428)
			(xy 131.271054 -244.263568) (xy 131.22144 -244.244096) (xy 131.175282 -244.217447) (xy 131.133611 -244.184216)
			(xy 131.097359 -244.145145) (xy 131.067335 -244.101108) (xy 131.044209 -244.053087) (xy 131.028499 -244.002157)
			(xy 131.020556 -243.949453) (xy 130.791976 -243.949453) (xy 130.784033 -244.002157) (xy 130.768323 -244.053087)
			(xy 130.745197 -244.101108) (xy 130.715173 -244.145145) (xy 130.678921 -244.184216) (xy 130.63725 -244.217447)
			(xy 130.591092 -244.244096) (xy 130.541478 -244.263568) (xy 130.489516 -244.275428) (xy 130.436366 -244.279412)
			(xy 130.383216 -244.275428) (xy 130.331254 -244.263568) (xy 130.28164 -244.244096) (xy 130.235482 -244.217447)
			(xy 130.193811 -244.184216) (xy 130.157559 -244.145145) (xy 130.127535 -244.101108) (xy 130.104409 -244.053087)
			(xy 130.088699 -244.002157) (xy 130.080756 -243.949453) (xy 129.851922 -243.949453) (xy 129.843979 -244.002157)
			(xy 129.828269 -244.053087) (xy 129.805143 -244.101108) (xy 129.775119 -244.145145) (xy 129.738867 -244.184216)
			(xy 129.697196 -244.217447) (xy 129.651038 -244.244096) (xy 129.601424 -244.263568) (xy 129.549462 -244.275428)
			(xy 129.496312 -244.279412) (xy 129.443162 -244.275428) (xy 129.3912 -244.263568) (xy 129.341586 -244.244096)
			(xy 129.295428 -244.217447) (xy 129.253757 -244.184216) (xy 129.217505 -244.145145) (xy 129.187481 -244.101108)
			(xy 129.164355 -244.053087) (xy 129.148645 -244.002157) (xy 129.140702 -243.949453) (xy 128.912376 -243.949453)
			(xy 128.904433 -244.002157) (xy 128.888723 -244.053087) (xy 128.865597 -244.101108) (xy 128.835573 -244.145145)
			(xy 128.799321 -244.184216) (xy 128.75765 -244.217447) (xy 128.711492 -244.244096) (xy 128.661878 -244.263568)
			(xy 128.609916 -244.275428) (xy 128.556766 -244.279412) (xy 128.503616 -244.275428) (xy 128.451654 -244.263568)
			(xy 128.40204 -244.244096) (xy 128.355882 -244.217447) (xy 128.314211 -244.184216) (xy 128.277959 -244.145145)
			(xy 128.247935 -244.101108) (xy 128.224809 -244.053087) (xy 128.209099 -244.002157) (xy 128.201156 -243.949453)
			(xy 127.972576 -243.949453) (xy 127.964633 -244.002157) (xy 127.948923 -244.053087) (xy 127.925797 -244.101108)
			(xy 127.895773 -244.145145) (xy 127.859521 -244.184216) (xy 127.81785 -244.217447) (xy 127.771692 -244.244096)
			(xy 127.722078 -244.263568) (xy 127.670116 -244.275428) (xy 127.616966 -244.279412) (xy 127.563816 -244.275428)
			(xy 127.511854 -244.263568) (xy 127.46224 -244.244096) (xy 127.416082 -244.217447) (xy 127.374411 -244.184216)
			(xy 127.338159 -244.145145) (xy 127.308135 -244.101108) (xy 127.285009 -244.053087) (xy 127.269299 -244.002157)
			(xy 127.261356 -243.949453) (xy 127.032776 -243.949453) (xy 127.024833 -244.002157) (xy 127.009123 -244.053087)
			(xy 126.985997 -244.101108) (xy 126.955973 -244.145145) (xy 126.919721 -244.184216) (xy 126.87805 -244.217447)
			(xy 126.831892 -244.244096) (xy 126.782278 -244.263568) (xy 126.730316 -244.275428) (xy 126.677166 -244.279412)
			(xy 126.624016 -244.275428) (xy 126.572054 -244.263568) (xy 126.52244 -244.244096) (xy 126.476282 -244.217447)
			(xy 126.434611 -244.184216) (xy 126.398359 -244.145145) (xy 126.368335 -244.101108) (xy 126.345209 -244.053087)
			(xy 126.329499 -244.002157) (xy 126.321556 -243.949453) (xy 126.092976 -243.949453) (xy 126.085033 -244.002157)
			(xy 126.069323 -244.053087) (xy 126.046197 -244.101108) (xy 126.016173 -244.145145) (xy 125.979921 -244.184216)
			(xy 125.93825 -244.217447) (xy 125.892092 -244.244096) (xy 125.842478 -244.263568) (xy 125.790516 -244.275428)
			(xy 125.737366 -244.279412) (xy 125.684216 -244.275428) (xy 125.632254 -244.263568) (xy 125.58264 -244.244096)
			(xy 125.536482 -244.217447) (xy 125.494811 -244.184216) (xy 125.458559 -244.145145) (xy 125.428535 -244.101108)
			(xy 125.405409 -244.053087) (xy 125.389699 -244.002157) (xy 125.381756 -243.949453) (xy 125.153176 -243.949453)
			(xy 125.145233 -244.002157) (xy 125.129523 -244.053087) (xy 125.106397 -244.101108) (xy 125.076373 -244.145145)
			(xy 125.040121 -244.184216) (xy 124.99845 -244.217447) (xy 124.952292 -244.244096) (xy 124.902678 -244.263568)
			(xy 124.850716 -244.275428) (xy 124.797566 -244.279412) (xy 124.744416 -244.275428) (xy 124.692454 -244.263568)
			(xy 124.64284 -244.244096) (xy 124.596682 -244.217447) (xy 124.555011 -244.184216) (xy 124.518759 -244.145145)
			(xy 124.488735 -244.101108) (xy 124.465609 -244.053087) (xy 124.449899 -244.002157) (xy 124.441956 -243.949453)
			(xy 124.213376 -243.949453) (xy 124.205433 -244.002157) (xy 124.189723 -244.053087) (xy 124.166597 -244.101108)
			(xy 124.136573 -244.145145) (xy 124.100321 -244.184216) (xy 124.05865 -244.217447) (xy 124.012492 -244.244096)
			(xy 123.962878 -244.263568) (xy 123.910916 -244.275428) (xy 123.857766 -244.279412) (xy 123.804616 -244.275428)
			(xy 123.752654 -244.263568) (xy 123.70304 -244.244096) (xy 123.656882 -244.217447) (xy 123.615211 -244.184216)
			(xy 123.578959 -244.145145) (xy 123.548935 -244.101108) (xy 123.525809 -244.053087) (xy 123.510099 -244.002157)
			(xy 123.502156 -243.949453) (xy 123.273322 -243.949453) (xy 123.265379 -244.002157) (xy 123.249669 -244.053087)
			(xy 123.226543 -244.101108) (xy 123.196519 -244.145145) (xy 123.160267 -244.184216) (xy 123.118596 -244.217447)
			(xy 123.072438 -244.244096) (xy 123.022824 -244.263568) (xy 122.970862 -244.275428) (xy 122.917712 -244.279412)
			(xy 122.864562 -244.275428) (xy 122.8126 -244.263568) (xy 122.762986 -244.244096) (xy 122.716828 -244.217447)
			(xy 122.675157 -244.184216) (xy 122.638905 -244.145145) (xy 122.608881 -244.101108) (xy 122.585755 -244.053087)
			(xy 122.570045 -244.002157) (xy 122.562102 -243.949453) (xy 122.333522 -243.949453) (xy 122.325579 -244.002157)
			(xy 122.309869 -244.053087) (xy 122.286743 -244.101108) (xy 122.256719 -244.145145) (xy 122.220467 -244.184216)
			(xy 122.178796 -244.217447) (xy 122.132638 -244.244096) (xy 122.083024 -244.263568) (xy 122.031062 -244.275428)
			(xy 121.977912 -244.279412) (xy 121.924762 -244.275428) (xy 121.8728 -244.263568) (xy 121.823186 -244.244096)
			(xy 121.777028 -244.217447) (xy 121.735357 -244.184216) (xy 121.699105 -244.145145) (xy 121.669081 -244.101108)
			(xy 121.645955 -244.053087) (xy 121.630245 -244.002157) (xy 121.622302 -243.949453) (xy 121.316945 -243.949453)
			(xy 121.311786 -243.967598) (xy 121.291863 -244.012735) (xy 121.265892 -244.054686) (xy 121.250456 -244.073934)
			(xy 121.241826 -244.085061) (xy 121.230481 -244.110823) (xy 121.226601 -244.138703) (xy 121.230482 -244.166583)
			(xy 121.241829 -244.192344) (xy 121.250456 -244.203474) (xy 121.26452 -244.220942) (xy 121.288585 -244.258785)
			(xy 121.307709 -244.299351) (xy 121.314972 -244.320568) (xy 121.32014 -244.334617) (xy 121.33722 -244.359176)
			(xy 121.360691 -244.377724) (xy 121.388535 -244.388662) (xy 121.418354 -244.391051) (xy 121.433082 -244.388386)
			(xy 121.45159 -244.38467) (xy 121.489136 -244.380729) (xy 121.508012 -244.380512) (xy 121.534662 -244.380971)
			(xy 121.587367 -244.388916) (xy 121.638299 -244.404628) (xy 121.686321 -244.427756) (xy 121.730359 -244.457782)
			(xy 121.76943 -244.494036) (xy 121.802662 -244.535708) (xy 121.829312 -244.581868) (xy 121.848784 -244.631484)
			(xy 121.860644 -244.683449) (xy 121.864628 -244.7366) (xy 121.862648 -244.763015) (xy 122.092202 -244.763015)
			(xy 122.092202 -244.709717) (xy 122.100145 -244.657013) (xy 122.115855 -244.606083) (xy 122.138981 -244.558062)
			(xy 122.169005 -244.514025) (xy 122.205257 -244.474954) (xy 122.246928 -244.441723) (xy 122.293086 -244.415074)
			(xy 122.3427 -244.395602) (xy 122.394662 -244.383742) (xy 122.447812 -244.379759) (xy 122.500962 -244.383742)
			(xy 122.552924 -244.395602) (xy 122.602538 -244.415074) (xy 122.648696 -244.441723) (xy 122.690367 -244.474954)
			(xy 122.726619 -244.514025) (xy 122.756643 -244.558062) (xy 122.779769 -244.606083) (xy 122.795479 -244.657013)
			(xy 122.803422 -244.709717) (xy 122.80392 -244.736366) (xy 122.803422 -244.763015) (xy 122.803384 -244.763269)
			(xy 123.032002 -244.763269) (xy 123.032002 -244.709971) (xy 123.039945 -244.657267) (xy 123.055655 -244.606337)
			(xy 123.078781 -244.558316) (xy 123.108805 -244.514279) (xy 123.145057 -244.475208) (xy 123.186728 -244.441977)
			(xy 123.232886 -244.415328) (xy 123.2825 -244.395856) (xy 123.334462 -244.383996) (xy 123.387612 -244.380013)
			(xy 123.440762 -244.383996) (xy 123.492724 -244.395856) (xy 123.542338 -244.415328) (xy 123.588496 -244.441977)
			(xy 123.630167 -244.475208) (xy 123.666419 -244.514279) (xy 123.696443 -244.558316) (xy 123.719569 -244.606337)
			(xy 123.735279 -244.657267) (xy 123.743222 -244.709971) (xy 123.74372 -244.73662) (xy 123.743222 -244.763269)
			(xy 123.971802 -244.763269) (xy 123.971802 -244.709971) (xy 123.979745 -244.657267) (xy 123.995455 -244.606337)
			(xy 124.018581 -244.558316) (xy 124.048605 -244.514279) (xy 124.084857 -244.475208) (xy 124.126528 -244.441977)
			(xy 124.172686 -244.415328) (xy 124.2223 -244.395856) (xy 124.274262 -244.383996) (xy 124.327412 -244.380013)
			(xy 124.380562 -244.383996) (xy 124.432524 -244.395856) (xy 124.482138 -244.415328) (xy 124.528296 -244.441977)
			(xy 124.569967 -244.475208) (xy 124.606219 -244.514279) (xy 124.636243 -244.558316) (xy 124.659369 -244.606337)
			(xy 124.675079 -244.657267) (xy 124.683022 -244.709971) (xy 124.68352 -244.73662) (xy 124.683022 -244.763269)
			(xy 124.911856 -244.763269) (xy 124.911856 -244.709971) (xy 124.919799 -244.657267) (xy 124.935509 -244.606337)
			(xy 124.958635 -244.558316) (xy 124.988659 -244.514279) (xy 125.024911 -244.475208) (xy 125.066582 -244.441977)
			(xy 125.11274 -244.415328) (xy 125.162354 -244.395856) (xy 125.214316 -244.383996) (xy 125.267466 -244.380013)
			(xy 125.320616 -244.383996) (xy 125.372578 -244.395856) (xy 125.422192 -244.415328) (xy 125.46835 -244.441977)
			(xy 125.510021 -244.475208) (xy 125.546273 -244.514279) (xy 125.576297 -244.558316) (xy 125.599423 -244.606337)
			(xy 125.615133 -244.657267) (xy 125.623076 -244.709971) (xy 125.623574 -244.73662) (xy 125.623076 -244.763269)
			(xy 125.851402 -244.763269) (xy 125.851402 -244.709971) (xy 125.859345 -244.657267) (xy 125.875055 -244.606337)
			(xy 125.898181 -244.558316) (xy 125.928205 -244.514279) (xy 125.964457 -244.475208) (xy 126.006128 -244.441977)
			(xy 126.052286 -244.415328) (xy 126.1019 -244.395856) (xy 126.153862 -244.383996) (xy 126.207012 -244.380013)
			(xy 126.260162 -244.383996) (xy 126.312124 -244.395856) (xy 126.361738 -244.415328) (xy 126.407896 -244.441977)
			(xy 126.449567 -244.475208) (xy 126.485819 -244.514279) (xy 126.515843 -244.558316) (xy 126.538969 -244.606337)
			(xy 126.554679 -244.657267) (xy 126.562622 -244.709971) (xy 126.56312 -244.73662) (xy 126.562622 -244.763269)
			(xy 126.791456 -244.763269) (xy 126.791456 -244.709971) (xy 126.799399 -244.657267) (xy 126.815109 -244.606337)
			(xy 126.838235 -244.558316) (xy 126.868259 -244.514279) (xy 126.904511 -244.475208) (xy 126.946182 -244.441977)
			(xy 126.99234 -244.415328) (xy 127.041954 -244.395856) (xy 127.093916 -244.383996) (xy 127.147066 -244.380013)
			(xy 127.200216 -244.383996) (xy 127.252178 -244.395856) (xy 127.301792 -244.415328) (xy 127.34795 -244.441977)
			(xy 127.389621 -244.475208) (xy 127.425873 -244.514279) (xy 127.455897 -244.558316) (xy 127.479023 -244.606337)
			(xy 127.494733 -244.657267) (xy 127.502676 -244.709971) (xy 127.503174 -244.73662) (xy 127.502676 -244.763269)
			(xy 127.731002 -244.763269) (xy 127.731002 -244.709971) (xy 127.738945 -244.657267) (xy 127.754655 -244.606337)
			(xy 127.777781 -244.558316) (xy 127.807805 -244.514279) (xy 127.844057 -244.475208) (xy 127.885728 -244.441977)
			(xy 127.931886 -244.415328) (xy 127.9815 -244.395856) (xy 128.033462 -244.383996) (xy 128.086612 -244.380013)
			(xy 128.139762 -244.383996) (xy 128.191724 -244.395856) (xy 128.241338 -244.415328) (xy 128.287496 -244.441977)
			(xy 128.329167 -244.475208) (xy 128.365419 -244.514279) (xy 128.395443 -244.558316) (xy 128.418569 -244.606337)
			(xy 128.434279 -244.657267) (xy 128.442222 -244.709971) (xy 128.44272 -244.73662) (xy 128.442222 -244.763269)
			(xy 128.670802 -244.763269) (xy 128.670802 -244.709971) (xy 128.678745 -244.657267) (xy 128.694455 -244.606337)
			(xy 128.717581 -244.558316) (xy 128.747605 -244.514279) (xy 128.783857 -244.475208) (xy 128.825528 -244.441977)
			(xy 128.871686 -244.415328) (xy 128.9213 -244.395856) (xy 128.973262 -244.383996) (xy 129.026412 -244.380013)
			(xy 129.079562 -244.383996) (xy 129.131524 -244.395856) (xy 129.181138 -244.415328) (xy 129.227296 -244.441977)
			(xy 129.268967 -244.475208) (xy 129.305219 -244.514279) (xy 129.335243 -244.558316) (xy 129.358369 -244.606337)
			(xy 129.374079 -244.657267) (xy 129.382022 -244.709971) (xy 129.38252 -244.73662) (xy 129.382022 -244.763269)
			(xy 129.610602 -244.763269) (xy 129.610602 -244.709971) (xy 129.618545 -244.657267) (xy 129.634255 -244.606337)
			(xy 129.657381 -244.558316) (xy 129.687405 -244.514279) (xy 129.723657 -244.475208) (xy 129.765328 -244.441977)
			(xy 129.811486 -244.415328) (xy 129.8611 -244.395856) (xy 129.913062 -244.383996) (xy 129.966212 -244.380013)
			(xy 130.019362 -244.383996) (xy 130.071324 -244.395856) (xy 130.120938 -244.415328) (xy 130.167096 -244.441977)
			(xy 130.208767 -244.475208) (xy 130.245019 -244.514279) (xy 130.275043 -244.558316) (xy 130.298169 -244.606337)
			(xy 130.313879 -244.657267) (xy 130.321822 -244.709971) (xy 130.32232 -244.73662) (xy 130.321822 -244.763269)
			(xy 130.550402 -244.763269) (xy 130.550402 -244.709971) (xy 130.558345 -244.657267) (xy 130.574055 -244.606337)
			(xy 130.597181 -244.558316) (xy 130.627205 -244.514279) (xy 130.663457 -244.475208) (xy 130.705128 -244.441977)
			(xy 130.751286 -244.415328) (xy 130.8009 -244.395856) (xy 130.852862 -244.383996) (xy 130.906012 -244.380013)
			(xy 130.959162 -244.383996) (xy 131.011124 -244.395856) (xy 131.060738 -244.415328) (xy 131.106896 -244.441977)
			(xy 131.148567 -244.475208) (xy 131.184819 -244.514279) (xy 131.214843 -244.558316) (xy 131.237969 -244.606337)
			(xy 131.253679 -244.657267) (xy 131.261622 -244.709971) (xy 131.26212 -244.73662) (xy 131.261622 -244.763269)
			(xy 131.490456 -244.763269) (xy 131.490456 -244.709971) (xy 131.498399 -244.657267) (xy 131.514109 -244.606337)
			(xy 131.537235 -244.558316) (xy 131.567259 -244.514279) (xy 131.603511 -244.475208) (xy 131.645182 -244.441977)
			(xy 131.69134 -244.415328) (xy 131.740954 -244.395856) (xy 131.792916 -244.383996) (xy 131.846066 -244.380013)
			(xy 131.899216 -244.383996) (xy 131.951178 -244.395856) (xy 132.000792 -244.415328) (xy 132.04695 -244.441977)
			(xy 132.088621 -244.475208) (xy 132.124873 -244.514279) (xy 132.154897 -244.558316) (xy 132.178023 -244.606337)
			(xy 132.193733 -244.657267) (xy 132.201676 -244.709971) (xy 132.202174 -244.73662) (xy 132.201676 -244.763269)
			(xy 132.430002 -244.763269) (xy 132.430002 -244.709971) (xy 132.437945 -244.657267) (xy 132.453655 -244.606337)
			(xy 132.476781 -244.558316) (xy 132.506805 -244.514279) (xy 132.543057 -244.475208) (xy 132.584728 -244.441977)
			(xy 132.630886 -244.415328) (xy 132.6805 -244.395856) (xy 132.732462 -244.383996) (xy 132.785612 -244.380013)
			(xy 132.838762 -244.383996) (xy 132.890724 -244.395856) (xy 132.940338 -244.415328) (xy 132.986496 -244.441977)
			(xy 133.028167 -244.475208) (xy 133.064419 -244.514279) (xy 133.094443 -244.558316) (xy 133.117569 -244.606337)
			(xy 133.133279 -244.657267) (xy 133.141222 -244.709971) (xy 133.14172 -244.73662) (xy 133.141222 -244.763269)
			(xy 133.370056 -244.763269) (xy 133.370056 -244.709971) (xy 133.377999 -244.657267) (xy 133.393709 -244.606337)
			(xy 133.416835 -244.558316) (xy 133.446859 -244.514279) (xy 133.483111 -244.475208) (xy 133.524782 -244.441977)
			(xy 133.57094 -244.415328) (xy 133.620554 -244.395856) (xy 133.672516 -244.383996) (xy 133.725666 -244.380013)
			(xy 133.778816 -244.383996) (xy 133.830778 -244.395856) (xy 133.880392 -244.415328) (xy 133.92655 -244.441977)
			(xy 133.968221 -244.475208) (xy 134.004473 -244.514279) (xy 134.034497 -244.558316) (xy 134.057623 -244.606337)
			(xy 134.073333 -244.657267) (xy 134.081276 -244.709971) (xy 134.081774 -244.73662) (xy 134.081276 -244.763269)
			(xy 134.309602 -244.763269) (xy 134.309602 -244.709971) (xy 134.317545 -244.657267) (xy 134.333255 -244.606337)
			(xy 134.356381 -244.558316) (xy 134.386405 -244.514279) (xy 134.422657 -244.475208) (xy 134.464328 -244.441977)
			(xy 134.510486 -244.415328) (xy 134.5601 -244.395856) (xy 134.612062 -244.383996) (xy 134.665212 -244.380013)
			(xy 134.718362 -244.383996) (xy 134.770324 -244.395856) (xy 134.819938 -244.415328) (xy 134.866096 -244.441977)
			(xy 134.907767 -244.475208) (xy 134.944019 -244.514279) (xy 134.974043 -244.558316) (xy 134.997169 -244.606337)
			(xy 135.012879 -244.657267) (xy 135.020822 -244.709971) (xy 135.02132 -244.73662) (xy 135.020822 -244.763269)
			(xy 135.012879 -244.815973) (xy 134.997169 -244.866903) (xy 134.974043 -244.914924) (xy 134.944019 -244.958961)
			(xy 134.907767 -244.998032) (xy 134.866096 -245.031263) (xy 134.819938 -245.057912) (xy 134.770324 -245.077384)
			(xy 134.718362 -245.089244) (xy 134.665212 -245.093228) (xy 134.612062 -245.089244) (xy 134.5601 -245.077384)
			(xy 134.510486 -245.057912) (xy 134.464328 -245.031263) (xy 134.422657 -244.998032) (xy 134.386405 -244.958961)
			(xy 134.356381 -244.914924) (xy 134.333255 -244.866903) (xy 134.317545 -244.815973) (xy 134.309602 -244.763269)
			(xy 134.081276 -244.763269) (xy 134.073333 -244.815973) (xy 134.057623 -244.866903) (xy 134.034497 -244.914924)
			(xy 134.004473 -244.958961) (xy 133.968221 -244.998032) (xy 133.92655 -245.031263) (xy 133.880392 -245.057912)
			(xy 133.830778 -245.077384) (xy 133.778816 -245.089244) (xy 133.725666 -245.093228) (xy 133.672516 -245.089244)
			(xy 133.620554 -245.077384) (xy 133.57094 -245.057912) (xy 133.524782 -245.031263) (xy 133.483111 -244.998032)
			(xy 133.446859 -244.958961) (xy 133.416835 -244.914924) (xy 133.393709 -244.866903) (xy 133.377999 -244.815973)
			(xy 133.370056 -244.763269) (xy 133.141222 -244.763269) (xy 133.133279 -244.815973) (xy 133.117569 -244.866903)
			(xy 133.094443 -244.914924) (xy 133.064419 -244.958961) (xy 133.028167 -244.998032) (xy 132.986496 -245.031263)
			(xy 132.940338 -245.057912) (xy 132.890724 -245.077384) (xy 132.838762 -245.089244) (xy 132.785612 -245.093228)
			(xy 132.732462 -245.089244) (xy 132.6805 -245.077384) (xy 132.630886 -245.057912) (xy 132.584728 -245.031263)
			(xy 132.543057 -244.998032) (xy 132.506805 -244.958961) (xy 132.476781 -244.914924) (xy 132.453655 -244.866903)
			(xy 132.437945 -244.815973) (xy 132.430002 -244.763269) (xy 132.201676 -244.763269) (xy 132.193733 -244.815973)
			(xy 132.178023 -244.866903) (xy 132.154897 -244.914924) (xy 132.124873 -244.958961) (xy 132.088621 -244.998032)
			(xy 132.04695 -245.031263) (xy 132.000792 -245.057912) (xy 131.951178 -245.077384) (xy 131.899216 -245.089244)
			(xy 131.846066 -245.093228) (xy 131.792916 -245.089244) (xy 131.740954 -245.077384) (xy 131.69134 -245.057912)
			(xy 131.645182 -245.031263) (xy 131.603511 -244.998032) (xy 131.567259 -244.958961) (xy 131.537235 -244.914924)
			(xy 131.514109 -244.866903) (xy 131.498399 -244.815973) (xy 131.490456 -244.763269) (xy 131.261622 -244.763269)
			(xy 131.253679 -244.815973) (xy 131.237969 -244.866903) (xy 131.214843 -244.914924) (xy 131.184819 -244.958961)
			(xy 131.148567 -244.998032) (xy 131.106896 -245.031263) (xy 131.060738 -245.057912) (xy 131.011124 -245.077384)
			(xy 130.959162 -245.089244) (xy 130.906012 -245.093228) (xy 130.852862 -245.089244) (xy 130.8009 -245.077384)
			(xy 130.751286 -245.057912) (xy 130.705128 -245.031263) (xy 130.663457 -244.998032) (xy 130.627205 -244.958961)
			(xy 130.597181 -244.914924) (xy 130.574055 -244.866903) (xy 130.558345 -244.815973) (xy 130.550402 -244.763269)
			(xy 130.321822 -244.763269) (xy 130.313879 -244.815973) (xy 130.298169 -244.866903) (xy 130.275043 -244.914924)
			(xy 130.245019 -244.958961) (xy 130.208767 -244.998032) (xy 130.167096 -245.031263) (xy 130.120938 -245.057912)
			(xy 130.071324 -245.077384) (xy 130.019362 -245.089244) (xy 129.966212 -245.093228) (xy 129.913062 -245.089244)
			(xy 129.8611 -245.077384) (xy 129.811486 -245.057912) (xy 129.765328 -245.031263) (xy 129.723657 -244.998032)
			(xy 129.687405 -244.958961) (xy 129.657381 -244.914924) (xy 129.634255 -244.866903) (xy 129.618545 -244.815973)
			(xy 129.610602 -244.763269) (xy 129.382022 -244.763269) (xy 129.374079 -244.815973) (xy 129.358369 -244.866903)
			(xy 129.335243 -244.914924) (xy 129.305219 -244.958961) (xy 129.268967 -244.998032) (xy 129.227296 -245.031263)
			(xy 129.181138 -245.057912) (xy 129.131524 -245.077384) (xy 129.079562 -245.089244) (xy 129.026412 -245.093228)
			(xy 128.973262 -245.089244) (xy 128.9213 -245.077384) (xy 128.871686 -245.057912) (xy 128.825528 -245.031263)
			(xy 128.783857 -244.998032) (xy 128.747605 -244.958961) (xy 128.717581 -244.914924) (xy 128.694455 -244.866903)
			(xy 128.678745 -244.815973) (xy 128.670802 -244.763269) (xy 128.442222 -244.763269) (xy 128.434279 -244.815973)
			(xy 128.418569 -244.866903) (xy 128.395443 -244.914924) (xy 128.365419 -244.958961) (xy 128.329167 -244.998032)
			(xy 128.287496 -245.031263) (xy 128.241338 -245.057912) (xy 128.191724 -245.077384) (xy 128.139762 -245.089244)
			(xy 128.086612 -245.093228) (xy 128.033462 -245.089244) (xy 127.9815 -245.077384) (xy 127.931886 -245.057912)
			(xy 127.885728 -245.031263) (xy 127.844057 -244.998032) (xy 127.807805 -244.958961) (xy 127.777781 -244.914924)
			(xy 127.754655 -244.866903) (xy 127.738945 -244.815973) (xy 127.731002 -244.763269) (xy 127.502676 -244.763269)
			(xy 127.494733 -244.815973) (xy 127.479023 -244.866903) (xy 127.455897 -244.914924) (xy 127.425873 -244.958961)
			(xy 127.389621 -244.998032) (xy 127.34795 -245.031263) (xy 127.301792 -245.057912) (xy 127.252178 -245.077384)
			(xy 127.200216 -245.089244) (xy 127.147066 -245.093228) (xy 127.093916 -245.089244) (xy 127.041954 -245.077384)
			(xy 126.99234 -245.057912) (xy 126.946182 -245.031263) (xy 126.904511 -244.998032) (xy 126.868259 -244.958961)
			(xy 126.838235 -244.914924) (xy 126.815109 -244.866903) (xy 126.799399 -244.815973) (xy 126.791456 -244.763269)
			(xy 126.562622 -244.763269) (xy 126.554679 -244.815973) (xy 126.538969 -244.866903) (xy 126.515843 -244.914924)
			(xy 126.485819 -244.958961) (xy 126.449567 -244.998032) (xy 126.407896 -245.031263) (xy 126.361738 -245.057912)
			(xy 126.312124 -245.077384) (xy 126.260162 -245.089244) (xy 126.207012 -245.093228) (xy 126.153862 -245.089244)
			(xy 126.1019 -245.077384) (xy 126.052286 -245.057912) (xy 126.006128 -245.031263) (xy 125.964457 -244.998032)
			(xy 125.928205 -244.958961) (xy 125.898181 -244.914924) (xy 125.875055 -244.866903) (xy 125.859345 -244.815973)
			(xy 125.851402 -244.763269) (xy 125.623076 -244.763269) (xy 125.615133 -244.815973) (xy 125.599423 -244.866903)
			(xy 125.576297 -244.914924) (xy 125.546273 -244.958961) (xy 125.510021 -244.998032) (xy 125.46835 -245.031263)
			(xy 125.422192 -245.057912) (xy 125.372578 -245.077384) (xy 125.320616 -245.089244) (xy 125.267466 -245.093228)
			(xy 125.214316 -245.089244) (xy 125.162354 -245.077384) (xy 125.11274 -245.057912) (xy 125.066582 -245.031263)
			(xy 125.024911 -244.998032) (xy 124.988659 -244.958961) (xy 124.958635 -244.914924) (xy 124.935509 -244.866903)
			(xy 124.919799 -244.815973) (xy 124.911856 -244.763269) (xy 124.683022 -244.763269) (xy 124.675079 -244.815973)
			(xy 124.659369 -244.866903) (xy 124.636243 -244.914924) (xy 124.606219 -244.958961) (xy 124.569967 -244.998032)
			(xy 124.528296 -245.031263) (xy 124.482138 -245.057912) (xy 124.432524 -245.077384) (xy 124.380562 -245.089244)
			(xy 124.327412 -245.093228) (xy 124.274262 -245.089244) (xy 124.2223 -245.077384) (xy 124.172686 -245.057912)
			(xy 124.126528 -245.031263) (xy 124.084857 -244.998032) (xy 124.048605 -244.958961) (xy 124.018581 -244.914924)
			(xy 123.995455 -244.866903) (xy 123.979745 -244.815973) (xy 123.971802 -244.763269) (xy 123.743222 -244.763269)
			(xy 123.735279 -244.815973) (xy 123.719569 -244.866903) (xy 123.696443 -244.914924) (xy 123.666419 -244.958961)
			(xy 123.630167 -244.998032) (xy 123.588496 -245.031263) (xy 123.542338 -245.057912) (xy 123.492724 -245.077384)
			(xy 123.440762 -245.089244) (xy 123.387612 -245.093228) (xy 123.334462 -245.089244) (xy 123.2825 -245.077384)
			(xy 123.232886 -245.057912) (xy 123.186728 -245.031263) (xy 123.145057 -244.998032) (xy 123.108805 -244.958961)
			(xy 123.078781 -244.914924) (xy 123.055655 -244.866903) (xy 123.039945 -244.815973) (xy 123.032002 -244.763269)
			(xy 122.803384 -244.763269) (xy 122.795479 -244.815719) (xy 122.779769 -244.866649) (xy 122.756643 -244.91467)
			(xy 122.726619 -244.958707) (xy 122.690367 -244.997778) (xy 122.648696 -245.031009) (xy 122.602538 -245.057658)
			(xy 122.552924 -245.07713) (xy 122.500962 -245.08899) (xy 122.447812 -245.092974) (xy 122.394662 -245.08899)
			(xy 122.3427 -245.07713) (xy 122.293086 -245.057658) (xy 122.246928 -245.031009) (xy 122.205257 -244.997778)
			(xy 122.169005 -244.958707) (xy 122.138981 -244.91467) (xy 122.115855 -244.866649) (xy 122.100145 -244.815719)
			(xy 122.092202 -244.763015) (xy 121.862648 -244.763015) (xy 121.860644 -244.789751) (xy 121.848784 -244.841716)
			(xy 121.829312 -244.891332) (xy 121.802662 -244.937492) (xy 121.76943 -244.979164) (xy 121.730359 -245.015418)
			(xy 121.686321 -245.045444) (xy 121.638299 -245.068572) (xy 121.587367 -245.084284) (xy 121.534662 -245.092229)
			(xy 121.508012 -245.092728) (xy 121.487308 -245.092402) (xy 121.446183 -245.087566) (xy 121.42597 -245.083076)
			(xy 121.411669 -245.080155) (xy 121.382534 -245.081687) (xy 121.355025 -245.091407) (xy 121.331394 -245.108519)
			(xy 121.313577 -245.131622) (xy 121.30786 -245.145052) (xy 121.296991 -245.171269) (xy 121.268149 -245.220143)
			(xy 121.250456 -245.242334) (xy 121.241826 -245.253461) (xy 121.230481 -245.279223) (xy 121.226601 -245.307103)
			(xy 121.230482 -245.334983) (xy 121.241829 -245.360744) (xy 121.250456 -245.371874) (xy 121.265907 -245.391109)
			(xy 121.291862 -245.433069) (xy 121.311776 -245.47821) (xy 121.325268 -245.525668) (xy 121.332079 -245.574535)
			(xy 121.332127 -245.577339) (xy 121.622556 -245.577339) (xy 121.622556 -245.524041) (xy 121.630499 -245.471337)
			(xy 121.646209 -245.420407) (xy 121.669335 -245.372386) (xy 121.699359 -245.328349) (xy 121.735611 -245.289278)
			(xy 121.777282 -245.256047) (xy 121.82344 -245.229398) (xy 121.873054 -245.209926) (xy 121.925016 -245.198066)
			(xy 121.978166 -245.194083) (xy 122.031316 -245.198066) (xy 122.083278 -245.209926) (xy 122.132892 -245.229398)
			(xy 122.17905 -245.256047) (xy 122.220721 -245.289278) (xy 122.256973 -245.328349) (xy 122.286997 -245.372386)
			(xy 122.310123 -245.420407) (xy 122.325833 -245.471337) (xy 122.333776 -245.524041) (xy 122.334274 -245.55069)
			(xy 122.333776 -245.577339) (xy 122.562356 -245.577339) (xy 122.562356 -245.524041) (xy 122.570299 -245.471337)
			(xy 122.586009 -245.420407) (xy 122.609135 -245.372386) (xy 122.639159 -245.328349) (xy 122.675411 -245.289278)
			(xy 122.717082 -245.256047) (xy 122.76324 -245.229398) (xy 122.812854 -245.209926) (xy 122.864816 -245.198066)
			(xy 122.917966 -245.194083) (xy 122.971116 -245.198066) (xy 123.023078 -245.209926) (xy 123.072692 -245.229398)
			(xy 123.11885 -245.256047) (xy 123.160521 -245.289278) (xy 123.196773 -245.328349) (xy 123.226797 -245.372386)
			(xy 123.249923 -245.420407) (xy 123.265633 -245.471337) (xy 123.273576 -245.524041) (xy 123.274074 -245.55069)
			(xy 123.273576 -245.577339) (xy 123.502156 -245.577339) (xy 123.502156 -245.524041) (xy 123.510099 -245.471337)
			(xy 123.525809 -245.420407) (xy 123.548935 -245.372386) (xy 123.578959 -245.328349) (xy 123.615211 -245.289278)
			(xy 123.656882 -245.256047) (xy 123.70304 -245.229398) (xy 123.752654 -245.209926) (xy 123.804616 -245.198066)
			(xy 123.857766 -245.194083) (xy 123.910916 -245.198066) (xy 123.962878 -245.209926) (xy 124.012492 -245.229398)
			(xy 124.05865 -245.256047) (xy 124.100321 -245.289278) (xy 124.136573 -245.328349) (xy 124.166597 -245.372386)
			(xy 124.189723 -245.420407) (xy 124.205433 -245.471337) (xy 124.213376 -245.524041) (xy 124.213874 -245.55069)
			(xy 124.213376 -245.577339) (xy 124.441956 -245.577339) (xy 124.441956 -245.524041) (xy 124.449899 -245.471337)
			(xy 124.465609 -245.420407) (xy 124.488735 -245.372386) (xy 124.518759 -245.328349) (xy 124.555011 -245.289278)
			(xy 124.596682 -245.256047) (xy 124.64284 -245.229398) (xy 124.692454 -245.209926) (xy 124.744416 -245.198066)
			(xy 124.797566 -245.194083) (xy 124.850716 -245.198066) (xy 124.902678 -245.209926) (xy 124.952292 -245.229398)
			(xy 124.99845 -245.256047) (xy 125.040121 -245.289278) (xy 125.076373 -245.328349) (xy 125.106397 -245.372386)
			(xy 125.129523 -245.420407) (xy 125.145233 -245.471337) (xy 125.153176 -245.524041) (xy 125.153674 -245.55069)
			(xy 125.153176 -245.577339) (xy 125.381502 -245.577339) (xy 125.381502 -245.524041) (xy 125.389445 -245.471337)
			(xy 125.405155 -245.420407) (xy 125.428281 -245.372386) (xy 125.458305 -245.328349) (xy 125.494557 -245.289278)
			(xy 125.536228 -245.256047) (xy 125.582386 -245.229398) (xy 125.632 -245.209926) (xy 125.683962 -245.198066)
			(xy 125.737112 -245.194083) (xy 125.790262 -245.198066) (xy 125.842224 -245.209926) (xy 125.891838 -245.229398)
			(xy 125.937996 -245.256047) (xy 125.979667 -245.289278) (xy 126.015919 -245.328349) (xy 126.045943 -245.372386)
			(xy 126.069069 -245.420407) (xy 126.084779 -245.471337) (xy 126.092722 -245.524041) (xy 126.09322 -245.55069)
			(xy 126.092722 -245.577339) (xy 126.321556 -245.577339) (xy 126.321556 -245.524041) (xy 126.329499 -245.471337)
			(xy 126.345209 -245.420407) (xy 126.368335 -245.372386) (xy 126.398359 -245.328349) (xy 126.434611 -245.289278)
			(xy 126.476282 -245.256047) (xy 126.52244 -245.229398) (xy 126.572054 -245.209926) (xy 126.624016 -245.198066)
			(xy 126.677166 -245.194083) (xy 126.730316 -245.198066) (xy 126.782278 -245.209926) (xy 126.831892 -245.229398)
			(xy 126.87805 -245.256047) (xy 126.919721 -245.289278) (xy 126.955973 -245.328349) (xy 126.985997 -245.372386)
			(xy 127.009123 -245.420407) (xy 127.024833 -245.471337) (xy 127.032776 -245.524041) (xy 127.033274 -245.55069)
			(xy 127.032776 -245.577339) (xy 127.261102 -245.577339) (xy 127.261102 -245.524041) (xy 127.269045 -245.471337)
			(xy 127.284755 -245.420407) (xy 127.307881 -245.372386) (xy 127.337905 -245.328349) (xy 127.374157 -245.289278)
			(xy 127.415828 -245.256047) (xy 127.461986 -245.229398) (xy 127.5116 -245.209926) (xy 127.563562 -245.198066)
			(xy 127.616712 -245.194083) (xy 127.669862 -245.198066) (xy 127.721824 -245.209926) (xy 127.771438 -245.229398)
			(xy 127.817596 -245.256047) (xy 127.859267 -245.289278) (xy 127.895519 -245.328349) (xy 127.925543 -245.372386)
			(xy 127.948669 -245.420407) (xy 127.964379 -245.471337) (xy 127.972322 -245.524041) (xy 127.97282 -245.55069)
			(xy 127.972322 -245.577339) (xy 128.201156 -245.577339) (xy 128.201156 -245.524041) (xy 128.209099 -245.471337)
			(xy 128.224809 -245.420407) (xy 128.247935 -245.372386) (xy 128.277959 -245.328349) (xy 128.314211 -245.289278)
			(xy 128.355882 -245.256047) (xy 128.40204 -245.229398) (xy 128.451654 -245.209926) (xy 128.503616 -245.198066)
			(xy 128.556766 -245.194083) (xy 128.609916 -245.198066) (xy 128.661878 -245.209926) (xy 128.711492 -245.229398)
			(xy 128.75765 -245.256047) (xy 128.799321 -245.289278) (xy 128.835573 -245.328349) (xy 128.865597 -245.372386)
			(xy 128.888723 -245.420407) (xy 128.904433 -245.471337) (xy 128.912376 -245.524041) (xy 128.912874 -245.55069)
			(xy 128.912376 -245.577339) (xy 129.140956 -245.577339) (xy 129.140956 -245.524041) (xy 129.148899 -245.471337)
			(xy 129.164609 -245.420407) (xy 129.187735 -245.372386) (xy 129.217759 -245.328349) (xy 129.254011 -245.289278)
			(xy 129.295682 -245.256047) (xy 129.34184 -245.229398) (xy 129.391454 -245.209926) (xy 129.443416 -245.198066)
			(xy 129.496566 -245.194083) (xy 129.549716 -245.198066) (xy 129.601678 -245.209926) (xy 129.651292 -245.229398)
			(xy 129.69745 -245.256047) (xy 129.739121 -245.289278) (xy 129.775373 -245.328349) (xy 129.805397 -245.372386)
			(xy 129.828523 -245.420407) (xy 129.844233 -245.471337) (xy 129.852176 -245.524041) (xy 129.852674 -245.55069)
			(xy 129.852176 -245.577339) (xy 130.080756 -245.577339) (xy 130.080756 -245.524041) (xy 130.088699 -245.471337)
			(xy 130.104409 -245.420407) (xy 130.127535 -245.372386) (xy 130.157559 -245.328349) (xy 130.193811 -245.289278)
			(xy 130.235482 -245.256047) (xy 130.28164 -245.229398) (xy 130.331254 -245.209926) (xy 130.383216 -245.198066)
			(xy 130.436366 -245.194083) (xy 130.489516 -245.198066) (xy 130.541478 -245.209926) (xy 130.591092 -245.229398)
			(xy 130.63725 -245.256047) (xy 130.678921 -245.289278) (xy 130.715173 -245.328349) (xy 130.745197 -245.372386)
			(xy 130.768323 -245.420407) (xy 130.784033 -245.471337) (xy 130.791976 -245.524041) (xy 130.792474 -245.55069)
			(xy 130.791976 -245.577339) (xy 131.020556 -245.577339) (xy 131.020556 -245.524041) (xy 131.028499 -245.471337)
			(xy 131.044209 -245.420407) (xy 131.067335 -245.372386) (xy 131.097359 -245.328349) (xy 131.133611 -245.289278)
			(xy 131.175282 -245.256047) (xy 131.22144 -245.229398) (xy 131.271054 -245.209926) (xy 131.323016 -245.198066)
			(xy 131.376166 -245.194083) (xy 131.429316 -245.198066) (xy 131.481278 -245.209926) (xy 131.530892 -245.229398)
			(xy 131.57705 -245.256047) (xy 131.618721 -245.289278) (xy 131.654973 -245.328349) (xy 131.684997 -245.372386)
			(xy 131.708123 -245.420407) (xy 131.723833 -245.471337) (xy 131.731776 -245.524041) (xy 131.732274 -245.55069)
			(xy 131.731776 -245.577339) (xy 131.960102 -245.577339) (xy 131.960102 -245.524041) (xy 131.968045 -245.471337)
			(xy 131.983755 -245.420407) (xy 132.006881 -245.372386) (xy 132.036905 -245.328349) (xy 132.073157 -245.289278)
			(xy 132.114828 -245.256047) (xy 132.160986 -245.229398) (xy 132.2106 -245.209926) (xy 132.262562 -245.198066)
			(xy 132.315712 -245.194083) (xy 132.368862 -245.198066) (xy 132.420824 -245.209926) (xy 132.470438 -245.229398)
			(xy 132.516596 -245.256047) (xy 132.558267 -245.289278) (xy 132.594519 -245.328349) (xy 132.624543 -245.372386)
			(xy 132.647669 -245.420407) (xy 132.663379 -245.471337) (xy 132.671322 -245.524041) (xy 132.67182 -245.55069)
			(xy 132.671322 -245.577339) (xy 132.900156 -245.577339) (xy 132.900156 -245.524041) (xy 132.908099 -245.471337)
			(xy 132.923809 -245.420407) (xy 132.946935 -245.372386) (xy 132.976959 -245.328349) (xy 133.013211 -245.289278)
			(xy 133.054882 -245.256047) (xy 133.10104 -245.229398) (xy 133.150654 -245.209926) (xy 133.202616 -245.198066)
			(xy 133.255766 -245.194083) (xy 133.308916 -245.198066) (xy 133.360878 -245.209926) (xy 133.410492 -245.229398)
			(xy 133.45665 -245.256047) (xy 133.498321 -245.289278) (xy 133.534573 -245.328349) (xy 133.564597 -245.372386)
			(xy 133.587723 -245.420407) (xy 133.603433 -245.471337) (xy 133.611376 -245.524041) (xy 133.611874 -245.55069)
			(xy 133.611376 -245.577339) (xy 133.839956 -245.577339) (xy 133.839956 -245.524041) (xy 133.847899 -245.471337)
			(xy 133.863609 -245.420407) (xy 133.886735 -245.372386) (xy 133.916759 -245.328349) (xy 133.953011 -245.289278)
			(xy 133.994682 -245.256047) (xy 134.04084 -245.229398) (xy 134.090454 -245.209926) (xy 134.142416 -245.198066)
			(xy 134.195566 -245.194083) (xy 134.248716 -245.198066) (xy 134.300678 -245.209926) (xy 134.350292 -245.229398)
			(xy 134.39645 -245.256047) (xy 134.438121 -245.289278) (xy 134.474373 -245.328349) (xy 134.504397 -245.372386)
			(xy 134.527523 -245.420407) (xy 134.543233 -245.471337) (xy 134.551176 -245.524041) (xy 134.551674 -245.55069)
			(xy 134.551176 -245.577339) (xy 134.543233 -245.630043) (xy 134.527523 -245.680973) (xy 134.504397 -245.728994)
			(xy 134.474373 -245.773031) (xy 134.438121 -245.812102) (xy 134.39645 -245.845333) (xy 134.350292 -245.871982)
			(xy 134.300678 -245.891454) (xy 134.248716 -245.903314) (xy 134.195566 -245.907298) (xy 134.142416 -245.903314)
			(xy 134.090454 -245.891454) (xy 134.04084 -245.871982) (xy 133.994682 -245.845333) (xy 133.953011 -245.812102)
			(xy 133.916759 -245.773031) (xy 133.886735 -245.728994) (xy 133.863609 -245.680973) (xy 133.847899 -245.630043)
			(xy 133.839956 -245.577339) (xy 133.611376 -245.577339) (xy 133.603433 -245.630043) (xy 133.587723 -245.680973)
			(xy 133.564597 -245.728994) (xy 133.534573 -245.773031) (xy 133.498321 -245.812102) (xy 133.45665 -245.845333)
			(xy 133.410492 -245.871982) (xy 133.360878 -245.891454) (xy 133.308916 -245.903314) (xy 133.255766 -245.907298)
			(xy 133.202616 -245.903314) (xy 133.150654 -245.891454) (xy 133.10104 -245.871982) (xy 133.054882 -245.845333)
			(xy 133.013211 -245.812102) (xy 132.976959 -245.773031) (xy 132.946935 -245.728994) (xy 132.923809 -245.680973)
			(xy 132.908099 -245.630043) (xy 132.900156 -245.577339) (xy 132.671322 -245.577339) (xy 132.663379 -245.630043)
			(xy 132.647669 -245.680973) (xy 132.624543 -245.728994) (xy 132.594519 -245.773031) (xy 132.558267 -245.812102)
			(xy 132.516596 -245.845333) (xy 132.470438 -245.871982) (xy 132.420824 -245.891454) (xy 132.368862 -245.903314)
			(xy 132.315712 -245.907298) (xy 132.262562 -245.903314) (xy 132.2106 -245.891454) (xy 132.160986 -245.871982)
			(xy 132.114828 -245.845333) (xy 132.073157 -245.812102) (xy 132.036905 -245.773031) (xy 132.006881 -245.728994)
			(xy 131.983755 -245.680973) (xy 131.968045 -245.630043) (xy 131.960102 -245.577339) (xy 131.731776 -245.577339)
			(xy 131.723833 -245.630043) (xy 131.708123 -245.680973) (xy 131.684997 -245.728994) (xy 131.654973 -245.773031)
			(xy 131.618721 -245.812102) (xy 131.57705 -245.845333) (xy 131.530892 -245.871982) (xy 131.481278 -245.891454)
			(xy 131.429316 -245.903314) (xy 131.376166 -245.907298) (xy 131.323016 -245.903314) (xy 131.271054 -245.891454)
			(xy 131.22144 -245.871982) (xy 131.175282 -245.845333) (xy 131.133611 -245.812102) (xy 131.097359 -245.773031)
			(xy 131.067335 -245.728994) (xy 131.044209 -245.680973) (xy 131.028499 -245.630043) (xy 131.020556 -245.577339)
			(xy 130.791976 -245.577339) (xy 130.784033 -245.630043) (xy 130.768323 -245.680973) (xy 130.745197 -245.728994)
			(xy 130.715173 -245.773031) (xy 130.678921 -245.812102) (xy 130.63725 -245.845333) (xy 130.591092 -245.871982)
			(xy 130.541478 -245.891454) (xy 130.489516 -245.903314) (xy 130.436366 -245.907298) (xy 130.383216 -245.903314)
			(xy 130.331254 -245.891454) (xy 130.28164 -245.871982) (xy 130.235482 -245.845333) (xy 130.193811 -245.812102)
			(xy 130.157559 -245.773031) (xy 130.127535 -245.728994) (xy 130.104409 -245.680973) (xy 130.088699 -245.630043)
			(xy 130.080756 -245.577339) (xy 129.852176 -245.577339) (xy 129.844233 -245.630043) (xy 129.828523 -245.680973)
			(xy 129.805397 -245.728994) (xy 129.775373 -245.773031) (xy 129.739121 -245.812102) (xy 129.69745 -245.845333)
			(xy 129.651292 -245.871982) (xy 129.601678 -245.891454) (xy 129.549716 -245.903314) (xy 129.496566 -245.907298)
			(xy 129.443416 -245.903314) (xy 129.391454 -245.891454) (xy 129.34184 -245.871982) (xy 129.295682 -245.845333)
			(xy 129.254011 -245.812102) (xy 129.217759 -245.773031) (xy 129.187735 -245.728994) (xy 129.164609 -245.680973)
			(xy 129.148899 -245.630043) (xy 129.140956 -245.577339) (xy 128.912376 -245.577339) (xy 128.904433 -245.630043)
			(xy 128.888723 -245.680973) (xy 128.865597 -245.728994) (xy 128.835573 -245.773031) (xy 128.799321 -245.812102)
			(xy 128.75765 -245.845333) (xy 128.711492 -245.871982) (xy 128.661878 -245.891454) (xy 128.609916 -245.903314)
			(xy 128.556766 -245.907298) (xy 128.503616 -245.903314) (xy 128.451654 -245.891454) (xy 128.40204 -245.871982)
			(xy 128.355882 -245.845333) (xy 128.314211 -245.812102) (xy 128.277959 -245.773031) (xy 128.247935 -245.728994)
			(xy 128.224809 -245.680973) (xy 128.209099 -245.630043) (xy 128.201156 -245.577339) (xy 127.972322 -245.577339)
			(xy 127.964379 -245.630043) (xy 127.948669 -245.680973) (xy 127.925543 -245.728994) (xy 127.895519 -245.773031)
			(xy 127.859267 -245.812102) (xy 127.817596 -245.845333) (xy 127.771438 -245.871982) (xy 127.721824 -245.891454)
			(xy 127.669862 -245.903314) (xy 127.616712 -245.907298) (xy 127.563562 -245.903314) (xy 127.5116 -245.891454)
			(xy 127.461986 -245.871982) (xy 127.415828 -245.845333) (xy 127.374157 -245.812102) (xy 127.337905 -245.773031)
			(xy 127.307881 -245.728994) (xy 127.284755 -245.680973) (xy 127.269045 -245.630043) (xy 127.261102 -245.577339)
			(xy 127.032776 -245.577339) (xy 127.024833 -245.630043) (xy 127.009123 -245.680973) (xy 126.985997 -245.728994)
			(xy 126.955973 -245.773031) (xy 126.919721 -245.812102) (xy 126.87805 -245.845333) (xy 126.831892 -245.871982)
			(xy 126.782278 -245.891454) (xy 126.730316 -245.903314) (xy 126.677166 -245.907298) (xy 126.624016 -245.903314)
			(xy 126.572054 -245.891454) (xy 126.52244 -245.871982) (xy 126.476282 -245.845333) (xy 126.434611 -245.812102)
			(xy 126.398359 -245.773031) (xy 126.368335 -245.728994) (xy 126.345209 -245.680973) (xy 126.329499 -245.630043)
			(xy 126.321556 -245.577339) (xy 126.092722 -245.577339) (xy 126.084779 -245.630043) (xy 126.069069 -245.680973)
			(xy 126.045943 -245.728994) (xy 126.015919 -245.773031) (xy 125.979667 -245.812102) (xy 125.937996 -245.845333)
			(xy 125.891838 -245.871982) (xy 125.842224 -245.891454) (xy 125.790262 -245.903314) (xy 125.737112 -245.907298)
			(xy 125.683962 -245.903314) (xy 125.632 -245.891454) (xy 125.582386 -245.871982) (xy 125.536228 -245.845333)
			(xy 125.494557 -245.812102) (xy 125.458305 -245.773031) (xy 125.428281 -245.728994) (xy 125.405155 -245.680973)
			(xy 125.389445 -245.630043) (xy 125.381502 -245.577339) (xy 125.153176 -245.577339) (xy 125.145233 -245.630043)
			(xy 125.129523 -245.680973) (xy 125.106397 -245.728994) (xy 125.076373 -245.773031) (xy 125.040121 -245.812102)
			(xy 124.99845 -245.845333) (xy 124.952292 -245.871982) (xy 124.902678 -245.891454) (xy 124.850716 -245.903314)
			(xy 124.797566 -245.907298) (xy 124.744416 -245.903314) (xy 124.692454 -245.891454) (xy 124.64284 -245.871982)
			(xy 124.596682 -245.845333) (xy 124.555011 -245.812102) (xy 124.518759 -245.773031) (xy 124.488735 -245.728994)
			(xy 124.465609 -245.680973) (xy 124.449899 -245.630043) (xy 124.441956 -245.577339) (xy 124.213376 -245.577339)
			(xy 124.205433 -245.630043) (xy 124.189723 -245.680973) (xy 124.166597 -245.728994) (xy 124.136573 -245.773031)
			(xy 124.100321 -245.812102) (xy 124.05865 -245.845333) (xy 124.012492 -245.871982) (xy 123.962878 -245.891454)
			(xy 123.910916 -245.903314) (xy 123.857766 -245.907298) (xy 123.804616 -245.903314) (xy 123.752654 -245.891454)
			(xy 123.70304 -245.871982) (xy 123.656882 -245.845333) (xy 123.615211 -245.812102) (xy 123.578959 -245.773031)
			(xy 123.548935 -245.728994) (xy 123.525809 -245.680973) (xy 123.510099 -245.630043) (xy 123.502156 -245.577339)
			(xy 123.273576 -245.577339) (xy 123.265633 -245.630043) (xy 123.249923 -245.680973) (xy 123.226797 -245.728994)
			(xy 123.196773 -245.773031) (xy 123.160521 -245.812102) (xy 123.11885 -245.845333) (xy 123.072692 -245.871982)
			(xy 123.023078 -245.891454) (xy 122.971116 -245.903314) (xy 122.917966 -245.907298) (xy 122.864816 -245.903314)
			(xy 122.812854 -245.891454) (xy 122.76324 -245.871982) (xy 122.717082 -245.845333) (xy 122.675411 -245.812102)
			(xy 122.639159 -245.773031) (xy 122.609135 -245.728994) (xy 122.586009 -245.680973) (xy 122.570299 -245.630043)
			(xy 122.562356 -245.577339) (xy 122.333776 -245.577339) (xy 122.325833 -245.630043) (xy 122.310123 -245.680973)
			(xy 122.286997 -245.728994) (xy 122.256973 -245.773031) (xy 122.220721 -245.812102) (xy 122.17905 -245.845333)
			(xy 122.132892 -245.871982) (xy 122.083278 -245.891454) (xy 122.031316 -245.903314) (xy 121.978166 -245.907298)
			(xy 121.925016 -245.903314) (xy 121.873054 -245.891454) (xy 121.82344 -245.871982) (xy 121.777282 -245.845333)
			(xy 121.735611 -245.812102) (xy 121.699359 -245.773031) (xy 121.669335 -245.728994) (xy 121.646209 -245.680973)
			(xy 121.630499 -245.630043) (xy 121.622556 -245.577339) (xy 121.332127 -245.577339) (xy 121.332498 -245.599204)
			(xy 121.332 -245.625853) (xy 121.324057 -245.678557) (xy 121.308347 -245.729487) (xy 121.285221 -245.777508)
			(xy 121.255197 -245.821545) (xy 121.218945 -245.860616) (xy 121.177274 -245.893847) (xy 121.131116 -245.920496)
			(xy 121.081502 -245.939968) (xy 121.02954 -245.951828) (xy 120.97639 -245.955812) (xy 120.92324 -245.951828)
			(xy 120.871278 -245.939968) (xy 120.821664 -245.920496) (xy 120.775506 -245.893847) (xy 120.733835 -245.860616)
			(xy 120.697583 -245.821545) (xy 120.667559 -245.777508) (xy 120.644433 -245.729487) (xy 120.628723 -245.678557)
			(xy 120.62078 -245.625853) (xy 120.620282 -245.599204) (xy 120.620681 -245.574534) (xy 120.627487 -245.525665)
			(xy 120.640983 -245.478207) (xy 120.66091 -245.43307) (xy 120.686886 -245.391121) (xy 120.702324 -245.371874)
			(xy 120.710948 -245.360742) (xy 120.722296 -245.334983) (xy 120.726178 -245.307103) (xy 120.722298 -245.279223)
			(xy 120.710951 -245.253464) (xy 120.702324 -245.242334) (xy 120.685204 -245.220916) (xy 120.657061 -245.17386)
			(xy 120.63647 -245.123044) (xy 120.623916 -245.06967) (xy 120.619698 -245.015003) (xy 118.87708 -245.015003)
			(xy 118.87708 -246.391155) (xy 121.152656 -246.391155) (xy 121.152656 -246.337857) (xy 121.160599 -246.285153)
			(xy 121.176309 -246.234223) (xy 121.199435 -246.186202) (xy 121.229459 -246.142165) (xy 121.265711 -246.103094)
			(xy 121.307382 -246.069863) (xy 121.35354 -246.043214) (xy 121.403154 -246.023742) (xy 121.455116 -246.011882)
			(xy 121.508266 -246.007899) (xy 121.561416 -246.011882) (xy 121.613378 -246.023742) (xy 121.662992 -246.043214)
			(xy 121.70915 -246.069863) (xy 121.750821 -246.103094) (xy 121.787073 -246.142165) (xy 121.817097 -246.186202)
			(xy 121.840223 -246.234223) (xy 121.855933 -246.285153) (xy 121.863876 -246.337857) (xy 121.864374 -246.364506)
			(xy 121.863876 -246.391155) (xy 122.092456 -246.391155) (xy 122.092456 -246.337857) (xy 122.100399 -246.285153)
			(xy 122.116109 -246.234223) (xy 122.139235 -246.186202) (xy 122.169259 -246.142165) (xy 122.205511 -246.103094)
			(xy 122.247182 -246.069863) (xy 122.29334 -246.043214) (xy 122.342954 -246.023742) (xy 122.394916 -246.011882)
			(xy 122.448066 -246.007899) (xy 122.501216 -246.011882) (xy 122.553178 -246.023742) (xy 122.602792 -246.043214)
			(xy 122.64895 -246.069863) (xy 122.690621 -246.103094) (xy 122.726873 -246.142165) (xy 122.756897 -246.186202)
			(xy 122.780023 -246.234223) (xy 122.795733 -246.285153) (xy 122.803676 -246.337857) (xy 122.804174 -246.364506)
			(xy 122.803676 -246.391155) (xy 123.032002 -246.391155) (xy 123.032002 -246.337857) (xy 123.039945 -246.285153)
			(xy 123.055655 -246.234223) (xy 123.078781 -246.186202) (xy 123.108805 -246.142165) (xy 123.145057 -246.103094)
			(xy 123.186728 -246.069863) (xy 123.232886 -246.043214) (xy 123.2825 -246.023742) (xy 123.334462 -246.011882)
			(xy 123.387612 -246.007899) (xy 123.440762 -246.011882) (xy 123.492724 -246.023742) (xy 123.542338 -246.043214)
			(xy 123.588496 -246.069863) (xy 123.630167 -246.103094) (xy 123.666419 -246.142165) (xy 123.696443 -246.186202)
			(xy 123.719569 -246.234223) (xy 123.735279 -246.285153) (xy 123.743222 -246.337857) (xy 123.74372 -246.364506)
			(xy 123.743222 -246.391155) (xy 123.971802 -246.391155) (xy 123.971802 -246.337857) (xy 123.979745 -246.285153)
			(xy 123.995455 -246.234223) (xy 124.018581 -246.186202) (xy 124.048605 -246.142165) (xy 124.084857 -246.103094)
			(xy 124.126528 -246.069863) (xy 124.172686 -246.043214) (xy 124.2223 -246.023742) (xy 124.274262 -246.011882)
			(xy 124.327412 -246.007899) (xy 124.380562 -246.011882) (xy 124.432524 -246.023742) (xy 124.482138 -246.043214)
			(xy 124.528296 -246.069863) (xy 124.569967 -246.103094) (xy 124.606219 -246.142165) (xy 124.636243 -246.186202)
			(xy 124.659369 -246.234223) (xy 124.675079 -246.285153) (xy 124.683022 -246.337857) (xy 124.68352 -246.364506)
			(xy 124.683022 -246.391155) (xy 124.911602 -246.391155) (xy 124.911602 -246.337857) (xy 124.919545 -246.285153)
			(xy 124.935255 -246.234223) (xy 124.958381 -246.186202) (xy 124.988405 -246.142165) (xy 125.024657 -246.103094)
			(xy 125.066328 -246.069863) (xy 125.112486 -246.043214) (xy 125.1621 -246.023742) (xy 125.214062 -246.011882)
			(xy 125.267212 -246.007899) (xy 125.320362 -246.011882) (xy 125.372324 -246.023742) (xy 125.421938 -246.043214)
			(xy 125.468096 -246.069863) (xy 125.509767 -246.103094) (xy 125.546019 -246.142165) (xy 125.576043 -246.186202)
			(xy 125.599169 -246.234223) (xy 125.614879 -246.285153) (xy 125.622822 -246.337857) (xy 125.62332 -246.364506)
			(xy 125.622822 -246.391155) (xy 125.851402 -246.391155) (xy 125.851402 -246.337857) (xy 125.859345 -246.285153)
			(xy 125.875055 -246.234223) (xy 125.898181 -246.186202) (xy 125.928205 -246.142165) (xy 125.964457 -246.103094)
			(xy 126.006128 -246.069863) (xy 126.052286 -246.043214) (xy 126.1019 -246.023742) (xy 126.153862 -246.011882)
			(xy 126.207012 -246.007899) (xy 126.260162 -246.011882) (xy 126.312124 -246.023742) (xy 126.361738 -246.043214)
			(xy 126.407896 -246.069863) (xy 126.449567 -246.103094) (xy 126.485819 -246.142165) (xy 126.515843 -246.186202)
			(xy 126.538969 -246.234223) (xy 126.554679 -246.285153) (xy 126.562622 -246.337857) (xy 126.56312 -246.364506)
			(xy 126.562622 -246.391155) (xy 126.791202 -246.391155) (xy 126.791202 -246.337857) (xy 126.799145 -246.285153)
			(xy 126.814855 -246.234223) (xy 126.837981 -246.186202) (xy 126.868005 -246.142165) (xy 126.904257 -246.103094)
			(xy 126.945928 -246.069863) (xy 126.992086 -246.043214) (xy 127.0417 -246.023742) (xy 127.093662 -246.011882)
			(xy 127.146812 -246.007899) (xy 127.199962 -246.011882) (xy 127.251924 -246.023742) (xy 127.301538 -246.043214)
			(xy 127.347696 -246.069863) (xy 127.389367 -246.103094) (xy 127.425619 -246.142165) (xy 127.455643 -246.186202)
			(xy 127.478769 -246.234223) (xy 127.494479 -246.285153) (xy 127.502422 -246.337857) (xy 127.50292 -246.364506)
			(xy 127.502422 -246.391155) (xy 127.731002 -246.391155) (xy 127.731002 -246.337857) (xy 127.738945 -246.285153)
			(xy 127.754655 -246.234223) (xy 127.777781 -246.186202) (xy 127.807805 -246.142165) (xy 127.844057 -246.103094)
			(xy 127.885728 -246.069863) (xy 127.931886 -246.043214) (xy 127.9815 -246.023742) (xy 128.033462 -246.011882)
			(xy 128.086612 -246.007899) (xy 128.139762 -246.011882) (xy 128.191724 -246.023742) (xy 128.241338 -246.043214)
			(xy 128.287496 -246.069863) (xy 128.329167 -246.103094) (xy 128.365419 -246.142165) (xy 128.395443 -246.186202)
			(xy 128.418569 -246.234223) (xy 128.434279 -246.285153) (xy 128.442222 -246.337857) (xy 128.44272 -246.364506)
			(xy 128.442222 -246.391155) (xy 128.671056 -246.391155) (xy 128.671056 -246.337857) (xy 128.678999 -246.285153)
			(xy 128.694709 -246.234223) (xy 128.717835 -246.186202) (xy 128.747859 -246.142165) (xy 128.784111 -246.103094)
			(xy 128.825782 -246.069863) (xy 128.87194 -246.043214) (xy 128.921554 -246.023742) (xy 128.973516 -246.011882)
			(xy 129.026666 -246.007899) (xy 129.079816 -246.011882) (xy 129.131778 -246.023742) (xy 129.181392 -246.043214)
			(xy 129.22755 -246.069863) (xy 129.269221 -246.103094) (xy 129.305473 -246.142165) (xy 129.335497 -246.186202)
			(xy 129.358623 -246.234223) (xy 129.374333 -246.285153) (xy 129.382276 -246.337857) (xy 129.382774 -246.364506)
			(xy 129.382276 -246.391155) (xy 129.610602 -246.391155) (xy 129.610602 -246.337857) (xy 129.618545 -246.285153)
			(xy 129.634255 -246.234223) (xy 129.657381 -246.186202) (xy 129.687405 -246.142165) (xy 129.723657 -246.103094)
			(xy 129.765328 -246.069863) (xy 129.811486 -246.043214) (xy 129.8611 -246.023742) (xy 129.913062 -246.011882)
			(xy 129.966212 -246.007899) (xy 130.019362 -246.011882) (xy 130.071324 -246.023742) (xy 130.120938 -246.043214)
			(xy 130.167096 -246.069863) (xy 130.208767 -246.103094) (xy 130.245019 -246.142165) (xy 130.275043 -246.186202)
			(xy 130.298169 -246.234223) (xy 130.313879 -246.285153) (xy 130.321822 -246.337857) (xy 130.32232 -246.364506)
			(xy 130.321822 -246.391155) (xy 130.550402 -246.391155) (xy 130.550402 -246.337857) (xy 130.558345 -246.285153)
			(xy 130.574055 -246.234223) (xy 130.597181 -246.186202) (xy 130.627205 -246.142165) (xy 130.663457 -246.103094)
			(xy 130.705128 -246.069863) (xy 130.751286 -246.043214) (xy 130.8009 -246.023742) (xy 130.852862 -246.011882)
			(xy 130.906012 -246.007899) (xy 130.959162 -246.011882) (xy 131.011124 -246.023742) (xy 131.060738 -246.043214)
			(xy 131.106896 -246.069863) (xy 131.148567 -246.103094) (xy 131.184819 -246.142165) (xy 131.214843 -246.186202)
			(xy 131.237969 -246.234223) (xy 131.253679 -246.285153) (xy 131.261622 -246.337857) (xy 131.26212 -246.364506)
			(xy 131.261622 -246.391155) (xy 131.490202 -246.391155) (xy 131.490202 -246.337857) (xy 131.498145 -246.285153)
			(xy 131.513855 -246.234223) (xy 131.536981 -246.186202) (xy 131.567005 -246.142165) (xy 131.603257 -246.103094)
			(xy 131.644928 -246.069863) (xy 131.691086 -246.043214) (xy 131.7407 -246.023742) (xy 131.792662 -246.011882)
			(xy 131.845812 -246.007899) (xy 131.898962 -246.011882) (xy 131.950924 -246.023742) (xy 132.000538 -246.043214)
			(xy 132.046696 -246.069863) (xy 132.088367 -246.103094) (xy 132.124619 -246.142165) (xy 132.154643 -246.186202)
			(xy 132.177769 -246.234223) (xy 132.193479 -246.285153) (xy 132.201422 -246.337857) (xy 132.20192 -246.364506)
			(xy 132.201422 -246.391155) (xy 132.430002 -246.391155) (xy 132.430002 -246.337857) (xy 132.437945 -246.285153)
			(xy 132.453655 -246.234223) (xy 132.476781 -246.186202) (xy 132.506805 -246.142165) (xy 132.543057 -246.103094)
			(xy 132.584728 -246.069863) (xy 132.630886 -246.043214) (xy 132.6805 -246.023742) (xy 132.732462 -246.011882)
			(xy 132.785612 -246.007899) (xy 132.838762 -246.011882) (xy 132.890724 -246.023742) (xy 132.940338 -246.043214)
			(xy 132.986496 -246.069863) (xy 133.028167 -246.103094) (xy 133.064419 -246.142165) (xy 133.094443 -246.186202)
			(xy 133.117569 -246.234223) (xy 133.133279 -246.285153) (xy 133.141222 -246.337857) (xy 133.14172 -246.364506)
			(xy 133.141222 -246.391155) (xy 133.370056 -246.391155) (xy 133.370056 -246.337857) (xy 133.377999 -246.285153)
			(xy 133.393709 -246.234223) (xy 133.416835 -246.186202) (xy 133.446859 -246.142165) (xy 133.483111 -246.103094)
			(xy 133.524782 -246.069863) (xy 133.57094 -246.043214) (xy 133.620554 -246.023742) (xy 133.672516 -246.011882)
			(xy 133.725666 -246.007899) (xy 133.778816 -246.011882) (xy 133.830778 -246.023742) (xy 133.880392 -246.043214)
			(xy 133.92655 -246.069863) (xy 133.968221 -246.103094) (xy 134.004473 -246.142165) (xy 134.034497 -246.186202)
			(xy 134.057623 -246.234223) (xy 134.073333 -246.285153) (xy 134.081276 -246.337857) (xy 134.081774 -246.364506)
			(xy 134.081276 -246.391155) (xy 134.309856 -246.391155) (xy 134.309856 -246.337857) (xy 134.317799 -246.285153)
			(xy 134.333509 -246.234223) (xy 134.356635 -246.186202) (xy 134.386659 -246.142165) (xy 134.422911 -246.103094)
			(xy 134.464582 -246.069863) (xy 134.51074 -246.043214) (xy 134.560354 -246.023742) (xy 134.612316 -246.011882)
			(xy 134.665466 -246.007899) (xy 134.718616 -246.011882) (xy 134.770578 -246.023742) (xy 134.820192 -246.043214)
			(xy 134.86635 -246.069863) (xy 134.908021 -246.103094) (xy 134.944273 -246.142165) (xy 134.974297 -246.186202)
			(xy 134.997423 -246.234223) (xy 135.013133 -246.285153) (xy 135.021076 -246.337857) (xy 135.021574 -246.364506)
			(xy 135.021076 -246.391155) (xy 135.013133 -246.443859) (xy 134.997423 -246.494789) (xy 134.974297 -246.54281)
			(xy 134.944273 -246.586847) (xy 134.908021 -246.625918) (xy 134.86635 -246.659149) (xy 134.820192 -246.685798)
			(xy 134.770578 -246.70527) (xy 134.718616 -246.71713) (xy 134.665466 -246.721114) (xy 134.612316 -246.71713)
			(xy 134.560354 -246.70527) (xy 134.51074 -246.685798) (xy 134.464582 -246.659149) (xy 134.422911 -246.625918)
			(xy 134.386659 -246.586847) (xy 134.356635 -246.54281) (xy 134.333509 -246.494789) (xy 134.317799 -246.443859)
			(xy 134.309856 -246.391155) (xy 134.081276 -246.391155) (xy 134.073333 -246.443859) (xy 134.057623 -246.494789)
			(xy 134.034497 -246.54281) (xy 134.004473 -246.586847) (xy 133.968221 -246.625918) (xy 133.92655 -246.659149)
			(xy 133.880392 -246.685798) (xy 133.830778 -246.70527) (xy 133.778816 -246.71713) (xy 133.725666 -246.721114)
			(xy 133.672516 -246.71713) (xy 133.620554 -246.70527) (xy 133.57094 -246.685798) (xy 133.524782 -246.659149)
			(xy 133.483111 -246.625918) (xy 133.446859 -246.586847) (xy 133.416835 -246.54281) (xy 133.393709 -246.494789)
			(xy 133.377999 -246.443859) (xy 133.370056 -246.391155) (xy 133.141222 -246.391155) (xy 133.133279 -246.443859)
			(xy 133.117569 -246.494789) (xy 133.094443 -246.54281) (xy 133.064419 -246.586847) (xy 133.028167 -246.625918)
			(xy 132.986496 -246.659149) (xy 132.940338 -246.685798) (xy 132.890724 -246.70527) (xy 132.838762 -246.71713)
			(xy 132.785612 -246.721114) (xy 132.732462 -246.71713) (xy 132.6805 -246.70527) (xy 132.630886 -246.685798)
			(xy 132.584728 -246.659149) (xy 132.543057 -246.625918) (xy 132.506805 -246.586847) (xy 132.476781 -246.54281)
			(xy 132.453655 -246.494789) (xy 132.437945 -246.443859) (xy 132.430002 -246.391155) (xy 132.201422 -246.391155)
			(xy 132.193479 -246.443859) (xy 132.177769 -246.494789) (xy 132.154643 -246.54281) (xy 132.124619 -246.586847)
			(xy 132.088367 -246.625918) (xy 132.046696 -246.659149) (xy 132.000538 -246.685798) (xy 131.950924 -246.70527)
			(xy 131.898962 -246.71713) (xy 131.845812 -246.721114) (xy 131.792662 -246.71713) (xy 131.7407 -246.70527)
			(xy 131.691086 -246.685798) (xy 131.644928 -246.659149) (xy 131.603257 -246.625918) (xy 131.567005 -246.586847)
			(xy 131.536981 -246.54281) (xy 131.513855 -246.494789) (xy 131.498145 -246.443859) (xy 131.490202 -246.391155)
			(xy 131.261622 -246.391155) (xy 131.253679 -246.443859) (xy 131.237969 -246.494789) (xy 131.214843 -246.54281)
			(xy 131.184819 -246.586847) (xy 131.148567 -246.625918) (xy 131.106896 -246.659149) (xy 131.060738 -246.685798)
			(xy 131.011124 -246.70527) (xy 130.959162 -246.71713) (xy 130.906012 -246.721114) (xy 130.852862 -246.71713)
			(xy 130.8009 -246.70527) (xy 130.751286 -246.685798) (xy 130.705128 -246.659149) (xy 130.663457 -246.625918)
			(xy 130.627205 -246.586847) (xy 130.597181 -246.54281) (xy 130.574055 -246.494789) (xy 130.558345 -246.443859)
			(xy 130.550402 -246.391155) (xy 130.321822 -246.391155) (xy 130.313879 -246.443859) (xy 130.298169 -246.494789)
			(xy 130.275043 -246.54281) (xy 130.245019 -246.586847) (xy 130.208767 -246.625918) (xy 130.167096 -246.659149)
			(xy 130.120938 -246.685798) (xy 130.071324 -246.70527) (xy 130.019362 -246.71713) (xy 129.966212 -246.721114)
			(xy 129.913062 -246.71713) (xy 129.8611 -246.70527) (xy 129.811486 -246.685798) (xy 129.765328 -246.659149)
			(xy 129.723657 -246.625918) (xy 129.687405 -246.586847) (xy 129.657381 -246.54281) (xy 129.634255 -246.494789)
			(xy 129.618545 -246.443859) (xy 129.610602 -246.391155) (xy 129.382276 -246.391155) (xy 129.374333 -246.443859)
			(xy 129.358623 -246.494789) (xy 129.335497 -246.54281) (xy 129.305473 -246.586847) (xy 129.269221 -246.625918)
			(xy 129.22755 -246.659149) (xy 129.181392 -246.685798) (xy 129.131778 -246.70527) (xy 129.079816 -246.71713)
			(xy 129.026666 -246.721114) (xy 128.973516 -246.71713) (xy 128.921554 -246.70527) (xy 128.87194 -246.685798)
			(xy 128.825782 -246.659149) (xy 128.784111 -246.625918) (xy 128.747859 -246.586847) (xy 128.717835 -246.54281)
			(xy 128.694709 -246.494789) (xy 128.678999 -246.443859) (xy 128.671056 -246.391155) (xy 128.442222 -246.391155)
			(xy 128.434279 -246.443859) (xy 128.418569 -246.494789) (xy 128.395443 -246.54281) (xy 128.365419 -246.586847)
			(xy 128.329167 -246.625918) (xy 128.287496 -246.659149) (xy 128.241338 -246.685798) (xy 128.191724 -246.70527)
			(xy 128.139762 -246.71713) (xy 128.086612 -246.721114) (xy 128.033462 -246.71713) (xy 127.9815 -246.70527)
			(xy 127.931886 -246.685798) (xy 127.885728 -246.659149) (xy 127.844057 -246.625918) (xy 127.807805 -246.586847)
			(xy 127.777781 -246.54281) (xy 127.754655 -246.494789) (xy 127.738945 -246.443859) (xy 127.731002 -246.391155)
			(xy 127.502422 -246.391155) (xy 127.494479 -246.443859) (xy 127.478769 -246.494789) (xy 127.455643 -246.54281)
			(xy 127.425619 -246.586847) (xy 127.389367 -246.625918) (xy 127.347696 -246.659149) (xy 127.301538 -246.685798)
			(xy 127.251924 -246.70527) (xy 127.199962 -246.71713) (xy 127.146812 -246.721114) (xy 127.093662 -246.71713)
			(xy 127.0417 -246.70527) (xy 126.992086 -246.685798) (xy 126.945928 -246.659149) (xy 126.904257 -246.625918)
			(xy 126.868005 -246.586847) (xy 126.837981 -246.54281) (xy 126.814855 -246.494789) (xy 126.799145 -246.443859)
			(xy 126.791202 -246.391155) (xy 126.562622 -246.391155) (xy 126.554679 -246.443859) (xy 126.538969 -246.494789)
			(xy 126.515843 -246.54281) (xy 126.485819 -246.586847) (xy 126.449567 -246.625918) (xy 126.407896 -246.659149)
			(xy 126.361738 -246.685798) (xy 126.312124 -246.70527) (xy 126.260162 -246.71713) (xy 126.207012 -246.721114)
			(xy 126.153862 -246.71713) (xy 126.1019 -246.70527) (xy 126.052286 -246.685798) (xy 126.006128 -246.659149)
			(xy 125.964457 -246.625918) (xy 125.928205 -246.586847) (xy 125.898181 -246.54281) (xy 125.875055 -246.494789)
			(xy 125.859345 -246.443859) (xy 125.851402 -246.391155) (xy 125.622822 -246.391155) (xy 125.614879 -246.443859)
			(xy 125.599169 -246.494789) (xy 125.576043 -246.54281) (xy 125.546019 -246.586847) (xy 125.509767 -246.625918)
			(xy 125.468096 -246.659149) (xy 125.421938 -246.685798) (xy 125.372324 -246.70527) (xy 125.320362 -246.71713)
			(xy 125.267212 -246.721114) (xy 125.214062 -246.71713) (xy 125.1621 -246.70527) (xy 125.112486 -246.685798)
			(xy 125.066328 -246.659149) (xy 125.024657 -246.625918) (xy 124.988405 -246.586847) (xy 124.958381 -246.54281)
			(xy 124.935255 -246.494789) (xy 124.919545 -246.443859) (xy 124.911602 -246.391155) (xy 124.683022 -246.391155)
			(xy 124.675079 -246.443859) (xy 124.659369 -246.494789) (xy 124.636243 -246.54281) (xy 124.606219 -246.586847)
			(xy 124.569967 -246.625918) (xy 124.528296 -246.659149) (xy 124.482138 -246.685798) (xy 124.432524 -246.70527)
			(xy 124.380562 -246.71713) (xy 124.327412 -246.721114) (xy 124.274262 -246.71713) (xy 124.2223 -246.70527)
			(xy 124.172686 -246.685798) (xy 124.126528 -246.659149) (xy 124.084857 -246.625918) (xy 124.048605 -246.586847)
			(xy 124.018581 -246.54281) (xy 123.995455 -246.494789) (xy 123.979745 -246.443859) (xy 123.971802 -246.391155)
			(xy 123.743222 -246.391155) (xy 123.735279 -246.443859) (xy 123.719569 -246.494789) (xy 123.696443 -246.54281)
			(xy 123.666419 -246.586847) (xy 123.630167 -246.625918) (xy 123.588496 -246.659149) (xy 123.542338 -246.685798)
			(xy 123.492724 -246.70527) (xy 123.440762 -246.71713) (xy 123.387612 -246.721114) (xy 123.334462 -246.71713)
			(xy 123.2825 -246.70527) (xy 123.232886 -246.685798) (xy 123.186728 -246.659149) (xy 123.145057 -246.625918)
			(xy 123.108805 -246.586847) (xy 123.078781 -246.54281) (xy 123.055655 -246.494789) (xy 123.039945 -246.443859)
			(xy 123.032002 -246.391155) (xy 122.803676 -246.391155) (xy 122.795733 -246.443859) (xy 122.780023 -246.494789)
			(xy 122.756897 -246.54281) (xy 122.726873 -246.586847) (xy 122.690621 -246.625918) (xy 122.64895 -246.659149)
			(xy 122.602792 -246.685798) (xy 122.553178 -246.70527) (xy 122.501216 -246.71713) (xy 122.448066 -246.721114)
			(xy 122.394916 -246.71713) (xy 122.342954 -246.70527) (xy 122.29334 -246.685798) (xy 122.247182 -246.659149)
			(xy 122.205511 -246.625918) (xy 122.169259 -246.586847) (xy 122.139235 -246.54281) (xy 122.116109 -246.494789)
			(xy 122.100399 -246.443859) (xy 122.092456 -246.391155) (xy 121.863876 -246.391155) (xy 121.855933 -246.443859)
			(xy 121.840223 -246.494789) (xy 121.817097 -246.54281) (xy 121.787073 -246.586847) (xy 121.750821 -246.625918)
			(xy 121.70915 -246.659149) (xy 121.662992 -246.685798) (xy 121.613378 -246.70527) (xy 121.561416 -246.71713)
			(xy 121.508266 -246.721114) (xy 121.455116 -246.71713) (xy 121.403154 -246.70527) (xy 121.35354 -246.685798)
			(xy 121.307382 -246.659149) (xy 121.265711 -246.625918) (xy 121.229459 -246.586847) (xy 121.199435 -246.54281)
			(xy 121.176309 -246.494789) (xy 121.160599 -246.443859) (xy 121.152656 -246.391155) (xy 118.87708 -246.391155)
			(xy 118.87708 -247.204971) (xy 121.622556 -247.204971) (xy 121.622556 -247.151673) (xy 121.630499 -247.098969)
			(xy 121.646209 -247.048039) (xy 121.669335 -247.000018) (xy 121.699359 -246.955981) (xy 121.735611 -246.91691)
			(xy 121.777282 -246.883679) (xy 121.82344 -246.85703) (xy 121.873054 -246.837558) (xy 121.925016 -246.825698)
			(xy 121.978166 -246.821715) (xy 122.031316 -246.825698) (xy 122.083278 -246.837558) (xy 122.132892 -246.85703)
			(xy 122.17905 -246.883679) (xy 122.220721 -246.91691) (xy 122.256973 -246.955981) (xy 122.286997 -247.000018)
			(xy 122.310123 -247.048039) (xy 122.325833 -247.098969) (xy 122.333776 -247.151673) (xy 122.334274 -247.178322)
			(xy 122.333776 -247.204971) (xy 122.562356 -247.204971) (xy 122.562356 -247.151673) (xy 122.570299 -247.098969)
			(xy 122.586009 -247.048039) (xy 122.609135 -247.000018) (xy 122.639159 -246.955981) (xy 122.675411 -246.91691)
			(xy 122.717082 -246.883679) (xy 122.76324 -246.85703) (xy 122.812854 -246.837558) (xy 122.864816 -246.825698)
			(xy 122.917966 -246.821715) (xy 122.971116 -246.825698) (xy 123.023078 -246.837558) (xy 123.072692 -246.85703)
			(xy 123.11885 -246.883679) (xy 123.160521 -246.91691) (xy 123.196773 -246.955981) (xy 123.226797 -247.000018)
			(xy 123.249923 -247.048039) (xy 123.265633 -247.098969) (xy 123.273576 -247.151673) (xy 123.274074 -247.178322)
			(xy 123.273576 -247.204971) (xy 123.502156 -247.204971) (xy 123.502156 -247.151673) (xy 123.510099 -247.098969)
			(xy 123.525809 -247.048039) (xy 123.548935 -247.000018) (xy 123.578959 -246.955981) (xy 123.615211 -246.91691)
			(xy 123.656882 -246.883679) (xy 123.70304 -246.85703) (xy 123.752654 -246.837558) (xy 123.804616 -246.825698)
			(xy 123.857766 -246.821715) (xy 123.910916 -246.825698) (xy 123.962878 -246.837558) (xy 124.012492 -246.85703)
			(xy 124.05865 -246.883679) (xy 124.100321 -246.91691) (xy 124.136573 -246.955981) (xy 124.166597 -247.000018)
			(xy 124.189723 -247.048039) (xy 124.205433 -247.098969) (xy 124.213376 -247.151673) (xy 124.213874 -247.178322)
			(xy 124.213376 -247.204971) (xy 124.441956 -247.204971) (xy 124.441956 -247.151673) (xy 124.449899 -247.098969)
			(xy 124.465609 -247.048039) (xy 124.488735 -247.000018) (xy 124.518759 -246.955981) (xy 124.555011 -246.91691)
			(xy 124.596682 -246.883679) (xy 124.64284 -246.85703) (xy 124.692454 -246.837558) (xy 124.744416 -246.825698)
			(xy 124.797566 -246.821715) (xy 124.850716 -246.825698) (xy 124.902678 -246.837558) (xy 124.952292 -246.85703)
			(xy 124.99845 -246.883679) (xy 125.040121 -246.91691) (xy 125.076373 -246.955981) (xy 125.106397 -247.000018)
			(xy 125.129523 -247.048039) (xy 125.145233 -247.098969) (xy 125.153176 -247.151673) (xy 125.153674 -247.178322)
			(xy 125.153176 -247.204971) (xy 125.381756 -247.204971) (xy 125.381756 -247.151673) (xy 125.389699 -247.098969)
			(xy 125.405409 -247.048039) (xy 125.428535 -247.000018) (xy 125.458559 -246.955981) (xy 125.494811 -246.91691)
			(xy 125.536482 -246.883679) (xy 125.58264 -246.85703) (xy 125.632254 -246.837558) (xy 125.684216 -246.825698)
			(xy 125.737366 -246.821715) (xy 125.790516 -246.825698) (xy 125.842478 -246.837558) (xy 125.892092 -246.85703)
			(xy 125.93825 -246.883679) (xy 125.979921 -246.91691) (xy 126.016173 -246.955981) (xy 126.046197 -247.000018)
			(xy 126.069323 -247.048039) (xy 126.085033 -247.098969) (xy 126.092976 -247.151673) (xy 126.093474 -247.178322)
			(xy 126.092976 -247.204971) (xy 126.321302 -247.204971) (xy 126.321302 -247.151673) (xy 126.329245 -247.098969)
			(xy 126.344955 -247.048039) (xy 126.368081 -247.000018) (xy 126.398105 -246.955981) (xy 126.434357 -246.91691)
			(xy 126.476028 -246.883679) (xy 126.522186 -246.85703) (xy 126.5718 -246.837558) (xy 126.623762 -246.825698)
			(xy 126.676912 -246.821715) (xy 126.730062 -246.825698) (xy 126.782024 -246.837558) (xy 126.831638 -246.85703)
			(xy 126.877796 -246.883679) (xy 126.919467 -246.91691) (xy 126.955719 -246.955981) (xy 126.985743 -247.000018)
			(xy 127.008869 -247.048039) (xy 127.024579 -247.098969) (xy 127.032522 -247.151673) (xy 127.03302 -247.178322)
			(xy 127.032522 -247.204971) (xy 127.261356 -247.204971) (xy 127.261356 -247.151673) (xy 127.269299 -247.098969)
			(xy 127.285009 -247.048039) (xy 127.308135 -247.000018) (xy 127.338159 -246.955981) (xy 127.374411 -246.91691)
			(xy 127.416082 -246.883679) (xy 127.46224 -246.85703) (xy 127.511854 -246.837558) (xy 127.563816 -246.825698)
			(xy 127.616966 -246.821715) (xy 127.670116 -246.825698) (xy 127.722078 -246.837558) (xy 127.771692 -246.85703)
			(xy 127.81785 -246.883679) (xy 127.859521 -246.91691) (xy 127.895773 -246.955981) (xy 127.925797 -247.000018)
			(xy 127.948923 -247.048039) (xy 127.964633 -247.098969) (xy 127.972576 -247.151673) (xy 127.973074 -247.178322)
			(xy 127.972576 -247.204971) (xy 128.201156 -247.204971) (xy 128.201156 -247.151673) (xy 128.209099 -247.098969)
			(xy 128.224809 -247.048039) (xy 128.247935 -247.000018) (xy 128.277959 -246.955981) (xy 128.314211 -246.91691)
			(xy 128.355882 -246.883679) (xy 128.40204 -246.85703) (xy 128.451654 -246.837558) (xy 128.503616 -246.825698)
			(xy 128.556766 -246.821715) (xy 128.609916 -246.825698) (xy 128.661878 -246.837558) (xy 128.711492 -246.85703)
			(xy 128.75765 -246.883679) (xy 128.799321 -246.91691) (xy 128.835573 -246.955981) (xy 128.865597 -247.000018)
			(xy 128.888723 -247.048039) (xy 128.904433 -247.098969) (xy 128.912376 -247.151673) (xy 128.912874 -247.178322)
			(xy 128.912376 -247.204971) (xy 129.140956 -247.204971) (xy 129.140956 -247.151673) (xy 129.148899 -247.098969)
			(xy 129.164609 -247.048039) (xy 129.187735 -247.000018) (xy 129.217759 -246.955981) (xy 129.254011 -246.91691)
			(xy 129.295682 -246.883679) (xy 129.34184 -246.85703) (xy 129.391454 -246.837558) (xy 129.443416 -246.825698)
			(xy 129.496566 -246.821715) (xy 129.549716 -246.825698) (xy 129.601678 -246.837558) (xy 129.651292 -246.85703)
			(xy 129.69745 -246.883679) (xy 129.739121 -246.91691) (xy 129.775373 -246.955981) (xy 129.805397 -247.000018)
			(xy 129.828523 -247.048039) (xy 129.844233 -247.098969) (xy 129.852176 -247.151673) (xy 129.852674 -247.178322)
			(xy 129.852176 -247.204971) (xy 130.080756 -247.204971) (xy 130.080756 -247.151673) (xy 130.088699 -247.098969)
			(xy 130.104409 -247.048039) (xy 130.127535 -247.000018) (xy 130.157559 -246.955981) (xy 130.193811 -246.91691)
			(xy 130.235482 -246.883679) (xy 130.28164 -246.85703) (xy 130.331254 -246.837558) (xy 130.383216 -246.825698)
			(xy 130.436366 -246.821715) (xy 130.489516 -246.825698) (xy 130.541478 -246.837558) (xy 130.591092 -246.85703)
			(xy 130.63725 -246.883679) (xy 130.678921 -246.91691) (xy 130.715173 -246.955981) (xy 130.745197 -247.000018)
			(xy 130.768323 -247.048039) (xy 130.784033 -247.098969) (xy 130.791976 -247.151673) (xy 130.792474 -247.178322)
			(xy 130.791976 -247.204971) (xy 131.020302 -247.204971) (xy 131.020302 -247.151673) (xy 131.028245 -247.098969)
			(xy 131.043955 -247.048039) (xy 131.067081 -247.000018) (xy 131.097105 -246.955981) (xy 131.133357 -246.91691)
			(xy 131.175028 -246.883679) (xy 131.221186 -246.85703) (xy 131.2708 -246.837558) (xy 131.322762 -246.825698)
			(xy 131.375912 -246.821715) (xy 131.429062 -246.825698) (xy 131.481024 -246.837558) (xy 131.530638 -246.85703)
			(xy 131.576796 -246.883679) (xy 131.618467 -246.91691) (xy 131.654719 -246.955981) (xy 131.684743 -247.000018)
			(xy 131.707869 -247.048039) (xy 131.723579 -247.098969) (xy 131.731522 -247.151673) (xy 131.73202 -247.178322)
			(xy 131.731522 -247.204971) (xy 131.960356 -247.204971) (xy 131.960356 -247.151673) (xy 131.968299 -247.098969)
			(xy 131.984009 -247.048039) (xy 132.007135 -247.000018) (xy 132.037159 -246.955981) (xy 132.073411 -246.91691)
			(xy 132.115082 -246.883679) (xy 132.16124 -246.85703) (xy 132.210854 -246.837558) (xy 132.262816 -246.825698)
			(xy 132.315966 -246.821715) (xy 132.369116 -246.825698) (xy 132.421078 -246.837558) (xy 132.470692 -246.85703)
			(xy 132.51685 -246.883679) (xy 132.558521 -246.91691) (xy 132.594773 -246.955981) (xy 132.624797 -247.000018)
			(xy 132.647923 -247.048039) (xy 132.663633 -247.098969) (xy 132.671576 -247.151673) (xy 132.672074 -247.178322)
			(xy 132.671576 -247.204971) (xy 132.899902 -247.204971) (xy 132.899902 -247.151673) (xy 132.907845 -247.098969)
			(xy 132.923555 -247.048039) (xy 132.946681 -247.000018) (xy 132.976705 -246.955981) (xy 133.012957 -246.91691)
			(xy 133.054628 -246.883679) (xy 133.100786 -246.85703) (xy 133.1504 -246.837558) (xy 133.202362 -246.825698)
			(xy 133.255512 -246.821715) (xy 133.308662 -246.825698) (xy 133.360624 -246.837558) (xy 133.410238 -246.85703)
			(xy 133.456396 -246.883679) (xy 133.498067 -246.91691) (xy 133.534319 -246.955981) (xy 133.564343 -247.000018)
			(xy 133.587469 -247.048039) (xy 133.603179 -247.098969) (xy 133.611122 -247.151673) (xy 133.61162 -247.178322)
			(xy 133.611122 -247.204971) (xy 133.839956 -247.204971) (xy 133.839956 -247.151673) (xy 133.847899 -247.098969)
			(xy 133.863609 -247.048039) (xy 133.886735 -247.000018) (xy 133.916759 -246.955981) (xy 133.953011 -246.91691)
			(xy 133.994682 -246.883679) (xy 134.04084 -246.85703) (xy 134.090454 -246.837558) (xy 134.142416 -246.825698)
			(xy 134.195566 -246.821715) (xy 134.248716 -246.825698) (xy 134.300678 -246.837558) (xy 134.350292 -246.85703)
			(xy 134.39645 -246.883679) (xy 134.438121 -246.91691) (xy 134.474373 -246.955981) (xy 134.504397 -247.000018)
			(xy 134.527523 -247.048039) (xy 134.543233 -247.098969) (xy 134.551176 -247.151673) (xy 134.551674 -247.178322)
			(xy 134.551176 -247.204971) (xy 134.543233 -247.257675) (xy 134.527523 -247.308605) (xy 134.504397 -247.356626)
			(xy 134.474373 -247.400663) (xy 134.438121 -247.439734) (xy 134.39645 -247.472965) (xy 134.350292 -247.499614)
			(xy 134.300678 -247.519086) (xy 134.248716 -247.530946) (xy 134.195566 -247.53493) (xy 134.142416 -247.530946)
			(xy 134.090454 -247.519086) (xy 134.04084 -247.499614) (xy 133.994682 -247.472965) (xy 133.953011 -247.439734)
			(xy 133.916759 -247.400663) (xy 133.886735 -247.356626) (xy 133.863609 -247.308605) (xy 133.847899 -247.257675)
			(xy 133.839956 -247.204971) (xy 133.611122 -247.204971) (xy 133.603179 -247.257675) (xy 133.587469 -247.308605)
			(xy 133.564343 -247.356626) (xy 133.534319 -247.400663) (xy 133.498067 -247.439734) (xy 133.456396 -247.472965)
			(xy 133.410238 -247.499614) (xy 133.360624 -247.519086) (xy 133.308662 -247.530946) (xy 133.255512 -247.53493)
			(xy 133.202362 -247.530946) (xy 133.1504 -247.519086) (xy 133.100786 -247.499614) (xy 133.054628 -247.472965)
			(xy 133.012957 -247.439734) (xy 132.976705 -247.400663) (xy 132.946681 -247.356626) (xy 132.923555 -247.308605)
			(xy 132.907845 -247.257675) (xy 132.899902 -247.204971) (xy 132.671576 -247.204971) (xy 132.663633 -247.257675)
			(xy 132.647923 -247.308605) (xy 132.624797 -247.356626) (xy 132.594773 -247.400663) (xy 132.558521 -247.439734)
			(xy 132.51685 -247.472965) (xy 132.470692 -247.499614) (xy 132.421078 -247.519086) (xy 132.369116 -247.530946)
			(xy 132.315966 -247.53493) (xy 132.262816 -247.530946) (xy 132.210854 -247.519086) (xy 132.16124 -247.499614)
			(xy 132.115082 -247.472965) (xy 132.073411 -247.439734) (xy 132.037159 -247.400663) (xy 132.007135 -247.356626)
			(xy 131.984009 -247.308605) (xy 131.968299 -247.257675) (xy 131.960356 -247.204971) (xy 131.731522 -247.204971)
			(xy 131.723579 -247.257675) (xy 131.707869 -247.308605) (xy 131.684743 -247.356626) (xy 131.654719 -247.400663)
			(xy 131.618467 -247.439734) (xy 131.576796 -247.472965) (xy 131.530638 -247.499614) (xy 131.481024 -247.519086)
			(xy 131.429062 -247.530946) (xy 131.375912 -247.53493) (xy 131.322762 -247.530946) (xy 131.2708 -247.519086)
			(xy 131.221186 -247.499614) (xy 131.175028 -247.472965) (xy 131.133357 -247.439734) (xy 131.097105 -247.400663)
			(xy 131.067081 -247.356626) (xy 131.043955 -247.308605) (xy 131.028245 -247.257675) (xy 131.020302 -247.204971)
			(xy 130.791976 -247.204971) (xy 130.784033 -247.257675) (xy 130.768323 -247.308605) (xy 130.745197 -247.356626)
			(xy 130.715173 -247.400663) (xy 130.678921 -247.439734) (xy 130.63725 -247.472965) (xy 130.591092 -247.499614)
			(xy 130.541478 -247.519086) (xy 130.489516 -247.530946) (xy 130.436366 -247.53493) (xy 130.383216 -247.530946)
			(xy 130.331254 -247.519086) (xy 130.28164 -247.499614) (xy 130.235482 -247.472965) (xy 130.193811 -247.439734)
			(xy 130.157559 -247.400663) (xy 130.127535 -247.356626) (xy 130.104409 -247.308605) (xy 130.088699 -247.257675)
			(xy 130.080756 -247.204971) (xy 129.852176 -247.204971) (xy 129.844233 -247.257675) (xy 129.828523 -247.308605)
			(xy 129.805397 -247.356626) (xy 129.775373 -247.400663) (xy 129.739121 -247.439734) (xy 129.69745 -247.472965)
			(xy 129.651292 -247.499614) (xy 129.601678 -247.519086) (xy 129.549716 -247.530946) (xy 129.496566 -247.53493)
			(xy 129.443416 -247.530946) (xy 129.391454 -247.519086) (xy 129.34184 -247.499614) (xy 129.295682 -247.472965)
			(xy 129.254011 -247.439734) (xy 129.217759 -247.400663) (xy 129.187735 -247.356626) (xy 129.164609 -247.308605)
			(xy 129.148899 -247.257675) (xy 129.140956 -247.204971) (xy 128.912376 -247.204971) (xy 128.904433 -247.257675)
			(xy 128.888723 -247.308605) (xy 128.865597 -247.356626) (xy 128.835573 -247.400663) (xy 128.799321 -247.439734)
			(xy 128.75765 -247.472965) (xy 128.711492 -247.499614) (xy 128.661878 -247.519086) (xy 128.609916 -247.530946)
			(xy 128.556766 -247.53493) (xy 128.503616 -247.530946) (xy 128.451654 -247.519086) (xy 128.40204 -247.499614)
			(xy 128.355882 -247.472965) (xy 128.314211 -247.439734) (xy 128.277959 -247.400663) (xy 128.247935 -247.356626)
			(xy 128.224809 -247.308605) (xy 128.209099 -247.257675) (xy 128.201156 -247.204971) (xy 127.972576 -247.204971)
			(xy 127.964633 -247.257675) (xy 127.948923 -247.308605) (xy 127.925797 -247.356626) (xy 127.895773 -247.400663)
			(xy 127.859521 -247.439734) (xy 127.81785 -247.472965) (xy 127.771692 -247.499614) (xy 127.722078 -247.519086)
			(xy 127.670116 -247.530946) (xy 127.616966 -247.53493) (xy 127.563816 -247.530946) (xy 127.511854 -247.519086)
			(xy 127.46224 -247.499614) (xy 127.416082 -247.472965) (xy 127.374411 -247.439734) (xy 127.338159 -247.400663)
			(xy 127.308135 -247.356626) (xy 127.285009 -247.308605) (xy 127.269299 -247.257675) (xy 127.261356 -247.204971)
			(xy 127.032522 -247.204971) (xy 127.024579 -247.257675) (xy 127.008869 -247.308605) (xy 126.985743 -247.356626)
			(xy 126.955719 -247.400663) (xy 126.919467 -247.439734) (xy 126.877796 -247.472965) (xy 126.831638 -247.499614)
			(xy 126.782024 -247.519086) (xy 126.730062 -247.530946) (xy 126.676912 -247.53493) (xy 126.623762 -247.530946)
			(xy 126.5718 -247.519086) (xy 126.522186 -247.499614) (xy 126.476028 -247.472965) (xy 126.434357 -247.439734)
			(xy 126.398105 -247.400663) (xy 126.368081 -247.356626) (xy 126.344955 -247.308605) (xy 126.329245 -247.257675)
			(xy 126.321302 -247.204971) (xy 126.092976 -247.204971) (xy 126.085033 -247.257675) (xy 126.069323 -247.308605)
			(xy 126.046197 -247.356626) (xy 126.016173 -247.400663) (xy 125.979921 -247.439734) (xy 125.93825 -247.472965)
			(xy 125.892092 -247.499614) (xy 125.842478 -247.519086) (xy 125.790516 -247.530946) (xy 125.737366 -247.53493)
			(xy 125.684216 -247.530946) (xy 125.632254 -247.519086) (xy 125.58264 -247.499614) (xy 125.536482 -247.472965)
			(xy 125.494811 -247.439734) (xy 125.458559 -247.400663) (xy 125.428535 -247.356626) (xy 125.405409 -247.308605)
			(xy 125.389699 -247.257675) (xy 125.381756 -247.204971) (xy 125.153176 -247.204971) (xy 125.145233 -247.257675)
			(xy 125.129523 -247.308605) (xy 125.106397 -247.356626) (xy 125.076373 -247.400663) (xy 125.040121 -247.439734)
			(xy 124.99845 -247.472965) (xy 124.952292 -247.499614) (xy 124.902678 -247.519086) (xy 124.850716 -247.530946)
			(xy 124.797566 -247.53493) (xy 124.744416 -247.530946) (xy 124.692454 -247.519086) (xy 124.64284 -247.499614)
			(xy 124.596682 -247.472965) (xy 124.555011 -247.439734) (xy 124.518759 -247.400663) (xy 124.488735 -247.356626)
			(xy 124.465609 -247.308605) (xy 124.449899 -247.257675) (xy 124.441956 -247.204971) (xy 124.213376 -247.204971)
			(xy 124.205433 -247.257675) (xy 124.189723 -247.308605) (xy 124.166597 -247.356626) (xy 124.136573 -247.400663)
			(xy 124.100321 -247.439734) (xy 124.05865 -247.472965) (xy 124.012492 -247.499614) (xy 123.962878 -247.519086)
			(xy 123.910916 -247.530946) (xy 123.857766 -247.53493) (xy 123.804616 -247.530946) (xy 123.752654 -247.519086)
			(xy 123.70304 -247.499614) (xy 123.656882 -247.472965) (xy 123.615211 -247.439734) (xy 123.578959 -247.400663)
			(xy 123.548935 -247.356626) (xy 123.525809 -247.308605) (xy 123.510099 -247.257675) (xy 123.502156 -247.204971)
			(xy 123.273576 -247.204971) (xy 123.265633 -247.257675) (xy 123.249923 -247.308605) (xy 123.226797 -247.356626)
			(xy 123.196773 -247.400663) (xy 123.160521 -247.439734) (xy 123.11885 -247.472965) (xy 123.072692 -247.499614)
			(xy 123.023078 -247.519086) (xy 122.971116 -247.530946) (xy 122.917966 -247.53493) (xy 122.864816 -247.530946)
			(xy 122.812854 -247.519086) (xy 122.76324 -247.499614) (xy 122.717082 -247.472965) (xy 122.675411 -247.439734)
			(xy 122.639159 -247.400663) (xy 122.609135 -247.356626) (xy 122.586009 -247.308605) (xy 122.570299 -247.257675)
			(xy 122.562356 -247.204971) (xy 122.333776 -247.204971) (xy 122.325833 -247.257675) (xy 122.310123 -247.308605)
			(xy 122.286997 -247.356626) (xy 122.256973 -247.400663) (xy 122.220721 -247.439734) (xy 122.17905 -247.472965)
			(xy 122.132892 -247.499614) (xy 122.083278 -247.519086) (xy 122.031316 -247.530946) (xy 121.978166 -247.53493)
			(xy 121.925016 -247.530946) (xy 121.873054 -247.519086) (xy 121.82344 -247.499614) (xy 121.777282 -247.472965)
			(xy 121.735611 -247.439734) (xy 121.699359 -247.400663) (xy 121.669335 -247.356626) (xy 121.646209 -247.308605)
			(xy 121.630499 -247.257675) (xy 121.622556 -247.204971) (xy 118.87708 -247.204971) (xy 118.87708 -248.32818)
			(xy 120.59666 -248.32818) (xy 120.597222 -248.300198) (xy 120.605979 -248.244923) (xy 120.623275 -248.191699)
			(xy 120.648683 -248.141834) (xy 120.681577 -248.096558) (xy 120.721149 -248.056985) (xy 120.766424 -248.024089)
			(xy 120.816287 -247.998679) (xy 120.869511 -247.981382) (xy 120.924786 -247.972623) (xy 120.952768 -247.972072)
			(xy 120.97445 -247.972355) (xy 121.017497 -247.977583) (xy 121.03862 -247.982486) (xy 121.051682 -247.985435)
			(xy 121.078451 -247.984994) (xy 121.104183 -247.977603) (xy 121.127106 -247.963772) (xy 121.145641 -247.944453)
			(xy 121.158511 -247.920977) (xy 121.162064 -247.908064) (xy 121.168725 -247.882542) (xy 121.188581 -247.833677)
			(xy 121.215433 -247.788279) (xy 121.248691 -247.74734) (xy 121.287627 -247.711759) (xy 121.331389 -247.682315)
			(xy 121.379018 -247.659653) (xy 121.429469 -247.644269) (xy 121.481639 -247.6365) (xy 121.508012 -247.63603)
			(xy 121.534664 -247.636453) (xy 121.587371 -247.644399) (xy 121.638306 -247.660111) (xy 121.68633 -247.68324)
			(xy 121.73037 -247.713268) (xy 121.769444 -247.749524) (xy 121.802677 -247.791198) (xy 121.829328 -247.83736)
			(xy 121.848801 -247.886979) (xy 121.860662 -247.938946) (xy 121.864646 -247.9921) (xy 121.862646 -248.018787)
			(xy 122.092202 -248.018787) (xy 122.092202 -247.965489) (xy 122.100145 -247.912785) (xy 122.115855 -247.861855)
			(xy 122.138981 -247.813834) (xy 122.169005 -247.769797) (xy 122.205257 -247.730726) (xy 122.246928 -247.697495)
			(xy 122.293086 -247.670846) (xy 122.3427 -247.651374) (xy 122.394662 -247.639514) (xy 122.447812 -247.635531)
			(xy 122.500962 -247.639514) (xy 122.552924 -247.651374) (xy 122.602538 -247.670846) (xy 122.648696 -247.697495)
			(xy 122.690367 -247.730726) (xy 122.726619 -247.769797) (xy 122.756643 -247.813834) (xy 122.779769 -247.861855)
			(xy 122.795479 -247.912785) (xy 122.803422 -247.965489) (xy 122.80392 -247.992138) (xy 122.803422 -248.018787)
			(xy 123.032002 -248.018787) (xy 123.032002 -247.965489) (xy 123.039945 -247.912785) (xy 123.055655 -247.861855)
			(xy 123.078781 -247.813834) (xy 123.108805 -247.769797) (xy 123.145057 -247.730726) (xy 123.186728 -247.697495)
			(xy 123.232886 -247.670846) (xy 123.2825 -247.651374) (xy 123.334462 -247.639514) (xy 123.387612 -247.635531)
			(xy 123.440762 -247.639514) (xy 123.492724 -247.651374) (xy 123.542338 -247.670846) (xy 123.588496 -247.697495)
			(xy 123.630167 -247.730726) (xy 123.666419 -247.769797) (xy 123.696443 -247.813834) (xy 123.719569 -247.861855)
			(xy 123.735279 -247.912785) (xy 123.743222 -247.965489) (xy 123.74372 -247.992138) (xy 123.743222 -248.018787)
			(xy 123.971802 -248.018787) (xy 123.971802 -247.965489) (xy 123.979745 -247.912785) (xy 123.995455 -247.861855)
			(xy 124.018581 -247.813834) (xy 124.048605 -247.769797) (xy 124.084857 -247.730726) (xy 124.126528 -247.697495)
			(xy 124.172686 -247.670846) (xy 124.2223 -247.651374) (xy 124.274262 -247.639514) (xy 124.327412 -247.635531)
			(xy 124.380562 -247.639514) (xy 124.432524 -247.651374) (xy 124.482138 -247.670846) (xy 124.528296 -247.697495)
			(xy 124.569967 -247.730726) (xy 124.606219 -247.769797) (xy 124.636243 -247.813834) (xy 124.659369 -247.861855)
			(xy 124.675079 -247.912785) (xy 124.683022 -247.965489) (xy 124.68352 -247.992138) (xy 124.683022 -248.018787)
			(xy 124.911602 -248.018787) (xy 124.911602 -247.965489) (xy 124.919545 -247.912785) (xy 124.935255 -247.861855)
			(xy 124.958381 -247.813834) (xy 124.988405 -247.769797) (xy 125.024657 -247.730726) (xy 125.066328 -247.697495)
			(xy 125.112486 -247.670846) (xy 125.1621 -247.651374) (xy 125.214062 -247.639514) (xy 125.267212 -247.635531)
			(xy 125.320362 -247.639514) (xy 125.372324 -247.651374) (xy 125.421938 -247.670846) (xy 125.468096 -247.697495)
			(xy 125.509767 -247.730726) (xy 125.546019 -247.769797) (xy 125.576043 -247.813834) (xy 125.599169 -247.861855)
			(xy 125.614879 -247.912785) (xy 125.622822 -247.965489) (xy 125.62332 -247.992138) (xy 125.622822 -248.018787)
			(xy 125.851656 -248.018787) (xy 125.851656 -247.965489) (xy 125.859599 -247.912785) (xy 125.875309 -247.861855)
			(xy 125.898435 -247.813834) (xy 125.928459 -247.769797) (xy 125.964711 -247.730726) (xy 126.006382 -247.697495)
			(xy 126.05254 -247.670846) (xy 126.102154 -247.651374) (xy 126.154116 -247.639514) (xy 126.207266 -247.635531)
			(xy 126.260416 -247.639514) (xy 126.312378 -247.651374) (xy 126.361992 -247.670846) (xy 126.40815 -247.697495)
			(xy 126.449821 -247.730726) (xy 126.486073 -247.769797) (xy 126.516097 -247.813834) (xy 126.539223 -247.861855)
			(xy 126.554933 -247.912785) (xy 126.562876 -247.965489) (xy 126.563374 -247.992138) (xy 126.562876 -248.018787)
			(xy 126.791202 -248.018787) (xy 126.791202 -247.965489) (xy 126.799145 -247.912785) (xy 126.814855 -247.861855)
			(xy 126.837981 -247.813834) (xy 126.868005 -247.769797) (xy 126.904257 -247.730726) (xy 126.945928 -247.697495)
			(xy 126.992086 -247.670846) (xy 127.0417 -247.651374) (xy 127.093662 -247.639514) (xy 127.146812 -247.635531)
			(xy 127.199962 -247.639514) (xy 127.251924 -247.651374) (xy 127.301538 -247.670846) (xy 127.347696 -247.697495)
			(xy 127.389367 -247.730726) (xy 127.425619 -247.769797) (xy 127.455643 -247.813834) (xy 127.478769 -247.861855)
			(xy 127.494479 -247.912785) (xy 127.502422 -247.965489) (xy 127.50292 -247.992138) (xy 127.502422 -248.018787)
			(xy 127.731002 -248.018787) (xy 127.731002 -247.965489) (xy 127.738945 -247.912785) (xy 127.754655 -247.861855)
			(xy 127.777781 -247.813834) (xy 127.807805 -247.769797) (xy 127.844057 -247.730726) (xy 127.885728 -247.697495)
			(xy 127.931886 -247.670846) (xy 127.9815 -247.651374) (xy 128.033462 -247.639514) (xy 128.086612 -247.635531)
			(xy 128.139762 -247.639514) (xy 128.191724 -247.651374) (xy 128.241338 -247.670846) (xy 128.287496 -247.697495)
			(xy 128.329167 -247.730726) (xy 128.365419 -247.769797) (xy 128.395443 -247.813834) (xy 128.418569 -247.861855)
			(xy 128.434279 -247.912785) (xy 128.442222 -247.965489) (xy 128.44272 -247.992138) (xy 128.442222 -248.018787)
			(xy 128.670802 -248.018787) (xy 128.670802 -247.965489) (xy 128.678745 -247.912785) (xy 128.694455 -247.861855)
			(xy 128.717581 -247.813834) (xy 128.747605 -247.769797) (xy 128.783857 -247.730726) (xy 128.825528 -247.697495)
			(xy 128.871686 -247.670846) (xy 128.9213 -247.651374) (xy 128.973262 -247.639514) (xy 129.026412 -247.635531)
			(xy 129.079562 -247.639514) (xy 129.131524 -247.651374) (xy 129.181138 -247.670846) (xy 129.227296 -247.697495)
			(xy 129.268967 -247.730726) (xy 129.305219 -247.769797) (xy 129.335243 -247.813834) (xy 129.358369 -247.861855)
			(xy 129.374079 -247.912785) (xy 129.382022 -247.965489) (xy 129.38252 -247.992138) (xy 129.382022 -248.018787)
			(xy 129.610602 -248.018787) (xy 129.610602 -247.965489) (xy 129.618545 -247.912785) (xy 129.634255 -247.861855)
			(xy 129.657381 -247.813834) (xy 129.687405 -247.769797) (xy 129.723657 -247.730726) (xy 129.765328 -247.697495)
			(xy 129.811486 -247.670846) (xy 129.8611 -247.651374) (xy 129.913062 -247.639514) (xy 129.966212 -247.635531)
			(xy 130.019362 -247.639514) (xy 130.071324 -247.651374) (xy 130.120938 -247.670846) (xy 130.167096 -247.697495)
			(xy 130.208767 -247.730726) (xy 130.245019 -247.769797) (xy 130.275043 -247.813834) (xy 130.298169 -247.861855)
			(xy 130.313879 -247.912785) (xy 130.321822 -247.965489) (xy 130.32232 -247.992138) (xy 130.321822 -248.018787)
			(xy 130.550656 -248.018787) (xy 130.550656 -247.965489) (xy 130.558599 -247.912785) (xy 130.574309 -247.861855)
			(xy 130.597435 -247.813834) (xy 130.627459 -247.769797) (xy 130.663711 -247.730726) (xy 130.705382 -247.697495)
			(xy 130.75154 -247.670846) (xy 130.801154 -247.651374) (xy 130.853116 -247.639514) (xy 130.906266 -247.635531)
			(xy 130.959416 -247.639514) (xy 131.011378 -247.651374) (xy 131.060992 -247.670846) (xy 131.10715 -247.697495)
			(xy 131.148821 -247.730726) (xy 131.185073 -247.769797) (xy 131.215097 -247.813834) (xy 131.238223 -247.861855)
			(xy 131.253933 -247.912785) (xy 131.261876 -247.965489) (xy 131.262374 -247.992138) (xy 131.261876 -248.018787)
			(xy 131.490202 -248.018787) (xy 131.490202 -247.965489) (xy 131.498145 -247.912785) (xy 131.513855 -247.861855)
			(xy 131.536981 -247.813834) (xy 131.567005 -247.769797) (xy 131.603257 -247.730726) (xy 131.644928 -247.697495)
			(xy 131.691086 -247.670846) (xy 131.7407 -247.651374) (xy 131.792662 -247.639514) (xy 131.845812 -247.635531)
			(xy 131.898962 -247.639514) (xy 131.950924 -247.651374) (xy 132.000538 -247.670846) (xy 132.046696 -247.697495)
			(xy 132.088367 -247.730726) (xy 132.124619 -247.769797) (xy 132.154643 -247.813834) (xy 132.177769 -247.861855)
			(xy 132.193479 -247.912785) (xy 132.201422 -247.965489) (xy 132.20192 -247.992138) (xy 132.201422 -248.018787)
			(xy 132.430256 -248.018787) (xy 132.430256 -247.965489) (xy 132.438199 -247.912785) (xy 132.453909 -247.861855)
			(xy 132.477035 -247.813834) (xy 132.507059 -247.769797) (xy 132.543311 -247.730726) (xy 132.584982 -247.697495)
			(xy 132.63114 -247.670846) (xy 132.680754 -247.651374) (xy 132.732716 -247.639514) (xy 132.785866 -247.635531)
			(xy 132.839016 -247.639514) (xy 132.890978 -247.651374) (xy 132.940592 -247.670846) (xy 132.98675 -247.697495)
			(xy 133.028421 -247.730726) (xy 133.064673 -247.769797) (xy 133.094697 -247.813834) (xy 133.117823 -247.861855)
			(xy 133.133533 -247.912785) (xy 133.141476 -247.965489) (xy 133.141974 -247.992138) (xy 133.141476 -248.018787)
			(xy 133.133533 -248.071491) (xy 133.117823 -248.122421) (xy 133.094697 -248.170442) (xy 133.064673 -248.214479)
			(xy 133.028421 -248.25355) (xy 132.98675 -248.286781) (xy 132.940592 -248.31343) (xy 132.890978 -248.332902)
			(xy 132.839016 -248.344762) (xy 132.785866 -248.348746) (xy 132.732716 -248.344762) (xy 132.680754 -248.332902)
			(xy 132.63114 -248.31343) (xy 132.584982 -248.286781) (xy 132.543311 -248.25355) (xy 132.507059 -248.214479)
			(xy 132.477035 -248.170442) (xy 132.453909 -248.122421) (xy 132.438199 -248.071491) (xy 132.430256 -248.018787)
			(xy 132.201422 -248.018787) (xy 132.193479 -248.071491) (xy 132.177769 -248.122421) (xy 132.154643 -248.170442)
			(xy 132.124619 -248.214479) (xy 132.088367 -248.25355) (xy 132.046696 -248.286781) (xy 132.000538 -248.31343)
			(xy 131.950924 -248.332902) (xy 131.898962 -248.344762) (xy 131.845812 -248.348746) (xy 131.792662 -248.344762)
			(xy 131.7407 -248.332902) (xy 131.691086 -248.31343) (xy 131.644928 -248.286781) (xy 131.603257 -248.25355)
			(xy 131.567005 -248.214479) (xy 131.536981 -248.170442) (xy 131.513855 -248.122421) (xy 131.498145 -248.071491)
			(xy 131.490202 -248.018787) (xy 131.261876 -248.018787) (xy 131.253933 -248.071491) (xy 131.238223 -248.122421)
			(xy 131.215097 -248.170442) (xy 131.185073 -248.214479) (xy 131.148821 -248.25355) (xy 131.10715 -248.286781)
			(xy 131.060992 -248.31343) (xy 131.011378 -248.332902) (xy 130.959416 -248.344762) (xy 130.906266 -248.348746)
			(xy 130.853116 -248.344762) (xy 130.801154 -248.332902) (xy 130.75154 -248.31343) (xy 130.705382 -248.286781)
			(xy 130.663711 -248.25355) (xy 130.627459 -248.214479) (xy 130.597435 -248.170442) (xy 130.574309 -248.122421)
			(xy 130.558599 -248.071491) (xy 130.550656 -248.018787) (xy 130.321822 -248.018787) (xy 130.313879 -248.071491)
			(xy 130.298169 -248.122421) (xy 130.275043 -248.170442) (xy 130.245019 -248.214479) (xy 130.208767 -248.25355)
			(xy 130.167096 -248.286781) (xy 130.120938 -248.31343) (xy 130.071324 -248.332902) (xy 130.019362 -248.344762)
			(xy 129.966212 -248.348746) (xy 129.913062 -248.344762) (xy 129.8611 -248.332902) (xy 129.811486 -248.31343)
			(xy 129.765328 -248.286781) (xy 129.723657 -248.25355) (xy 129.687405 -248.214479) (xy 129.657381 -248.170442)
			(xy 129.634255 -248.122421) (xy 129.618545 -248.071491) (xy 129.610602 -248.018787) (xy 129.382022 -248.018787)
			(xy 129.374079 -248.071491) (xy 129.358369 -248.122421) (xy 129.335243 -248.170442) (xy 129.305219 -248.214479)
			(xy 129.268967 -248.25355) (xy 129.227296 -248.286781) (xy 129.181138 -248.31343) (xy 129.131524 -248.332902)
			(xy 129.079562 -248.344762) (xy 129.026412 -248.348746) (xy 128.973262 -248.344762) (xy 128.9213 -248.332902)
			(xy 128.871686 -248.31343) (xy 128.825528 -248.286781) (xy 128.783857 -248.25355) (xy 128.747605 -248.214479)
			(xy 128.717581 -248.170442) (xy 128.694455 -248.122421) (xy 128.678745 -248.071491) (xy 128.670802 -248.018787)
			(xy 128.442222 -248.018787) (xy 128.434279 -248.071491) (xy 128.418569 -248.122421) (xy 128.395443 -248.170442)
			(xy 128.365419 -248.214479) (xy 128.329167 -248.25355) (xy 128.287496 -248.286781) (xy 128.241338 -248.31343)
			(xy 128.191724 -248.332902) (xy 128.139762 -248.344762) (xy 128.086612 -248.348746) (xy 128.033462 -248.344762)
			(xy 127.9815 -248.332902) (xy 127.931886 -248.31343) (xy 127.885728 -248.286781) (xy 127.844057 -248.25355)
			(xy 127.807805 -248.214479) (xy 127.777781 -248.170442) (xy 127.754655 -248.122421) (xy 127.738945 -248.071491)
			(xy 127.731002 -248.018787) (xy 127.502422 -248.018787) (xy 127.494479 -248.071491) (xy 127.478769 -248.122421)
			(xy 127.455643 -248.170442) (xy 127.425619 -248.214479) (xy 127.389367 -248.25355) (xy 127.347696 -248.286781)
			(xy 127.301538 -248.31343) (xy 127.251924 -248.332902) (xy 127.199962 -248.344762) (xy 127.146812 -248.348746)
			(xy 127.093662 -248.344762) (xy 127.0417 -248.332902) (xy 126.992086 -248.31343) (xy 126.945928 -248.286781)
			(xy 126.904257 -248.25355) (xy 126.868005 -248.214479) (xy 126.837981 -248.170442) (xy 126.814855 -248.122421)
			(xy 126.799145 -248.071491) (xy 126.791202 -248.018787) (xy 126.562876 -248.018787) (xy 126.554933 -248.071491)
			(xy 126.539223 -248.122421) (xy 126.516097 -248.170442) (xy 126.486073 -248.214479) (xy 126.449821 -248.25355)
			(xy 126.40815 -248.286781) (xy 126.361992 -248.31343) (xy 126.312378 -248.332902) (xy 126.260416 -248.344762)
			(xy 126.207266 -248.348746) (xy 126.154116 -248.344762) (xy 126.102154 -248.332902) (xy 126.05254 -248.31343)
			(xy 126.006382 -248.286781) (xy 125.964711 -248.25355) (xy 125.928459 -248.214479) (xy 125.898435 -248.170442)
			(xy 125.875309 -248.122421) (xy 125.859599 -248.071491) (xy 125.851656 -248.018787) (xy 125.622822 -248.018787)
			(xy 125.614879 -248.071491) (xy 125.599169 -248.122421) (xy 125.576043 -248.170442) (xy 125.546019 -248.214479)
			(xy 125.509767 -248.25355) (xy 125.468096 -248.286781) (xy 125.421938 -248.31343) (xy 125.372324 -248.332902)
			(xy 125.320362 -248.344762) (xy 125.267212 -248.348746) (xy 125.214062 -248.344762) (xy 125.1621 -248.332902)
			(xy 125.112486 -248.31343) (xy 125.066328 -248.286781) (xy 125.024657 -248.25355) (xy 124.988405 -248.214479)
			(xy 124.958381 -248.170442) (xy 124.935255 -248.122421) (xy 124.919545 -248.071491) (xy 124.911602 -248.018787)
			(xy 124.683022 -248.018787) (xy 124.675079 -248.071491) (xy 124.659369 -248.122421) (xy 124.636243 -248.170442)
			(xy 124.606219 -248.214479) (xy 124.569967 -248.25355) (xy 124.528296 -248.286781) (xy 124.482138 -248.31343)
			(xy 124.432524 -248.332902) (xy 124.380562 -248.344762) (xy 124.327412 -248.348746) (xy 124.274262 -248.344762)
			(xy 124.2223 -248.332902) (xy 124.172686 -248.31343) (xy 124.126528 -248.286781) (xy 124.084857 -248.25355)
			(xy 124.048605 -248.214479) (xy 124.018581 -248.170442) (xy 123.995455 -248.122421) (xy 123.979745 -248.071491)
			(xy 123.971802 -248.018787) (xy 123.743222 -248.018787) (xy 123.735279 -248.071491) (xy 123.719569 -248.122421)
			(xy 123.696443 -248.170442) (xy 123.666419 -248.214479) (xy 123.630167 -248.25355) (xy 123.588496 -248.286781)
			(xy 123.542338 -248.31343) (xy 123.492724 -248.332902) (xy 123.440762 -248.344762) (xy 123.387612 -248.348746)
			(xy 123.334462 -248.344762) (xy 123.2825 -248.332902) (xy 123.232886 -248.31343) (xy 123.186728 -248.286781)
			(xy 123.145057 -248.25355) (xy 123.108805 -248.214479) (xy 123.078781 -248.170442) (xy 123.055655 -248.122421)
			(xy 123.039945 -248.071491) (xy 123.032002 -248.018787) (xy 122.803422 -248.018787) (xy 122.795479 -248.071491)
			(xy 122.779769 -248.122421) (xy 122.756643 -248.170442) (xy 122.726619 -248.214479) (xy 122.690367 -248.25355)
			(xy 122.648696 -248.286781) (xy 122.602538 -248.31343) (xy 122.552924 -248.332902) (xy 122.500962 -248.344762)
			(xy 122.447812 -248.348746) (xy 122.394662 -248.344762) (xy 122.3427 -248.332902) (xy 122.293086 -248.31343)
			(xy 122.246928 -248.286781) (xy 122.205257 -248.25355) (xy 122.169005 -248.214479) (xy 122.138981 -248.170442)
			(xy 122.115855 -248.122421) (xy 122.100145 -248.071491) (xy 122.092202 -248.018787) (xy 121.862646 -248.018787)
			(xy 121.860662 -248.045254) (xy 121.848801 -248.097221) (xy 121.829328 -248.14684) (xy 121.802677 -248.193002)
			(xy 121.769444 -248.234676) (xy 121.73037 -248.270932) (xy 121.68633 -248.30096) (xy 121.638306 -248.324089)
			(xy 121.587371 -248.339801) (xy 121.534664 -248.347747) (xy 121.508012 -248.348246) (xy 121.48633 -248.347948)
			(xy 121.443283 -248.34273) (xy 121.42216 -248.337832) (xy 121.409084 -248.334956) (xy 121.382323 -248.335379)
			(xy 121.356595 -248.342753) (xy 121.333673 -248.356571) (xy 121.315138 -248.375879) (xy 121.302269 -248.399346)
			(xy 121.298716 -248.412254) (xy 121.292077 -248.437578) (xy 121.272449 -248.486108) (xy 121.245914 -248.531234)
			(xy 121.213044 -248.571977) (xy 121.174552 -248.607457) (xy 121.153174 -248.622566) (xy 121.141261 -248.631409)
			(xy 121.122594 -248.654444) (xy 121.111323 -248.681867) (xy 121.108397 -248.711372) (xy 121.114062 -248.740474)
			(xy 121.127841 -248.766727) (xy 121.148575 -248.787921) (xy 121.161302 -248.79554) (xy 121.184791 -248.809119)
			(xy 121.215575 -248.832857) (xy 121.622556 -248.832857) (xy 121.622556 -248.779559) (xy 121.630499 -248.726855)
			(xy 121.646209 -248.675925) (xy 121.669335 -248.627904) (xy 121.699359 -248.583867) (xy 121.735611 -248.544796)
			(xy 121.777282 -248.511565) (xy 121.82344 -248.484916) (xy 121.873054 -248.465444) (xy 121.925016 -248.453584)
			(xy 121.978166 -248.449601) (xy 122.031316 -248.453584) (xy 122.083278 -248.465444) (xy 122.132892 -248.484916)
			(xy 122.17905 -248.511565) (xy 122.220721 -248.544796) (xy 122.256973 -248.583867) (xy 122.286997 -248.627904)
			(xy 122.310123 -248.675925) (xy 122.325833 -248.726855) (xy 122.333776 -248.779559) (xy 122.334274 -248.806208)
			(xy 122.333776 -248.832857) (xy 122.562102 -248.832857) (xy 122.562102 -248.779559) (xy 122.570045 -248.726855)
			(xy 122.585755 -248.675925) (xy 122.608881 -248.627904) (xy 122.638905 -248.583867) (xy 122.675157 -248.544796)
			(xy 122.716828 -248.511565) (xy 122.762986 -248.484916) (xy 122.8126 -248.465444) (xy 122.864562 -248.453584)
			(xy 122.917712 -248.449601) (xy 122.970862 -248.453584) (xy 123.022824 -248.465444) (xy 123.072438 -248.484916)
			(xy 123.118596 -248.511565) (xy 123.160267 -248.544796) (xy 123.196519 -248.583867) (xy 123.226543 -248.627904)
			(xy 123.249669 -248.675925) (xy 123.265379 -248.726855) (xy 123.273322 -248.779559) (xy 123.27382 -248.806208)
			(xy 123.273322 -248.832857) (xy 123.502156 -248.832857) (xy 123.502156 -248.779559) (xy 123.510099 -248.726855)
			(xy 123.525809 -248.675925) (xy 123.548935 -248.627904) (xy 123.578959 -248.583867) (xy 123.615211 -248.544796)
			(xy 123.656882 -248.511565) (xy 123.70304 -248.484916) (xy 123.752654 -248.465444) (xy 123.804616 -248.453584)
			(xy 123.857766 -248.449601) (xy 123.910916 -248.453584) (xy 123.962878 -248.465444) (xy 124.012492 -248.484916)
			(xy 124.05865 -248.511565) (xy 124.100321 -248.544796) (xy 124.136573 -248.583867) (xy 124.166597 -248.627904)
			(xy 124.189723 -248.675925) (xy 124.205433 -248.726855) (xy 124.213376 -248.779559) (xy 124.213874 -248.806208)
			(xy 124.213376 -248.832857) (xy 124.441956 -248.832857) (xy 124.441956 -248.779559) (xy 124.449899 -248.726855)
			(xy 124.465609 -248.675925) (xy 124.488735 -248.627904) (xy 124.518759 -248.583867) (xy 124.555011 -248.544796)
			(xy 124.596682 -248.511565) (xy 124.64284 -248.484916) (xy 124.692454 -248.465444) (xy 124.744416 -248.453584)
			(xy 124.797566 -248.449601) (xy 124.850716 -248.453584) (xy 124.902678 -248.465444) (xy 124.952292 -248.484916)
			(xy 124.99845 -248.511565) (xy 125.040121 -248.544796) (xy 125.076373 -248.583867) (xy 125.106397 -248.627904)
			(xy 125.129523 -248.675925) (xy 125.145233 -248.726855) (xy 125.153176 -248.779559) (xy 125.153674 -248.806208)
			(xy 125.153176 -248.832857) (xy 125.381756 -248.832857) (xy 125.381756 -248.779559) (xy 125.389699 -248.726855)
			(xy 125.405409 -248.675925) (xy 125.428535 -248.627904) (xy 125.458559 -248.583867) (xy 125.494811 -248.544796)
			(xy 125.536482 -248.511565) (xy 125.58264 -248.484916) (xy 125.632254 -248.465444) (xy 125.684216 -248.453584)
			(xy 125.737366 -248.449601) (xy 125.790516 -248.453584) (xy 125.842478 -248.465444) (xy 125.892092 -248.484916)
			(xy 125.93825 -248.511565) (xy 125.979921 -248.544796) (xy 126.016173 -248.583867) (xy 126.046197 -248.627904)
			(xy 126.069323 -248.675925) (xy 126.085033 -248.726855) (xy 126.092976 -248.779559) (xy 126.093474 -248.806208)
			(xy 126.092976 -248.832857) (xy 126.321556 -248.832857) (xy 126.321556 -248.779559) (xy 126.329499 -248.726855)
			(xy 126.345209 -248.675925) (xy 126.368335 -248.627904) (xy 126.398359 -248.583867) (xy 126.434611 -248.544796)
			(xy 126.476282 -248.511565) (xy 126.52244 -248.484916) (xy 126.572054 -248.465444) (xy 126.624016 -248.453584)
			(xy 126.677166 -248.449601) (xy 126.730316 -248.453584) (xy 126.782278 -248.465444) (xy 126.831892 -248.484916)
			(xy 126.87805 -248.511565) (xy 126.919721 -248.544796) (xy 126.955973 -248.583867) (xy 126.985997 -248.627904)
			(xy 127.009123 -248.675925) (xy 127.024833 -248.726855) (xy 127.032776 -248.779559) (xy 127.033274 -248.806208)
			(xy 127.032776 -248.832857) (xy 127.261356 -248.832857) (xy 127.261356 -248.779559) (xy 127.269299 -248.726855)
			(xy 127.285009 -248.675925) (xy 127.308135 -248.627904) (xy 127.338159 -248.583867) (xy 127.374411 -248.544796)
			(xy 127.416082 -248.511565) (xy 127.46224 -248.484916) (xy 127.511854 -248.465444) (xy 127.563816 -248.453584)
			(xy 127.616966 -248.449601) (xy 127.670116 -248.453584) (xy 127.722078 -248.465444) (xy 127.771692 -248.484916)
			(xy 127.81785 -248.511565) (xy 127.859521 -248.544796) (xy 127.895773 -248.583867) (xy 127.925797 -248.627904)
			(xy 127.948923 -248.675925) (xy 127.964633 -248.726855) (xy 127.972576 -248.779559) (xy 127.973074 -248.806208)
			(xy 127.972576 -248.832857) (xy 128.201156 -248.832857) (xy 128.201156 -248.779559) (xy 128.209099 -248.726855)
			(xy 128.224809 -248.675925) (xy 128.247935 -248.627904) (xy 128.277959 -248.583867) (xy 128.314211 -248.544796)
			(xy 128.355882 -248.511565) (xy 128.40204 -248.484916) (xy 128.451654 -248.465444) (xy 128.503616 -248.453584)
			(xy 128.556766 -248.449601) (xy 128.609916 -248.453584) (xy 128.661878 -248.465444) (xy 128.711492 -248.484916)
			(xy 128.75765 -248.511565) (xy 128.799321 -248.544796) (xy 128.835573 -248.583867) (xy 128.865597 -248.627904)
			(xy 128.888723 -248.675925) (xy 128.904433 -248.726855) (xy 128.912376 -248.779559) (xy 128.912874 -248.806208)
			(xy 128.912376 -248.832857) (xy 129.140702 -248.832857) (xy 129.140702 -248.779559) (xy 129.148645 -248.726855)
			(xy 129.164355 -248.675925) (xy 129.187481 -248.627904) (xy 129.217505 -248.583867) (xy 129.253757 -248.544796)
			(xy 129.295428 -248.511565) (xy 129.341586 -248.484916) (xy 129.3912 -248.465444) (xy 129.443162 -248.453584)
			(xy 129.496312 -248.449601) (xy 129.549462 -248.453584) (xy 129.601424 -248.465444) (xy 129.651038 -248.484916)
			(xy 129.697196 -248.511565) (xy 129.738867 -248.544796) (xy 129.775119 -248.583867) (xy 129.805143 -248.627904)
			(xy 129.828269 -248.675925) (xy 129.843979 -248.726855) (xy 129.851922 -248.779559) (xy 129.85242 -248.806208)
			(xy 129.851922 -248.832857) (xy 130.080756 -248.832857) (xy 130.080756 -248.779559) (xy 130.088699 -248.726855)
			(xy 130.104409 -248.675925) (xy 130.127535 -248.627904) (xy 130.157559 -248.583867) (xy 130.193811 -248.544796)
			(xy 130.235482 -248.511565) (xy 130.28164 -248.484916) (xy 130.331254 -248.465444) (xy 130.383216 -248.453584)
			(xy 130.436366 -248.449601) (xy 130.489516 -248.453584) (xy 130.541478 -248.465444) (xy 130.591092 -248.484916)
			(xy 130.63725 -248.511565) (xy 130.678921 -248.544796) (xy 130.715173 -248.583867) (xy 130.745197 -248.627904)
			(xy 130.768323 -248.675925) (xy 130.784033 -248.726855) (xy 130.791976 -248.779559) (xy 130.792474 -248.806208)
			(xy 130.791976 -248.832857) (xy 131.020556 -248.832857) (xy 131.020556 -248.779559) (xy 131.028499 -248.726855)
			(xy 131.044209 -248.675925) (xy 131.067335 -248.627904) (xy 131.097359 -248.583867) (xy 131.133611 -248.544796)
			(xy 131.175282 -248.511565) (xy 131.22144 -248.484916) (xy 131.271054 -248.465444) (xy 131.323016 -248.453584)
			(xy 131.376166 -248.449601) (xy 131.429316 -248.453584) (xy 131.481278 -248.465444) (xy 131.530892 -248.484916)
			(xy 131.57705 -248.511565) (xy 131.618721 -248.544796) (xy 131.654973 -248.583867) (xy 131.684997 -248.627904)
			(xy 131.708123 -248.675925) (xy 131.723833 -248.726855) (xy 131.731776 -248.779559) (xy 131.732274 -248.806208)
			(xy 131.731776 -248.832857) (xy 131.960356 -248.832857) (xy 131.960356 -248.779559) (xy 131.968299 -248.726855)
			(xy 131.984009 -248.675925) (xy 132.007135 -248.627904) (xy 132.037159 -248.583867) (xy 132.073411 -248.544796)
			(xy 132.115082 -248.511565) (xy 132.16124 -248.484916) (xy 132.210854 -248.465444) (xy 132.262816 -248.453584)
			(xy 132.315966 -248.449601) (xy 132.369116 -248.453584) (xy 132.421078 -248.465444) (xy 132.470692 -248.484916)
			(xy 132.51685 -248.511565) (xy 132.558521 -248.544796) (xy 132.594773 -248.583867) (xy 132.624797 -248.627904)
			(xy 132.647923 -248.675925) (xy 132.663633 -248.726855) (xy 132.671576 -248.779559) (xy 132.672074 -248.806208)
			(xy 132.671576 -248.832857) (xy 133.839956 -248.832857) (xy 133.839956 -248.779559) (xy 133.847899 -248.726855)
			(xy 133.863609 -248.675925) (xy 133.886735 -248.627904) (xy 133.916759 -248.583867) (xy 133.953011 -248.544796)
			(xy 133.994682 -248.511565) (xy 134.04084 -248.484916) (xy 134.090454 -248.465444) (xy 134.142416 -248.453584)
			(xy 134.195566 -248.449601) (xy 134.248716 -248.453584) (xy 134.300678 -248.465444) (xy 134.350292 -248.484916)
			(xy 134.39645 -248.511565) (xy 134.438121 -248.544796) (xy 134.474373 -248.583867) (xy 134.504397 -248.627904)
			(xy 134.527523 -248.675925) (xy 134.543233 -248.726855) (xy 134.551176 -248.779559) (xy 134.551674 -248.806208)
			(xy 134.551176 -248.832857) (xy 134.543233 -248.885561) (xy 134.527523 -248.936491) (xy 134.504397 -248.984512)
			(xy 134.474373 -249.028549) (xy 134.438121 -249.06762) (xy 134.39645 -249.100851) (xy 134.350292 -249.1275)
			(xy 134.300678 -249.146972) (xy 134.248716 -249.158832) (xy 134.195566 -249.162816) (xy 134.142416 -249.158832)
			(xy 134.090454 -249.146972) (xy 134.04084 -249.1275) (xy 133.994682 -249.100851) (xy 133.953011 -249.06762)
			(xy 133.916759 -249.028549) (xy 133.886735 -248.984512) (xy 133.863609 -248.936491) (xy 133.847899 -248.885561)
			(xy 133.839956 -248.832857) (xy 132.671576 -248.832857) (xy 132.663633 -248.885561) (xy 132.647923 -248.936491)
			(xy 132.624797 -248.984512) (xy 132.594773 -249.028549) (xy 132.558521 -249.06762) (xy 132.51685 -249.100851)
			(xy 132.470692 -249.1275) (xy 132.421078 -249.146972) (xy 132.369116 -249.158832) (xy 132.315966 -249.162816)
			(xy 132.262816 -249.158832) (xy 132.210854 -249.146972) (xy 132.16124 -249.1275) (xy 132.115082 -249.100851)
			(xy 132.073411 -249.06762) (xy 132.037159 -249.028549) (xy 132.007135 -248.984512) (xy 131.984009 -248.936491)
			(xy 131.968299 -248.885561) (xy 131.960356 -248.832857) (xy 131.731776 -248.832857) (xy 131.723833 -248.885561)
			(xy 131.708123 -248.936491) (xy 131.684997 -248.984512) (xy 131.654973 -249.028549) (xy 131.618721 -249.06762)
			(xy 131.57705 -249.100851) (xy 131.530892 -249.1275) (xy 131.481278 -249.146972) (xy 131.429316 -249.158832)
			(xy 131.376166 -249.162816) (xy 131.323016 -249.158832) (xy 131.271054 -249.146972) (xy 131.22144 -249.1275)
			(xy 131.175282 -249.100851) (xy 131.133611 -249.06762) (xy 131.097359 -249.028549) (xy 131.067335 -248.984512)
			(xy 131.044209 -248.936491) (xy 131.028499 -248.885561) (xy 131.020556 -248.832857) (xy 130.791976 -248.832857)
			(xy 130.784033 -248.885561) (xy 130.768323 -248.936491) (xy 130.745197 -248.984512) (xy 130.715173 -249.028549)
			(xy 130.678921 -249.06762) (xy 130.63725 -249.100851) (xy 130.591092 -249.1275) (xy 130.541478 -249.146972)
			(xy 130.489516 -249.158832) (xy 130.436366 -249.162816) (xy 130.383216 -249.158832) (xy 130.331254 -249.146972)
			(xy 130.28164 -249.1275) (xy 130.235482 -249.100851) (xy 130.193811 -249.06762) (xy 130.157559 -249.028549)
			(xy 130.127535 -248.984512) (xy 130.104409 -248.936491) (xy 130.088699 -248.885561) (xy 130.080756 -248.832857)
			(xy 129.851922 -248.832857) (xy 129.843979 -248.885561) (xy 129.828269 -248.936491) (xy 129.805143 -248.984512)
			(xy 129.775119 -249.028549) (xy 129.738867 -249.06762) (xy 129.697196 -249.100851) (xy 129.651038 -249.1275)
			(xy 129.601424 -249.146972) (xy 129.549462 -249.158832) (xy 129.496312 -249.162816) (xy 129.443162 -249.158832)
			(xy 129.3912 -249.146972) (xy 129.341586 -249.1275) (xy 129.295428 -249.100851) (xy 129.253757 -249.06762)
			(xy 129.217505 -249.028549) (xy 129.187481 -248.984512) (xy 129.164355 -248.936491) (xy 129.148645 -248.885561)
			(xy 129.140702 -248.832857) (xy 128.912376 -248.832857) (xy 128.904433 -248.885561) (xy 128.888723 -248.936491)
			(xy 128.865597 -248.984512) (xy 128.835573 -249.028549) (xy 128.799321 -249.06762) (xy 128.75765 -249.100851)
			(xy 128.711492 -249.1275) (xy 128.661878 -249.146972) (xy 128.609916 -249.158832) (xy 128.556766 -249.162816)
			(xy 128.503616 -249.158832) (xy 128.451654 -249.146972) (xy 128.40204 -249.1275) (xy 128.355882 -249.100851)
			(xy 128.314211 -249.06762) (xy 128.277959 -249.028549) (xy 128.247935 -248.984512) (xy 128.224809 -248.936491)
			(xy 128.209099 -248.885561) (xy 128.201156 -248.832857) (xy 127.972576 -248.832857) (xy 127.964633 -248.885561)
			(xy 127.948923 -248.936491) (xy 127.925797 -248.984512) (xy 127.895773 -249.028549) (xy 127.859521 -249.06762)
			(xy 127.81785 -249.100851) (xy 127.771692 -249.1275) (xy 127.722078 -249.146972) (xy 127.670116 -249.158832)
			(xy 127.616966 -249.162816) (xy 127.563816 -249.158832) (xy 127.511854 -249.146972) (xy 127.46224 -249.1275)
			(xy 127.416082 -249.100851) (xy 127.374411 -249.06762) (xy 127.338159 -249.028549) (xy 127.308135 -248.984512)
			(xy 127.285009 -248.936491) (xy 127.269299 -248.885561) (xy 127.261356 -248.832857) (xy 127.032776 -248.832857)
			(xy 127.024833 -248.885561) (xy 127.009123 -248.936491) (xy 126.985997 -248.984512) (xy 126.955973 -249.028549)
			(xy 126.919721 -249.06762) (xy 126.87805 -249.100851) (xy 126.831892 -249.1275) (xy 126.782278 -249.146972)
			(xy 126.730316 -249.158832) (xy 126.677166 -249.162816) (xy 126.624016 -249.158832) (xy 126.572054 -249.146972)
			(xy 126.52244 -249.1275) (xy 126.476282 -249.100851) (xy 126.434611 -249.06762) (xy 126.398359 -249.028549)
			(xy 126.368335 -248.984512) (xy 126.345209 -248.936491) (xy 126.329499 -248.885561) (xy 126.321556 -248.832857)
			(xy 126.092976 -248.832857) (xy 126.085033 -248.885561) (xy 126.069323 -248.936491) (xy 126.046197 -248.984512)
			(xy 126.016173 -249.028549) (xy 125.979921 -249.06762) (xy 125.93825 -249.100851) (xy 125.892092 -249.1275)
			(xy 125.842478 -249.146972) (xy 125.790516 -249.158832) (xy 125.737366 -249.162816) (xy 125.684216 -249.158832)
			(xy 125.632254 -249.146972) (xy 125.58264 -249.1275) (xy 125.536482 -249.100851) (xy 125.494811 -249.06762)
			(xy 125.458559 -249.028549) (xy 125.428535 -248.984512) (xy 125.405409 -248.936491) (xy 125.389699 -248.885561)
			(xy 125.381756 -248.832857) (xy 125.153176 -248.832857) (xy 125.145233 -248.885561) (xy 125.129523 -248.936491)
			(xy 125.106397 -248.984512) (xy 125.076373 -249.028549) (xy 125.040121 -249.06762) (xy 124.99845 -249.100851)
			(xy 124.952292 -249.1275) (xy 124.902678 -249.146972) (xy 124.850716 -249.158832) (xy 124.797566 -249.162816)
			(xy 124.744416 -249.158832) (xy 124.692454 -249.146972) (xy 124.64284 -249.1275) (xy 124.596682 -249.100851)
			(xy 124.555011 -249.06762) (xy 124.518759 -249.028549) (xy 124.488735 -248.984512) (xy 124.465609 -248.936491)
			(xy 124.449899 -248.885561) (xy 124.441956 -248.832857) (xy 124.213376 -248.832857) (xy 124.205433 -248.885561)
			(xy 124.189723 -248.936491) (xy 124.166597 -248.984512) (xy 124.136573 -249.028549) (xy 124.100321 -249.06762)
			(xy 124.05865 -249.100851) (xy 124.012492 -249.1275) (xy 123.962878 -249.146972) (xy 123.910916 -249.158832)
			(xy 123.857766 -249.162816) (xy 123.804616 -249.158832) (xy 123.752654 -249.146972) (xy 123.70304 -249.1275)
			(xy 123.656882 -249.100851) (xy 123.615211 -249.06762) (xy 123.578959 -249.028549) (xy 123.548935 -248.984512)
			(xy 123.525809 -248.936491) (xy 123.510099 -248.885561) (xy 123.502156 -248.832857) (xy 123.273322 -248.832857)
			(xy 123.265379 -248.885561) (xy 123.249669 -248.936491) (xy 123.226543 -248.984512) (xy 123.196519 -249.028549)
			(xy 123.160267 -249.06762) (xy 123.118596 -249.100851) (xy 123.072438 -249.1275) (xy 123.022824 -249.146972)
			(xy 122.970862 -249.158832) (xy 122.917712 -249.162816) (xy 122.864562 -249.158832) (xy 122.8126 -249.146972)
			(xy 122.762986 -249.1275) (xy 122.716828 -249.100851) (xy 122.675157 -249.06762) (xy 122.638905 -249.028549)
			(xy 122.608881 -248.984512) (xy 122.585755 -248.936491) (xy 122.570045 -248.885561) (xy 122.562102 -248.832857)
			(xy 122.333776 -248.832857) (xy 122.325833 -248.885561) (xy 122.310123 -248.936491) (xy 122.286997 -248.984512)
			(xy 122.256973 -249.028549) (xy 122.220721 -249.06762) (xy 122.17905 -249.100851) (xy 122.132892 -249.1275)
			(xy 122.083278 -249.146972) (xy 122.031316 -249.158832) (xy 121.978166 -249.162816) (xy 121.925016 -249.158832)
			(xy 121.873054 -249.146972) (xy 121.82344 -249.1275) (xy 121.777282 -249.100851) (xy 121.735611 -249.06762)
			(xy 121.699359 -249.028549) (xy 121.669335 -248.984512) (xy 121.646209 -248.936491) (xy 121.630499 -248.885561)
			(xy 121.622556 -248.832857) (xy 121.215575 -248.832857) (xy 121.227755 -248.842249) (xy 121.265195 -248.881513)
			(xy 121.296244 -248.926004) (xy 121.320182 -248.974691) (xy 121.336456 -249.026446) (xy 121.344688 -249.080071)
			(xy 121.345198 -249.107198) (xy 121.345107 -249.118853) (xy 121.343581 -249.142113) (xy 121.34215 -249.15368)
			(xy 121.340808 -249.167024) (xy 121.344315 -249.193601) (xy 121.354632 -249.218345) (xy 121.371045 -249.23954)
			(xy 121.392419 -249.255722) (xy 121.417273 -249.265769) (xy 121.443887 -249.268985) (xy 121.457212 -249.267472)
			(xy 121.469845 -249.265794) (xy 121.495269 -249.264013) (xy 121.508012 -249.263916) (xy 121.535091 -249.26441)
			(xy 121.588623 -249.272613) (xy 121.640297 -249.288827) (xy 121.688919 -249.312679) (xy 121.733368 -249.343618)
			(xy 121.772621 -249.380932) (xy 121.80577 -249.423758) (xy 121.832052 -249.471111) (xy 121.850861 -249.521897)
			(xy 121.861763 -249.574946) (xy 121.864506 -249.629034) (xy 121.862712 -249.646673) (xy 122.092202 -249.646673)
			(xy 122.092202 -249.593375) (xy 122.100145 -249.540671) (xy 122.115855 -249.489741) (xy 122.138981 -249.44172)
			(xy 122.169005 -249.397683) (xy 122.205257 -249.358612) (xy 122.246928 -249.325381) (xy 122.293086 -249.298732)
			(xy 122.3427 -249.27926) (xy 122.394662 -249.2674) (xy 122.447812 -249.263417) (xy 122.500962 -249.2674)
			(xy 122.552924 -249.27926) (xy 122.602538 -249.298732) (xy 122.648696 -249.325381) (xy 122.690367 -249.358612)
			(xy 122.726619 -249.397683) (xy 122.756643 -249.44172) (xy 122.779769 -249.489741) (xy 122.795479 -249.540671)
			(xy 122.803422 -249.593375) (xy 122.80392 -249.620024) (xy 122.803422 -249.646673) (xy 123.032002 -249.646673)
			(xy 123.032002 -249.593375) (xy 123.039945 -249.540671) (xy 123.055655 -249.489741) (xy 123.078781 -249.44172)
			(xy 123.108805 -249.397683) (xy 123.145057 -249.358612) (xy 123.186728 -249.325381) (xy 123.232886 -249.298732)
			(xy 123.2825 -249.27926) (xy 123.334462 -249.2674) (xy 123.387612 -249.263417) (xy 123.440762 -249.2674)
			(xy 123.492724 -249.27926) (xy 123.542338 -249.298732) (xy 123.588496 -249.325381) (xy 123.630167 -249.358612)
			(xy 123.666419 -249.397683) (xy 123.696443 -249.44172) (xy 123.719569 -249.489741) (xy 123.735279 -249.540671)
			(xy 123.743222 -249.593375) (xy 123.74372 -249.620024) (xy 123.743222 -249.646673) (xy 123.971802 -249.646673)
			(xy 123.971802 -249.593375) (xy 123.979745 -249.540671) (xy 123.995455 -249.489741) (xy 124.018581 -249.44172)
			(xy 124.048605 -249.397683) (xy 124.084857 -249.358612) (xy 124.126528 -249.325381) (xy 124.172686 -249.298732)
			(xy 124.2223 -249.27926) (xy 124.274262 -249.2674) (xy 124.327412 -249.263417) (xy 124.380562 -249.2674)
			(xy 124.432524 -249.27926) (xy 124.482138 -249.298732) (xy 124.528296 -249.325381) (xy 124.569967 -249.358612)
			(xy 124.606219 -249.397683) (xy 124.636243 -249.44172) (xy 124.659369 -249.489741) (xy 124.675079 -249.540671)
			(xy 124.683022 -249.593375) (xy 124.68352 -249.620024) (xy 124.683022 -249.646673) (xy 124.911856 -249.646673)
			(xy 124.911856 -249.593375) (xy 124.919799 -249.540671) (xy 124.935509 -249.489741) (xy 124.958635 -249.44172)
			(xy 124.988659 -249.397683) (xy 125.024911 -249.358612) (xy 125.066582 -249.325381) (xy 125.11274 -249.298732)
			(xy 125.162354 -249.27926) (xy 125.214316 -249.2674) (xy 125.267466 -249.263417) (xy 125.320616 -249.2674)
			(xy 125.372578 -249.27926) (xy 125.422192 -249.298732) (xy 125.46835 -249.325381) (xy 125.510021 -249.358612)
			(xy 125.546273 -249.397683) (xy 125.576297 -249.44172) (xy 125.599423 -249.489741) (xy 125.615133 -249.540671)
			(xy 125.623076 -249.593375) (xy 125.623574 -249.620024) (xy 125.623076 -249.646673) (xy 125.851402 -249.646673)
			(xy 125.851402 -249.593375) (xy 125.859345 -249.540671) (xy 125.875055 -249.489741) (xy 125.898181 -249.44172)
			(xy 125.928205 -249.397683) (xy 125.964457 -249.358612) (xy 126.006128 -249.325381) (xy 126.052286 -249.298732)
			(xy 126.1019 -249.27926) (xy 126.153862 -249.2674) (xy 126.207012 -249.263417) (xy 126.260162 -249.2674)
			(xy 126.312124 -249.27926) (xy 126.361738 -249.298732) (xy 126.407896 -249.325381) (xy 126.449567 -249.358612)
			(xy 126.485819 -249.397683) (xy 126.515843 -249.44172) (xy 126.538969 -249.489741) (xy 126.554679 -249.540671)
			(xy 126.562622 -249.593375) (xy 126.56312 -249.620024) (xy 126.562622 -249.646673) (xy 126.791202 -249.646673)
			(xy 126.791202 -249.593375) (xy 126.799145 -249.540671) (xy 126.814855 -249.489741) (xy 126.837981 -249.44172)
			(xy 126.868005 -249.397683) (xy 126.904257 -249.358612) (xy 126.945928 -249.325381) (xy 126.992086 -249.298732)
			(xy 127.0417 -249.27926) (xy 127.093662 -249.2674) (xy 127.146812 -249.263417) (xy 127.199962 -249.2674)
			(xy 127.251924 -249.27926) (xy 127.301538 -249.298732) (xy 127.347696 -249.325381) (xy 127.389367 -249.358612)
			(xy 127.425619 -249.397683) (xy 127.455643 -249.44172) (xy 127.478769 -249.489741) (xy 127.494479 -249.540671)
			(xy 127.502422 -249.593375) (xy 127.50292 -249.620024) (xy 127.502422 -249.646673) (xy 127.731002 -249.646673)
			(xy 127.731002 -249.593375) (xy 127.738945 -249.540671) (xy 127.754655 -249.489741) (xy 127.777781 -249.44172)
			(xy 127.807805 -249.397683) (xy 127.844057 -249.358612) (xy 127.885728 -249.325381) (xy 127.931886 -249.298732)
			(xy 127.9815 -249.27926) (xy 128.033462 -249.2674) (xy 128.086612 -249.263417) (xy 128.139762 -249.2674)
			(xy 128.191724 -249.27926) (xy 128.241338 -249.298732) (xy 128.287496 -249.325381) (xy 128.329167 -249.358612)
			(xy 128.365419 -249.397683) (xy 128.395443 -249.44172) (xy 128.418569 -249.489741) (xy 128.434279 -249.540671)
			(xy 128.442222 -249.593375) (xy 128.44272 -249.620024) (xy 128.442222 -249.646673) (xy 128.670802 -249.646673)
			(xy 128.670802 -249.593375) (xy 128.678745 -249.540671) (xy 128.694455 -249.489741) (xy 128.717581 -249.44172)
			(xy 128.747605 -249.397683) (xy 128.783857 -249.358612) (xy 128.825528 -249.325381) (xy 128.871686 -249.298732)
			(xy 128.9213 -249.27926) (xy 128.973262 -249.2674) (xy 129.026412 -249.263417) (xy 129.079562 -249.2674)
			(xy 129.131524 -249.27926) (xy 129.181138 -249.298732) (xy 129.227296 -249.325381) (xy 129.268967 -249.358612)
			(xy 129.305219 -249.397683) (xy 129.335243 -249.44172) (xy 129.358369 -249.489741) (xy 129.374079 -249.540671)
			(xy 129.382022 -249.593375) (xy 129.38252 -249.620024) (xy 129.382022 -249.646673) (xy 129.610602 -249.646673)
			(xy 129.610602 -249.593375) (xy 129.618545 -249.540671) (xy 129.634255 -249.489741) (xy 129.657381 -249.44172)
			(xy 129.687405 -249.397683) (xy 129.723657 -249.358612) (xy 129.765328 -249.325381) (xy 129.811486 -249.298732)
			(xy 129.8611 -249.27926) (xy 129.913062 -249.2674) (xy 129.966212 -249.263417) (xy 130.019362 -249.2674)
			(xy 130.071324 -249.27926) (xy 130.120938 -249.298732) (xy 130.167096 -249.325381) (xy 130.208767 -249.358612)
			(xy 130.245019 -249.397683) (xy 130.275043 -249.44172) (xy 130.298169 -249.489741) (xy 130.313879 -249.540671)
			(xy 130.321822 -249.593375) (xy 130.32232 -249.620024) (xy 130.321822 -249.646673) (xy 130.550402 -249.646673)
			(xy 130.550402 -249.593375) (xy 130.558345 -249.540671) (xy 130.574055 -249.489741) (xy 130.597181 -249.44172)
			(xy 130.627205 -249.397683) (xy 130.663457 -249.358612) (xy 130.705128 -249.325381) (xy 130.751286 -249.298732)
			(xy 130.8009 -249.27926) (xy 130.852862 -249.2674) (xy 130.906012 -249.263417) (xy 130.959162 -249.2674)
			(xy 131.011124 -249.27926) (xy 131.060738 -249.298732) (xy 131.106896 -249.325381) (xy 131.148567 -249.358612)
			(xy 131.184819 -249.397683) (xy 131.214843 -249.44172) (xy 131.237969 -249.489741) (xy 131.253679 -249.540671)
			(xy 131.261622 -249.593375) (xy 131.26212 -249.620024) (xy 131.261622 -249.646673) (xy 131.490456 -249.646673)
			(xy 131.490456 -249.593375) (xy 131.498399 -249.540671) (xy 131.514109 -249.489741) (xy 131.537235 -249.44172)
			(xy 131.567259 -249.397683) (xy 131.603511 -249.358612) (xy 131.645182 -249.325381) (xy 131.69134 -249.298732)
			(xy 131.740954 -249.27926) (xy 131.792916 -249.2674) (xy 131.846066 -249.263417) (xy 131.899216 -249.2674)
			(xy 131.951178 -249.27926) (xy 132.000792 -249.298732) (xy 132.04695 -249.325381) (xy 132.088621 -249.358612)
			(xy 132.124873 -249.397683) (xy 132.154897 -249.44172) (xy 132.178023 -249.489741) (xy 132.193733 -249.540671)
			(xy 132.201676 -249.593375) (xy 132.202174 -249.620024) (xy 132.201676 -249.646673) (xy 132.193733 -249.699377)
			(xy 132.178023 -249.750307) (xy 132.154897 -249.798328) (xy 132.124873 -249.842365) (xy 132.088621 -249.881436)
			(xy 132.04695 -249.914667) (xy 132.000792 -249.941316) (xy 131.951178 -249.960788) (xy 131.899216 -249.972648)
			(xy 131.846066 -249.976632) (xy 131.792916 -249.972648) (xy 131.740954 -249.960788) (xy 131.69134 -249.941316)
			(xy 131.645182 -249.914667) (xy 131.603511 -249.881436) (xy 131.567259 -249.842365) (xy 131.537235 -249.798328)
			(xy 131.514109 -249.750307) (xy 131.498399 -249.699377) (xy 131.490456 -249.646673) (xy 131.261622 -249.646673)
			(xy 131.253679 -249.699377) (xy 131.237969 -249.750307) (xy 131.214843 -249.798328) (xy 131.184819 -249.842365)
			(xy 131.148567 -249.881436) (xy 131.106896 -249.914667) (xy 131.060738 -249.941316) (xy 131.011124 -249.960788)
			(xy 130.959162 -249.972648) (xy 130.906012 -249.976632) (xy 130.852862 -249.972648) (xy 130.8009 -249.960788)
			(xy 130.751286 -249.941316) (xy 130.705128 -249.914667) (xy 130.663457 -249.881436) (xy 130.627205 -249.842365)
			(xy 130.597181 -249.798328) (xy 130.574055 -249.750307) (xy 130.558345 -249.699377) (xy 130.550402 -249.646673)
			(xy 130.321822 -249.646673) (xy 130.313879 -249.699377) (xy 130.298169 -249.750307) (xy 130.275043 -249.798328)
			(xy 130.245019 -249.842365) (xy 130.208767 -249.881436) (xy 130.167096 -249.914667) (xy 130.120938 -249.941316)
			(xy 130.071324 -249.960788) (xy 130.019362 -249.972648) (xy 129.966212 -249.976632) (xy 129.913062 -249.972648)
			(xy 129.8611 -249.960788) (xy 129.811486 -249.941316) (xy 129.765328 -249.914667) (xy 129.723657 -249.881436)
			(xy 129.687405 -249.842365) (xy 129.657381 -249.798328) (xy 129.634255 -249.750307) (xy 129.618545 -249.699377)
			(xy 129.610602 -249.646673) (xy 129.382022 -249.646673) (xy 129.374079 -249.699377) (xy 129.358369 -249.750307)
			(xy 129.335243 -249.798328) (xy 129.305219 -249.842365) (xy 129.268967 -249.881436) (xy 129.227296 -249.914667)
			(xy 129.181138 -249.941316) (xy 129.131524 -249.960788) (xy 129.079562 -249.972648) (xy 129.026412 -249.976632)
			(xy 128.973262 -249.972648) (xy 128.9213 -249.960788) (xy 128.871686 -249.941316) (xy 128.825528 -249.914667)
			(xy 128.783857 -249.881436) (xy 128.747605 -249.842365) (xy 128.717581 -249.798328) (xy 128.694455 -249.750307)
			(xy 128.678745 -249.699377) (xy 128.670802 -249.646673) (xy 128.442222 -249.646673) (xy 128.434279 -249.699377)
			(xy 128.418569 -249.750307) (xy 128.395443 -249.798328) (xy 128.365419 -249.842365) (xy 128.329167 -249.881436)
			(xy 128.287496 -249.914667) (xy 128.241338 -249.941316) (xy 128.191724 -249.960788) (xy 128.139762 -249.972648)
			(xy 128.086612 -249.976632) (xy 128.033462 -249.972648) (xy 127.9815 -249.960788) (xy 127.931886 -249.941316)
			(xy 127.885728 -249.914667) (xy 127.844057 -249.881436) (xy 127.807805 -249.842365) (xy 127.777781 -249.798328)
			(xy 127.754655 -249.750307) (xy 127.738945 -249.699377) (xy 127.731002 -249.646673) (xy 127.502422 -249.646673)
			(xy 127.494479 -249.699377) (xy 127.478769 -249.750307) (xy 127.455643 -249.798328) (xy 127.425619 -249.842365)
			(xy 127.389367 -249.881436) (xy 127.347696 -249.914667) (xy 127.301538 -249.941316) (xy 127.251924 -249.960788)
			(xy 127.199962 -249.972648) (xy 127.146812 -249.976632) (xy 127.093662 -249.972648) (xy 127.0417 -249.960788)
			(xy 126.992086 -249.941316) (xy 126.945928 -249.914667) (xy 126.904257 -249.881436) (xy 126.868005 -249.842365)
			(xy 126.837981 -249.798328) (xy 126.814855 -249.750307) (xy 126.799145 -249.699377) (xy 126.791202 -249.646673)
			(xy 126.562622 -249.646673) (xy 126.554679 -249.699377) (xy 126.538969 -249.750307) (xy 126.515843 -249.798328)
			(xy 126.485819 -249.842365) (xy 126.449567 -249.881436) (xy 126.407896 -249.914667) (xy 126.361738 -249.941316)
			(xy 126.312124 -249.960788) (xy 126.260162 -249.972648) (xy 126.207012 -249.976632) (xy 126.153862 -249.972648)
			(xy 126.1019 -249.960788) (xy 126.052286 -249.941316) (xy 126.006128 -249.914667) (xy 125.964457 -249.881436)
			(xy 125.928205 -249.842365) (xy 125.898181 -249.798328) (xy 125.875055 -249.750307) (xy 125.859345 -249.699377)
			(xy 125.851402 -249.646673) (xy 125.623076 -249.646673) (xy 125.615133 -249.699377) (xy 125.599423 -249.750307)
			(xy 125.576297 -249.798328) (xy 125.546273 -249.842365) (xy 125.510021 -249.881436) (xy 125.46835 -249.914667)
			(xy 125.422192 -249.941316) (xy 125.372578 -249.960788) (xy 125.320616 -249.972648) (xy 125.267466 -249.976632)
			(xy 125.214316 -249.972648) (xy 125.162354 -249.960788) (xy 125.11274 -249.941316) (xy 125.066582 -249.914667)
			(xy 125.024911 -249.881436) (xy 124.988659 -249.842365) (xy 124.958635 -249.798328) (xy 124.935509 -249.750307)
			(xy 124.919799 -249.699377) (xy 124.911856 -249.646673) (xy 124.683022 -249.646673) (xy 124.675079 -249.699377)
			(xy 124.659369 -249.750307) (xy 124.636243 -249.798328) (xy 124.606219 -249.842365) (xy 124.569967 -249.881436)
			(xy 124.528296 -249.914667) (xy 124.482138 -249.941316) (xy 124.432524 -249.960788) (xy 124.380562 -249.972648)
			(xy 124.327412 -249.976632) (xy 124.274262 -249.972648) (xy 124.2223 -249.960788) (xy 124.172686 -249.941316)
			(xy 124.126528 -249.914667) (xy 124.084857 -249.881436) (xy 124.048605 -249.842365) (xy 124.018581 -249.798328)
			(xy 123.995455 -249.750307) (xy 123.979745 -249.699377) (xy 123.971802 -249.646673) (xy 123.743222 -249.646673)
			(xy 123.735279 -249.699377) (xy 123.719569 -249.750307) (xy 123.696443 -249.798328) (xy 123.666419 -249.842365)
			(xy 123.630167 -249.881436) (xy 123.588496 -249.914667) (xy 123.542338 -249.941316) (xy 123.492724 -249.960788)
			(xy 123.440762 -249.972648) (xy 123.387612 -249.976632) (xy 123.334462 -249.972648) (xy 123.2825 -249.960788)
			(xy 123.232886 -249.941316) (xy 123.186728 -249.914667) (xy 123.145057 -249.881436) (xy 123.108805 -249.842365)
			(xy 123.078781 -249.798328) (xy 123.055655 -249.750307) (xy 123.039945 -249.699377) (xy 123.032002 -249.646673)
			(xy 122.803422 -249.646673) (xy 122.795479 -249.699377) (xy 122.779769 -249.750307) (xy 122.756643 -249.798328)
			(xy 122.726619 -249.842365) (xy 122.690367 -249.881436) (xy 122.648696 -249.914667) (xy 122.602538 -249.941316)
			(xy 122.552924 -249.960788) (xy 122.500962 -249.972648) (xy 122.447812 -249.976632) (xy 122.394662 -249.972648)
			(xy 122.3427 -249.960788) (xy 122.293086 -249.941316) (xy 122.246928 -249.914667) (xy 122.205257 -249.881436)
			(xy 122.169005 -249.842365) (xy 122.138981 -249.798328) (xy 122.115855 -249.750307) (xy 122.100145 -249.699377)
			(xy 122.092202 -249.646673) (xy 121.862712 -249.646673) (xy 121.859027 -249.682913) (xy 121.845452 -249.735342)
			(xy 121.824095 -249.785111) (xy 121.795449 -249.831071) (xy 121.760173 -249.872164) (xy 121.719081 -249.907442)
			(xy 121.673121 -249.93609) (xy 121.623353 -249.957448) (xy 121.570925 -249.971025) (xy 121.517046 -249.976505)
			(xy 121.462958 -249.973764) (xy 121.409909 -249.962864) (xy 121.359122 -249.944057) (xy 121.311768 -249.917777)
			(xy 121.26894 -249.884629) (xy 121.231626 -249.845378) (xy 121.200685 -249.800929) (xy 121.176832 -249.752308)
			(xy 121.160616 -249.700635) (xy 121.152411 -249.647103) (xy 121.151904 -249.620024) (xy 121.151997 -249.608369)
			(xy 121.153522 -249.585109) (xy 121.154952 -249.573542) (xy 121.15627 -249.560196) (xy 121.152768 -249.533621)
			(xy 121.142456 -249.508878) (xy 121.126046 -249.487682) (xy 121.104676 -249.471501) (xy 121.079825 -249.461454)
			(xy 121.053213 -249.458237) (xy 121.03989 -249.45975) (xy 121.027257 -249.461428) (xy 121.001833 -249.463209)
			(xy 120.98909 -249.463306) (xy 120.961107 -249.462768) (xy 120.905829 -249.454012) (xy 120.852601 -249.436716)
			(xy 120.802735 -249.411306) (xy 120.757457 -249.378409) (xy 120.717884 -249.338833) (xy 120.684988 -249.293555)
			(xy 120.65958 -249.243687) (xy 120.642286 -249.190459) (xy 120.633531 -249.135181) (xy 120.632982 -249.107198)
			(xy 120.63356 -249.078302) (xy 120.64288 -249.021267) (xy 120.661289 -248.966486) (xy 120.688306 -248.915398)
			(xy 120.723219 -248.869345) (xy 120.765114 -248.829537) (xy 120.788684 -248.812812) (xy 120.800626 -248.804002)
			(xy 120.819302 -248.780962) (xy 120.830577 -248.75353) (xy 120.833501 -248.724016) (xy 120.82783 -248.694905)
			(xy 120.814039 -248.668647) (xy 120.79329 -248.647454) (xy 120.780556 -248.639838) (xy 120.757071 -248.626251)
			(xy 120.714104 -248.593126) (xy 120.676661 -248.553864) (xy 120.645611 -248.509374) (xy 120.621672 -248.460688)
			(xy 120.605399 -248.408932) (xy 120.597169 -248.355307) (xy 120.59666 -248.32818) (xy 118.87708 -248.32818)
			(xy 118.87708 -248.376948) (xy 120.62968 -250.129548) (xy 120.62968 -250.470416) (xy 120.630112 -250.483998)
			(xy 120.637279 -250.5102) (xy 120.651102 -250.533584) (xy 120.670602 -250.552495) (xy 120.694399 -250.565596)
			(xy 120.720807 -250.571957) (xy 120.747959 -250.571129) (xy 120.773931 -250.563171) (xy 120.785636 -250.556268)
			(xy 120.80713 -250.543157) (xy 120.853024 -250.522455) (xy 120.901373 -250.508415) (xy 120.951217 -250.501317)
			(xy 120.97639 -250.500896) (xy 121.004376 -250.501416) (xy 121.059658 -250.51017) (xy 121.112891 -250.527465)
			(xy 121.162762 -250.552875) (xy 121.208044 -250.585774) (xy 121.247622 -250.625351) (xy 121.280522 -250.670633)
			(xy 121.305932 -250.720504) (xy 121.323228 -250.773736) (xy 121.331984 -250.829018) (xy 121.332498 -250.857004)
			(xy 121.332078 -250.881673) (xy 121.325266 -250.930539) (xy 121.311774 -250.977996) (xy 121.291859 -251.023137)
			(xy 121.265903 -251.065096) (xy 121.250456 -251.084334) (xy 121.241831 -251.095464) (xy 121.230486 -251.121224)
			(xy 121.226607 -251.149103) (xy 121.230488 -251.176982) (xy 121.241834 -251.202741) (xy 121.250456 -251.213874)
			(xy 121.265891 -251.233122) (xy 121.291861 -251.275073) (xy 121.311784 -251.32021) (xy 121.325277 -251.367668)
			(xy 121.332082 -251.416535) (xy 121.332498 -251.441204) (xy 121.331977 -251.469189) (xy 121.323221 -251.524469)
			(xy 121.305924 -251.577699) (xy 121.280514 -251.627568) (xy 121.247615 -251.672848) (xy 121.208038 -251.712424)
			(xy 121.162756 -251.745321) (xy 121.112887 -251.77073) (xy 121.059656 -251.788024) (xy 121.004375 -251.796778)
			(xy 120.97639 -251.797312) (xy 120.951218 -251.796877) (xy 120.901375 -251.789785) (xy 120.853028 -251.775743)
			(xy 120.80714 -251.755033) (xy 120.785636 -251.74194) (xy 120.77393 -251.735041) (xy 120.747959 -251.727082)
			(xy 120.720809 -251.726254) (xy 120.694402 -251.732615) (xy 120.670607 -251.745715) (xy 120.651108 -251.764626)
			(xy 120.637287 -251.78801) (xy 120.630122 -251.814211) (xy 120.62968 -251.827792) (xy 120.62968 -252.223016)
			(xy 120.630112 -252.236598) (xy 120.637279 -252.2628) (xy 120.651102 -252.286184) (xy 120.670602 -252.305095)
			(xy 120.694399 -252.318196) (xy 120.720807 -252.324557) (xy 120.747959 -252.323729) (xy 120.773931 -252.315771)
			(xy 120.785636 -252.308868) (xy 120.80713 -252.295757) (xy 120.853024 -252.275055) (xy 120.901373 -252.261015)
			(xy 120.951217 -252.253917) (xy 120.97639 -252.253496) (xy 121.004376 -252.254016) (xy 121.059658 -252.26277)
			(xy 121.112891 -252.280065) (xy 121.162762 -252.305475) (xy 121.208044 -252.338374) (xy 121.247622 -252.377951)
			(xy 121.280522 -252.423233) (xy 121.305932 -252.473104) (xy 121.323228 -252.526336) (xy 121.331984 -252.581618)
			(xy 121.332498 -252.609604) (xy 121.332078 -252.634273) (xy 121.325266 -252.683139) (xy 121.311774 -252.730596)
			(xy 121.291859 -252.775737) (xy 121.265903 -252.817696) (xy 121.250456 -252.836934) (xy 121.241831 -252.848064)
			(xy 121.230486 -252.873824) (xy 121.226607 -252.901703) (xy 121.230488 -252.929582) (xy 121.241834 -252.955341)
			(xy 121.250456 -252.966474) (xy 121.265891 -252.985722) (xy 121.291861 -253.027673) (xy 121.311784 -253.07281)
			(xy 121.325277 -253.120268) (xy 121.332082 -253.169135) (xy 121.332498 -253.193804) (xy 121.331977 -253.221789)
			(xy 121.323221 -253.277069) (xy 121.305924 -253.330299) (xy 121.280514 -253.380168) (xy 121.247615 -253.425448)
			(xy 121.208038 -253.465024) (xy 121.162756 -253.497921) (xy 121.112887 -253.52333) (xy 121.059656 -253.540624)
			(xy 121.004375 -253.549378) (xy 120.97639 -253.549912) (xy 120.951218 -253.549477) (xy 120.901375 -253.542385)
			(xy 120.853028 -253.528343) (xy 120.80714 -253.507633) (xy 120.785636 -253.49454) (xy 120.77393 -253.487641)
			(xy 120.747959 -253.479682) (xy 120.720809 -253.478854) (xy 120.694402 -253.485215) (xy 120.670607 -253.498315)
			(xy 120.651108 -253.517226) (xy 120.637287 -253.54061) (xy 120.630122 -253.566811) (xy 120.62968 -253.580392)
			(xy 120.62968 -253.946385) (xy 121.732538 -253.946385) (xy 121.732538 -253.893087) (xy 121.740481 -253.840383)
			(xy 121.756191 -253.789453) (xy 121.779317 -253.741432) (xy 121.809341 -253.697395) (xy 121.845593 -253.658324)
			(xy 121.887264 -253.625093) (xy 121.933422 -253.598444) (xy 121.983036 -253.578972) (xy 122.034998 -253.567112)
			(xy 122.088148 -253.563129) (xy 122.141298 -253.567112) (xy 122.19326 -253.578972) (xy 122.242874 -253.598444)
			(xy 122.289032 -253.625093) (xy 122.330703 -253.658324) (xy 122.366955 -253.697395) (xy 122.396979 -253.741432)
			(xy 122.420105 -253.789453) (xy 122.435815 -253.840383) (xy 122.443758 -253.893087) (xy 122.444256 -253.919736)
			(xy 122.443758 -253.946385) (xy 122.672084 -253.946385) (xy 122.672084 -253.893087) (xy 122.680027 -253.840383)
			(xy 122.695737 -253.789453) (xy 122.718863 -253.741432) (xy 122.748887 -253.697395) (xy 122.785139 -253.658324)
			(xy 122.82681 -253.625093) (xy 122.872968 -253.598444) (xy 122.922582 -253.578972) (xy 122.974544 -253.567112)
			(xy 123.027694 -253.563129) (xy 123.080844 -253.567112) (xy 123.132806 -253.578972) (xy 123.18242 -253.598444)
			(xy 123.228578 -253.625093) (xy 123.270249 -253.658324) (xy 123.306501 -253.697395) (xy 123.336525 -253.741432)
			(xy 123.359651 -253.789453) (xy 123.375361 -253.840383) (xy 123.383304 -253.893087) (xy 123.383802 -253.919736)
			(xy 123.383304 -253.946385) (xy 123.612138 -253.946385) (xy 123.612138 -253.893087) (xy 123.620081 -253.840383)
			(xy 123.635791 -253.789453) (xy 123.658917 -253.741432) (xy 123.688941 -253.697395) (xy 123.725193 -253.658324)
			(xy 123.766864 -253.625093) (xy 123.813022 -253.598444) (xy 123.862636 -253.578972) (xy 123.914598 -253.567112)
			(xy 123.967748 -253.563129) (xy 124.020898 -253.567112) (xy 124.07286 -253.578972) (xy 124.122474 -253.598444)
			(xy 124.168632 -253.625093) (xy 124.210303 -253.658324) (xy 124.246555 -253.697395) (xy 124.276579 -253.741432)
			(xy 124.299705 -253.789453) (xy 124.315415 -253.840383) (xy 124.323358 -253.893087) (xy 124.323856 -253.919736)
			(xy 124.323358 -253.946385) (xy 124.551938 -253.946385) (xy 124.551938 -253.893087) (xy 124.559881 -253.840383)
			(xy 124.575591 -253.789453) (xy 124.598717 -253.741432) (xy 124.628741 -253.697395) (xy 124.664993 -253.658324)
			(xy 124.706664 -253.625093) (xy 124.752822 -253.598444) (xy 124.802436 -253.578972) (xy 124.854398 -253.567112)
			(xy 124.907548 -253.563129) (xy 124.960698 -253.567112) (xy 125.01266 -253.578972) (xy 125.062274 -253.598444)
			(xy 125.108432 -253.625093) (xy 125.150103 -253.658324) (xy 125.186355 -253.697395) (xy 125.216379 -253.741432)
			(xy 125.239505 -253.789453) (xy 125.255215 -253.840383) (xy 125.263158 -253.893087) (xy 125.263656 -253.919736)
			(xy 125.263158 -253.946385) (xy 125.491738 -253.946385) (xy 125.491738 -253.893087) (xy 125.499681 -253.840383)
			(xy 125.515391 -253.789453) (xy 125.538517 -253.741432) (xy 125.568541 -253.697395) (xy 125.604793 -253.658324)
			(xy 125.646464 -253.625093) (xy 125.692622 -253.598444) (xy 125.742236 -253.578972) (xy 125.794198 -253.567112)
			(xy 125.847348 -253.563129) (xy 125.900498 -253.567112) (xy 125.95246 -253.578972) (xy 126.002074 -253.598444)
			(xy 126.048232 -253.625093) (xy 126.089903 -253.658324) (xy 126.126155 -253.697395) (xy 126.156179 -253.741432)
			(xy 126.179305 -253.789453) (xy 126.195015 -253.840383) (xy 126.202958 -253.893087) (xy 126.203456 -253.919736)
			(xy 126.202958 -253.946385) (xy 126.431538 -253.946385) (xy 126.431538 -253.893087) (xy 126.439481 -253.840383)
			(xy 126.455191 -253.789453) (xy 126.478317 -253.741432) (xy 126.508341 -253.697395) (xy 126.544593 -253.658324)
			(xy 126.586264 -253.625093) (xy 126.632422 -253.598444) (xy 126.682036 -253.578972) (xy 126.733998 -253.567112)
			(xy 126.787148 -253.563129) (xy 126.840298 -253.567112) (xy 126.89226 -253.578972) (xy 126.941874 -253.598444)
			(xy 126.988032 -253.625093) (xy 127.029703 -253.658324) (xy 127.065955 -253.697395) (xy 127.095979 -253.741432)
			(xy 127.119105 -253.789453) (xy 127.134815 -253.840383) (xy 127.142758 -253.893087) (xy 127.143256 -253.919736)
			(xy 127.142758 -253.946385) (xy 127.371338 -253.946385) (xy 127.371338 -253.893087) (xy 127.379281 -253.840383)
			(xy 127.394991 -253.789453) (xy 127.418117 -253.741432) (xy 127.448141 -253.697395) (xy 127.484393 -253.658324)
			(xy 127.526064 -253.625093) (xy 127.572222 -253.598444) (xy 127.621836 -253.578972) (xy 127.673798 -253.567112)
			(xy 127.726948 -253.563129) (xy 127.780098 -253.567112) (xy 127.83206 -253.578972) (xy 127.881674 -253.598444)
			(xy 127.927832 -253.625093) (xy 127.969503 -253.658324) (xy 128.005755 -253.697395) (xy 128.035779 -253.741432)
			(xy 128.058905 -253.789453) (xy 128.074615 -253.840383) (xy 128.082558 -253.893087) (xy 128.083056 -253.919736)
			(xy 128.082558 -253.946385) (xy 128.310884 -253.946385) (xy 128.310884 -253.893087) (xy 128.318827 -253.840383)
			(xy 128.334537 -253.789453) (xy 128.357663 -253.741432) (xy 128.387687 -253.697395) (xy 128.423939 -253.658324)
			(xy 128.46561 -253.625093) (xy 128.511768 -253.598444) (xy 128.561382 -253.578972) (xy 128.613344 -253.567112)
			(xy 128.666494 -253.563129) (xy 128.719644 -253.567112) (xy 128.771606 -253.578972) (xy 128.82122 -253.598444)
			(xy 128.867378 -253.625093) (xy 128.909049 -253.658324) (xy 128.945301 -253.697395) (xy 128.975325 -253.741432)
			(xy 128.998451 -253.789453) (xy 129.014161 -253.840383) (xy 129.022104 -253.893087) (xy 129.022602 -253.919736)
			(xy 129.022104 -253.946385) (xy 129.250684 -253.946385) (xy 129.250684 -253.893087) (xy 129.258627 -253.840383)
			(xy 129.274337 -253.789453) (xy 129.297463 -253.741432) (xy 129.327487 -253.697395) (xy 129.363739 -253.658324)
			(xy 129.40541 -253.625093) (xy 129.451568 -253.598444) (xy 129.501182 -253.578972) (xy 129.553144 -253.567112)
			(xy 129.606294 -253.563129) (xy 129.659444 -253.567112) (xy 129.711406 -253.578972) (xy 129.76102 -253.598444)
			(xy 129.807178 -253.625093) (xy 129.848849 -253.658324) (xy 129.885101 -253.697395) (xy 129.915125 -253.741432)
			(xy 129.938251 -253.789453) (xy 129.953961 -253.840383) (xy 129.961904 -253.893087) (xy 129.962402 -253.919736)
			(xy 129.961904 -253.946385) (xy 130.190738 -253.946385) (xy 130.190738 -253.893087) (xy 130.198681 -253.840383)
			(xy 130.214391 -253.789453) (xy 130.237517 -253.741432) (xy 130.267541 -253.697395) (xy 130.303793 -253.658324)
			(xy 130.345464 -253.625093) (xy 130.391622 -253.598444) (xy 130.441236 -253.578972) (xy 130.493198 -253.567112)
			(xy 130.546348 -253.563129) (xy 130.599498 -253.567112) (xy 130.65146 -253.578972) (xy 130.701074 -253.598444)
			(xy 130.747232 -253.625093) (xy 130.788903 -253.658324) (xy 130.825155 -253.697395) (xy 130.855179 -253.741432)
			(xy 130.878305 -253.789453) (xy 130.894015 -253.840383) (xy 130.901958 -253.893087) (xy 130.902456 -253.919736)
			(xy 130.901958 -253.946385) (xy 131.130284 -253.946385) (xy 131.130284 -253.893087) (xy 131.138227 -253.840383)
			(xy 131.153937 -253.789453) (xy 131.177063 -253.741432) (xy 131.207087 -253.697395) (xy 131.243339 -253.658324)
			(xy 131.28501 -253.625093) (xy 131.331168 -253.598444) (xy 131.380782 -253.578972) (xy 131.432744 -253.567112)
			(xy 131.485894 -253.563129) (xy 131.539044 -253.567112) (xy 131.591006 -253.578972) (xy 131.64062 -253.598444)
			(xy 131.686778 -253.625093) (xy 131.728449 -253.658324) (xy 131.764701 -253.697395) (xy 131.794725 -253.741432)
			(xy 131.817851 -253.789453) (xy 131.833561 -253.840383) (xy 131.841504 -253.893087) (xy 131.842002 -253.919736)
			(xy 131.841504 -253.946385) (xy 132.070084 -253.946385) (xy 132.070084 -253.893087) (xy 132.078027 -253.840383)
			(xy 132.093737 -253.789453) (xy 132.116863 -253.741432) (xy 132.146887 -253.697395) (xy 132.183139 -253.658324)
			(xy 132.22481 -253.625093) (xy 132.270968 -253.598444) (xy 132.320582 -253.578972) (xy 132.372544 -253.567112)
			(xy 132.425694 -253.563129) (xy 132.478844 -253.567112) (xy 132.530806 -253.578972) (xy 132.58042 -253.598444)
			(xy 132.626578 -253.625093) (xy 132.668249 -253.658324) (xy 132.704501 -253.697395) (xy 132.734525 -253.741432)
			(xy 132.757651 -253.789453) (xy 132.773361 -253.840383) (xy 132.781304 -253.893087) (xy 132.781802 -253.919736)
			(xy 132.781304 -253.946385) (xy 133.010138 -253.946385) (xy 133.010138 -253.893087) (xy 133.018081 -253.840383)
			(xy 133.033791 -253.789453) (xy 133.056917 -253.741432) (xy 133.086941 -253.697395) (xy 133.123193 -253.658324)
			(xy 133.164864 -253.625093) (xy 133.211022 -253.598444) (xy 133.260636 -253.578972) (xy 133.312598 -253.567112)
			(xy 133.365748 -253.563129) (xy 133.418898 -253.567112) (xy 133.47086 -253.578972) (xy 133.520474 -253.598444)
			(xy 133.566632 -253.625093) (xy 133.608303 -253.658324) (xy 133.644555 -253.697395) (xy 133.674579 -253.741432)
			(xy 133.697705 -253.789453) (xy 133.713415 -253.840383) (xy 133.721358 -253.893087) (xy 133.721856 -253.919736)
			(xy 133.721358 -253.946385) (xy 133.949938 -253.946385) (xy 133.949938 -253.893087) (xy 133.957881 -253.840383)
			(xy 133.973591 -253.789453) (xy 133.996717 -253.741432) (xy 134.026741 -253.697395) (xy 134.062993 -253.658324)
			(xy 134.104664 -253.625093) (xy 134.150822 -253.598444) (xy 134.200436 -253.578972) (xy 134.252398 -253.567112)
			(xy 134.305548 -253.563129) (xy 134.358698 -253.567112) (xy 134.41066 -253.578972) (xy 134.460274 -253.598444)
			(xy 134.506432 -253.625093) (xy 134.548103 -253.658324) (xy 134.584355 -253.697395) (xy 134.614379 -253.741432)
			(xy 134.637505 -253.789453) (xy 134.653215 -253.840383) (xy 134.661158 -253.893087) (xy 134.661656 -253.919736)
			(xy 134.661158 -253.946385) (xy 134.653215 -253.999089) (xy 134.637505 -254.050019) (xy 134.614379 -254.09804)
			(xy 134.584355 -254.142077) (xy 134.548103 -254.181148) (xy 134.506432 -254.214379) (xy 134.460274 -254.241028)
			(xy 134.41066 -254.2605) (xy 134.358698 -254.27236) (xy 134.305548 -254.276344) (xy 134.252398 -254.27236)
			(xy 134.200436 -254.2605) (xy 134.150822 -254.241028) (xy 134.104664 -254.214379) (xy 134.062993 -254.181148)
			(xy 134.026741 -254.142077) (xy 133.996717 -254.09804) (xy 133.973591 -254.050019) (xy 133.957881 -253.999089)
			(xy 133.949938 -253.946385) (xy 133.721358 -253.946385) (xy 133.713415 -253.999089) (xy 133.697705 -254.050019)
			(xy 133.674579 -254.09804) (xy 133.644555 -254.142077) (xy 133.608303 -254.181148) (xy 133.566632 -254.214379)
			(xy 133.520474 -254.241028) (xy 133.47086 -254.2605) (xy 133.418898 -254.27236) (xy 133.365748 -254.276344)
			(xy 133.312598 -254.27236) (xy 133.260636 -254.2605) (xy 133.211022 -254.241028) (xy 133.164864 -254.214379)
			(xy 133.123193 -254.181148) (xy 133.086941 -254.142077) (xy 133.056917 -254.09804) (xy 133.033791 -254.050019)
			(xy 133.018081 -253.999089) (xy 133.010138 -253.946385) (xy 132.781304 -253.946385) (xy 132.773361 -253.999089)
			(xy 132.757651 -254.050019) (xy 132.734525 -254.09804) (xy 132.704501 -254.142077) (xy 132.668249 -254.181148)
			(xy 132.626578 -254.214379) (xy 132.58042 -254.241028) (xy 132.530806 -254.2605) (xy 132.478844 -254.27236)
			(xy 132.425694 -254.276344) (xy 132.372544 -254.27236) (xy 132.320582 -254.2605) (xy 132.270968 -254.241028)
			(xy 132.22481 -254.214379) (xy 132.183139 -254.181148) (xy 132.146887 -254.142077) (xy 132.116863 -254.09804)
			(xy 132.093737 -254.050019) (xy 132.078027 -253.999089) (xy 132.070084 -253.946385) (xy 131.841504 -253.946385)
			(xy 131.833561 -253.999089) (xy 131.817851 -254.050019) (xy 131.794725 -254.09804) (xy 131.764701 -254.142077)
			(xy 131.728449 -254.181148) (xy 131.686778 -254.214379) (xy 131.64062 -254.241028) (xy 131.591006 -254.2605)
			(xy 131.539044 -254.27236) (xy 131.485894 -254.276344) (xy 131.432744 -254.27236) (xy 131.380782 -254.2605)
			(xy 131.331168 -254.241028) (xy 131.28501 -254.214379) (xy 131.243339 -254.181148) (xy 131.207087 -254.142077)
			(xy 131.177063 -254.09804) (xy 131.153937 -254.050019) (xy 131.138227 -253.999089) (xy 131.130284 -253.946385)
			(xy 130.901958 -253.946385) (xy 130.894015 -253.999089) (xy 130.878305 -254.050019) (xy 130.855179 -254.09804)
			(xy 130.825155 -254.142077) (xy 130.788903 -254.181148) (xy 130.747232 -254.214379) (xy 130.701074 -254.241028)
			(xy 130.65146 -254.2605) (xy 130.599498 -254.27236) (xy 130.546348 -254.276344) (xy 130.493198 -254.27236)
			(xy 130.441236 -254.2605) (xy 130.391622 -254.241028) (xy 130.345464 -254.214379) (xy 130.303793 -254.181148)
			(xy 130.267541 -254.142077) (xy 130.237517 -254.09804) (xy 130.214391 -254.050019) (xy 130.198681 -253.999089)
			(xy 130.190738 -253.946385) (xy 129.961904 -253.946385) (xy 129.953961 -253.999089) (xy 129.938251 -254.050019)
			(xy 129.915125 -254.09804) (xy 129.885101 -254.142077) (xy 129.848849 -254.181148) (xy 129.807178 -254.214379)
			(xy 129.76102 -254.241028) (xy 129.711406 -254.2605) (xy 129.659444 -254.27236) (xy 129.606294 -254.276344)
			(xy 129.553144 -254.27236) (xy 129.501182 -254.2605) (xy 129.451568 -254.241028) (xy 129.40541 -254.214379)
			(xy 129.363739 -254.181148) (xy 129.327487 -254.142077) (xy 129.297463 -254.09804) (xy 129.274337 -254.050019)
			(xy 129.258627 -253.999089) (xy 129.250684 -253.946385) (xy 129.022104 -253.946385) (xy 129.014161 -253.999089)
			(xy 128.998451 -254.050019) (xy 128.975325 -254.09804) (xy 128.945301 -254.142077) (xy 128.909049 -254.181148)
			(xy 128.867378 -254.214379) (xy 128.82122 -254.241028) (xy 128.771606 -254.2605) (xy 128.719644 -254.27236)
			(xy 128.666494 -254.276344) (xy 128.613344 -254.27236) (xy 128.561382 -254.2605) (xy 128.511768 -254.241028)
			(xy 128.46561 -254.214379) (xy 128.423939 -254.181148) (xy 128.387687 -254.142077) (xy 128.357663 -254.09804)
			(xy 128.334537 -254.050019) (xy 128.318827 -253.999089) (xy 128.310884 -253.946385) (xy 128.082558 -253.946385)
			(xy 128.074615 -253.999089) (xy 128.058905 -254.050019) (xy 128.035779 -254.09804) (xy 128.005755 -254.142077)
			(xy 127.969503 -254.181148) (xy 127.927832 -254.214379) (xy 127.881674 -254.241028) (xy 127.83206 -254.2605)
			(xy 127.780098 -254.27236) (xy 127.726948 -254.276344) (xy 127.673798 -254.27236) (xy 127.621836 -254.2605)
			(xy 127.572222 -254.241028) (xy 127.526064 -254.214379) (xy 127.484393 -254.181148) (xy 127.448141 -254.142077)
			(xy 127.418117 -254.09804) (xy 127.394991 -254.050019) (xy 127.379281 -253.999089) (xy 127.371338 -253.946385)
			(xy 127.142758 -253.946385) (xy 127.134815 -253.999089) (xy 127.119105 -254.050019) (xy 127.095979 -254.09804)
			(xy 127.065955 -254.142077) (xy 127.029703 -254.181148) (xy 126.988032 -254.214379) (xy 126.941874 -254.241028)
			(xy 126.89226 -254.2605) (xy 126.840298 -254.27236) (xy 126.787148 -254.276344) (xy 126.733998 -254.27236)
			(xy 126.682036 -254.2605) (xy 126.632422 -254.241028) (xy 126.586264 -254.214379) (xy 126.544593 -254.181148)
			(xy 126.508341 -254.142077) (xy 126.478317 -254.09804) (xy 126.455191 -254.050019) (xy 126.439481 -253.999089)
			(xy 126.431538 -253.946385) (xy 126.202958 -253.946385) (xy 126.195015 -253.999089) (xy 126.179305 -254.050019)
			(xy 126.156179 -254.09804) (xy 126.126155 -254.142077) (xy 126.089903 -254.181148) (xy 126.048232 -254.214379)
			(xy 126.002074 -254.241028) (xy 125.95246 -254.2605) (xy 125.900498 -254.27236) (xy 125.847348 -254.276344)
			(xy 125.794198 -254.27236) (xy 125.742236 -254.2605) (xy 125.692622 -254.241028) (xy 125.646464 -254.214379)
			(xy 125.604793 -254.181148) (xy 125.568541 -254.142077) (xy 125.538517 -254.09804) (xy 125.515391 -254.050019)
			(xy 125.499681 -253.999089) (xy 125.491738 -253.946385) (xy 125.263158 -253.946385) (xy 125.255215 -253.999089)
			(xy 125.239505 -254.050019) (xy 125.216379 -254.09804) (xy 125.186355 -254.142077) (xy 125.150103 -254.181148)
			(xy 125.108432 -254.214379) (xy 125.062274 -254.241028) (xy 125.01266 -254.2605) (xy 124.960698 -254.27236)
			(xy 124.907548 -254.276344) (xy 124.854398 -254.27236) (xy 124.802436 -254.2605) (xy 124.752822 -254.241028)
			(xy 124.706664 -254.214379) (xy 124.664993 -254.181148) (xy 124.628741 -254.142077) (xy 124.598717 -254.09804)
			(xy 124.575591 -254.050019) (xy 124.559881 -253.999089) (xy 124.551938 -253.946385) (xy 124.323358 -253.946385)
			(xy 124.315415 -253.999089) (xy 124.299705 -254.050019) (xy 124.276579 -254.09804) (xy 124.246555 -254.142077)
			(xy 124.210303 -254.181148) (xy 124.168632 -254.214379) (xy 124.122474 -254.241028) (xy 124.07286 -254.2605)
			(xy 124.020898 -254.27236) (xy 123.967748 -254.276344) (xy 123.914598 -254.27236) (xy 123.862636 -254.2605)
			(xy 123.813022 -254.241028) (xy 123.766864 -254.214379) (xy 123.725193 -254.181148) (xy 123.688941 -254.142077)
			(xy 123.658917 -254.09804) (xy 123.635791 -254.050019) (xy 123.620081 -253.999089) (xy 123.612138 -253.946385)
			(xy 123.383304 -253.946385) (xy 123.375361 -253.999089) (xy 123.359651 -254.050019) (xy 123.336525 -254.09804)
			(xy 123.306501 -254.142077) (xy 123.270249 -254.181148) (xy 123.228578 -254.214379) (xy 123.18242 -254.241028)
			(xy 123.132806 -254.2605) (xy 123.080844 -254.27236) (xy 123.027694 -254.276344) (xy 122.974544 -254.27236)
			(xy 122.922582 -254.2605) (xy 122.872968 -254.241028) (xy 122.82681 -254.214379) (xy 122.785139 -254.181148)
			(xy 122.748887 -254.142077) (xy 122.718863 -254.09804) (xy 122.695737 -254.050019) (xy 122.680027 -253.999089)
			(xy 122.672084 -253.946385) (xy 122.443758 -253.946385) (xy 122.435815 -253.999089) (xy 122.420105 -254.050019)
			(xy 122.396979 -254.09804) (xy 122.366955 -254.142077) (xy 122.330703 -254.181148) (xy 122.289032 -254.214379)
			(xy 122.242874 -254.241028) (xy 122.19326 -254.2605) (xy 122.141298 -254.27236) (xy 122.088148 -254.276344)
			(xy 122.034998 -254.27236) (xy 121.983036 -254.2605) (xy 121.933422 -254.241028) (xy 121.887264 -254.214379)
			(xy 121.845593 -254.181148) (xy 121.809341 -254.142077) (xy 121.779317 -254.09804) (xy 121.756191 -254.050019)
			(xy 121.740481 -253.999089) (xy 121.732538 -253.946385) (xy 120.62968 -253.946385) (xy 120.62968 -254.559816)
			(xy 120.630112 -254.573398) (xy 120.637279 -254.5996) (xy 120.651102 -254.622984) (xy 120.670602 -254.641895)
			(xy 120.694399 -254.654996) (xy 120.720807 -254.661357) (xy 120.747959 -254.660529) (xy 120.773931 -254.652571)
			(xy 120.785636 -254.645668) (xy 120.80713 -254.632557) (xy 120.853024 -254.611855) (xy 120.901373 -254.597815)
			(xy 120.951217 -254.590717) (xy 120.97639 -254.590296) (xy 121.006713 -254.590902) (xy 121.066481 -254.601181)
			(xy 121.123636 -254.621458) (xy 121.15038 -254.635762) (xy 121.1629 -254.642274) (xy 121.190337 -254.648831)
			(xy 121.218521 -254.647622) (xy 121.245296 -254.638739) (xy 121.268614 -254.622862) (xy 121.286691 -254.601205)
			(xy 121.292874 -254.588518) (xy 121.303707 -254.565282) (xy 121.331063 -254.521923) (xy 121.364358 -254.48294)
			(xy 121.402904 -254.449139) (xy 121.445903 -254.421221) (xy 121.492464 -254.399764) (xy 121.541622 -254.385212)
			(xy 121.59236 -254.377867) (xy 121.617994 -254.377444) (xy 121.644649 -254.377917) (xy 121.697364 -254.385862)
			(xy 121.748306 -254.401574) (xy 121.796337 -254.424704) (xy 121.840384 -254.454734) (xy 121.879463 -254.490994)
			(xy 121.912702 -254.532673) (xy 121.939357 -254.578841) (xy 121.958833 -254.628466) (xy 121.970696 -254.680439)
			(xy 121.97468 -254.7336) (xy 121.972686 -254.760201) (xy 122.202184 -254.760201) (xy 122.202184 -254.706903)
			(xy 122.210127 -254.654199) (xy 122.225837 -254.603269) (xy 122.248963 -254.555248) (xy 122.278987 -254.511211)
			(xy 122.315239 -254.47214) (xy 122.35691 -254.438909) (xy 122.403068 -254.41226) (xy 122.452682 -254.392788)
			(xy 122.504644 -254.380928) (xy 122.557794 -254.376945) (xy 122.610944 -254.380928) (xy 122.662906 -254.392788)
			(xy 122.71252 -254.41226) (xy 122.758678 -254.438909) (xy 122.800349 -254.47214) (xy 122.836601 -254.511211)
			(xy 122.866625 -254.555248) (xy 122.889751 -254.603269) (xy 122.905461 -254.654199) (xy 122.913404 -254.706903)
			(xy 122.913902 -254.733552) (xy 122.913404 -254.760201) (xy 123.141984 -254.760201) (xy 123.141984 -254.706903)
			(xy 123.149927 -254.654199) (xy 123.165637 -254.603269) (xy 123.188763 -254.555248) (xy 123.218787 -254.511211)
			(xy 123.255039 -254.47214) (xy 123.29671 -254.438909) (xy 123.342868 -254.41226) (xy 123.392482 -254.392788)
			(xy 123.444444 -254.380928) (xy 123.497594 -254.376945) (xy 123.550744 -254.380928) (xy 123.602706 -254.392788)
			(xy 123.65232 -254.41226) (xy 123.698478 -254.438909) (xy 123.740149 -254.47214) (xy 123.776401 -254.511211)
			(xy 123.806425 -254.555248) (xy 123.829551 -254.603269) (xy 123.845261 -254.654199) (xy 123.853204 -254.706903)
			(xy 123.853702 -254.733552) (xy 123.853204 -254.760201) (xy 124.082038 -254.760201) (xy 124.082038 -254.706903)
			(xy 124.089981 -254.654199) (xy 124.105691 -254.603269) (xy 124.128817 -254.555248) (xy 124.158841 -254.511211)
			(xy 124.195093 -254.47214) (xy 124.236764 -254.438909) (xy 124.282922 -254.41226) (xy 124.332536 -254.392788)
			(xy 124.384498 -254.380928) (xy 124.437648 -254.376945) (xy 124.490798 -254.380928) (xy 124.54276 -254.392788)
			(xy 124.592374 -254.41226) (xy 124.638532 -254.438909) (xy 124.680203 -254.47214) (xy 124.716455 -254.511211)
			(xy 124.746479 -254.555248) (xy 124.769605 -254.603269) (xy 124.785315 -254.654199) (xy 124.793258 -254.706903)
			(xy 124.793756 -254.733552) (xy 124.793258 -254.760201) (xy 125.021584 -254.760201) (xy 125.021584 -254.706903)
			(xy 125.029527 -254.654199) (xy 125.045237 -254.603269) (xy 125.068363 -254.555248) (xy 125.098387 -254.511211)
			(xy 125.134639 -254.47214) (xy 125.17631 -254.438909) (xy 125.222468 -254.41226) (xy 125.272082 -254.392788)
			(xy 125.324044 -254.380928) (xy 125.377194 -254.376945) (xy 125.430344 -254.380928) (xy 125.482306 -254.392788)
			(xy 125.53192 -254.41226) (xy 125.578078 -254.438909) (xy 125.619749 -254.47214) (xy 125.656001 -254.511211)
			(xy 125.686025 -254.555248) (xy 125.709151 -254.603269) (xy 125.724861 -254.654199) (xy 125.732804 -254.706903)
			(xy 125.733302 -254.733552) (xy 125.732804 -254.760201) (xy 125.961638 -254.760201) (xy 125.961638 -254.706903)
			(xy 125.969581 -254.654199) (xy 125.985291 -254.603269) (xy 126.008417 -254.555248) (xy 126.038441 -254.511211)
			(xy 126.074693 -254.47214) (xy 126.116364 -254.438909) (xy 126.162522 -254.41226) (xy 126.212136 -254.392788)
			(xy 126.264098 -254.380928) (xy 126.317248 -254.376945) (xy 126.370398 -254.380928) (xy 126.42236 -254.392788)
			(xy 126.471974 -254.41226) (xy 126.518132 -254.438909) (xy 126.559803 -254.47214) (xy 126.596055 -254.511211)
			(xy 126.626079 -254.555248) (xy 126.649205 -254.603269) (xy 126.664915 -254.654199) (xy 126.672858 -254.706903)
			(xy 126.673356 -254.733552) (xy 126.672858 -254.760201) (xy 126.901184 -254.760201) (xy 126.901184 -254.706903)
			(xy 126.909127 -254.654199) (xy 126.924837 -254.603269) (xy 126.947963 -254.555248) (xy 126.977987 -254.511211)
			(xy 127.014239 -254.47214) (xy 127.05591 -254.438909) (xy 127.102068 -254.41226) (xy 127.151682 -254.392788)
			(xy 127.203644 -254.380928) (xy 127.256794 -254.376945) (xy 127.309944 -254.380928) (xy 127.361906 -254.392788)
			(xy 127.41152 -254.41226) (xy 127.457678 -254.438909) (xy 127.499349 -254.47214) (xy 127.535601 -254.511211)
			(xy 127.565625 -254.555248) (xy 127.588751 -254.603269) (xy 127.604461 -254.654199) (xy 127.612404 -254.706903)
			(xy 127.612902 -254.733552) (xy 127.612404 -254.760201) (xy 127.840984 -254.760201) (xy 127.840984 -254.706903)
			(xy 127.848927 -254.654199) (xy 127.864637 -254.603269) (xy 127.887763 -254.555248) (xy 127.917787 -254.511211)
			(xy 127.954039 -254.47214) (xy 127.99571 -254.438909) (xy 128.041868 -254.41226) (xy 128.091482 -254.392788)
			(xy 128.143444 -254.380928) (xy 128.196594 -254.376945) (xy 128.249744 -254.380928) (xy 128.301706 -254.392788)
			(xy 128.35132 -254.41226) (xy 128.397478 -254.438909) (xy 128.439149 -254.47214) (xy 128.475401 -254.511211)
			(xy 128.505425 -254.555248) (xy 128.528551 -254.603269) (xy 128.544261 -254.654199) (xy 128.552204 -254.706903)
			(xy 128.552702 -254.733552) (xy 128.552204 -254.760201) (xy 128.780784 -254.760201) (xy 128.780784 -254.706903)
			(xy 128.788727 -254.654199) (xy 128.804437 -254.603269) (xy 128.827563 -254.555248) (xy 128.857587 -254.511211)
			(xy 128.893839 -254.47214) (xy 128.93551 -254.438909) (xy 128.981668 -254.41226) (xy 129.031282 -254.392788)
			(xy 129.083244 -254.380928) (xy 129.136394 -254.376945) (xy 129.189544 -254.380928) (xy 129.241506 -254.392788)
			(xy 129.29112 -254.41226) (xy 129.337278 -254.438909) (xy 129.378949 -254.47214) (xy 129.415201 -254.511211)
			(xy 129.445225 -254.555248) (xy 129.468351 -254.603269) (xy 129.484061 -254.654199) (xy 129.492004 -254.706903)
			(xy 129.492502 -254.733552) (xy 129.492004 -254.760201) (xy 129.720584 -254.760201) (xy 129.720584 -254.706903)
			(xy 129.728527 -254.654199) (xy 129.744237 -254.603269) (xy 129.767363 -254.555248) (xy 129.797387 -254.511211)
			(xy 129.833639 -254.47214) (xy 129.87531 -254.438909) (xy 129.921468 -254.41226) (xy 129.971082 -254.392788)
			(xy 130.023044 -254.380928) (xy 130.076194 -254.376945) (xy 130.129344 -254.380928) (xy 130.181306 -254.392788)
			(xy 130.23092 -254.41226) (xy 130.277078 -254.438909) (xy 130.318749 -254.47214) (xy 130.355001 -254.511211)
			(xy 130.385025 -254.555248) (xy 130.408151 -254.603269) (xy 130.423861 -254.654199) (xy 130.431804 -254.706903)
			(xy 130.432302 -254.733552) (xy 130.431804 -254.760201) (xy 130.660384 -254.760201) (xy 130.660384 -254.706903)
			(xy 130.668327 -254.654199) (xy 130.684037 -254.603269) (xy 130.707163 -254.555248) (xy 130.737187 -254.511211)
			(xy 130.773439 -254.47214) (xy 130.81511 -254.438909) (xy 130.861268 -254.41226) (xy 130.910882 -254.392788)
			(xy 130.962844 -254.380928) (xy 131.015994 -254.376945) (xy 131.069144 -254.380928) (xy 131.121106 -254.392788)
			(xy 131.17072 -254.41226) (xy 131.216878 -254.438909) (xy 131.258549 -254.47214) (xy 131.294801 -254.511211)
			(xy 131.324825 -254.555248) (xy 131.347951 -254.603269) (xy 131.363661 -254.654199) (xy 131.371604 -254.706903)
			(xy 131.372102 -254.733552) (xy 131.371604 -254.760201) (xy 131.600692 -254.760201) (xy 131.600692 -254.706903)
			(xy 131.608635 -254.654199) (xy 131.624345 -254.603269) (xy 131.647471 -254.555248) (xy 131.677495 -254.511211)
			(xy 131.713747 -254.47214) (xy 131.755418 -254.438909) (xy 131.801576 -254.41226) (xy 131.85119 -254.392788)
			(xy 131.903152 -254.380928) (xy 131.956302 -254.376945) (xy 132.009452 -254.380928) (xy 132.061414 -254.392788)
			(xy 132.111028 -254.41226) (xy 132.157186 -254.438909) (xy 132.198857 -254.47214) (xy 132.235109 -254.511211)
			(xy 132.265133 -254.555248) (xy 132.288259 -254.603269) (xy 132.303969 -254.654199) (xy 132.311912 -254.706903)
			(xy 132.31241 -254.733552) (xy 132.311912 -254.760201) (xy 132.540238 -254.760201) (xy 132.540238 -254.706903)
			(xy 132.548181 -254.654199) (xy 132.563891 -254.603269) (xy 132.587017 -254.555248) (xy 132.617041 -254.511211)
			(xy 132.653293 -254.47214) (xy 132.694964 -254.438909) (xy 132.741122 -254.41226) (xy 132.790736 -254.392788)
			(xy 132.842698 -254.380928) (xy 132.895848 -254.376945) (xy 132.948998 -254.380928) (xy 133.00096 -254.392788)
			(xy 133.050574 -254.41226) (xy 133.096732 -254.438909) (xy 133.138403 -254.47214) (xy 133.174655 -254.511211)
			(xy 133.204679 -254.555248) (xy 133.227805 -254.603269) (xy 133.243515 -254.654199) (xy 133.251458 -254.706903)
			(xy 133.251956 -254.733552) (xy 133.251458 -254.760201) (xy 133.479784 -254.760201) (xy 133.479784 -254.706903)
			(xy 133.487727 -254.654199) (xy 133.503437 -254.603269) (xy 133.526563 -254.555248) (xy 133.556587 -254.511211)
			(xy 133.592839 -254.47214) (xy 133.63451 -254.438909) (xy 133.680668 -254.41226) (xy 133.730282 -254.392788)
			(xy 133.782244 -254.380928) (xy 133.835394 -254.376945) (xy 133.888544 -254.380928) (xy 133.940506 -254.392788)
			(xy 133.99012 -254.41226) (xy 134.036278 -254.438909) (xy 134.077949 -254.47214) (xy 134.114201 -254.511211)
			(xy 134.144225 -254.555248) (xy 134.167351 -254.603269) (xy 134.183061 -254.654199) (xy 134.191004 -254.706903)
			(xy 134.191502 -254.733552) (xy 134.191004 -254.760201) (xy 134.419584 -254.760201) (xy 134.419584 -254.706903)
			(xy 134.427527 -254.654199) (xy 134.443237 -254.603269) (xy 134.466363 -254.555248) (xy 134.496387 -254.511211)
			(xy 134.532639 -254.47214) (xy 134.57431 -254.438909) (xy 134.620468 -254.41226) (xy 134.670082 -254.392788)
			(xy 134.722044 -254.380928) (xy 134.775194 -254.376945) (xy 134.828344 -254.380928) (xy 134.880306 -254.392788)
			(xy 134.92992 -254.41226) (xy 134.976078 -254.438909) (xy 135.017749 -254.47214) (xy 135.054001 -254.511211)
			(xy 135.084025 -254.555248) (xy 135.107151 -254.603269) (xy 135.122861 -254.654199) (xy 135.130804 -254.706903)
			(xy 135.131302 -254.733552) (xy 135.130804 -254.760201) (xy 135.122861 -254.812905) (xy 135.107151 -254.863835)
			(xy 135.084025 -254.911856) (xy 135.054001 -254.955893) (xy 135.017749 -254.994964) (xy 134.976078 -255.028195)
			(xy 134.92992 -255.054844) (xy 134.880306 -255.074316) (xy 134.828344 -255.086176) (xy 134.775194 -255.09016)
			(xy 134.722044 -255.086176) (xy 134.670082 -255.074316) (xy 134.620468 -255.054844) (xy 134.57431 -255.028195)
			(xy 134.532639 -254.994964) (xy 134.496387 -254.955893) (xy 134.466363 -254.911856) (xy 134.443237 -254.863835)
			(xy 134.427527 -254.812905) (xy 134.419584 -254.760201) (xy 134.191004 -254.760201) (xy 134.183061 -254.812905)
			(xy 134.167351 -254.863835) (xy 134.144225 -254.911856) (xy 134.114201 -254.955893) (xy 134.077949 -254.994964)
			(xy 134.036278 -255.028195) (xy 133.99012 -255.054844) (xy 133.940506 -255.074316) (xy 133.888544 -255.086176)
			(xy 133.835394 -255.09016) (xy 133.782244 -255.086176) (xy 133.730282 -255.074316) (xy 133.680668 -255.054844)
			(xy 133.63451 -255.028195) (xy 133.592839 -254.994964) (xy 133.556587 -254.955893) (xy 133.526563 -254.911856)
			(xy 133.503437 -254.863835) (xy 133.487727 -254.812905) (xy 133.479784 -254.760201) (xy 133.251458 -254.760201)
			(xy 133.243515 -254.812905) (xy 133.227805 -254.863835) (xy 133.204679 -254.911856) (xy 133.174655 -254.955893)
			(xy 133.138403 -254.994964) (xy 133.096732 -255.028195) (xy 133.050574 -255.054844) (xy 133.00096 -255.074316)
			(xy 132.948998 -255.086176) (xy 132.895848 -255.09016) (xy 132.842698 -255.086176) (xy 132.790736 -255.074316)
			(xy 132.741122 -255.054844) (xy 132.694964 -255.028195) (xy 132.653293 -254.994964) (xy 132.617041 -254.955893)
			(xy 132.587017 -254.911856) (xy 132.563891 -254.863835) (xy 132.548181 -254.812905) (xy 132.540238 -254.760201)
			(xy 132.311912 -254.760201) (xy 132.303969 -254.812905) (xy 132.288259 -254.863835) (xy 132.265133 -254.911856)
			(xy 132.235109 -254.955893) (xy 132.198857 -254.994964) (xy 132.157186 -255.028195) (xy 132.111028 -255.054844)
			(xy 132.061414 -255.074316) (xy 132.009452 -255.086176) (xy 131.956302 -255.09016) (xy 131.903152 -255.086176)
			(xy 131.85119 -255.074316) (xy 131.801576 -255.054844) (xy 131.755418 -255.028195) (xy 131.713747 -254.994964)
			(xy 131.677495 -254.955893) (xy 131.647471 -254.911856) (xy 131.624345 -254.863835) (xy 131.608635 -254.812905)
			(xy 131.600692 -254.760201) (xy 131.371604 -254.760201) (xy 131.363661 -254.812905) (xy 131.347951 -254.863835)
			(xy 131.324825 -254.911856) (xy 131.294801 -254.955893) (xy 131.258549 -254.994964) (xy 131.216878 -255.028195)
			(xy 131.17072 -255.054844) (xy 131.121106 -255.074316) (xy 131.069144 -255.086176) (xy 131.015994 -255.09016)
			(xy 130.962844 -255.086176) (xy 130.910882 -255.074316) (xy 130.861268 -255.054844) (xy 130.81511 -255.028195)
			(xy 130.773439 -254.994964) (xy 130.737187 -254.955893) (xy 130.707163 -254.911856) (xy 130.684037 -254.863835)
			(xy 130.668327 -254.812905) (xy 130.660384 -254.760201) (xy 130.431804 -254.760201) (xy 130.423861 -254.812905)
			(xy 130.408151 -254.863835) (xy 130.385025 -254.911856) (xy 130.355001 -254.955893) (xy 130.318749 -254.994964)
			(xy 130.277078 -255.028195) (xy 130.23092 -255.054844) (xy 130.181306 -255.074316) (xy 130.129344 -255.086176)
			(xy 130.076194 -255.09016) (xy 130.023044 -255.086176) (xy 129.971082 -255.074316) (xy 129.921468 -255.054844)
			(xy 129.87531 -255.028195) (xy 129.833639 -254.994964) (xy 129.797387 -254.955893) (xy 129.767363 -254.911856)
			(xy 129.744237 -254.863835) (xy 129.728527 -254.812905) (xy 129.720584 -254.760201) (xy 129.492004 -254.760201)
			(xy 129.484061 -254.812905) (xy 129.468351 -254.863835) (xy 129.445225 -254.911856) (xy 129.415201 -254.955893)
			(xy 129.378949 -254.994964) (xy 129.337278 -255.028195) (xy 129.29112 -255.054844) (xy 129.241506 -255.074316)
			(xy 129.189544 -255.086176) (xy 129.136394 -255.09016) (xy 129.083244 -255.086176) (xy 129.031282 -255.074316)
			(xy 128.981668 -255.054844) (xy 128.93551 -255.028195) (xy 128.893839 -254.994964) (xy 128.857587 -254.955893)
			(xy 128.827563 -254.911856) (xy 128.804437 -254.863835) (xy 128.788727 -254.812905) (xy 128.780784 -254.760201)
			(xy 128.552204 -254.760201) (xy 128.544261 -254.812905) (xy 128.528551 -254.863835) (xy 128.505425 -254.911856)
			(xy 128.475401 -254.955893) (xy 128.439149 -254.994964) (xy 128.397478 -255.028195) (xy 128.35132 -255.054844)
			(xy 128.301706 -255.074316) (xy 128.249744 -255.086176) (xy 128.196594 -255.09016) (xy 128.143444 -255.086176)
			(xy 128.091482 -255.074316) (xy 128.041868 -255.054844) (xy 127.99571 -255.028195) (xy 127.954039 -254.994964)
			(xy 127.917787 -254.955893) (xy 127.887763 -254.911856) (xy 127.864637 -254.863835) (xy 127.848927 -254.812905)
			(xy 127.840984 -254.760201) (xy 127.612404 -254.760201) (xy 127.604461 -254.812905) (xy 127.588751 -254.863835)
			(xy 127.565625 -254.911856) (xy 127.535601 -254.955893) (xy 127.499349 -254.994964) (xy 127.457678 -255.028195)
			(xy 127.41152 -255.054844) (xy 127.361906 -255.074316) (xy 127.309944 -255.086176) (xy 127.256794 -255.09016)
			(xy 127.203644 -255.086176) (xy 127.151682 -255.074316) (xy 127.102068 -255.054844) (xy 127.05591 -255.028195)
			(xy 127.014239 -254.994964) (xy 126.977987 -254.955893) (xy 126.947963 -254.911856) (xy 126.924837 -254.863835)
			(xy 126.909127 -254.812905) (xy 126.901184 -254.760201) (xy 126.672858 -254.760201) (xy 126.664915 -254.812905)
			(xy 126.649205 -254.863835) (xy 126.626079 -254.911856) (xy 126.596055 -254.955893) (xy 126.559803 -254.994964)
			(xy 126.518132 -255.028195) (xy 126.471974 -255.054844) (xy 126.42236 -255.074316) (xy 126.370398 -255.086176)
			(xy 126.317248 -255.09016) (xy 126.264098 -255.086176) (xy 126.212136 -255.074316) (xy 126.162522 -255.054844)
			(xy 126.116364 -255.028195) (xy 126.074693 -254.994964) (xy 126.038441 -254.955893) (xy 126.008417 -254.911856)
			(xy 125.985291 -254.863835) (xy 125.969581 -254.812905) (xy 125.961638 -254.760201) (xy 125.732804 -254.760201)
			(xy 125.724861 -254.812905) (xy 125.709151 -254.863835) (xy 125.686025 -254.911856) (xy 125.656001 -254.955893)
			(xy 125.619749 -254.994964) (xy 125.578078 -255.028195) (xy 125.53192 -255.054844) (xy 125.482306 -255.074316)
			(xy 125.430344 -255.086176) (xy 125.377194 -255.09016) (xy 125.324044 -255.086176) (xy 125.272082 -255.074316)
			(xy 125.222468 -255.054844) (xy 125.17631 -255.028195) (xy 125.134639 -254.994964) (xy 125.098387 -254.955893)
			(xy 125.068363 -254.911856) (xy 125.045237 -254.863835) (xy 125.029527 -254.812905) (xy 125.021584 -254.760201)
			(xy 124.793258 -254.760201) (xy 124.785315 -254.812905) (xy 124.769605 -254.863835) (xy 124.746479 -254.911856)
			(xy 124.716455 -254.955893) (xy 124.680203 -254.994964) (xy 124.638532 -255.028195) (xy 124.592374 -255.054844)
			(xy 124.54276 -255.074316) (xy 124.490798 -255.086176) (xy 124.437648 -255.09016) (xy 124.384498 -255.086176)
			(xy 124.332536 -255.074316) (xy 124.282922 -255.054844) (xy 124.236764 -255.028195) (xy 124.195093 -254.994964)
			(xy 124.158841 -254.955893) (xy 124.128817 -254.911856) (xy 124.105691 -254.863835) (xy 124.089981 -254.812905)
			(xy 124.082038 -254.760201) (xy 123.853204 -254.760201) (xy 123.845261 -254.812905) (xy 123.829551 -254.863835)
			(xy 123.806425 -254.911856) (xy 123.776401 -254.955893) (xy 123.740149 -254.994964) (xy 123.698478 -255.028195)
			(xy 123.65232 -255.054844) (xy 123.602706 -255.074316) (xy 123.550744 -255.086176) (xy 123.497594 -255.09016)
			(xy 123.444444 -255.086176) (xy 123.392482 -255.074316) (xy 123.342868 -255.054844) (xy 123.29671 -255.028195)
			(xy 123.255039 -254.994964) (xy 123.218787 -254.955893) (xy 123.188763 -254.911856) (xy 123.165637 -254.863835)
			(xy 123.149927 -254.812905) (xy 123.141984 -254.760201) (xy 122.913404 -254.760201) (xy 122.905461 -254.812905)
			(xy 122.889751 -254.863835) (xy 122.866625 -254.911856) (xy 122.836601 -254.955893) (xy 122.800349 -254.994964)
			(xy 122.758678 -255.028195) (xy 122.71252 -255.054844) (xy 122.662906 -255.074316) (xy 122.610944 -255.086176)
			(xy 122.557794 -255.09016) (xy 122.504644 -255.086176) (xy 122.452682 -255.074316) (xy 122.403068 -255.054844)
			(xy 122.35691 -255.028195) (xy 122.315239 -254.994964) (xy 122.278987 -254.955893) (xy 122.248963 -254.911856)
			(xy 122.225837 -254.863835) (xy 122.210127 -254.812905) (xy 122.202184 -254.760201) (xy 121.972686 -254.760201)
			(xy 121.970696 -254.786761) (xy 121.958833 -254.838734) (xy 121.939357 -254.888359) (xy 121.912702 -254.934527)
			(xy 121.879463 -254.976206) (xy 121.840384 -255.012466) (xy 121.796337 -255.042496) (xy 121.748306 -255.065626)
			(xy 121.697364 -255.081338) (xy 121.644649 -255.089283) (xy 121.617994 -255.08966) (xy 121.587672 -255.089052)
			(xy 121.527905 -255.07877) (xy 121.470753 -255.058489) (xy 121.444004 -255.044194) (xy 121.431482 -255.037667)
			(xy 121.404033 -255.031084) (xy 121.375831 -255.032277) (xy 121.349036 -255.041154) (xy 121.325701 -255.057035)
			(xy 121.307612 -255.078705) (xy 121.30151 -255.091438) (xy 121.291275 -255.113479) (xy 121.26566 -255.154776)
			(xy 121.250456 -255.173734) (xy 121.241831 -255.184864) (xy 121.230486 -255.210624) (xy 121.226607 -255.238503)
			(xy 121.230488 -255.266382) (xy 121.241834 -255.292141) (xy 121.250456 -255.303274) (xy 121.265891 -255.322522)
			(xy 121.291861 -255.364473) (xy 121.311784 -255.40961) (xy 121.325277 -255.457068) (xy 121.332082 -255.505935)
			(xy 121.332498 -255.530604) (xy 121.331977 -255.558589) (xy 121.329493 -255.574271) (xy 122.672338 -255.574271)
			(xy 122.672338 -255.520973) (xy 122.680281 -255.468269) (xy 122.695991 -255.417339) (xy 122.719117 -255.369318)
			(xy 122.749141 -255.325281) (xy 122.785393 -255.28621) (xy 122.827064 -255.252979) (xy 122.873222 -255.22633)
			(xy 122.922836 -255.206858) (xy 122.974798 -255.194998) (xy 123.027948 -255.191015) (xy 123.081098 -255.194998)
			(xy 123.13306 -255.206858) (xy 123.182674 -255.22633) (xy 123.228832 -255.252979) (xy 123.270503 -255.28621)
			(xy 123.306755 -255.325281) (xy 123.336779 -255.369318) (xy 123.359905 -255.417339) (xy 123.375615 -255.468269)
			(xy 123.383558 -255.520973) (xy 123.384056 -255.547622) (xy 123.383558 -255.574271) (xy 123.612138 -255.574271)
			(xy 123.612138 -255.520973) (xy 123.620081 -255.468269) (xy 123.635791 -255.417339) (xy 123.658917 -255.369318)
			(xy 123.688941 -255.325281) (xy 123.725193 -255.28621) (xy 123.766864 -255.252979) (xy 123.813022 -255.22633)
			(xy 123.862636 -255.206858) (xy 123.914598 -255.194998) (xy 123.967748 -255.191015) (xy 124.020898 -255.194998)
			(xy 124.07286 -255.206858) (xy 124.122474 -255.22633) (xy 124.168632 -255.252979) (xy 124.210303 -255.28621)
			(xy 124.246555 -255.325281) (xy 124.276579 -255.369318) (xy 124.299705 -255.417339) (xy 124.315415 -255.468269)
			(xy 124.323358 -255.520973) (xy 124.323856 -255.547622) (xy 124.323358 -255.574271) (xy 124.551684 -255.574271)
			(xy 124.551684 -255.520973) (xy 124.559627 -255.468269) (xy 124.575337 -255.417339) (xy 124.598463 -255.369318)
			(xy 124.628487 -255.325281) (xy 124.664739 -255.28621) (xy 124.70641 -255.252979) (xy 124.752568 -255.22633)
			(xy 124.802182 -255.206858) (xy 124.854144 -255.194998) (xy 124.907294 -255.191015) (xy 124.960444 -255.194998)
			(xy 125.012406 -255.206858) (xy 125.06202 -255.22633) (xy 125.108178 -255.252979) (xy 125.149849 -255.28621)
			(xy 125.186101 -255.325281) (xy 125.216125 -255.369318) (xy 125.239251 -255.417339) (xy 125.254961 -255.468269)
			(xy 125.262904 -255.520973) (xy 125.263402 -255.547622) (xy 125.262904 -255.574271) (xy 125.491738 -255.574271)
			(xy 125.491738 -255.520973) (xy 125.499681 -255.468269) (xy 125.515391 -255.417339) (xy 125.538517 -255.369318)
			(xy 125.568541 -255.325281) (xy 125.604793 -255.28621) (xy 125.646464 -255.252979) (xy 125.692622 -255.22633)
			(xy 125.742236 -255.206858) (xy 125.794198 -255.194998) (xy 125.847348 -255.191015) (xy 125.900498 -255.194998)
			(xy 125.95246 -255.206858) (xy 126.002074 -255.22633) (xy 126.048232 -255.252979) (xy 126.089903 -255.28621)
			(xy 126.126155 -255.325281) (xy 126.156179 -255.369318) (xy 126.179305 -255.417339) (xy 126.195015 -255.468269)
			(xy 126.202958 -255.520973) (xy 126.203456 -255.547622) (xy 126.202958 -255.574271) (xy 126.431284 -255.574271)
			(xy 126.431284 -255.520973) (xy 126.439227 -255.468269) (xy 126.454937 -255.417339) (xy 126.478063 -255.369318)
			(xy 126.508087 -255.325281) (xy 126.544339 -255.28621) (xy 126.58601 -255.252979) (xy 126.632168 -255.22633)
			(xy 126.681782 -255.206858) (xy 126.733744 -255.194998) (xy 126.786894 -255.191015) (xy 126.840044 -255.194998)
			(xy 126.892006 -255.206858) (xy 126.94162 -255.22633) (xy 126.987778 -255.252979) (xy 127.029449 -255.28621)
			(xy 127.065701 -255.325281) (xy 127.095725 -255.369318) (xy 127.118851 -255.417339) (xy 127.134561 -255.468269)
			(xy 127.142504 -255.520973) (xy 127.143002 -255.547622) (xy 127.383035 -255.547622) (xy 127.387065 -255.495124)
			(xy 127.399062 -255.443856) (xy 127.418745 -255.395021) (xy 127.445651 -255.349762) (xy 127.479151 -255.309141)
			(xy 127.518459 -255.27411) (xy 127.562654 -255.24549) (xy 127.610699 -255.223951) (xy 127.66147 -255.209999)
			(xy 127.713775 -255.203961) (xy 127.766389 -255.205978) (xy 127.818079 -255.216002) (xy 127.867632 -255.2338)
			(xy 127.913888 -255.258953) (xy 127.955762 -255.290872) (xy 127.992274 -255.32881) (xy 128.022566 -255.371876)
			(xy 128.045929 -255.419061) (xy 128.061815 -255.46926) (xy 128.069852 -255.521296) (xy 128.070356 -255.547622)
			(xy 128.069852 -255.573948) (xy 128.069802 -255.574271) (xy 128.311138 -255.574271) (xy 128.311138 -255.520973)
			(xy 128.319081 -255.468269) (xy 128.334791 -255.417339) (xy 128.357917 -255.369318) (xy 128.387941 -255.325281)
			(xy 128.424193 -255.28621) (xy 128.465864 -255.252979) (xy 128.512022 -255.22633) (xy 128.561636 -255.206858)
			(xy 128.613598 -255.194998) (xy 128.666748 -255.191015) (xy 128.719898 -255.194998) (xy 128.77186 -255.206858)
			(xy 128.821474 -255.22633) (xy 128.867632 -255.252979) (xy 128.909303 -255.28621) (xy 128.945555 -255.325281)
			(xy 128.975579 -255.369318) (xy 128.998705 -255.417339) (xy 129.014415 -255.468269) (xy 129.022358 -255.520973)
			(xy 129.022856 -255.547622) (xy 129.022358 -255.574271) (xy 129.250938 -255.574271) (xy 129.250938 -255.520973)
			(xy 129.258881 -255.468269) (xy 129.274591 -255.417339) (xy 129.297717 -255.369318) (xy 129.327741 -255.325281)
			(xy 129.363993 -255.28621) (xy 129.405664 -255.252979) (xy 129.451822 -255.22633) (xy 129.501436 -255.206858)
			(xy 129.553398 -255.194998) (xy 129.606548 -255.191015) (xy 129.659698 -255.194998) (xy 129.71166 -255.206858)
			(xy 129.761274 -255.22633) (xy 129.807432 -255.252979) (xy 129.849103 -255.28621) (xy 129.885355 -255.325281)
			(xy 129.915379 -255.369318) (xy 129.938505 -255.417339) (xy 129.954215 -255.468269) (xy 129.962158 -255.520973)
			(xy 129.962656 -255.547622) (xy 129.962158 -255.574271) (xy 130.190738 -255.574271) (xy 130.190738 -255.520973)
			(xy 130.198681 -255.468269) (xy 130.214391 -255.417339) (xy 130.237517 -255.369318) (xy 130.267541 -255.325281)
			(xy 130.303793 -255.28621) (xy 130.345464 -255.252979) (xy 130.391622 -255.22633) (xy 130.441236 -255.206858)
			(xy 130.493198 -255.194998) (xy 130.546348 -255.191015) (xy 130.599498 -255.194998) (xy 130.65146 -255.206858)
			(xy 130.701074 -255.22633) (xy 130.747232 -255.252979) (xy 130.788903 -255.28621) (xy 130.825155 -255.325281)
			(xy 130.855179 -255.369318) (xy 130.878305 -255.417339) (xy 130.894015 -255.468269) (xy 130.901958 -255.520973)
			(xy 130.902456 -255.547622) (xy 130.901958 -255.574271) (xy 131.130538 -255.574271) (xy 131.130538 -255.520973)
			(xy 131.138481 -255.468269) (xy 131.154191 -255.417339) (xy 131.177317 -255.369318) (xy 131.207341 -255.325281)
			(xy 131.243593 -255.28621) (xy 131.285264 -255.252979) (xy 131.331422 -255.22633) (xy 131.381036 -255.206858)
			(xy 131.432998 -255.194998) (xy 131.486148 -255.191015) (xy 131.539298 -255.194998) (xy 131.59126 -255.206858)
			(xy 131.640874 -255.22633) (xy 131.687032 -255.252979) (xy 131.728703 -255.28621) (xy 131.764955 -255.325281)
			(xy 131.794979 -255.369318) (xy 131.818105 -255.417339) (xy 131.833815 -255.468269) (xy 131.841758 -255.520973)
			(xy 131.842256 -255.547622) (xy 131.841758 -255.574271) (xy 132.070338 -255.574271) (xy 132.070338 -255.520973)
			(xy 132.078281 -255.468269) (xy 132.093991 -255.417339) (xy 132.117117 -255.369318) (xy 132.147141 -255.325281)
			(xy 132.183393 -255.28621) (xy 132.225064 -255.252979) (xy 132.271222 -255.22633) (xy 132.320836 -255.206858)
			(xy 132.372798 -255.194998) (xy 132.425948 -255.191015) (xy 132.479098 -255.194998) (xy 132.53106 -255.206858)
			(xy 132.580674 -255.22633) (xy 132.626832 -255.252979) (xy 132.668503 -255.28621) (xy 132.704755 -255.325281)
			(xy 132.734779 -255.369318) (xy 132.757905 -255.417339) (xy 132.773615 -255.468269) (xy 132.781558 -255.520973)
			(xy 132.782056 -255.547622) (xy 132.781558 -255.574271) (xy 133.009884 -255.574271) (xy 133.009884 -255.520973)
			(xy 133.017827 -255.468269) (xy 133.033537 -255.417339) (xy 133.056663 -255.369318) (xy 133.086687 -255.325281)
			(xy 133.122939 -255.28621) (xy 133.16461 -255.252979) (xy 133.210768 -255.22633) (xy 133.260382 -255.206858)
			(xy 133.312344 -255.194998) (xy 133.365494 -255.191015) (xy 133.418644 -255.194998) (xy 133.470606 -255.206858)
			(xy 133.52022 -255.22633) (xy 133.566378 -255.252979) (xy 133.608049 -255.28621) (xy 133.644301 -255.325281)
			(xy 133.674325 -255.369318) (xy 133.697451 -255.417339) (xy 133.713161 -255.468269) (xy 133.721104 -255.520973)
			(xy 133.721602 -255.547622) (xy 133.721104 -255.574271) (xy 133.949938 -255.574271) (xy 133.949938 -255.520973)
			(xy 133.957881 -255.468269) (xy 133.973591 -255.417339) (xy 133.996717 -255.369318) (xy 134.026741 -255.325281)
			(xy 134.062993 -255.28621) (xy 134.104664 -255.252979) (xy 134.150822 -255.22633) (xy 134.200436 -255.206858)
			(xy 134.252398 -255.194998) (xy 134.305548 -255.191015) (xy 134.358698 -255.194998) (xy 134.41066 -255.206858)
			(xy 134.460274 -255.22633) (xy 134.506432 -255.252979) (xy 134.548103 -255.28621) (xy 134.584355 -255.325281)
			(xy 134.614379 -255.369318) (xy 134.637505 -255.417339) (xy 134.653215 -255.468269) (xy 134.661158 -255.520973)
			(xy 134.661656 -255.547622) (xy 134.661158 -255.574271) (xy 134.653215 -255.626975) (xy 134.637505 -255.677905)
			(xy 134.614379 -255.725926) (xy 134.584355 -255.769963) (xy 134.548103 -255.809034) (xy 134.506432 -255.842265)
			(xy 134.460274 -255.868914) (xy 134.41066 -255.888386) (xy 134.358698 -255.900246) (xy 134.305548 -255.90423)
			(xy 134.252398 -255.900246) (xy 134.200436 -255.888386) (xy 134.150822 -255.868914) (xy 134.104664 -255.842265)
			(xy 134.062993 -255.809034) (xy 134.026741 -255.769963) (xy 133.996717 -255.725926) (xy 133.973591 -255.677905)
			(xy 133.957881 -255.626975) (xy 133.949938 -255.574271) (xy 133.721104 -255.574271) (xy 133.713161 -255.626975)
			(xy 133.697451 -255.677905) (xy 133.674325 -255.725926) (xy 133.644301 -255.769963) (xy 133.608049 -255.809034)
			(xy 133.566378 -255.842265) (xy 133.52022 -255.868914) (xy 133.470606 -255.888386) (xy 133.418644 -255.900246)
			(xy 133.365494 -255.90423) (xy 133.312344 -255.900246) (xy 133.260382 -255.888386) (xy 133.210768 -255.868914)
			(xy 133.16461 -255.842265) (xy 133.122939 -255.809034) (xy 133.086687 -255.769963) (xy 133.056663 -255.725926)
			(xy 133.033537 -255.677905) (xy 133.017827 -255.626975) (xy 133.009884 -255.574271) (xy 132.781558 -255.574271)
			(xy 132.773615 -255.626975) (xy 132.757905 -255.677905) (xy 132.734779 -255.725926) (xy 132.704755 -255.769963)
			(xy 132.668503 -255.809034) (xy 132.626832 -255.842265) (xy 132.580674 -255.868914) (xy 132.53106 -255.888386)
			(xy 132.479098 -255.900246) (xy 132.425948 -255.90423) (xy 132.372798 -255.900246) (xy 132.320836 -255.888386)
			(xy 132.271222 -255.868914) (xy 132.225064 -255.842265) (xy 132.183393 -255.809034) (xy 132.147141 -255.769963)
			(xy 132.117117 -255.725926) (xy 132.093991 -255.677905) (xy 132.078281 -255.626975) (xy 132.070338 -255.574271)
			(xy 131.841758 -255.574271) (xy 131.833815 -255.626975) (xy 131.818105 -255.677905) (xy 131.794979 -255.725926)
			(xy 131.764955 -255.769963) (xy 131.728703 -255.809034) (xy 131.687032 -255.842265) (xy 131.640874 -255.868914)
			(xy 131.59126 -255.888386) (xy 131.539298 -255.900246) (xy 131.486148 -255.90423) (xy 131.432998 -255.900246)
			(xy 131.381036 -255.888386) (xy 131.331422 -255.868914) (xy 131.285264 -255.842265) (xy 131.243593 -255.809034)
			(xy 131.207341 -255.769963) (xy 131.177317 -255.725926) (xy 131.154191 -255.677905) (xy 131.138481 -255.626975)
			(xy 131.130538 -255.574271) (xy 130.901958 -255.574271) (xy 130.894015 -255.626975) (xy 130.878305 -255.677905)
			(xy 130.855179 -255.725926) (xy 130.825155 -255.769963) (xy 130.788903 -255.809034) (xy 130.747232 -255.842265)
			(xy 130.701074 -255.868914) (xy 130.65146 -255.888386) (xy 130.599498 -255.900246) (xy 130.546348 -255.90423)
			(xy 130.493198 -255.900246) (xy 130.441236 -255.888386) (xy 130.391622 -255.868914) (xy 130.345464 -255.842265)
			(xy 130.303793 -255.809034) (xy 130.267541 -255.769963) (xy 130.237517 -255.725926) (xy 130.214391 -255.677905)
			(xy 130.198681 -255.626975) (xy 130.190738 -255.574271) (xy 129.962158 -255.574271) (xy 129.954215 -255.626975)
			(xy 129.938505 -255.677905) (xy 129.915379 -255.725926) (xy 129.885355 -255.769963) (xy 129.849103 -255.809034)
			(xy 129.807432 -255.842265) (xy 129.761274 -255.868914) (xy 129.71166 -255.888386) (xy 129.659698 -255.900246)
			(xy 129.606548 -255.90423) (xy 129.553398 -255.900246) (xy 129.501436 -255.888386) (xy 129.451822 -255.868914)
			(xy 129.405664 -255.842265) (xy 129.363993 -255.809034) (xy 129.327741 -255.769963) (xy 129.297717 -255.725926)
			(xy 129.274591 -255.677905) (xy 129.258881 -255.626975) (xy 129.250938 -255.574271) (xy 129.022358 -255.574271)
			(xy 129.014415 -255.626975) (xy 128.998705 -255.677905) (xy 128.975579 -255.725926) (xy 128.945555 -255.769963)
			(xy 128.909303 -255.809034) (xy 128.867632 -255.842265) (xy 128.821474 -255.868914) (xy 128.77186 -255.888386)
			(xy 128.719898 -255.900246) (xy 128.666748 -255.90423) (xy 128.613598 -255.900246) (xy 128.561636 -255.888386)
			(xy 128.512022 -255.868914) (xy 128.465864 -255.842265) (xy 128.424193 -255.809034) (xy 128.387941 -255.769963)
			(xy 128.357917 -255.725926) (xy 128.334791 -255.677905) (xy 128.319081 -255.626975) (xy 128.311138 -255.574271)
			(xy 128.069802 -255.574271) (xy 128.061815 -255.625984) (xy 128.045929 -255.676183) (xy 128.022566 -255.723368)
			(xy 127.992274 -255.766434) (xy 127.955762 -255.804372) (xy 127.913888 -255.836291) (xy 127.867632 -255.861444)
			(xy 127.818079 -255.879242) (xy 127.766389 -255.889266) (xy 127.713775 -255.891283) (xy 127.66147 -255.885245)
			(xy 127.610699 -255.871293) (xy 127.562654 -255.849754) (xy 127.518459 -255.821134) (xy 127.479151 -255.786103)
			(xy 127.445651 -255.745482) (xy 127.418745 -255.700223) (xy 127.399062 -255.651388) (xy 127.387065 -255.60012)
			(xy 127.383035 -255.547622) (xy 127.143002 -255.547622) (xy 127.142504 -255.574271) (xy 127.134561 -255.626975)
			(xy 127.118851 -255.677905) (xy 127.095725 -255.725926) (xy 127.065701 -255.769963) (xy 127.029449 -255.809034)
			(xy 126.987778 -255.842265) (xy 126.94162 -255.868914) (xy 126.892006 -255.888386) (xy 126.840044 -255.900246)
			(xy 126.786894 -255.90423) (xy 126.733744 -255.900246) (xy 126.681782 -255.888386) (xy 126.632168 -255.868914)
			(xy 126.58601 -255.842265) (xy 126.544339 -255.809034) (xy 126.508087 -255.769963) (xy 126.478063 -255.725926)
			(xy 126.454937 -255.677905) (xy 126.439227 -255.626975) (xy 126.431284 -255.574271) (xy 126.202958 -255.574271)
			(xy 126.195015 -255.626975) (xy 126.179305 -255.677905) (xy 126.156179 -255.725926) (xy 126.126155 -255.769963)
			(xy 126.089903 -255.809034) (xy 126.048232 -255.842265) (xy 126.002074 -255.868914) (xy 125.95246 -255.888386)
			(xy 125.900498 -255.900246) (xy 125.847348 -255.90423) (xy 125.794198 -255.900246) (xy 125.742236 -255.888386)
			(xy 125.692622 -255.868914) (xy 125.646464 -255.842265) (xy 125.604793 -255.809034) (xy 125.568541 -255.769963)
			(xy 125.538517 -255.725926) (xy 125.515391 -255.677905) (xy 125.499681 -255.626975) (xy 125.491738 -255.574271)
			(xy 125.262904 -255.574271) (xy 125.254961 -255.626975) (xy 125.239251 -255.677905) (xy 125.216125 -255.725926)
			(xy 125.186101 -255.769963) (xy 125.149849 -255.809034) (xy 125.108178 -255.842265) (xy 125.06202 -255.868914)
			(xy 125.012406 -255.888386) (xy 124.960444 -255.900246) (xy 124.907294 -255.90423) (xy 124.854144 -255.900246)
			(xy 124.802182 -255.888386) (xy 124.752568 -255.868914) (xy 124.70641 -255.842265) (xy 124.664739 -255.809034)
			(xy 124.628487 -255.769963) (xy 124.598463 -255.725926) (xy 124.575337 -255.677905) (xy 124.559627 -255.626975)
			(xy 124.551684 -255.574271) (xy 124.323358 -255.574271) (xy 124.315415 -255.626975) (xy 124.299705 -255.677905)
			(xy 124.276579 -255.725926) (xy 124.246555 -255.769963) (xy 124.210303 -255.809034) (xy 124.168632 -255.842265)
			(xy 124.122474 -255.868914) (xy 124.07286 -255.888386) (xy 124.020898 -255.900246) (xy 123.967748 -255.90423)
			(xy 123.914598 -255.900246) (xy 123.862636 -255.888386) (xy 123.813022 -255.868914) (xy 123.766864 -255.842265)
			(xy 123.725193 -255.809034) (xy 123.688941 -255.769963) (xy 123.658917 -255.725926) (xy 123.635791 -255.677905)
			(xy 123.620081 -255.626975) (xy 123.612138 -255.574271) (xy 123.383558 -255.574271) (xy 123.375615 -255.626975)
			(xy 123.359905 -255.677905) (xy 123.336779 -255.725926) (xy 123.306755 -255.769963) (xy 123.270503 -255.809034)
			(xy 123.228832 -255.842265) (xy 123.182674 -255.868914) (xy 123.13306 -255.888386) (xy 123.081098 -255.900246)
			(xy 123.027948 -255.90423) (xy 122.974798 -255.900246) (xy 122.922836 -255.888386) (xy 122.873222 -255.868914)
			(xy 122.827064 -255.842265) (xy 122.785393 -255.809034) (xy 122.749141 -255.769963) (xy 122.719117 -255.725926)
			(xy 122.695991 -255.677905) (xy 122.680281 -255.626975) (xy 122.672338 -255.574271) (xy 121.329493 -255.574271)
			(xy 121.323221 -255.613869) (xy 121.305924 -255.667099) (xy 121.280514 -255.716968) (xy 121.247615 -255.762248)
			(xy 121.208038 -255.801824) (xy 121.162756 -255.834721) (xy 121.112887 -255.86013) (xy 121.059656 -255.877424)
			(xy 121.004375 -255.886178) (xy 120.97639 -255.886712) (xy 120.951218 -255.886277) (xy 120.901375 -255.879185)
			(xy 120.853028 -255.865143) (xy 120.80714 -255.844433) (xy 120.785636 -255.83134) (xy 120.77393 -255.824441)
			(xy 120.747959 -255.816482) (xy 120.720809 -255.815654) (xy 120.694402 -255.822015) (xy 120.670607 -255.835115)
			(xy 120.651108 -255.854026) (xy 120.637287 -255.87741) (xy 120.630122 -255.903611) (xy 120.62968 -255.917192)
			(xy 120.62968 -256.28219) (xy 120.630103 -256.295812) (xy 120.637293 -256.322089) (xy 120.651188 -256.345522)
			(xy 120.670795 -256.364436) (xy 120.694714 -256.377479) (xy 120.721233 -256.383718) (xy 120.748457 -256.382708)
			(xy 120.774441 -256.37452) (xy 120.786144 -256.367534) (xy 120.807804 -256.354118) (xy 120.854143 -256.33294)
			(xy 120.903025 -256.318578) (xy 120.953455 -256.311325) (xy 120.97893 -256.310892) (xy 121.005003 -256.311349)
			(xy 121.056591 -256.318958) (xy 121.106517 -256.334009) (xy 121.130314 -256.344674) (xy 121.144123 -256.350578)
			(xy 121.173828 -256.3549) (xy 121.203504 -256.350388) (xy 121.230582 -256.337433) (xy 121.252716 -256.317157)
			(xy 121.26799 -256.291316) (xy 121.272046 -256.276856) (xy 121.278764 -256.251376) (xy 121.298684 -256.202595)
			(xy 121.325575 -256.157281) (xy 121.358852 -256.116426) (xy 121.397786 -256.080922) (xy 121.441528 -256.051543)
			(xy 121.489122 -256.028933) (xy 121.539529 -256.013584) (xy 121.591648 -256.005831) (xy 121.617994 -256.00533)
			(xy 121.644643 -256.005803) (xy 121.697345 -256.013745) (xy 121.748274 -256.029454) (xy 121.796294 -256.052579)
			(xy 121.84033 -256.082601) (xy 121.8794 -256.118852) (xy 121.91263 -256.160522) (xy 121.939279 -256.206678)
			(xy 121.958751 -256.256291) (xy 121.970611 -256.308252) (xy 121.974594 -256.3614) (xy 121.972594 -256.388087)
			(xy 122.202438 -256.388087) (xy 122.202438 -256.334789) (xy 122.210381 -256.282085) (xy 122.226091 -256.231155)
			(xy 122.249217 -256.183134) (xy 122.279241 -256.139097) (xy 122.315493 -256.100026) (xy 122.357164 -256.066795)
			(xy 122.403322 -256.040146) (xy 122.452936 -256.020674) (xy 122.504898 -256.008814) (xy 122.558048 -256.004831)
			(xy 122.611198 -256.008814) (xy 122.66316 -256.020674) (xy 122.712774 -256.040146) (xy 122.758932 -256.066795)
			(xy 122.800603 -256.100026) (xy 122.836855 -256.139097) (xy 122.866879 -256.183134) (xy 122.890005 -256.231155)
			(xy 122.905715 -256.282085) (xy 122.913658 -256.334789) (xy 122.914156 -256.361438) (xy 122.913658 -256.388087)
			(xy 123.141984 -256.388087) (xy 123.141984 -256.334789) (xy 123.149927 -256.282085) (xy 123.165637 -256.231155)
			(xy 123.188763 -256.183134) (xy 123.218787 -256.139097) (xy 123.255039 -256.100026) (xy 123.29671 -256.066795)
			(xy 123.342868 -256.040146) (xy 123.392482 -256.020674) (xy 123.444444 -256.008814) (xy 123.497594 -256.004831)
			(xy 123.550744 -256.008814) (xy 123.602706 -256.020674) (xy 123.65232 -256.040146) (xy 123.698478 -256.066795)
			(xy 123.740149 -256.100026) (xy 123.776401 -256.139097) (xy 123.806425 -256.183134) (xy 123.829551 -256.231155)
			(xy 123.845261 -256.282085) (xy 123.853204 -256.334789) (xy 123.853702 -256.361438) (xy 123.853204 -256.388087)
			(xy 124.081784 -256.388087) (xy 124.081784 -256.334789) (xy 124.089727 -256.282085) (xy 124.105437 -256.231155)
			(xy 124.128563 -256.183134) (xy 124.158587 -256.139097) (xy 124.194839 -256.100026) (xy 124.23651 -256.066795)
			(xy 124.282668 -256.040146) (xy 124.332282 -256.020674) (xy 124.384244 -256.008814) (xy 124.437394 -256.004831)
			(xy 124.490544 -256.008814) (xy 124.542506 -256.020674) (xy 124.59212 -256.040146) (xy 124.638278 -256.066795)
			(xy 124.679949 -256.100026) (xy 124.716201 -256.139097) (xy 124.746225 -256.183134) (xy 124.769351 -256.231155)
			(xy 124.785061 -256.282085) (xy 124.793004 -256.334789) (xy 124.793502 -256.361438) (xy 124.793004 -256.388087)
			(xy 125.021584 -256.388087) (xy 125.021584 -256.334789) (xy 125.029527 -256.282085) (xy 125.045237 -256.231155)
			(xy 125.068363 -256.183134) (xy 125.098387 -256.139097) (xy 125.134639 -256.100026) (xy 125.17631 -256.066795)
			(xy 125.222468 -256.040146) (xy 125.272082 -256.020674) (xy 125.324044 -256.008814) (xy 125.377194 -256.004831)
			(xy 125.430344 -256.008814) (xy 125.482306 -256.020674) (xy 125.53192 -256.040146) (xy 125.578078 -256.066795)
			(xy 125.619749 -256.100026) (xy 125.656001 -256.139097) (xy 125.686025 -256.183134) (xy 125.709151 -256.231155)
			(xy 125.724861 -256.282085) (xy 125.732804 -256.334789) (xy 125.733302 -256.361438) (xy 125.732804 -256.388087)
			(xy 125.961384 -256.388087) (xy 125.961384 -256.334789) (xy 125.969327 -256.282085) (xy 125.985037 -256.231155)
			(xy 126.008163 -256.183134) (xy 126.038187 -256.139097) (xy 126.074439 -256.100026) (xy 126.11611 -256.066795)
			(xy 126.162268 -256.040146) (xy 126.211882 -256.020674) (xy 126.263844 -256.008814) (xy 126.316994 -256.004831)
			(xy 126.370144 -256.008814) (xy 126.422106 -256.020674) (xy 126.47172 -256.040146) (xy 126.517878 -256.066795)
			(xy 126.559549 -256.100026) (xy 126.595801 -256.139097) (xy 126.625825 -256.183134) (xy 126.648951 -256.231155)
			(xy 126.664661 -256.282085) (xy 126.672604 -256.334789) (xy 126.673102 -256.361438) (xy 126.672604 -256.388087)
			(xy 126.901184 -256.388087) (xy 126.901184 -256.334789) (xy 126.909127 -256.282085) (xy 126.924837 -256.231155)
			(xy 126.947963 -256.183134) (xy 126.977987 -256.139097) (xy 127.014239 -256.100026) (xy 127.05591 -256.066795)
			(xy 127.102068 -256.040146) (xy 127.151682 -256.020674) (xy 127.203644 -256.008814) (xy 127.256794 -256.004831)
			(xy 127.309944 -256.008814) (xy 127.361906 -256.020674) (xy 127.41152 -256.040146) (xy 127.457678 -256.066795)
			(xy 127.499349 -256.100026) (xy 127.535601 -256.139097) (xy 127.565625 -256.183134) (xy 127.588751 -256.231155)
			(xy 127.604461 -256.282085) (xy 127.612404 -256.334789) (xy 127.612902 -256.361438) (xy 127.612404 -256.388087)
			(xy 127.840984 -256.388087) (xy 127.840984 -256.334789) (xy 127.848927 -256.282085) (xy 127.864637 -256.231155)
			(xy 127.887763 -256.183134) (xy 127.917787 -256.139097) (xy 127.954039 -256.100026) (xy 127.99571 -256.066795)
			(xy 128.041868 -256.040146) (xy 128.091482 -256.020674) (xy 128.143444 -256.008814) (xy 128.196594 -256.004831)
			(xy 128.249744 -256.008814) (xy 128.301706 -256.020674) (xy 128.35132 -256.040146) (xy 128.397478 -256.066795)
			(xy 128.439149 -256.100026) (xy 128.475401 -256.139097) (xy 128.505425 -256.183134) (xy 128.528551 -256.231155)
			(xy 128.544261 -256.282085) (xy 128.552204 -256.334789) (xy 128.552702 -256.361438) (xy 128.552204 -256.388087)
			(xy 128.781038 -256.388087) (xy 128.781038 -256.334789) (xy 128.788981 -256.282085) (xy 128.804691 -256.231155)
			(xy 128.827817 -256.183134) (xy 128.857841 -256.139097) (xy 128.894093 -256.100026) (xy 128.935764 -256.066795)
			(xy 128.981922 -256.040146) (xy 129.031536 -256.020674) (xy 129.083498 -256.008814) (xy 129.136648 -256.004831)
			(xy 129.189798 -256.008814) (xy 129.24176 -256.020674) (xy 129.291374 -256.040146) (xy 129.337532 -256.066795)
			(xy 129.379203 -256.100026) (xy 129.415455 -256.139097) (xy 129.445479 -256.183134) (xy 129.468605 -256.231155)
			(xy 129.484315 -256.282085) (xy 129.492258 -256.334789) (xy 129.492756 -256.361438) (xy 129.492258 -256.388087)
			(xy 129.720584 -256.388087) (xy 129.720584 -256.334789) (xy 129.728527 -256.282085) (xy 129.744237 -256.231155)
			(xy 129.767363 -256.183134) (xy 129.797387 -256.139097) (xy 129.833639 -256.100026) (xy 129.87531 -256.066795)
			(xy 129.921468 -256.040146) (xy 129.971082 -256.020674) (xy 130.023044 -256.008814) (xy 130.076194 -256.004831)
			(xy 130.129344 -256.008814) (xy 130.181306 -256.020674) (xy 130.23092 -256.040146) (xy 130.277078 -256.066795)
			(xy 130.318749 -256.100026) (xy 130.355001 -256.139097) (xy 130.385025 -256.183134) (xy 130.408151 -256.231155)
			(xy 130.423861 -256.282085) (xy 130.431804 -256.334789) (xy 130.432302 -256.361438) (xy 130.431804 -256.388087)
			(xy 130.660384 -256.388087) (xy 130.660384 -256.334789) (xy 130.668327 -256.282085) (xy 130.684037 -256.231155)
			(xy 130.707163 -256.183134) (xy 130.737187 -256.139097) (xy 130.773439 -256.100026) (xy 130.81511 -256.066795)
			(xy 130.861268 -256.040146) (xy 130.910882 -256.020674) (xy 130.962844 -256.008814) (xy 131.015994 -256.004831)
			(xy 131.069144 -256.008814) (xy 131.121106 -256.020674) (xy 131.17072 -256.040146) (xy 131.216878 -256.066795)
			(xy 131.258549 -256.100026) (xy 131.294801 -256.139097) (xy 131.324825 -256.183134) (xy 131.347951 -256.231155)
			(xy 131.363661 -256.282085) (xy 131.371604 -256.334789) (xy 131.372102 -256.361438) (xy 131.371604 -256.388087)
			(xy 131.600184 -256.388087) (xy 131.600184 -256.334789) (xy 131.608127 -256.282085) (xy 131.623837 -256.231155)
			(xy 131.646963 -256.183134) (xy 131.676987 -256.139097) (xy 131.713239 -256.100026) (xy 131.75491 -256.066795)
			(xy 131.801068 -256.040146) (xy 131.850682 -256.020674) (xy 131.902644 -256.008814) (xy 131.955794 -256.004831)
			(xy 132.008944 -256.008814) (xy 132.060906 -256.020674) (xy 132.11052 -256.040146) (xy 132.156678 -256.066795)
			(xy 132.198349 -256.100026) (xy 132.234601 -256.139097) (xy 132.264625 -256.183134) (xy 132.287751 -256.231155)
			(xy 132.303461 -256.282085) (xy 132.311404 -256.334789) (xy 132.311902 -256.361438) (xy 132.311404 -256.388087)
			(xy 132.539984 -256.388087) (xy 132.539984 -256.334789) (xy 132.547927 -256.282085) (xy 132.563637 -256.231155)
			(xy 132.586763 -256.183134) (xy 132.616787 -256.139097) (xy 132.653039 -256.100026) (xy 132.69471 -256.066795)
			(xy 132.740868 -256.040146) (xy 132.790482 -256.020674) (xy 132.842444 -256.008814) (xy 132.895594 -256.004831)
			(xy 132.948744 -256.008814) (xy 133.000706 -256.020674) (xy 133.05032 -256.040146) (xy 133.096478 -256.066795)
			(xy 133.138149 -256.100026) (xy 133.174401 -256.139097) (xy 133.204425 -256.183134) (xy 133.227551 -256.231155)
			(xy 133.243261 -256.282085) (xy 133.251204 -256.334789) (xy 133.251702 -256.361438) (xy 133.251204 -256.388087)
			(xy 133.479784 -256.388087) (xy 133.479784 -256.334789) (xy 133.487727 -256.282085) (xy 133.503437 -256.231155)
			(xy 133.526563 -256.183134) (xy 133.556587 -256.139097) (xy 133.592839 -256.100026) (xy 133.63451 -256.066795)
			(xy 133.680668 -256.040146) (xy 133.730282 -256.020674) (xy 133.782244 -256.008814) (xy 133.835394 -256.004831)
			(xy 133.888544 -256.008814) (xy 133.940506 -256.020674) (xy 133.99012 -256.040146) (xy 134.036278 -256.066795)
			(xy 134.077949 -256.100026) (xy 134.114201 -256.139097) (xy 134.144225 -256.183134) (xy 134.167351 -256.231155)
			(xy 134.183061 -256.282085) (xy 134.191004 -256.334789) (xy 134.191502 -256.361438) (xy 134.191004 -256.388087)
			(xy 134.419584 -256.388087) (xy 134.419584 -256.334789) (xy 134.427527 -256.282085) (xy 134.443237 -256.231155)
			(xy 134.466363 -256.183134) (xy 134.496387 -256.139097) (xy 134.532639 -256.100026) (xy 134.57431 -256.066795)
			(xy 134.620468 -256.040146) (xy 134.670082 -256.020674) (xy 134.722044 -256.008814) (xy 134.775194 -256.004831)
			(xy 134.828344 -256.008814) (xy 134.880306 -256.020674) (xy 134.92992 -256.040146) (xy 134.976078 -256.066795)
			(xy 135.017749 -256.100026) (xy 135.054001 -256.139097) (xy 135.084025 -256.183134) (xy 135.107151 -256.231155)
			(xy 135.122861 -256.282085) (xy 135.130804 -256.334789) (xy 135.131302 -256.361438) (xy 135.130804 -256.388087)
			(xy 135.122861 -256.440791) (xy 135.107151 -256.491721) (xy 135.084025 -256.539742) (xy 135.054001 -256.583779)
			(xy 135.017749 -256.62285) (xy 134.976078 -256.656081) (xy 134.92992 -256.68273) (xy 134.880306 -256.702202)
			(xy 134.828344 -256.714062) (xy 134.775194 -256.718046) (xy 134.722044 -256.714062) (xy 134.670082 -256.702202)
			(xy 134.620468 -256.68273) (xy 134.57431 -256.656081) (xy 134.532639 -256.62285) (xy 134.496387 -256.583779)
			(xy 134.466363 -256.539742) (xy 134.443237 -256.491721) (xy 134.427527 -256.440791) (xy 134.419584 -256.388087)
			(xy 134.191004 -256.388087) (xy 134.183061 -256.440791) (xy 134.167351 -256.491721) (xy 134.144225 -256.539742)
			(xy 134.114201 -256.583779) (xy 134.077949 -256.62285) (xy 134.036278 -256.656081) (xy 133.99012 -256.68273)
			(xy 133.940506 -256.702202) (xy 133.888544 -256.714062) (xy 133.835394 -256.718046) (xy 133.782244 -256.714062)
			(xy 133.730282 -256.702202) (xy 133.680668 -256.68273) (xy 133.63451 -256.656081) (xy 133.592839 -256.62285)
			(xy 133.556587 -256.583779) (xy 133.526563 -256.539742) (xy 133.503437 -256.491721) (xy 133.487727 -256.440791)
			(xy 133.479784 -256.388087) (xy 133.251204 -256.388087) (xy 133.243261 -256.440791) (xy 133.227551 -256.491721)
			(xy 133.204425 -256.539742) (xy 133.174401 -256.583779) (xy 133.138149 -256.62285) (xy 133.096478 -256.656081)
			(xy 133.05032 -256.68273) (xy 133.000706 -256.702202) (xy 132.948744 -256.714062) (xy 132.895594 -256.718046)
			(xy 132.842444 -256.714062) (xy 132.790482 -256.702202) (xy 132.740868 -256.68273) (xy 132.69471 -256.656081)
			(xy 132.653039 -256.62285) (xy 132.616787 -256.583779) (xy 132.586763 -256.539742) (xy 132.563637 -256.491721)
			(xy 132.547927 -256.440791) (xy 132.539984 -256.388087) (xy 132.311404 -256.388087) (xy 132.303461 -256.440791)
			(xy 132.287751 -256.491721) (xy 132.264625 -256.539742) (xy 132.234601 -256.583779) (xy 132.198349 -256.62285)
			(xy 132.156678 -256.656081) (xy 132.11052 -256.68273) (xy 132.060906 -256.702202) (xy 132.008944 -256.714062)
			(xy 131.955794 -256.718046) (xy 131.902644 -256.714062) (xy 131.850682 -256.702202) (xy 131.801068 -256.68273)
			(xy 131.75491 -256.656081) (xy 131.713239 -256.62285) (xy 131.676987 -256.583779) (xy 131.646963 -256.539742)
			(xy 131.623837 -256.491721) (xy 131.608127 -256.440791) (xy 131.600184 -256.388087) (xy 131.371604 -256.388087)
			(xy 131.363661 -256.440791) (xy 131.347951 -256.491721) (xy 131.324825 -256.539742) (xy 131.294801 -256.583779)
			(xy 131.258549 -256.62285) (xy 131.216878 -256.656081) (xy 131.17072 -256.68273) (xy 131.121106 -256.702202)
			(xy 131.069144 -256.714062) (xy 131.015994 -256.718046) (xy 130.962844 -256.714062) (xy 130.910882 -256.702202)
			(xy 130.861268 -256.68273) (xy 130.81511 -256.656081) (xy 130.773439 -256.62285) (xy 130.737187 -256.583779)
			(xy 130.707163 -256.539742) (xy 130.684037 -256.491721) (xy 130.668327 -256.440791) (xy 130.660384 -256.388087)
			(xy 130.431804 -256.388087) (xy 130.423861 -256.440791) (xy 130.408151 -256.491721) (xy 130.385025 -256.539742)
			(xy 130.355001 -256.583779) (xy 130.318749 -256.62285) (xy 130.277078 -256.656081) (xy 130.23092 -256.68273)
			(xy 130.181306 -256.702202) (xy 130.129344 -256.714062) (xy 130.076194 -256.718046) (xy 130.023044 -256.714062)
			(xy 129.971082 -256.702202) (xy 129.921468 -256.68273) (xy 129.87531 -256.656081) (xy 129.833639 -256.62285)
			(xy 129.797387 -256.583779) (xy 129.767363 -256.539742) (xy 129.744237 -256.491721) (xy 129.728527 -256.440791)
			(xy 129.720584 -256.388087) (xy 129.492258 -256.388087) (xy 129.484315 -256.440791) (xy 129.468605 -256.491721)
			(xy 129.445479 -256.539742) (xy 129.415455 -256.583779) (xy 129.379203 -256.62285) (xy 129.337532 -256.656081)
			(xy 129.291374 -256.68273) (xy 129.24176 -256.702202) (xy 129.189798 -256.714062) (xy 129.136648 -256.718046)
			(xy 129.083498 -256.714062) (xy 129.031536 -256.702202) (xy 128.981922 -256.68273) (xy 128.935764 -256.656081)
			(xy 128.894093 -256.62285) (xy 128.857841 -256.583779) (xy 128.827817 -256.539742) (xy 128.804691 -256.491721)
			(xy 128.788981 -256.440791) (xy 128.781038 -256.388087) (xy 128.552204 -256.388087) (xy 128.544261 -256.440791)
			(xy 128.528551 -256.491721) (xy 128.505425 -256.539742) (xy 128.475401 -256.583779) (xy 128.439149 -256.62285)
			(xy 128.397478 -256.656081) (xy 128.35132 -256.68273) (xy 128.301706 -256.702202) (xy 128.249744 -256.714062)
			(xy 128.196594 -256.718046) (xy 128.143444 -256.714062) (xy 128.091482 -256.702202) (xy 128.041868 -256.68273)
			(xy 127.99571 -256.656081) (xy 127.954039 -256.62285) (xy 127.917787 -256.583779) (xy 127.887763 -256.539742)
			(xy 127.864637 -256.491721) (xy 127.848927 -256.440791) (xy 127.840984 -256.388087) (xy 127.612404 -256.388087)
			(xy 127.604461 -256.440791) (xy 127.588751 -256.491721) (xy 127.565625 -256.539742) (xy 127.535601 -256.583779)
			(xy 127.499349 -256.62285) (xy 127.457678 -256.656081) (xy 127.41152 -256.68273) (xy 127.361906 -256.702202)
			(xy 127.309944 -256.714062) (xy 127.256794 -256.718046) (xy 127.203644 -256.714062) (xy 127.151682 -256.702202)
			(xy 127.102068 -256.68273) (xy 127.05591 -256.656081) (xy 127.014239 -256.62285) (xy 126.977987 -256.583779)
			(xy 126.947963 -256.539742) (xy 126.924837 -256.491721) (xy 126.909127 -256.440791) (xy 126.901184 -256.388087)
			(xy 126.672604 -256.388087) (xy 126.664661 -256.440791) (xy 126.648951 -256.491721) (xy 126.625825 -256.539742)
			(xy 126.595801 -256.583779) (xy 126.559549 -256.62285) (xy 126.517878 -256.656081) (xy 126.47172 -256.68273)
			(xy 126.422106 -256.702202) (xy 126.370144 -256.714062) (xy 126.316994 -256.718046) (xy 126.263844 -256.714062)
			(xy 126.211882 -256.702202) (xy 126.162268 -256.68273) (xy 126.11611 -256.656081) (xy 126.074439 -256.62285)
			(xy 126.038187 -256.583779) (xy 126.008163 -256.539742) (xy 125.985037 -256.491721) (xy 125.969327 -256.440791)
			(xy 125.961384 -256.388087) (xy 125.732804 -256.388087) (xy 125.724861 -256.440791) (xy 125.709151 -256.491721)
			(xy 125.686025 -256.539742) (xy 125.656001 -256.583779) (xy 125.619749 -256.62285) (xy 125.578078 -256.656081)
			(xy 125.53192 -256.68273) (xy 125.482306 -256.702202) (xy 125.430344 -256.714062) (xy 125.377194 -256.718046)
			(xy 125.324044 -256.714062) (xy 125.272082 -256.702202) (xy 125.222468 -256.68273) (xy 125.17631 -256.656081)
			(xy 125.134639 -256.62285) (xy 125.098387 -256.583779) (xy 125.068363 -256.539742) (xy 125.045237 -256.491721)
			(xy 125.029527 -256.440791) (xy 125.021584 -256.388087) (xy 124.793004 -256.388087) (xy 124.785061 -256.440791)
			(xy 124.769351 -256.491721) (xy 124.746225 -256.539742) (xy 124.716201 -256.583779) (xy 124.679949 -256.62285)
			(xy 124.638278 -256.656081) (xy 124.59212 -256.68273) (xy 124.542506 -256.702202) (xy 124.490544 -256.714062)
			(xy 124.437394 -256.718046) (xy 124.384244 -256.714062) (xy 124.332282 -256.702202) (xy 124.282668 -256.68273)
			(xy 124.23651 -256.656081) (xy 124.194839 -256.62285) (xy 124.158587 -256.583779) (xy 124.128563 -256.539742)
			(xy 124.105437 -256.491721) (xy 124.089727 -256.440791) (xy 124.081784 -256.388087) (xy 123.853204 -256.388087)
			(xy 123.845261 -256.440791) (xy 123.829551 -256.491721) (xy 123.806425 -256.539742) (xy 123.776401 -256.583779)
			(xy 123.740149 -256.62285) (xy 123.698478 -256.656081) (xy 123.65232 -256.68273) (xy 123.602706 -256.702202)
			(xy 123.550744 -256.714062) (xy 123.497594 -256.718046) (xy 123.444444 -256.714062) (xy 123.392482 -256.702202)
			(xy 123.342868 -256.68273) (xy 123.29671 -256.656081) (xy 123.255039 -256.62285) (xy 123.218787 -256.583779)
			(xy 123.188763 -256.539742) (xy 123.165637 -256.491721) (xy 123.149927 -256.440791) (xy 123.141984 -256.388087)
			(xy 122.913658 -256.388087) (xy 122.905715 -256.440791) (xy 122.890005 -256.491721) (xy 122.866879 -256.539742)
			(xy 122.836855 -256.583779) (xy 122.800603 -256.62285) (xy 122.758932 -256.656081) (xy 122.712774 -256.68273)
			(xy 122.66316 -256.702202) (xy 122.611198 -256.714062) (xy 122.558048 -256.718046) (xy 122.504898 -256.714062)
			(xy 122.452936 -256.702202) (xy 122.403322 -256.68273) (xy 122.357164 -256.656081) (xy 122.315493 -256.62285)
			(xy 122.279241 -256.583779) (xy 122.249217 -256.539742) (xy 122.226091 -256.491721) (xy 122.210381 -256.440791)
			(xy 122.202438 -256.388087) (xy 121.972594 -256.388087) (xy 121.970611 -256.414548) (xy 121.958751 -256.466509)
			(xy 121.939279 -256.516122) (xy 121.912631 -256.562278) (xy 121.8794 -256.603948) (xy 121.84033 -256.640199)
			(xy 121.796294 -256.670221) (xy 121.748274 -256.693346) (xy 121.697345 -256.709055) (xy 121.644643 -256.716997)
			(xy 121.617994 -256.717546) (xy 121.591921 -256.71709) (xy 121.540332 -256.709483) (xy 121.490405 -256.694432)
			(xy 121.46661 -256.683764) (xy 121.452801 -256.677855) (xy 121.423093 -256.673525) (xy 121.393412 -256.678033)
			(xy 121.36633 -256.690989) (xy 121.344194 -256.71127) (xy 121.328924 -256.737117) (xy 121.324878 -256.751582)
			(xy 121.3172 -256.780444) (xy 121.293543 -256.835277) (xy 121.261068 -256.885394) (xy 121.241312 -256.907792)
			(xy 121.23152 -256.919238) (xy 121.218489 -256.946378) (xy 121.213943 -256.976138) (xy 121.218278 -257.005931)
			(xy 121.231117 -257.033162) (xy 121.240804 -257.044698) (xy 121.257977 -257.064422) (xy 121.286953 -257.107959)
			(xy 121.309251 -257.155265) (xy 121.323359 -257.201903) (xy 121.732538 -257.201903) (xy 121.732538 -257.148605)
			(xy 121.740481 -257.095901) (xy 121.756191 -257.044971) (xy 121.779317 -256.99695) (xy 121.809341 -256.952913)
			(xy 121.845593 -256.913842) (xy 121.887264 -256.880611) (xy 121.933422 -256.853962) (xy 121.983036 -256.83449)
			(xy 122.034998 -256.82263) (xy 122.088148 -256.818647) (xy 122.141298 -256.82263) (xy 122.19326 -256.83449)
			(xy 122.242874 -256.853962) (xy 122.289032 -256.880611) (xy 122.330703 -256.913842) (xy 122.366955 -256.952913)
			(xy 122.396979 -256.99695) (xy 122.420105 -257.044971) (xy 122.435815 -257.095901) (xy 122.443758 -257.148605)
			(xy 122.444256 -257.175254) (xy 122.443758 -257.201903) (xy 122.672338 -257.201903) (xy 122.672338 -257.148605)
			(xy 122.680281 -257.095901) (xy 122.695991 -257.044971) (xy 122.719117 -256.99695) (xy 122.749141 -256.952913)
			(xy 122.785393 -256.913842) (xy 122.827064 -256.880611) (xy 122.873222 -256.853962) (xy 122.922836 -256.83449)
			(xy 122.974798 -256.82263) (xy 123.027948 -256.818647) (xy 123.081098 -256.82263) (xy 123.13306 -256.83449)
			(xy 123.182674 -256.853962) (xy 123.228832 -256.880611) (xy 123.270503 -256.913842) (xy 123.306755 -256.952913)
			(xy 123.336779 -256.99695) (xy 123.359905 -257.044971) (xy 123.375615 -257.095901) (xy 123.383558 -257.148605)
			(xy 123.384056 -257.175254) (xy 123.383558 -257.201903) (xy 123.612138 -257.201903) (xy 123.612138 -257.148605)
			(xy 123.620081 -257.095901) (xy 123.635791 -257.044971) (xy 123.658917 -256.99695) (xy 123.688941 -256.952913)
			(xy 123.725193 -256.913842) (xy 123.766864 -256.880611) (xy 123.813022 -256.853962) (xy 123.862636 -256.83449)
			(xy 123.914598 -256.82263) (xy 123.967748 -256.818647) (xy 124.020898 -256.82263) (xy 124.07286 -256.83449)
			(xy 124.122474 -256.853962) (xy 124.168632 -256.880611) (xy 124.210303 -256.913842) (xy 124.246555 -256.952913)
			(xy 124.276579 -256.99695) (xy 124.299705 -257.044971) (xy 124.315415 -257.095901) (xy 124.323358 -257.148605)
			(xy 124.323856 -257.175254) (xy 124.323358 -257.201903) (xy 124.551684 -257.201903) (xy 124.551684 -257.148605)
			(xy 124.559627 -257.095901) (xy 124.575337 -257.044971) (xy 124.598463 -256.99695) (xy 124.628487 -256.952913)
			(xy 124.664739 -256.913842) (xy 124.70641 -256.880611) (xy 124.752568 -256.853962) (xy 124.802182 -256.83449)
			(xy 124.854144 -256.82263) (xy 124.907294 -256.818647) (xy 124.960444 -256.82263) (xy 125.012406 -256.83449)
			(xy 125.06202 -256.853962) (xy 125.108178 -256.880611) (xy 125.149849 -256.913842) (xy 125.186101 -256.952913)
			(xy 125.216125 -256.99695) (xy 125.239251 -257.044971) (xy 125.254961 -257.095901) (xy 125.262904 -257.148605)
			(xy 125.263402 -257.175254) (xy 125.262904 -257.201903) (xy 125.491484 -257.201903) (xy 125.491484 -257.148605)
			(xy 125.499427 -257.095901) (xy 125.515137 -257.044971) (xy 125.538263 -256.99695) (xy 125.568287 -256.952913)
			(xy 125.604539 -256.913842) (xy 125.64621 -256.880611) (xy 125.692368 -256.853962) (xy 125.741982 -256.83449)
			(xy 125.793944 -256.82263) (xy 125.847094 -256.818647) (xy 125.900244 -256.82263) (xy 125.952206 -256.83449)
			(xy 126.00182 -256.853962) (xy 126.047978 -256.880611) (xy 126.089649 -256.913842) (xy 126.125901 -256.952913)
			(xy 126.155925 -256.99695) (xy 126.179051 -257.044971) (xy 126.194761 -257.095901) (xy 126.202704 -257.148605)
			(xy 126.203202 -257.175254) (xy 126.202704 -257.201903) (xy 126.431538 -257.201903) (xy 126.431538 -257.148605)
			(xy 126.439481 -257.095901) (xy 126.455191 -257.044971) (xy 126.478317 -256.99695) (xy 126.508341 -256.952913)
			(xy 126.544593 -256.913842) (xy 126.586264 -256.880611) (xy 126.632422 -256.853962) (xy 126.682036 -256.83449)
			(xy 126.733998 -256.82263) (xy 126.787148 -256.818647) (xy 126.840298 -256.82263) (xy 126.89226 -256.83449)
			(xy 126.941874 -256.853962) (xy 126.988032 -256.880611) (xy 127.029703 -256.913842) (xy 127.065955 -256.952913)
			(xy 127.095979 -256.99695) (xy 127.119105 -257.044971) (xy 127.134815 -257.095901) (xy 127.142758 -257.148605)
			(xy 127.143256 -257.175254) (xy 127.142758 -257.201903) (xy 127.371084 -257.201903) (xy 127.371084 -257.148605)
			(xy 127.379027 -257.095901) (xy 127.394737 -257.044971) (xy 127.417863 -256.99695) (xy 127.447887 -256.952913)
			(xy 127.484139 -256.913842) (xy 127.52581 -256.880611) (xy 127.571968 -256.853962) (xy 127.621582 -256.83449)
			(xy 127.673544 -256.82263) (xy 127.726694 -256.818647) (xy 127.779844 -256.82263) (xy 127.831806 -256.83449)
			(xy 127.88142 -256.853962) (xy 127.927578 -256.880611) (xy 127.969249 -256.913842) (xy 128.005501 -256.952913)
			(xy 128.035525 -256.99695) (xy 128.058651 -257.044971) (xy 128.074361 -257.095901) (xy 128.082304 -257.148605)
			(xy 128.082802 -257.175254) (xy 128.082304 -257.201903) (xy 128.311138 -257.201903) (xy 128.311138 -257.148605)
			(xy 128.319081 -257.095901) (xy 128.334791 -257.044971) (xy 128.357917 -256.99695) (xy 128.387941 -256.952913)
			(xy 128.424193 -256.913842) (xy 128.465864 -256.880611) (xy 128.512022 -256.853962) (xy 128.561636 -256.83449)
			(xy 128.613598 -256.82263) (xy 128.666748 -256.818647) (xy 128.719898 -256.82263) (xy 128.77186 -256.83449)
			(xy 128.821474 -256.853962) (xy 128.867632 -256.880611) (xy 128.909303 -256.913842) (xy 128.945555 -256.952913)
			(xy 128.975579 -256.99695) (xy 128.998705 -257.044971) (xy 129.014415 -257.095901) (xy 129.022358 -257.148605)
			(xy 129.022856 -257.175254) (xy 129.022358 -257.201903) (xy 129.250938 -257.201903) (xy 129.250938 -257.148605)
			(xy 129.258881 -257.095901) (xy 129.274591 -257.044971) (xy 129.297717 -256.99695) (xy 129.327741 -256.952913)
			(xy 129.363993 -256.913842) (xy 129.405664 -256.880611) (xy 129.451822 -256.853962) (xy 129.501436 -256.83449)
			(xy 129.553398 -256.82263) (xy 129.606548 -256.818647) (xy 129.659698 -256.82263) (xy 129.71166 -256.83449)
			(xy 129.761274 -256.853962) (xy 129.807432 -256.880611) (xy 129.849103 -256.913842) (xy 129.885355 -256.952913)
			(xy 129.915379 -256.99695) (xy 129.938505 -257.044971) (xy 129.954215 -257.095901) (xy 129.962158 -257.148605)
			(xy 129.962656 -257.175254) (xy 129.962158 -257.201903) (xy 130.190738 -257.201903) (xy 130.190738 -257.148605)
			(xy 130.198681 -257.095901) (xy 130.214391 -257.044971) (xy 130.237517 -256.99695) (xy 130.267541 -256.952913)
			(xy 130.303793 -256.913842) (xy 130.345464 -256.880611) (xy 130.391622 -256.853962) (xy 130.441236 -256.83449)
			(xy 130.493198 -256.82263) (xy 130.546348 -256.818647) (xy 130.599498 -256.82263) (xy 130.65146 -256.83449)
			(xy 130.701074 -256.853962) (xy 130.747232 -256.880611) (xy 130.788903 -256.913842) (xy 130.825155 -256.952913)
			(xy 130.855179 -256.99695) (xy 130.878305 -257.044971) (xy 130.894015 -257.095901) (xy 130.901958 -257.148605)
			(xy 130.902456 -257.175254) (xy 130.901958 -257.201903) (xy 131.130538 -257.201903) (xy 131.130538 -257.148605)
			(xy 131.138481 -257.095901) (xy 131.154191 -257.044971) (xy 131.177317 -256.99695) (xy 131.207341 -256.952913)
			(xy 131.243593 -256.913842) (xy 131.285264 -256.880611) (xy 131.331422 -256.853962) (xy 131.381036 -256.83449)
			(xy 131.432998 -256.82263) (xy 131.486148 -256.818647) (xy 131.539298 -256.82263) (xy 131.59126 -256.83449)
			(xy 131.640874 -256.853962) (xy 131.687032 -256.880611) (xy 131.728703 -256.913842) (xy 131.764955 -256.952913)
			(xy 131.794979 -256.99695) (xy 131.818105 -257.044971) (xy 131.833815 -257.095901) (xy 131.841758 -257.148605)
			(xy 131.842256 -257.175254) (xy 131.841758 -257.201903) (xy 132.070084 -257.201903) (xy 132.070084 -257.148605)
			(xy 132.078027 -257.095901) (xy 132.093737 -257.044971) (xy 132.116863 -256.99695) (xy 132.146887 -256.952913)
			(xy 132.183139 -256.913842) (xy 132.22481 -256.880611) (xy 132.270968 -256.853962) (xy 132.320582 -256.83449)
			(xy 132.372544 -256.82263) (xy 132.425694 -256.818647) (xy 132.478844 -256.82263) (xy 132.530806 -256.83449)
			(xy 132.58042 -256.853962) (xy 132.626578 -256.880611) (xy 132.668249 -256.913842) (xy 132.704501 -256.952913)
			(xy 132.734525 -256.99695) (xy 132.757651 -257.044971) (xy 132.773361 -257.095901) (xy 132.781304 -257.148605)
			(xy 132.781802 -257.175254) (xy 132.781304 -257.201903) (xy 133.010138 -257.201903) (xy 133.010138 -257.148605)
			(xy 133.018081 -257.095901) (xy 133.033791 -257.044971) (xy 133.056917 -256.99695) (xy 133.086941 -256.952913)
			(xy 133.123193 -256.913842) (xy 133.164864 -256.880611) (xy 133.211022 -256.853962) (xy 133.260636 -256.83449)
			(xy 133.312598 -256.82263) (xy 133.365748 -256.818647) (xy 133.418898 -256.82263) (xy 133.47086 -256.83449)
			(xy 133.520474 -256.853962) (xy 133.566632 -256.880611) (xy 133.608303 -256.913842) (xy 133.644555 -256.952913)
			(xy 133.674579 -256.99695) (xy 133.697705 -257.044971) (xy 133.713415 -257.095901) (xy 133.721358 -257.148605)
			(xy 133.721856 -257.175254) (xy 133.721358 -257.201903) (xy 133.949684 -257.201903) (xy 133.949684 -257.148605)
			(xy 133.957627 -257.095901) (xy 133.973337 -257.044971) (xy 133.996463 -256.99695) (xy 134.026487 -256.952913)
			(xy 134.062739 -256.913842) (xy 134.10441 -256.880611) (xy 134.150568 -256.853962) (xy 134.200182 -256.83449)
			(xy 134.252144 -256.82263) (xy 134.305294 -256.818647) (xy 134.358444 -256.82263) (xy 134.410406 -256.83449)
			(xy 134.46002 -256.853962) (xy 134.506178 -256.880611) (xy 134.547849 -256.913842) (xy 134.584101 -256.952913)
			(xy 134.614125 -256.99695) (xy 134.637251 -257.044971) (xy 134.652961 -257.095901) (xy 134.660904 -257.148605)
			(xy 134.661402 -257.175254) (xy 134.660904 -257.201903) (xy 134.652961 -257.254607) (xy 134.637251 -257.305537)
			(xy 134.614125 -257.353558) (xy 134.584101 -257.397595) (xy 134.547849 -257.436666) (xy 134.506178 -257.469897)
			(xy 134.46002 -257.496546) (xy 134.410406 -257.516018) (xy 134.358444 -257.527878) (xy 134.305294 -257.531862)
			(xy 134.252144 -257.527878) (xy 134.200182 -257.516018) (xy 134.150568 -257.496546) (xy 134.10441 -257.469897)
			(xy 134.062739 -257.436666) (xy 134.026487 -257.397595) (xy 133.996463 -257.353558) (xy 133.973337 -257.305537)
			(xy 133.957627 -257.254607) (xy 133.949684 -257.201903) (xy 133.721358 -257.201903) (xy 133.713415 -257.254607)
			(xy 133.697705 -257.305537) (xy 133.674579 -257.353558) (xy 133.644555 -257.397595) (xy 133.608303 -257.436666)
			(xy 133.566632 -257.469897) (xy 133.520474 -257.496546) (xy 133.47086 -257.516018) (xy 133.418898 -257.527878)
			(xy 133.365748 -257.531862) (xy 133.312598 -257.527878) (xy 133.260636 -257.516018) (xy 133.211022 -257.496546)
			(xy 133.164864 -257.469897) (xy 133.123193 -257.436666) (xy 133.086941 -257.397595) (xy 133.056917 -257.353558)
			(xy 133.033791 -257.305537) (xy 133.018081 -257.254607) (xy 133.010138 -257.201903) (xy 132.781304 -257.201903)
			(xy 132.773361 -257.254607) (xy 132.757651 -257.305537) (xy 132.734525 -257.353558) (xy 132.704501 -257.397595)
			(xy 132.668249 -257.436666) (xy 132.626578 -257.469897) (xy 132.58042 -257.496546) (xy 132.530806 -257.516018)
			(xy 132.478844 -257.527878) (xy 132.425694 -257.531862) (xy 132.372544 -257.527878) (xy 132.320582 -257.516018)
			(xy 132.270968 -257.496546) (xy 132.22481 -257.469897) (xy 132.183139 -257.436666) (xy 132.146887 -257.397595)
			(xy 132.116863 -257.353558) (xy 132.093737 -257.305537) (xy 132.078027 -257.254607) (xy 132.070084 -257.201903)
			(xy 131.841758 -257.201903) (xy 131.833815 -257.254607) (xy 131.818105 -257.305537) (xy 131.794979 -257.353558)
			(xy 131.764955 -257.397595) (xy 131.728703 -257.436666) (xy 131.687032 -257.469897) (xy 131.640874 -257.496546)
			(xy 131.59126 -257.516018) (xy 131.539298 -257.527878) (xy 131.486148 -257.531862) (xy 131.432998 -257.527878)
			(xy 131.381036 -257.516018) (xy 131.331422 -257.496546) (xy 131.285264 -257.469897) (xy 131.243593 -257.436666)
			(xy 131.207341 -257.397595) (xy 131.177317 -257.353558) (xy 131.154191 -257.305537) (xy 131.138481 -257.254607)
			(xy 131.130538 -257.201903) (xy 130.901958 -257.201903) (xy 130.894015 -257.254607) (xy 130.878305 -257.305537)
			(xy 130.855179 -257.353558) (xy 130.825155 -257.397595) (xy 130.788903 -257.436666) (xy 130.747232 -257.469897)
			(xy 130.701074 -257.496546) (xy 130.65146 -257.516018) (xy 130.599498 -257.527878) (xy 130.546348 -257.531862)
			(xy 130.493198 -257.527878) (xy 130.441236 -257.516018) (xy 130.391622 -257.496546) (xy 130.345464 -257.469897)
			(xy 130.303793 -257.436666) (xy 130.267541 -257.397595) (xy 130.237517 -257.353558) (xy 130.214391 -257.305537)
			(xy 130.198681 -257.254607) (xy 130.190738 -257.201903) (xy 129.962158 -257.201903) (xy 129.954215 -257.254607)
			(xy 129.938505 -257.305537) (xy 129.915379 -257.353558) (xy 129.885355 -257.397595) (xy 129.849103 -257.436666)
			(xy 129.807432 -257.469897) (xy 129.761274 -257.496546) (xy 129.71166 -257.516018) (xy 129.659698 -257.527878)
			(xy 129.606548 -257.531862) (xy 129.553398 -257.527878) (xy 129.501436 -257.516018) (xy 129.451822 -257.496546)
			(xy 129.405664 -257.469897) (xy 129.363993 -257.436666) (xy 129.327741 -257.397595) (xy 129.297717 -257.353558)
			(xy 129.274591 -257.305537) (xy 129.258881 -257.254607) (xy 129.250938 -257.201903) (xy 129.022358 -257.201903)
			(xy 129.014415 -257.254607) (xy 128.998705 -257.305537) (xy 128.975579 -257.353558) (xy 128.945555 -257.397595)
			(xy 128.909303 -257.436666) (xy 128.867632 -257.469897) (xy 128.821474 -257.496546) (xy 128.77186 -257.516018)
			(xy 128.719898 -257.527878) (xy 128.666748 -257.531862) (xy 128.613598 -257.527878) (xy 128.561636 -257.516018)
			(xy 128.512022 -257.496546) (xy 128.465864 -257.469897) (xy 128.424193 -257.436666) (xy 128.387941 -257.397595)
			(xy 128.357917 -257.353558) (xy 128.334791 -257.305537) (xy 128.319081 -257.254607) (xy 128.311138 -257.201903)
			(xy 128.082304 -257.201903) (xy 128.074361 -257.254607) (xy 128.058651 -257.305537) (xy 128.035525 -257.353558)
			(xy 128.005501 -257.397595) (xy 127.969249 -257.436666) (xy 127.927578 -257.469897) (xy 127.88142 -257.496546)
			(xy 127.831806 -257.516018) (xy 127.779844 -257.527878) (xy 127.726694 -257.531862) (xy 127.673544 -257.527878)
			(xy 127.621582 -257.516018) (xy 127.571968 -257.496546) (xy 127.52581 -257.469897) (xy 127.484139 -257.436666)
			(xy 127.447887 -257.397595) (xy 127.417863 -257.353558) (xy 127.394737 -257.305537) (xy 127.379027 -257.254607)
			(xy 127.371084 -257.201903) (xy 127.142758 -257.201903) (xy 127.134815 -257.254607) (xy 127.119105 -257.305537)
			(xy 127.095979 -257.353558) (xy 127.065955 -257.397595) (xy 127.029703 -257.436666) (xy 126.988032 -257.469897)
			(xy 126.941874 -257.496546) (xy 126.89226 -257.516018) (xy 126.840298 -257.527878) (xy 126.787148 -257.531862)
			(xy 126.733998 -257.527878) (xy 126.682036 -257.516018) (xy 126.632422 -257.496546) (xy 126.586264 -257.469897)
			(xy 126.544593 -257.436666) (xy 126.508341 -257.397595) (xy 126.478317 -257.353558) (xy 126.455191 -257.305537)
			(xy 126.439481 -257.254607) (xy 126.431538 -257.201903) (xy 126.202704 -257.201903) (xy 126.194761 -257.254607)
			(xy 126.179051 -257.305537) (xy 126.155925 -257.353558) (xy 126.125901 -257.397595) (xy 126.089649 -257.436666)
			(xy 126.047978 -257.469897) (xy 126.00182 -257.496546) (xy 125.952206 -257.516018) (xy 125.900244 -257.527878)
			(xy 125.847094 -257.531862) (xy 125.793944 -257.527878) (xy 125.741982 -257.516018) (xy 125.692368 -257.496546)
			(xy 125.64621 -257.469897) (xy 125.604539 -257.436666) (xy 125.568287 -257.397595) (xy 125.538263 -257.353558)
			(xy 125.515137 -257.305537) (xy 125.499427 -257.254607) (xy 125.491484 -257.201903) (xy 125.262904 -257.201903)
			(xy 125.254961 -257.254607) (xy 125.239251 -257.305537) (xy 125.216125 -257.353558) (xy 125.186101 -257.397595)
			(xy 125.149849 -257.436666) (xy 125.108178 -257.469897) (xy 125.06202 -257.496546) (xy 125.012406 -257.516018)
			(xy 124.960444 -257.527878) (xy 124.907294 -257.531862) (xy 124.854144 -257.527878) (xy 124.802182 -257.516018)
			(xy 124.752568 -257.496546) (xy 124.70641 -257.469897) (xy 124.664739 -257.436666) (xy 124.628487 -257.397595)
			(xy 124.598463 -257.353558) (xy 124.575337 -257.305537) (xy 124.559627 -257.254607) (xy 124.551684 -257.201903)
			(xy 124.323358 -257.201903) (xy 124.315415 -257.254607) (xy 124.299705 -257.305537) (xy 124.276579 -257.353558)
			(xy 124.246555 -257.397595) (xy 124.210303 -257.436666) (xy 124.168632 -257.469897) (xy 124.122474 -257.496546)
			(xy 124.07286 -257.516018) (xy 124.020898 -257.527878) (xy 123.967748 -257.531862) (xy 123.914598 -257.527878)
			(xy 123.862636 -257.516018) (xy 123.813022 -257.496546) (xy 123.766864 -257.469897) (xy 123.725193 -257.436666)
			(xy 123.688941 -257.397595) (xy 123.658917 -257.353558) (xy 123.635791 -257.305537) (xy 123.620081 -257.254607)
			(xy 123.612138 -257.201903) (xy 123.383558 -257.201903) (xy 123.375615 -257.254607) (xy 123.359905 -257.305537)
			(xy 123.336779 -257.353558) (xy 123.306755 -257.397595) (xy 123.270503 -257.436666) (xy 123.228832 -257.469897)
			(xy 123.182674 -257.496546) (xy 123.13306 -257.516018) (xy 123.081098 -257.527878) (xy 123.027948 -257.531862)
			(xy 122.974798 -257.527878) (xy 122.922836 -257.516018) (xy 122.873222 -257.496546) (xy 122.827064 -257.469897)
			(xy 122.785393 -257.436666) (xy 122.749141 -257.397595) (xy 122.719117 -257.353558) (xy 122.695991 -257.305537)
			(xy 122.680281 -257.254607) (xy 122.672338 -257.201903) (xy 122.443758 -257.201903) (xy 122.435815 -257.254607)
			(xy 122.420105 -257.305537) (xy 122.396979 -257.353558) (xy 122.366955 -257.397595) (xy 122.330703 -257.436666)
			(xy 122.289032 -257.469897) (xy 122.242874 -257.496546) (xy 122.19326 -257.516018) (xy 122.141298 -257.527878)
			(xy 122.088148 -257.531862) (xy 122.034998 -257.527878) (xy 121.983036 -257.516018) (xy 121.933422 -257.496546)
			(xy 121.887264 -257.469897) (xy 121.845593 -257.436666) (xy 121.809341 -257.397595) (xy 121.779317 -257.353558)
			(xy 121.756191 -257.305537) (xy 121.740481 -257.254607) (xy 121.732538 -257.201903) (xy 121.323359 -257.201903)
			(xy 121.324393 -257.205322) (xy 121.332054 -257.257055) (xy 121.332498 -257.283204) (xy 121.331977 -257.311189)
			(xy 121.323221 -257.366469) (xy 121.305924 -257.419699) (xy 121.280514 -257.469568) (xy 121.247615 -257.514848)
			(xy 121.208038 -257.554424) (xy 121.162756 -257.587321) (xy 121.112887 -257.61273) (xy 121.059656 -257.630024)
			(xy 121.004375 -257.638778) (xy 120.97639 -257.639312) (xy 120.951218 -257.638877) (xy 120.901375 -257.631785)
			(xy 120.853028 -257.617743) (xy 120.80714 -257.597033) (xy 120.785636 -257.58394) (xy 120.77393 -257.577041)
			(xy 120.747959 -257.569082) (xy 120.720809 -257.568254) (xy 120.694402 -257.574615) (xy 120.670607 -257.587715)
			(xy 120.651108 -257.606626) (xy 120.637287 -257.63001) (xy 120.630122 -257.656211) (xy 120.62968 -257.669792)
			(xy 120.62968 -258.015719) (xy 122.202184 -258.015719) (xy 122.202184 -257.962421) (xy 122.210127 -257.909717)
			(xy 122.225837 -257.858787) (xy 122.248963 -257.810766) (xy 122.278987 -257.766729) (xy 122.315239 -257.727658)
			(xy 122.35691 -257.694427) (xy 122.403068 -257.667778) (xy 122.452682 -257.648306) (xy 122.504644 -257.636446)
			(xy 122.557794 -257.632463) (xy 122.610944 -257.636446) (xy 122.662906 -257.648306) (xy 122.71252 -257.667778)
			(xy 122.758678 -257.694427) (xy 122.800349 -257.727658) (xy 122.836601 -257.766729) (xy 122.866625 -257.810766)
			(xy 122.889751 -257.858787) (xy 122.905461 -257.909717) (xy 122.913404 -257.962421) (xy 122.913902 -257.98907)
			(xy 122.913404 -258.015719) (xy 123.141984 -258.015719) (xy 123.141984 -257.962421) (xy 123.149927 -257.909717)
			(xy 123.165637 -257.858787) (xy 123.188763 -257.810766) (xy 123.218787 -257.766729) (xy 123.255039 -257.727658)
			(xy 123.29671 -257.694427) (xy 123.342868 -257.667778) (xy 123.392482 -257.648306) (xy 123.444444 -257.636446)
			(xy 123.497594 -257.632463) (xy 123.550744 -257.636446) (xy 123.602706 -257.648306) (xy 123.65232 -257.667778)
			(xy 123.698478 -257.694427) (xy 123.740149 -257.727658) (xy 123.776401 -257.766729) (xy 123.806425 -257.810766)
			(xy 123.829551 -257.858787) (xy 123.845261 -257.909717) (xy 123.853204 -257.962421) (xy 123.853702 -257.98907)
			(xy 123.853204 -258.015719) (xy 124.081784 -258.015719) (xy 124.081784 -257.962421) (xy 124.089727 -257.909717)
			(xy 124.105437 -257.858787) (xy 124.128563 -257.810766) (xy 124.158587 -257.766729) (xy 124.194839 -257.727658)
			(xy 124.23651 -257.694427) (xy 124.282668 -257.667778) (xy 124.332282 -257.648306) (xy 124.384244 -257.636446)
			(xy 124.437394 -257.632463) (xy 124.490544 -257.636446) (xy 124.542506 -257.648306) (xy 124.59212 -257.667778)
			(xy 124.638278 -257.694427) (xy 124.679949 -257.727658) (xy 124.716201 -257.766729) (xy 124.746225 -257.810766)
			(xy 124.769351 -257.858787) (xy 124.785061 -257.909717) (xy 124.793004 -257.962421) (xy 124.793502 -257.98907)
			(xy 124.793004 -258.015719) (xy 125.021838 -258.015719) (xy 125.021838 -257.962421) (xy 125.029781 -257.909717)
			(xy 125.045491 -257.858787) (xy 125.068617 -257.810766) (xy 125.098641 -257.766729) (xy 125.134893 -257.727658)
			(xy 125.176564 -257.694427) (xy 125.222722 -257.667778) (xy 125.272336 -257.648306) (xy 125.324298 -257.636446)
			(xy 125.377448 -257.632463) (xy 125.430598 -257.636446) (xy 125.48256 -257.648306) (xy 125.532174 -257.667778)
			(xy 125.578332 -257.694427) (xy 125.620003 -257.727658) (xy 125.656255 -257.766729) (xy 125.686279 -257.810766)
			(xy 125.709405 -257.858787) (xy 125.725115 -257.909717) (xy 125.733058 -257.962421) (xy 125.733556 -257.98907)
			(xy 125.733058 -258.015719) (xy 125.961384 -258.015719) (xy 125.961384 -257.962421) (xy 125.969327 -257.909717)
			(xy 125.985037 -257.858787) (xy 126.008163 -257.810766) (xy 126.038187 -257.766729) (xy 126.074439 -257.727658)
			(xy 126.11611 -257.694427) (xy 126.162268 -257.667778) (xy 126.211882 -257.648306) (xy 126.263844 -257.636446)
			(xy 126.316994 -257.632463) (xy 126.370144 -257.636446) (xy 126.422106 -257.648306) (xy 126.47172 -257.667778)
			(xy 126.517878 -257.694427) (xy 126.559549 -257.727658) (xy 126.595801 -257.766729) (xy 126.625825 -257.810766)
			(xy 126.648951 -257.858787) (xy 126.664661 -257.909717) (xy 126.672604 -257.962421) (xy 126.673102 -257.98907)
			(xy 126.672604 -258.015719) (xy 126.901438 -258.015719) (xy 126.901438 -257.962421) (xy 126.909381 -257.909717)
			(xy 126.925091 -257.858787) (xy 126.948217 -257.810766) (xy 126.978241 -257.766729) (xy 127.014493 -257.727658)
			(xy 127.056164 -257.694427) (xy 127.102322 -257.667778) (xy 127.151936 -257.648306) (xy 127.203898 -257.636446)
			(xy 127.257048 -257.632463) (xy 127.310198 -257.636446) (xy 127.36216 -257.648306) (xy 127.411774 -257.667778)
			(xy 127.457932 -257.694427) (xy 127.499603 -257.727658) (xy 127.535855 -257.766729) (xy 127.565879 -257.810766)
			(xy 127.589005 -257.858787) (xy 127.604715 -257.909717) (xy 127.612658 -257.962421) (xy 127.613156 -257.98907)
			(xy 127.612658 -258.015719) (xy 127.840984 -258.015719) (xy 127.840984 -257.962421) (xy 127.848927 -257.909717)
			(xy 127.864637 -257.858787) (xy 127.887763 -257.810766) (xy 127.917787 -257.766729) (xy 127.954039 -257.727658)
			(xy 127.99571 -257.694427) (xy 128.041868 -257.667778) (xy 128.091482 -257.648306) (xy 128.143444 -257.636446)
			(xy 128.196594 -257.632463) (xy 128.249744 -257.636446) (xy 128.301706 -257.648306) (xy 128.35132 -257.667778)
			(xy 128.397478 -257.694427) (xy 128.439149 -257.727658) (xy 128.475401 -257.766729) (xy 128.505425 -257.810766)
			(xy 128.528551 -257.858787) (xy 128.544261 -257.909717) (xy 128.552204 -257.962421) (xy 128.552702 -257.98907)
			(xy 128.552204 -258.015719) (xy 128.780784 -258.015719) (xy 128.780784 -257.962421) (xy 128.788727 -257.909717)
			(xy 128.804437 -257.858787) (xy 128.827563 -257.810766) (xy 128.857587 -257.766729) (xy 128.893839 -257.727658)
			(xy 128.93551 -257.694427) (xy 128.981668 -257.667778) (xy 129.031282 -257.648306) (xy 129.083244 -257.636446)
			(xy 129.136394 -257.632463) (xy 129.189544 -257.636446) (xy 129.241506 -257.648306) (xy 129.29112 -257.667778)
			(xy 129.337278 -257.694427) (xy 129.378949 -257.727658) (xy 129.415201 -257.766729) (xy 129.445225 -257.810766)
			(xy 129.468351 -257.858787) (xy 129.484061 -257.909717) (xy 129.492004 -257.962421) (xy 129.492502 -257.98907)
			(xy 129.492004 -258.015719) (xy 129.720584 -258.015719) (xy 129.720584 -257.962421) (xy 129.728527 -257.909717)
			(xy 129.744237 -257.858787) (xy 129.767363 -257.810766) (xy 129.797387 -257.766729) (xy 129.833639 -257.727658)
			(xy 129.87531 -257.694427) (xy 129.921468 -257.667778) (xy 129.971082 -257.648306) (xy 130.023044 -257.636446)
			(xy 130.076194 -257.632463) (xy 130.129344 -257.636446) (xy 130.181306 -257.648306) (xy 130.23092 -257.667778)
			(xy 130.277078 -257.694427) (xy 130.318749 -257.727658) (xy 130.355001 -257.766729) (xy 130.385025 -257.810766)
			(xy 130.408151 -257.858787) (xy 130.423861 -257.909717) (xy 130.431804 -257.962421) (xy 130.432302 -257.98907)
			(xy 130.431804 -258.015719) (xy 130.660384 -258.015719) (xy 130.660384 -257.962421) (xy 130.668327 -257.909717)
			(xy 130.684037 -257.858787) (xy 130.707163 -257.810766) (xy 130.737187 -257.766729) (xy 130.773439 -257.727658)
			(xy 130.81511 -257.694427) (xy 130.861268 -257.667778) (xy 130.910882 -257.648306) (xy 130.962844 -257.636446)
			(xy 131.015994 -257.632463) (xy 131.069144 -257.636446) (xy 131.121106 -257.648306) (xy 131.17072 -257.667778)
			(xy 131.216878 -257.694427) (xy 131.258549 -257.727658) (xy 131.294801 -257.766729) (xy 131.324825 -257.810766)
			(xy 131.347951 -257.858787) (xy 131.363661 -257.909717) (xy 131.371604 -257.962421) (xy 131.372102 -257.98907)
			(xy 131.371604 -258.015719) (xy 131.600438 -258.015719) (xy 131.600438 -257.962421) (xy 131.608381 -257.909717)
			(xy 131.624091 -257.858787) (xy 131.647217 -257.810766) (xy 131.677241 -257.766729) (xy 131.713493 -257.727658)
			(xy 131.755164 -257.694427) (xy 131.801322 -257.667778) (xy 131.850936 -257.648306) (xy 131.902898 -257.636446)
			(xy 131.956048 -257.632463) (xy 132.009198 -257.636446) (xy 132.06116 -257.648306) (xy 132.110774 -257.667778)
			(xy 132.156932 -257.694427) (xy 132.198603 -257.727658) (xy 132.234855 -257.766729) (xy 132.264879 -257.810766)
			(xy 132.288005 -257.858787) (xy 132.303715 -257.909717) (xy 132.311658 -257.962421) (xy 132.312156 -257.98907)
			(xy 132.311658 -258.015719) (xy 132.539984 -258.015719) (xy 132.539984 -257.962421) (xy 132.547927 -257.909717)
			(xy 132.563637 -257.858787) (xy 132.586763 -257.810766) (xy 132.616787 -257.766729) (xy 132.653039 -257.727658)
			(xy 132.69471 -257.694427) (xy 132.740868 -257.667778) (xy 132.790482 -257.648306) (xy 132.842444 -257.636446)
			(xy 132.895594 -257.632463) (xy 132.948744 -257.636446) (xy 133.000706 -257.648306) (xy 133.05032 -257.667778)
			(xy 133.096478 -257.694427) (xy 133.138149 -257.727658) (xy 133.174401 -257.766729) (xy 133.204425 -257.810766)
			(xy 133.227551 -257.858787) (xy 133.243261 -257.909717) (xy 133.251204 -257.962421) (xy 133.251702 -257.98907)
			(xy 133.251204 -258.015719) (xy 133.480038 -258.015719) (xy 133.480038 -257.962421) (xy 133.487981 -257.909717)
			(xy 133.503691 -257.858787) (xy 133.526817 -257.810766) (xy 133.556841 -257.766729) (xy 133.593093 -257.727658)
			(xy 133.634764 -257.694427) (xy 133.680922 -257.667778) (xy 133.730536 -257.648306) (xy 133.782498 -257.636446)
			(xy 133.835648 -257.632463) (xy 133.888798 -257.636446) (xy 133.94076 -257.648306) (xy 133.990374 -257.667778)
			(xy 134.036532 -257.694427) (xy 134.078203 -257.727658) (xy 134.114455 -257.766729) (xy 134.144479 -257.810766)
			(xy 134.167605 -257.858787) (xy 134.183315 -257.909717) (xy 134.191258 -257.962421) (xy 134.191756 -257.98907)
			(xy 134.191258 -258.015719) (xy 134.419584 -258.015719) (xy 134.419584 -257.962421) (xy 134.427527 -257.909717)
			(xy 134.443237 -257.858787) (xy 134.466363 -257.810766) (xy 134.496387 -257.766729) (xy 134.532639 -257.727658)
			(xy 134.57431 -257.694427) (xy 134.620468 -257.667778) (xy 134.670082 -257.648306) (xy 134.722044 -257.636446)
			(xy 134.775194 -257.632463) (xy 134.828344 -257.636446) (xy 134.880306 -257.648306) (xy 134.92992 -257.667778)
			(xy 134.976078 -257.694427) (xy 135.017749 -257.727658) (xy 135.054001 -257.766729) (xy 135.084025 -257.810766)
			(xy 135.107151 -257.858787) (xy 135.122861 -257.909717) (xy 135.130804 -257.962421) (xy 135.131302 -257.98907)
			(xy 135.130804 -258.015719) (xy 135.122861 -258.068423) (xy 135.107151 -258.119353) (xy 135.084025 -258.167374)
			(xy 135.054001 -258.211411) (xy 135.017749 -258.250482) (xy 134.976078 -258.283713) (xy 134.92992 -258.310362)
			(xy 134.880306 -258.329834) (xy 134.828344 -258.341694) (xy 134.775194 -258.345678) (xy 134.722044 -258.341694)
			(xy 134.670082 -258.329834) (xy 134.620468 -258.310362) (xy 134.57431 -258.283713) (xy 134.532639 -258.250482)
			(xy 134.496387 -258.211411) (xy 134.466363 -258.167374) (xy 134.443237 -258.119353) (xy 134.427527 -258.068423)
			(xy 134.419584 -258.015719) (xy 134.191258 -258.015719) (xy 134.183315 -258.068423) (xy 134.167605 -258.119353)
			(xy 134.144479 -258.167374) (xy 134.114455 -258.211411) (xy 134.078203 -258.250482) (xy 134.036532 -258.283713)
			(xy 133.990374 -258.310362) (xy 133.94076 -258.329834) (xy 133.888798 -258.341694) (xy 133.835648 -258.345678)
			(xy 133.782498 -258.341694) (xy 133.730536 -258.329834) (xy 133.680922 -258.310362) (xy 133.634764 -258.283713)
			(xy 133.593093 -258.250482) (xy 133.556841 -258.211411) (xy 133.526817 -258.167374) (xy 133.503691 -258.119353)
			(xy 133.487981 -258.068423) (xy 133.480038 -258.015719) (xy 133.251204 -258.015719) (xy 133.243261 -258.068423)
			(xy 133.227551 -258.119353) (xy 133.204425 -258.167374) (xy 133.174401 -258.211411) (xy 133.138149 -258.250482)
			(xy 133.096478 -258.283713) (xy 133.05032 -258.310362) (xy 133.000706 -258.329834) (xy 132.948744 -258.341694)
			(xy 132.895594 -258.345678) (xy 132.842444 -258.341694) (xy 132.790482 -258.329834) (xy 132.740868 -258.310362)
			(xy 132.69471 -258.283713) (xy 132.653039 -258.250482) (xy 132.616787 -258.211411) (xy 132.586763 -258.167374)
			(xy 132.563637 -258.119353) (xy 132.547927 -258.068423) (xy 132.539984 -258.015719) (xy 132.311658 -258.015719)
			(xy 132.303715 -258.068423) (xy 132.288005 -258.119353) (xy 132.264879 -258.167374) (xy 132.234855 -258.211411)
			(xy 132.198603 -258.250482) (xy 132.156932 -258.283713) (xy 132.110774 -258.310362) (xy 132.06116 -258.329834)
			(xy 132.009198 -258.341694) (xy 131.956048 -258.345678) (xy 131.902898 -258.341694) (xy 131.850936 -258.329834)
			(xy 131.801322 -258.310362) (xy 131.755164 -258.283713) (xy 131.713493 -258.250482) (xy 131.677241 -258.211411)
			(xy 131.647217 -258.167374) (xy 131.624091 -258.119353) (xy 131.608381 -258.068423) (xy 131.600438 -258.015719)
			(xy 131.371604 -258.015719) (xy 131.363661 -258.068423) (xy 131.347951 -258.119353) (xy 131.324825 -258.167374)
			(xy 131.294801 -258.211411) (xy 131.258549 -258.250482) (xy 131.216878 -258.283713) (xy 131.17072 -258.310362)
			(xy 131.121106 -258.329834) (xy 131.069144 -258.341694) (xy 131.015994 -258.345678) (xy 130.962844 -258.341694)
			(xy 130.910882 -258.329834) (xy 130.861268 -258.310362) (xy 130.81511 -258.283713) (xy 130.773439 -258.250482)
			(xy 130.737187 -258.211411) (xy 130.707163 -258.167374) (xy 130.684037 -258.119353) (xy 130.668327 -258.068423)
			(xy 130.660384 -258.015719) (xy 130.431804 -258.015719) (xy 130.423861 -258.068423) (xy 130.408151 -258.119353)
			(xy 130.385025 -258.167374) (xy 130.355001 -258.211411) (xy 130.318749 -258.250482) (xy 130.277078 -258.283713)
			(xy 130.23092 -258.310362) (xy 130.181306 -258.329834) (xy 130.129344 -258.341694) (xy 130.076194 -258.345678)
			(xy 130.023044 -258.341694) (xy 129.971082 -258.329834) (xy 129.921468 -258.310362) (xy 129.87531 -258.283713)
			(xy 129.833639 -258.250482) (xy 129.797387 -258.211411) (xy 129.767363 -258.167374) (xy 129.744237 -258.119353)
			(xy 129.728527 -258.068423) (xy 129.720584 -258.015719) (xy 129.492004 -258.015719) (xy 129.484061 -258.068423)
			(xy 129.468351 -258.119353) (xy 129.445225 -258.167374) (xy 129.415201 -258.211411) (xy 129.378949 -258.250482)
			(xy 129.337278 -258.283713) (xy 129.29112 -258.310362) (xy 129.241506 -258.329834) (xy 129.189544 -258.341694)
			(xy 129.136394 -258.345678) (xy 129.083244 -258.341694) (xy 129.031282 -258.329834) (xy 128.981668 -258.310362)
			(xy 128.93551 -258.283713) (xy 128.893839 -258.250482) (xy 128.857587 -258.211411) (xy 128.827563 -258.167374)
			(xy 128.804437 -258.119353) (xy 128.788727 -258.068423) (xy 128.780784 -258.015719) (xy 128.552204 -258.015719)
			(xy 128.544261 -258.068423) (xy 128.528551 -258.119353) (xy 128.505425 -258.167374) (xy 128.475401 -258.211411)
			(xy 128.439149 -258.250482) (xy 128.397478 -258.283713) (xy 128.35132 -258.310362) (xy 128.301706 -258.329834)
			(xy 128.249744 -258.341694) (xy 128.196594 -258.345678) (xy 128.143444 -258.341694) (xy 128.091482 -258.329834)
			(xy 128.041868 -258.310362) (xy 127.99571 -258.283713) (xy 127.954039 -258.250482) (xy 127.917787 -258.211411)
			(xy 127.887763 -258.167374) (xy 127.864637 -258.119353) (xy 127.848927 -258.068423) (xy 127.840984 -258.015719)
			(xy 127.612658 -258.015719) (xy 127.604715 -258.068423) (xy 127.589005 -258.119353) (xy 127.565879 -258.167374)
			(xy 127.535855 -258.211411) (xy 127.499603 -258.250482) (xy 127.457932 -258.283713) (xy 127.411774 -258.310362)
			(xy 127.36216 -258.329834) (xy 127.310198 -258.341694) (xy 127.257048 -258.345678) (xy 127.203898 -258.341694)
			(xy 127.151936 -258.329834) (xy 127.102322 -258.310362) (xy 127.056164 -258.283713) (xy 127.014493 -258.250482)
			(xy 126.978241 -258.211411) (xy 126.948217 -258.167374) (xy 126.925091 -258.119353) (xy 126.909381 -258.068423)
			(xy 126.901438 -258.015719) (xy 126.672604 -258.015719) (xy 126.664661 -258.068423) (xy 126.648951 -258.119353)
			(xy 126.625825 -258.167374) (xy 126.595801 -258.211411) (xy 126.559549 -258.250482) (xy 126.517878 -258.283713)
			(xy 126.47172 -258.310362) (xy 126.422106 -258.329834) (xy 126.370144 -258.341694) (xy 126.316994 -258.345678)
			(xy 126.263844 -258.341694) (xy 126.211882 -258.329834) (xy 126.162268 -258.310362) (xy 126.11611 -258.283713)
			(xy 126.074439 -258.250482) (xy 126.038187 -258.211411) (xy 126.008163 -258.167374) (xy 125.985037 -258.119353)
			(xy 125.969327 -258.068423) (xy 125.961384 -258.015719) (xy 125.733058 -258.015719) (xy 125.725115 -258.068423)
			(xy 125.709405 -258.119353) (xy 125.686279 -258.167374) (xy 125.656255 -258.211411) (xy 125.620003 -258.250482)
			(xy 125.578332 -258.283713) (xy 125.532174 -258.310362) (xy 125.48256 -258.329834) (xy 125.430598 -258.341694)
			(xy 125.377448 -258.345678) (xy 125.324298 -258.341694) (xy 125.272336 -258.329834) (xy 125.222722 -258.310362)
			(xy 125.176564 -258.283713) (xy 125.134893 -258.250482) (xy 125.098641 -258.211411) (xy 125.068617 -258.167374)
			(xy 125.045491 -258.119353) (xy 125.029781 -258.068423) (xy 125.021838 -258.015719) (xy 124.793004 -258.015719)
			(xy 124.785061 -258.068423) (xy 124.769351 -258.119353) (xy 124.746225 -258.167374) (xy 124.716201 -258.211411)
			(xy 124.679949 -258.250482) (xy 124.638278 -258.283713) (xy 124.59212 -258.310362) (xy 124.542506 -258.329834)
			(xy 124.490544 -258.341694) (xy 124.437394 -258.345678) (xy 124.384244 -258.341694) (xy 124.332282 -258.329834)
			(xy 124.282668 -258.310362) (xy 124.23651 -258.283713) (xy 124.194839 -258.250482) (xy 124.158587 -258.211411)
			(xy 124.128563 -258.167374) (xy 124.105437 -258.119353) (xy 124.089727 -258.068423) (xy 124.081784 -258.015719)
			(xy 123.853204 -258.015719) (xy 123.845261 -258.068423) (xy 123.829551 -258.119353) (xy 123.806425 -258.167374)
			(xy 123.776401 -258.211411) (xy 123.740149 -258.250482) (xy 123.698478 -258.283713) (xy 123.65232 -258.310362)
			(xy 123.602706 -258.329834) (xy 123.550744 -258.341694) (xy 123.497594 -258.345678) (xy 123.444444 -258.341694)
			(xy 123.392482 -258.329834) (xy 123.342868 -258.310362) (xy 123.29671 -258.283713) (xy 123.255039 -258.250482)
			(xy 123.218787 -258.211411) (xy 123.188763 -258.167374) (xy 123.165637 -258.119353) (xy 123.149927 -258.068423)
			(xy 123.141984 -258.015719) (xy 122.913404 -258.015719) (xy 122.905461 -258.068423) (xy 122.889751 -258.119353)
			(xy 122.866625 -258.167374) (xy 122.836601 -258.211411) (xy 122.800349 -258.250482) (xy 122.758678 -258.283713)
			(xy 122.71252 -258.310362) (xy 122.662906 -258.329834) (xy 122.610944 -258.341694) (xy 122.557794 -258.345678)
			(xy 122.504644 -258.341694) (xy 122.452682 -258.329834) (xy 122.403068 -258.310362) (xy 122.35691 -258.283713)
			(xy 122.315239 -258.250482) (xy 122.278987 -258.211411) (xy 122.248963 -258.167374) (xy 122.225837 -258.119353)
			(xy 122.210127 -258.068423) (xy 122.202184 -258.015719) (xy 120.62968 -258.015719) (xy 120.62968 -258.065016)
			(xy 120.630112 -258.078598) (xy 120.637279 -258.1048) (xy 120.651102 -258.128184) (xy 120.670602 -258.147095)
			(xy 120.694399 -258.160196) (xy 120.720807 -258.166557) (xy 120.747959 -258.165729) (xy 120.773931 -258.157771)
			(xy 120.785636 -258.150868) (xy 120.80713 -258.137757) (xy 120.853024 -258.117055) (xy 120.901373 -258.103015)
			(xy 120.951217 -258.095917) (xy 120.97639 -258.095496) (xy 121.003041 -258.095968) (xy 121.055749 -258.103911)
			(xy 121.106684 -258.119622) (xy 121.154708 -258.142748) (xy 121.198749 -258.172773) (xy 121.237824 -258.209028)
			(xy 121.271058 -258.250701) (xy 121.297709 -258.296862) (xy 121.317183 -258.34648) (xy 121.329045 -258.398446)
			(xy 121.333028 -258.4516) (xy 121.329045 -258.504754) (xy 121.317183 -258.55672) (xy 121.297709 -258.606338)
			(xy 121.271058 -258.652499) (xy 121.237824 -258.694172) (xy 121.198749 -258.730427) (xy 121.154708 -258.760452)
			(xy 121.106684 -258.783578) (xy 121.055749 -258.799289) (xy 121.003041 -258.807232) (xy 120.97639 -258.807712)
			(xy 120.951218 -258.807277) (xy 120.901375 -258.800185) (xy 120.853028 -258.786143) (xy 120.80714 -258.765433)
			(xy 120.785636 -258.75234) (xy 120.77393 -258.745441) (xy 120.747959 -258.737482) (xy 120.720809 -258.736654)
			(xy 120.694402 -258.743015) (xy 120.670607 -258.756115) (xy 120.651108 -258.775026) (xy 120.637287 -258.79841)
			(xy 120.630122 -258.824611) (xy 120.629953 -258.829789) (xy 122.672084 -258.829789) (xy 122.672084 -258.776491)
			(xy 122.680027 -258.723787) (xy 122.695737 -258.672857) (xy 122.718863 -258.624836) (xy 122.748887 -258.580799)
			(xy 122.785139 -258.541728) (xy 122.82681 -258.508497) (xy 122.872968 -258.481848) (xy 122.922582 -258.462376)
			(xy 122.974544 -258.450516) (xy 123.027694 -258.446533) (xy 123.080844 -258.450516) (xy 123.132806 -258.462376)
			(xy 123.18242 -258.481848) (xy 123.228578 -258.508497) (xy 123.270249 -258.541728) (xy 123.306501 -258.580799)
			(xy 123.336525 -258.624836) (xy 123.359651 -258.672857) (xy 123.375361 -258.723787) (xy 123.383304 -258.776491)
			(xy 123.383802 -258.80314) (xy 123.383304 -258.829789) (xy 123.612138 -258.829789) (xy 123.612138 -258.776491)
			(xy 123.620081 -258.723787) (xy 123.635791 -258.672857) (xy 123.658917 -258.624836) (xy 123.688941 -258.580799)
			(xy 123.725193 -258.541728) (xy 123.766864 -258.508497) (xy 123.813022 -258.481848) (xy 123.862636 -258.462376)
			(xy 123.914598 -258.450516) (xy 123.967748 -258.446533) (xy 124.020898 -258.450516) (xy 124.07286 -258.462376)
			(xy 124.122474 -258.481848) (xy 124.168632 -258.508497) (xy 124.210303 -258.541728) (xy 124.246555 -258.580799)
			(xy 124.276579 -258.624836) (xy 124.299705 -258.672857) (xy 124.315415 -258.723787) (xy 124.323358 -258.776491)
			(xy 124.323856 -258.80314) (xy 124.323358 -258.829789) (xy 124.551938 -258.829789) (xy 124.551938 -258.776491)
			(xy 124.559881 -258.723787) (xy 124.575591 -258.672857) (xy 124.598717 -258.624836) (xy 124.628741 -258.580799)
			(xy 124.664993 -258.541728) (xy 124.706664 -258.508497) (xy 124.752822 -258.481848) (xy 124.802436 -258.462376)
			(xy 124.854398 -258.450516) (xy 124.907548 -258.446533) (xy 124.960698 -258.450516) (xy 125.01266 -258.462376)
			(xy 125.062274 -258.481848) (xy 125.108432 -258.508497) (xy 125.150103 -258.541728) (xy 125.186355 -258.580799)
			(xy 125.216379 -258.624836) (xy 125.239505 -258.672857) (xy 125.255215 -258.723787) (xy 125.263158 -258.776491)
			(xy 125.263656 -258.80314) (xy 125.263158 -258.829789) (xy 125.491738 -258.829789) (xy 125.491738 -258.776491)
			(xy 125.499681 -258.723787) (xy 125.515391 -258.672857) (xy 125.538517 -258.624836) (xy 125.568541 -258.580799)
			(xy 125.604793 -258.541728) (xy 125.646464 -258.508497) (xy 125.692622 -258.481848) (xy 125.742236 -258.462376)
			(xy 125.794198 -258.450516) (xy 125.847348 -258.446533) (xy 125.900498 -258.450516) (xy 125.95246 -258.462376)
			(xy 126.002074 -258.481848) (xy 126.048232 -258.508497) (xy 126.089903 -258.541728) (xy 126.126155 -258.580799)
			(xy 126.156179 -258.624836) (xy 126.179305 -258.672857) (xy 126.195015 -258.723787) (xy 126.202958 -258.776491)
			(xy 126.203456 -258.80314) (xy 126.202958 -258.829789) (xy 126.431538 -258.829789) (xy 126.431538 -258.776491)
			(xy 126.439481 -258.723787) (xy 126.455191 -258.672857) (xy 126.478317 -258.624836) (xy 126.508341 -258.580799)
			(xy 126.544593 -258.541728) (xy 126.586264 -258.508497) (xy 126.632422 -258.481848) (xy 126.682036 -258.462376)
			(xy 126.733998 -258.450516) (xy 126.787148 -258.446533) (xy 126.840298 -258.450516) (xy 126.89226 -258.462376)
			(xy 126.941874 -258.481848) (xy 126.988032 -258.508497) (xy 127.029703 -258.541728) (xy 127.065955 -258.580799)
			(xy 127.095979 -258.624836) (xy 127.119105 -258.672857) (xy 127.134815 -258.723787) (xy 127.142758 -258.776491)
			(xy 127.143256 -258.80314) (xy 127.142758 -258.829789) (xy 127.371338 -258.829789) (xy 127.371338 -258.776491)
			(xy 127.379281 -258.723787) (xy 127.394991 -258.672857) (xy 127.418117 -258.624836) (xy 127.448141 -258.580799)
			(xy 127.484393 -258.541728) (xy 127.526064 -258.508497) (xy 127.572222 -258.481848) (xy 127.621836 -258.462376)
			(xy 127.673798 -258.450516) (xy 127.726948 -258.446533) (xy 127.780098 -258.450516) (xy 127.83206 -258.462376)
			(xy 127.881674 -258.481848) (xy 127.927832 -258.508497) (xy 127.969503 -258.541728) (xy 128.005755 -258.580799)
			(xy 128.035779 -258.624836) (xy 128.058905 -258.672857) (xy 128.074615 -258.723787) (xy 128.082558 -258.776491)
			(xy 128.083056 -258.80314) (xy 128.082558 -258.829789) (xy 128.311138 -258.829789) (xy 128.311138 -258.776491)
			(xy 128.319081 -258.723787) (xy 128.334791 -258.672857) (xy 128.357917 -258.624836) (xy 128.387941 -258.580799)
			(xy 128.424193 -258.541728) (xy 128.465864 -258.508497) (xy 128.512022 -258.481848) (xy 128.561636 -258.462376)
			(xy 128.613598 -258.450516) (xy 128.666748 -258.446533) (xy 128.719898 -258.450516) (xy 128.77186 -258.462376)
			(xy 128.821474 -258.481848) (xy 128.867632 -258.508497) (xy 128.909303 -258.541728) (xy 128.945555 -258.580799)
			(xy 128.975579 -258.624836) (xy 128.998705 -258.672857) (xy 129.014415 -258.723787) (xy 129.022358 -258.776491)
			(xy 129.022856 -258.80314) (xy 129.022358 -258.829789) (xy 129.250684 -258.829789) (xy 129.250684 -258.776491)
			(xy 129.258627 -258.723787) (xy 129.274337 -258.672857) (xy 129.297463 -258.624836) (xy 129.327487 -258.580799)
			(xy 129.363739 -258.541728) (xy 129.40541 -258.508497) (xy 129.451568 -258.481848) (xy 129.501182 -258.462376)
			(xy 129.553144 -258.450516) (xy 129.606294 -258.446533) (xy 129.659444 -258.450516) (xy 129.711406 -258.462376)
			(xy 129.76102 -258.481848) (xy 129.807178 -258.508497) (xy 129.848849 -258.541728) (xy 129.885101 -258.580799)
			(xy 129.915125 -258.624836) (xy 129.938251 -258.672857) (xy 129.953961 -258.723787) (xy 129.961904 -258.776491)
			(xy 129.962402 -258.80314) (xy 129.961904 -258.829789) (xy 130.190738 -258.829789) (xy 130.190738 -258.776491)
			(xy 130.198681 -258.723787) (xy 130.214391 -258.672857) (xy 130.237517 -258.624836) (xy 130.267541 -258.580799)
			(xy 130.303793 -258.541728) (xy 130.345464 -258.508497) (xy 130.391622 -258.481848) (xy 130.441236 -258.462376)
			(xy 130.493198 -258.450516) (xy 130.546348 -258.446533) (xy 130.599498 -258.450516) (xy 130.65146 -258.462376)
			(xy 130.701074 -258.481848) (xy 130.747232 -258.508497) (xy 130.788903 -258.541728) (xy 130.825155 -258.580799)
			(xy 130.855179 -258.624836) (xy 130.878305 -258.672857) (xy 130.894015 -258.723787) (xy 130.901958 -258.776491)
			(xy 130.902456 -258.80314) (xy 130.901958 -258.829789) (xy 131.130538 -258.829789) (xy 131.130538 -258.776491)
			(xy 131.138481 -258.723787) (xy 131.154191 -258.672857) (xy 131.177317 -258.624836) (xy 131.207341 -258.580799)
			(xy 131.243593 -258.541728) (xy 131.285264 -258.508497) (xy 131.331422 -258.481848) (xy 131.381036 -258.462376)
			(xy 131.432998 -258.450516) (xy 131.486148 -258.446533) (xy 131.539298 -258.450516) (xy 131.59126 -258.462376)
			(xy 131.640874 -258.481848) (xy 131.687032 -258.508497) (xy 131.728703 -258.541728) (xy 131.764955 -258.580799)
			(xy 131.794979 -258.624836) (xy 131.818105 -258.672857) (xy 131.833815 -258.723787) (xy 131.841758 -258.776491)
			(xy 131.842256 -258.80314) (xy 131.841758 -258.829789) (xy 132.070338 -258.829789) (xy 132.070338 -258.776491)
			(xy 132.078281 -258.723787) (xy 132.093991 -258.672857) (xy 132.117117 -258.624836) (xy 132.147141 -258.580799)
			(xy 132.183393 -258.541728) (xy 132.225064 -258.508497) (xy 132.271222 -258.481848) (xy 132.320836 -258.462376)
			(xy 132.372798 -258.450516) (xy 132.425948 -258.446533) (xy 132.479098 -258.450516) (xy 132.53106 -258.462376)
			(xy 132.580674 -258.481848) (xy 132.626832 -258.508497) (xy 132.668503 -258.541728) (xy 132.704755 -258.580799)
			(xy 132.734779 -258.624836) (xy 132.757905 -258.672857) (xy 132.773615 -258.723787) (xy 132.781558 -258.776491)
			(xy 132.782056 -258.80314) (xy 132.781558 -258.829789) (xy 133.010138 -258.829789) (xy 133.010138 -258.776491)
			(xy 133.018081 -258.723787) (xy 133.033791 -258.672857) (xy 133.056917 -258.624836) (xy 133.086941 -258.580799)
			(xy 133.123193 -258.541728) (xy 133.164864 -258.508497) (xy 133.211022 -258.481848) (xy 133.260636 -258.462376)
			(xy 133.312598 -258.450516) (xy 133.365748 -258.446533) (xy 133.418898 -258.450516) (xy 133.47086 -258.462376)
			(xy 133.520474 -258.481848) (xy 133.566632 -258.508497) (xy 133.608303 -258.541728) (xy 133.644555 -258.580799)
			(xy 133.674579 -258.624836) (xy 133.697705 -258.672857) (xy 133.713415 -258.723787) (xy 133.721358 -258.776491)
			(xy 133.721856 -258.80314) (xy 133.721358 -258.829789) (xy 133.949938 -258.829789) (xy 133.949938 -258.776491)
			(xy 133.957881 -258.723787) (xy 133.973591 -258.672857) (xy 133.996717 -258.624836) (xy 134.026741 -258.580799)
			(xy 134.062993 -258.541728) (xy 134.104664 -258.508497) (xy 134.150822 -258.481848) (xy 134.200436 -258.462376)
			(xy 134.252398 -258.450516) (xy 134.305548 -258.446533) (xy 134.358698 -258.450516) (xy 134.41066 -258.462376)
			(xy 134.460274 -258.481848) (xy 134.506432 -258.508497) (xy 134.548103 -258.541728) (xy 134.584355 -258.580799)
			(xy 134.614379 -258.624836) (xy 134.637505 -258.672857) (xy 134.653215 -258.723787) (xy 134.661158 -258.776491)
			(xy 134.661656 -258.80314) (xy 134.661158 -258.829789) (xy 134.653215 -258.882493) (xy 134.637505 -258.933423)
			(xy 134.614379 -258.981444) (xy 134.584355 -259.025481) (xy 134.548103 -259.064552) (xy 134.506432 -259.097783)
			(xy 134.460274 -259.124432) (xy 134.41066 -259.143904) (xy 134.358698 -259.155764) (xy 134.305548 -259.159748)
			(xy 134.252398 -259.155764) (xy 134.200436 -259.143904) (xy 134.150822 -259.124432) (xy 134.104664 -259.097783)
			(xy 134.062993 -259.064552) (xy 134.026741 -259.025481) (xy 133.996717 -258.981444) (xy 133.973591 -258.933423)
			(xy 133.957881 -258.882493) (xy 133.949938 -258.829789) (xy 133.721358 -258.829789) (xy 133.713415 -258.882493)
			(xy 133.697705 -258.933423) (xy 133.674579 -258.981444) (xy 133.644555 -259.025481) (xy 133.608303 -259.064552)
			(xy 133.566632 -259.097783) (xy 133.520474 -259.124432) (xy 133.47086 -259.143904) (xy 133.418898 -259.155764)
			(xy 133.365748 -259.159748) (xy 133.312598 -259.155764) (xy 133.260636 -259.143904) (xy 133.211022 -259.124432)
			(xy 133.164864 -259.097783) (xy 133.123193 -259.064552) (xy 133.086941 -259.025481) (xy 133.056917 -258.981444)
			(xy 133.033791 -258.933423) (xy 133.018081 -258.882493) (xy 133.010138 -258.829789) (xy 132.781558 -258.829789)
			(xy 132.773615 -258.882493) (xy 132.757905 -258.933423) (xy 132.734779 -258.981444) (xy 132.704755 -259.025481)
			(xy 132.668503 -259.064552) (xy 132.626832 -259.097783) (xy 132.580674 -259.124432) (xy 132.53106 -259.143904)
			(xy 132.479098 -259.155764) (xy 132.425948 -259.159748) (xy 132.372798 -259.155764) (xy 132.320836 -259.143904)
			(xy 132.271222 -259.124432) (xy 132.225064 -259.097783) (xy 132.183393 -259.064552) (xy 132.147141 -259.025481)
			(xy 132.117117 -258.981444) (xy 132.093991 -258.933423) (xy 132.078281 -258.882493) (xy 132.070338 -258.829789)
			(xy 131.841758 -258.829789) (xy 131.833815 -258.882493) (xy 131.818105 -258.933423) (xy 131.794979 -258.981444)
			(xy 131.764955 -259.025481) (xy 131.728703 -259.064552) (xy 131.687032 -259.097783) (xy 131.640874 -259.124432)
			(xy 131.59126 -259.143904) (xy 131.539298 -259.155764) (xy 131.486148 -259.159748) (xy 131.432998 -259.155764)
			(xy 131.381036 -259.143904) (xy 131.331422 -259.124432) (xy 131.285264 -259.097783) (xy 131.243593 -259.064552)
			(xy 131.207341 -259.025481) (xy 131.177317 -258.981444) (xy 131.154191 -258.933423) (xy 131.138481 -258.882493)
			(xy 131.130538 -258.829789) (xy 130.901958 -258.829789) (xy 130.894015 -258.882493) (xy 130.878305 -258.933423)
			(xy 130.855179 -258.981444) (xy 130.825155 -259.025481) (xy 130.788903 -259.064552) (xy 130.747232 -259.097783)
			(xy 130.701074 -259.124432) (xy 130.65146 -259.143904) (xy 130.599498 -259.155764) (xy 130.546348 -259.159748)
			(xy 130.493198 -259.155764) (xy 130.441236 -259.143904) (xy 130.391622 -259.124432) (xy 130.345464 -259.097783)
			(xy 130.303793 -259.064552) (xy 130.267541 -259.025481) (xy 130.237517 -258.981444) (xy 130.214391 -258.933423)
			(xy 130.198681 -258.882493) (xy 130.190738 -258.829789) (xy 129.961904 -258.829789) (xy 129.953961 -258.882493)
			(xy 129.938251 -258.933423) (xy 129.915125 -258.981444) (xy 129.885101 -259.025481) (xy 129.848849 -259.064552)
			(xy 129.807178 -259.097783) (xy 129.76102 -259.124432) (xy 129.711406 -259.143904) (xy 129.659444 -259.155764)
			(xy 129.606294 -259.159748) (xy 129.553144 -259.155764) (xy 129.501182 -259.143904) (xy 129.451568 -259.124432)
			(xy 129.40541 -259.097783) (xy 129.363739 -259.064552) (xy 129.327487 -259.025481) (xy 129.297463 -258.981444)
			(xy 129.274337 -258.933423) (xy 129.258627 -258.882493) (xy 129.250684 -258.829789) (xy 129.022358 -258.829789)
			(xy 129.014415 -258.882493) (xy 128.998705 -258.933423) (xy 128.975579 -258.981444) (xy 128.945555 -259.025481)
			(xy 128.909303 -259.064552) (xy 128.867632 -259.097783) (xy 128.821474 -259.124432) (xy 128.77186 -259.143904)
			(xy 128.719898 -259.155764) (xy 128.666748 -259.159748) (xy 128.613598 -259.155764) (xy 128.561636 -259.143904)
			(xy 128.512022 -259.124432) (xy 128.465864 -259.097783) (xy 128.424193 -259.064552) (xy 128.387941 -259.025481)
			(xy 128.357917 -258.981444) (xy 128.334791 -258.933423) (xy 128.319081 -258.882493) (xy 128.311138 -258.829789)
			(xy 128.082558 -258.829789) (xy 128.074615 -258.882493) (xy 128.058905 -258.933423) (xy 128.035779 -258.981444)
			(xy 128.005755 -259.025481) (xy 127.969503 -259.064552) (xy 127.927832 -259.097783) (xy 127.881674 -259.124432)
			(xy 127.83206 -259.143904) (xy 127.780098 -259.155764) (xy 127.726948 -259.159748) (xy 127.673798 -259.155764)
			(xy 127.621836 -259.143904) (xy 127.572222 -259.124432) (xy 127.526064 -259.097783) (xy 127.484393 -259.064552)
			(xy 127.448141 -259.025481) (xy 127.418117 -258.981444) (xy 127.394991 -258.933423) (xy 127.379281 -258.882493)
			(xy 127.371338 -258.829789) (xy 127.142758 -258.829789) (xy 127.134815 -258.882493) (xy 127.119105 -258.933423)
			(xy 127.095979 -258.981444) (xy 127.065955 -259.025481) (xy 127.029703 -259.064552) (xy 126.988032 -259.097783)
			(xy 126.941874 -259.124432) (xy 126.89226 -259.143904) (xy 126.840298 -259.155764) (xy 126.787148 -259.159748)
			(xy 126.733998 -259.155764) (xy 126.682036 -259.143904) (xy 126.632422 -259.124432) (xy 126.586264 -259.097783)
			(xy 126.544593 -259.064552) (xy 126.508341 -259.025481) (xy 126.478317 -258.981444) (xy 126.455191 -258.933423)
			(xy 126.439481 -258.882493) (xy 126.431538 -258.829789) (xy 126.202958 -258.829789) (xy 126.195015 -258.882493)
			(xy 126.179305 -258.933423) (xy 126.156179 -258.981444) (xy 126.126155 -259.025481) (xy 126.089903 -259.064552)
			(xy 126.048232 -259.097783) (xy 126.002074 -259.124432) (xy 125.95246 -259.143904) (xy 125.900498 -259.155764)
			(xy 125.847348 -259.159748) (xy 125.794198 -259.155764) (xy 125.742236 -259.143904) (xy 125.692622 -259.124432)
			(xy 125.646464 -259.097783) (xy 125.604793 -259.064552) (xy 125.568541 -259.025481) (xy 125.538517 -258.981444)
			(xy 125.515391 -258.933423) (xy 125.499681 -258.882493) (xy 125.491738 -258.829789) (xy 125.263158 -258.829789)
			(xy 125.255215 -258.882493) (xy 125.239505 -258.933423) (xy 125.216379 -258.981444) (xy 125.186355 -259.025481)
			(xy 125.150103 -259.064552) (xy 125.108432 -259.097783) (xy 125.062274 -259.124432) (xy 125.01266 -259.143904)
			(xy 124.960698 -259.155764) (xy 124.907548 -259.159748) (xy 124.854398 -259.155764) (xy 124.802436 -259.143904)
			(xy 124.752822 -259.124432) (xy 124.706664 -259.097783) (xy 124.664993 -259.064552) (xy 124.628741 -259.025481)
			(xy 124.598717 -258.981444) (xy 124.575591 -258.933423) (xy 124.559881 -258.882493) (xy 124.551938 -258.829789)
			(xy 124.323358 -258.829789) (xy 124.315415 -258.882493) (xy 124.299705 -258.933423) (xy 124.276579 -258.981444)
			(xy 124.246555 -259.025481) (xy 124.210303 -259.064552) (xy 124.168632 -259.097783) (xy 124.122474 -259.124432)
			(xy 124.07286 -259.143904) (xy 124.020898 -259.155764) (xy 123.967748 -259.159748) (xy 123.914598 -259.155764)
			(xy 123.862636 -259.143904) (xy 123.813022 -259.124432) (xy 123.766864 -259.097783) (xy 123.725193 -259.064552)
			(xy 123.688941 -259.025481) (xy 123.658917 -258.981444) (xy 123.635791 -258.933423) (xy 123.620081 -258.882493)
			(xy 123.612138 -258.829789) (xy 123.383304 -258.829789) (xy 123.375361 -258.882493) (xy 123.359651 -258.933423)
			(xy 123.336525 -258.981444) (xy 123.306501 -259.025481) (xy 123.270249 -259.064552) (xy 123.228578 -259.097783)
			(xy 123.18242 -259.124432) (xy 123.132806 -259.143904) (xy 123.080844 -259.155764) (xy 123.027694 -259.159748)
			(xy 122.974544 -259.155764) (xy 122.922582 -259.143904) (xy 122.872968 -259.124432) (xy 122.82681 -259.097783)
			(xy 122.785139 -259.064552) (xy 122.748887 -259.025481) (xy 122.718863 -258.981444) (xy 122.695737 -258.933423)
			(xy 122.680027 -258.882493) (xy 122.672084 -258.829789) (xy 120.629953 -258.829789) (xy 120.62968 -258.838192)
			(xy 120.62968 -259.361432) (xy 120.630098 -259.374979) (xy 120.637213 -259.401122) (xy 120.650961 -259.424469)
			(xy 120.67037 -259.443372) (xy 120.694071 -259.456499) (xy 120.720392 -259.462923) (xy 120.747476 -259.46219)
			(xy 120.773411 -259.454353) (xy 120.785128 -259.447538) (xy 120.806441 -259.434706) (xy 120.851888 -259.414469)
			(xy 120.89971 -259.400757) (xy 120.948975 -259.393837) (xy 120.97385 -259.393436) (xy 121.001829 -259.393989)
			(xy 121.057098 -259.40275) (xy 121.110315 -259.42005) (xy 121.160171 -259.445461) (xy 121.205439 -259.478359)
			(xy 121.245002 -259.517933) (xy 121.277888 -259.563209) (xy 121.303286 -259.613072) (xy 121.313203 -259.643605)
			(xy 122.202184 -259.643605) (xy 122.202184 -259.590307) (xy 122.210127 -259.537603) (xy 122.225837 -259.486673)
			(xy 122.248963 -259.438652) (xy 122.278987 -259.394615) (xy 122.315239 -259.355544) (xy 122.35691 -259.322313)
			(xy 122.403068 -259.295664) (xy 122.452682 -259.276192) (xy 122.504644 -259.264332) (xy 122.557794 -259.260349)
			(xy 122.610944 -259.264332) (xy 122.662906 -259.276192) (xy 122.71252 -259.295664) (xy 122.758678 -259.322313)
			(xy 122.800349 -259.355544) (xy 122.836601 -259.394615) (xy 122.866625 -259.438652) (xy 122.889751 -259.486673)
			(xy 122.905461 -259.537603) (xy 122.913404 -259.590307) (xy 122.913902 -259.616956) (xy 122.913404 -259.643605)
			(xy 123.141984 -259.643605) (xy 123.141984 -259.590307) (xy 123.149927 -259.537603) (xy 123.165637 -259.486673)
			(xy 123.188763 -259.438652) (xy 123.218787 -259.394615) (xy 123.255039 -259.355544) (xy 123.29671 -259.322313)
			(xy 123.342868 -259.295664) (xy 123.392482 -259.276192) (xy 123.444444 -259.264332) (xy 123.497594 -259.260349)
			(xy 123.550744 -259.264332) (xy 123.602706 -259.276192) (xy 123.65232 -259.295664) (xy 123.698478 -259.322313)
			(xy 123.740149 -259.355544) (xy 123.776401 -259.394615) (xy 123.806425 -259.438652) (xy 123.829551 -259.486673)
			(xy 123.845261 -259.537603) (xy 123.853204 -259.590307) (xy 123.853702 -259.616956) (xy 123.853204 -259.643605)
			(xy 124.081784 -259.643605) (xy 124.081784 -259.590307) (xy 124.089727 -259.537603) (xy 124.105437 -259.486673)
			(xy 124.128563 -259.438652) (xy 124.158587 -259.394615) (xy 124.194839 -259.355544) (xy 124.23651 -259.322313)
			(xy 124.282668 -259.295664) (xy 124.332282 -259.276192) (xy 124.384244 -259.264332) (xy 124.437394 -259.260349)
			(xy 124.490544 -259.264332) (xy 124.542506 -259.276192) (xy 124.59212 -259.295664) (xy 124.638278 -259.322313)
			(xy 124.679949 -259.355544) (xy 124.716201 -259.394615) (xy 124.746225 -259.438652) (xy 124.769351 -259.486673)
			(xy 124.785061 -259.537603) (xy 124.793004 -259.590307) (xy 124.793502 -259.616956) (xy 124.793004 -259.643605)
			(xy 125.021584 -259.643605) (xy 125.021584 -259.590307) (xy 125.029527 -259.537603) (xy 125.045237 -259.486673)
			(xy 125.068363 -259.438652) (xy 125.098387 -259.394615) (xy 125.134639 -259.355544) (xy 125.17631 -259.322313)
			(xy 125.222468 -259.295664) (xy 125.272082 -259.276192) (xy 125.324044 -259.264332) (xy 125.377194 -259.260349)
			(xy 125.430344 -259.264332) (xy 125.482306 -259.276192) (xy 125.53192 -259.295664) (xy 125.578078 -259.322313)
			(xy 125.619749 -259.355544) (xy 125.656001 -259.394615) (xy 125.686025 -259.438652) (xy 125.709151 -259.486673)
			(xy 125.724861 -259.537603) (xy 125.732804 -259.590307) (xy 125.733302 -259.616956) (xy 125.732804 -259.643605)
			(xy 125.961384 -259.643605) (xy 125.961384 -259.590307) (xy 125.969327 -259.537603) (xy 125.985037 -259.486673)
			(xy 126.008163 -259.438652) (xy 126.038187 -259.394615) (xy 126.074439 -259.355544) (xy 126.11611 -259.322313)
			(xy 126.162268 -259.295664) (xy 126.211882 -259.276192) (xy 126.263844 -259.264332) (xy 126.316994 -259.260349)
			(xy 126.370144 -259.264332) (xy 126.422106 -259.276192) (xy 126.47172 -259.295664) (xy 126.517878 -259.322313)
			(xy 126.559549 -259.355544) (xy 126.595801 -259.394615) (xy 126.625825 -259.438652) (xy 126.648951 -259.486673)
			(xy 126.664661 -259.537603) (xy 126.672604 -259.590307) (xy 126.673102 -259.616956) (xy 126.672604 -259.643605)
			(xy 126.901184 -259.643605) (xy 126.901184 -259.590307) (xy 126.909127 -259.537603) (xy 126.924837 -259.486673)
			(xy 126.947963 -259.438652) (xy 126.977987 -259.394615) (xy 127.014239 -259.355544) (xy 127.05591 -259.322313)
			(xy 127.102068 -259.295664) (xy 127.151682 -259.276192) (xy 127.203644 -259.264332) (xy 127.256794 -259.260349)
			(xy 127.309944 -259.264332) (xy 127.361906 -259.276192) (xy 127.41152 -259.295664) (xy 127.457678 -259.322313)
			(xy 127.499349 -259.355544) (xy 127.535601 -259.394615) (xy 127.565625 -259.438652) (xy 127.588751 -259.486673)
			(xy 127.604461 -259.537603) (xy 127.612404 -259.590307) (xy 127.612902 -259.616956) (xy 127.612404 -259.643605)
			(xy 127.840984 -259.643605) (xy 127.840984 -259.590307) (xy 127.848927 -259.537603) (xy 127.864637 -259.486673)
			(xy 127.887763 -259.438652) (xy 127.917787 -259.394615) (xy 127.954039 -259.355544) (xy 127.99571 -259.322313)
			(xy 128.041868 -259.295664) (xy 128.091482 -259.276192) (xy 128.143444 -259.264332) (xy 128.196594 -259.260349)
			(xy 128.249744 -259.264332) (xy 128.301706 -259.276192) (xy 128.35132 -259.295664) (xy 128.397478 -259.322313)
			(xy 128.439149 -259.355544) (xy 128.475401 -259.394615) (xy 128.505425 -259.438652) (xy 128.528551 -259.486673)
			(xy 128.544261 -259.537603) (xy 128.552204 -259.590307) (xy 128.552702 -259.616956) (xy 128.552204 -259.643605)
			(xy 128.780784 -259.643605) (xy 128.780784 -259.590307) (xy 128.788727 -259.537603) (xy 128.804437 -259.486673)
			(xy 128.827563 -259.438652) (xy 128.857587 -259.394615) (xy 128.893839 -259.355544) (xy 128.93551 -259.322313)
			(xy 128.981668 -259.295664) (xy 129.031282 -259.276192) (xy 129.083244 -259.264332) (xy 129.136394 -259.260349)
			(xy 129.189544 -259.264332) (xy 129.241506 -259.276192) (xy 129.29112 -259.295664) (xy 129.337278 -259.322313)
			(xy 129.378949 -259.355544) (xy 129.415201 -259.394615) (xy 129.445225 -259.438652) (xy 129.468351 -259.486673)
			(xy 129.484061 -259.537603) (xy 129.492004 -259.590307) (xy 129.492502 -259.616956) (xy 129.492004 -259.643605)
			(xy 129.720584 -259.643605) (xy 129.720584 -259.590307) (xy 129.728527 -259.537603) (xy 129.744237 -259.486673)
			(xy 129.767363 -259.438652) (xy 129.797387 -259.394615) (xy 129.833639 -259.355544) (xy 129.87531 -259.322313)
			(xy 129.921468 -259.295664) (xy 129.971082 -259.276192) (xy 130.023044 -259.264332) (xy 130.076194 -259.260349)
			(xy 130.129344 -259.264332) (xy 130.181306 -259.276192) (xy 130.23092 -259.295664) (xy 130.277078 -259.322313)
			(xy 130.318749 -259.355544) (xy 130.355001 -259.394615) (xy 130.385025 -259.438652) (xy 130.408151 -259.486673)
			(xy 130.423861 -259.537603) (xy 130.431804 -259.590307) (xy 130.432302 -259.616956) (xy 130.431804 -259.643605)
			(xy 130.660384 -259.643605) (xy 130.660384 -259.590307) (xy 130.668327 -259.537603) (xy 130.684037 -259.486673)
			(xy 130.707163 -259.438652) (xy 130.737187 -259.394615) (xy 130.773439 -259.355544) (xy 130.81511 -259.322313)
			(xy 130.861268 -259.295664) (xy 130.910882 -259.276192) (xy 130.962844 -259.264332) (xy 131.015994 -259.260349)
			(xy 131.069144 -259.264332) (xy 131.121106 -259.276192) (xy 131.17072 -259.295664) (xy 131.216878 -259.322313)
			(xy 131.258549 -259.355544) (xy 131.294801 -259.394615) (xy 131.324825 -259.438652) (xy 131.347951 -259.486673)
			(xy 131.363661 -259.537603) (xy 131.371604 -259.590307) (xy 131.372102 -259.616956) (xy 131.371604 -259.643605)
			(xy 131.600184 -259.643605) (xy 131.600184 -259.590307) (xy 131.608127 -259.537603) (xy 131.623837 -259.486673)
			(xy 131.646963 -259.438652) (xy 131.676987 -259.394615) (xy 131.713239 -259.355544) (xy 131.75491 -259.322313)
			(xy 131.801068 -259.295664) (xy 131.850682 -259.276192) (xy 131.902644 -259.264332) (xy 131.955794 -259.260349)
			(xy 132.008944 -259.264332) (xy 132.060906 -259.276192) (xy 132.11052 -259.295664) (xy 132.156678 -259.322313)
			(xy 132.198349 -259.355544) (xy 132.234601 -259.394615) (xy 132.264625 -259.438652) (xy 132.287751 -259.486673)
			(xy 132.303461 -259.537603) (xy 132.311404 -259.590307) (xy 132.311902 -259.616956) (xy 132.311404 -259.643605)
			(xy 132.539984 -259.643605) (xy 132.539984 -259.590307) (xy 132.547927 -259.537603) (xy 132.563637 -259.486673)
			(xy 132.586763 -259.438652) (xy 132.616787 -259.394615) (xy 132.653039 -259.355544) (xy 132.69471 -259.322313)
			(xy 132.740868 -259.295664) (xy 132.790482 -259.276192) (xy 132.842444 -259.264332) (xy 132.895594 -259.260349)
			(xy 132.948744 -259.264332) (xy 133.000706 -259.276192) (xy 133.05032 -259.295664) (xy 133.096478 -259.322313)
			(xy 133.138149 -259.355544) (xy 133.174401 -259.394615) (xy 133.204425 -259.438652) (xy 133.227551 -259.486673)
			(xy 133.243261 -259.537603) (xy 133.251204 -259.590307) (xy 133.251702 -259.616956) (xy 133.251204 -259.643605)
			(xy 133.479784 -259.643605) (xy 133.479784 -259.590307) (xy 133.487727 -259.537603) (xy 133.503437 -259.486673)
			(xy 133.526563 -259.438652) (xy 133.556587 -259.394615) (xy 133.592839 -259.355544) (xy 133.63451 -259.322313)
			(xy 133.680668 -259.295664) (xy 133.730282 -259.276192) (xy 133.782244 -259.264332) (xy 133.835394 -259.260349)
			(xy 133.888544 -259.264332) (xy 133.940506 -259.276192) (xy 133.99012 -259.295664) (xy 134.036278 -259.322313)
			(xy 134.077949 -259.355544) (xy 134.114201 -259.394615) (xy 134.144225 -259.438652) (xy 134.167351 -259.486673)
			(xy 134.183061 -259.537603) (xy 134.191004 -259.590307) (xy 134.191502 -259.616956) (xy 134.191004 -259.643605)
			(xy 134.419584 -259.643605) (xy 134.419584 -259.590307) (xy 134.427527 -259.537603) (xy 134.443237 -259.486673)
			(xy 134.466363 -259.438652) (xy 134.496387 -259.394615) (xy 134.532639 -259.355544) (xy 134.57431 -259.322313)
			(xy 134.620468 -259.295664) (xy 134.670082 -259.276192) (xy 134.722044 -259.264332) (xy 134.775194 -259.260349)
			(xy 134.828344 -259.264332) (xy 134.880306 -259.276192) (xy 134.92992 -259.295664) (xy 134.976078 -259.322313)
			(xy 135.017749 -259.355544) (xy 135.054001 -259.394615) (xy 135.084025 -259.438652) (xy 135.107151 -259.486673)
			(xy 135.122861 -259.537603) (xy 135.130804 -259.590307) (xy 135.131302 -259.616956) (xy 135.130804 -259.643605)
			(xy 135.122861 -259.696309) (xy 135.107151 -259.747239) (xy 135.084025 -259.79526) (xy 135.054001 -259.839297)
			(xy 135.017749 -259.878368) (xy 134.976078 -259.911599) (xy 134.92992 -259.938248) (xy 134.880306 -259.95772)
			(xy 134.828344 -259.96958) (xy 134.775194 -259.973564) (xy 134.722044 -259.96958) (xy 134.670082 -259.95772)
			(xy 134.620468 -259.938248) (xy 134.57431 -259.911599) (xy 134.532639 -259.878368) (xy 134.496387 -259.839297)
			(xy 134.466363 -259.79526) (xy 134.443237 -259.747239) (xy 134.427527 -259.696309) (xy 134.419584 -259.643605)
			(xy 134.191004 -259.643605) (xy 134.183061 -259.696309) (xy 134.167351 -259.747239) (xy 134.144225 -259.79526)
			(xy 134.114201 -259.839297) (xy 134.077949 -259.878368) (xy 134.036278 -259.911599) (xy 133.99012 -259.938248)
			(xy 133.940506 -259.95772) (xy 133.888544 -259.96958) (xy 133.835394 -259.973564) (xy 133.782244 -259.96958)
			(xy 133.730282 -259.95772) (xy 133.680668 -259.938248) (xy 133.63451 -259.911599) (xy 133.592839 -259.878368)
			(xy 133.556587 -259.839297) (xy 133.526563 -259.79526) (xy 133.503437 -259.747239) (xy 133.487727 -259.696309)
			(xy 133.479784 -259.643605) (xy 133.251204 -259.643605) (xy 133.243261 -259.696309) (xy 133.227551 -259.747239)
			(xy 133.204425 -259.79526) (xy 133.174401 -259.839297) (xy 133.138149 -259.878368) (xy 133.096478 -259.911599)
			(xy 133.05032 -259.938248) (xy 133.000706 -259.95772) (xy 132.948744 -259.96958) (xy 132.895594 -259.973564)
			(xy 132.842444 -259.96958) (xy 132.790482 -259.95772) (xy 132.740868 -259.938248) (xy 132.69471 -259.911599)
			(xy 132.653039 -259.878368) (xy 132.616787 -259.839297) (xy 132.586763 -259.79526) (xy 132.563637 -259.747239)
			(xy 132.547927 -259.696309) (xy 132.539984 -259.643605) (xy 132.311404 -259.643605) (xy 132.303461 -259.696309)
			(xy 132.287751 -259.747239) (xy 132.264625 -259.79526) (xy 132.234601 -259.839297) (xy 132.198349 -259.878368)
			(xy 132.156678 -259.911599) (xy 132.11052 -259.938248) (xy 132.060906 -259.95772) (xy 132.008944 -259.96958)
			(xy 131.955794 -259.973564) (xy 131.902644 -259.96958) (xy 131.850682 -259.95772) (xy 131.801068 -259.938248)
			(xy 131.75491 -259.911599) (xy 131.713239 -259.878368) (xy 131.676987 -259.839297) (xy 131.646963 -259.79526)
			(xy 131.623837 -259.747239) (xy 131.608127 -259.696309) (xy 131.600184 -259.643605) (xy 131.371604 -259.643605)
			(xy 131.363661 -259.696309) (xy 131.347951 -259.747239) (xy 131.324825 -259.79526) (xy 131.294801 -259.839297)
			(xy 131.258549 -259.878368) (xy 131.216878 -259.911599) (xy 131.17072 -259.938248) (xy 131.121106 -259.95772)
			(xy 131.069144 -259.96958) (xy 131.015994 -259.973564) (xy 130.962844 -259.96958) (xy 130.910882 -259.95772)
			(xy 130.861268 -259.938248) (xy 130.81511 -259.911599) (xy 130.773439 -259.878368) (xy 130.737187 -259.839297)
			(xy 130.707163 -259.79526) (xy 130.684037 -259.747239) (xy 130.668327 -259.696309) (xy 130.660384 -259.643605)
			(xy 130.431804 -259.643605) (xy 130.423861 -259.696309) (xy 130.408151 -259.747239) (xy 130.385025 -259.79526)
			(xy 130.355001 -259.839297) (xy 130.318749 -259.878368) (xy 130.277078 -259.911599) (xy 130.23092 -259.938248)
			(xy 130.181306 -259.95772) (xy 130.129344 -259.96958) (xy 130.076194 -259.973564) (xy 130.023044 -259.96958)
			(xy 129.971082 -259.95772) (xy 129.921468 -259.938248) (xy 129.87531 -259.911599) (xy 129.833639 -259.878368)
			(xy 129.797387 -259.839297) (xy 129.767363 -259.79526) (xy 129.744237 -259.747239) (xy 129.728527 -259.696309)
			(xy 129.720584 -259.643605) (xy 129.492004 -259.643605) (xy 129.484061 -259.696309) (xy 129.468351 -259.747239)
			(xy 129.445225 -259.79526) (xy 129.415201 -259.839297) (xy 129.378949 -259.878368) (xy 129.337278 -259.911599)
			(xy 129.29112 -259.938248) (xy 129.241506 -259.95772) (xy 129.189544 -259.96958) (xy 129.136394 -259.973564)
			(xy 129.083244 -259.96958) (xy 129.031282 -259.95772) (xy 128.981668 -259.938248) (xy 128.93551 -259.911599)
			(xy 128.893839 -259.878368) (xy 128.857587 -259.839297) (xy 128.827563 -259.79526) (xy 128.804437 -259.747239)
			(xy 128.788727 -259.696309) (xy 128.780784 -259.643605) (xy 128.552204 -259.643605) (xy 128.544261 -259.696309)
			(xy 128.528551 -259.747239) (xy 128.505425 -259.79526) (xy 128.475401 -259.839297) (xy 128.439149 -259.878368)
			(xy 128.397478 -259.911599) (xy 128.35132 -259.938248) (xy 128.301706 -259.95772) (xy 128.249744 -259.96958)
			(xy 128.196594 -259.973564) (xy 128.143444 -259.96958) (xy 128.091482 -259.95772) (xy 128.041868 -259.938248)
			(xy 127.99571 -259.911599) (xy 127.954039 -259.878368) (xy 127.917787 -259.839297) (xy 127.887763 -259.79526)
			(xy 127.864637 -259.747239) (xy 127.848927 -259.696309) (xy 127.840984 -259.643605) (xy 127.612404 -259.643605)
			(xy 127.604461 -259.696309) (xy 127.588751 -259.747239) (xy 127.565625 -259.79526) (xy 127.535601 -259.839297)
			(xy 127.499349 -259.878368) (xy 127.457678 -259.911599) (xy 127.41152 -259.938248) (xy 127.361906 -259.95772)
			(xy 127.309944 -259.96958) (xy 127.256794 -259.973564) (xy 127.203644 -259.96958) (xy 127.151682 -259.95772)
			(xy 127.102068 -259.938248) (xy 127.05591 -259.911599) (xy 127.014239 -259.878368) (xy 126.977987 -259.839297)
			(xy 126.947963 -259.79526) (xy 126.924837 -259.747239) (xy 126.909127 -259.696309) (xy 126.901184 -259.643605)
			(xy 126.672604 -259.643605) (xy 126.664661 -259.696309) (xy 126.648951 -259.747239) (xy 126.625825 -259.79526)
			(xy 126.595801 -259.839297) (xy 126.559549 -259.878368) (xy 126.517878 -259.911599) (xy 126.47172 -259.938248)
			(xy 126.422106 -259.95772) (xy 126.370144 -259.96958) (xy 126.316994 -259.973564) (xy 126.263844 -259.96958)
			(xy 126.211882 -259.95772) (xy 126.162268 -259.938248) (xy 126.11611 -259.911599) (xy 126.074439 -259.878368)
			(xy 126.038187 -259.839297) (xy 126.008163 -259.79526) (xy 125.985037 -259.747239) (xy 125.969327 -259.696309)
			(xy 125.961384 -259.643605) (xy 125.732804 -259.643605) (xy 125.724861 -259.696309) (xy 125.709151 -259.747239)
			(xy 125.686025 -259.79526) (xy 125.656001 -259.839297) (xy 125.619749 -259.878368) (xy 125.578078 -259.911599)
			(xy 125.53192 -259.938248) (xy 125.482306 -259.95772) (xy 125.430344 -259.96958) (xy 125.377194 -259.973564)
			(xy 125.324044 -259.96958) (xy 125.272082 -259.95772) (xy 125.222468 -259.938248) (xy 125.17631 -259.911599)
			(xy 125.134639 -259.878368) (xy 125.098387 -259.839297) (xy 125.068363 -259.79526) (xy 125.045237 -259.747239)
			(xy 125.029527 -259.696309) (xy 125.021584 -259.643605) (xy 124.793004 -259.643605) (xy 124.785061 -259.696309)
			(xy 124.769351 -259.747239) (xy 124.746225 -259.79526) (xy 124.716201 -259.839297) (xy 124.679949 -259.878368)
			(xy 124.638278 -259.911599) (xy 124.59212 -259.938248) (xy 124.542506 -259.95772) (xy 124.490544 -259.96958)
			(xy 124.437394 -259.973564) (xy 124.384244 -259.96958) (xy 124.332282 -259.95772) (xy 124.282668 -259.938248)
			(xy 124.23651 -259.911599) (xy 124.194839 -259.878368) (xy 124.158587 -259.839297) (xy 124.128563 -259.79526)
			(xy 124.105437 -259.747239) (xy 124.089727 -259.696309) (xy 124.081784 -259.643605) (xy 123.853204 -259.643605)
			(xy 123.845261 -259.696309) (xy 123.829551 -259.747239) (xy 123.806425 -259.79526) (xy 123.776401 -259.839297)
			(xy 123.740149 -259.878368) (xy 123.698478 -259.911599) (xy 123.65232 -259.938248) (xy 123.602706 -259.95772)
			(xy 123.550744 -259.96958) (xy 123.497594 -259.973564) (xy 123.444444 -259.96958) (xy 123.392482 -259.95772)
			(xy 123.342868 -259.938248) (xy 123.29671 -259.911599) (xy 123.255039 -259.878368) (xy 123.218787 -259.839297)
			(xy 123.188763 -259.79526) (xy 123.165637 -259.747239) (xy 123.149927 -259.696309) (xy 123.141984 -259.643605)
			(xy 122.913404 -259.643605) (xy 122.905461 -259.696309) (xy 122.889751 -259.747239) (xy 122.866625 -259.79526)
			(xy 122.836601 -259.839297) (xy 122.800349 -259.878368) (xy 122.758678 -259.911599) (xy 122.71252 -259.938248)
			(xy 122.662906 -259.95772) (xy 122.610944 -259.96958) (xy 122.557794 -259.973564) (xy 122.504644 -259.96958)
			(xy 122.452682 -259.95772) (xy 122.403068 -259.938248) (xy 122.35691 -259.911599) (xy 122.315239 -259.878368)
			(xy 122.278987 -259.839297) (xy 122.248963 -259.79526) (xy 122.225837 -259.747239) (xy 122.210127 -259.696309)
			(xy 122.202184 -259.643605) (xy 121.313203 -259.643605) (xy 121.320572 -259.666294) (xy 121.329319 -259.721565)
			(xy 121.329958 -259.749544) (xy 121.329527 -259.77503) (xy 121.322268 -259.825484) (xy 121.307891 -259.874387)
			(xy 121.286688 -259.92074) (xy 121.259095 -259.963598) (xy 121.225673 -260.002084) (xy 121.187106 -260.035413)
			(xy 121.165874 -260.049518) (xy 121.153411 -260.058144) (xy 121.1338 -260.081233) (xy 121.121834 -260.109063)
			(xy 121.118567 -260.13918) (xy 121.124289 -260.168928) (xy 121.138494 -260.195685) (xy 121.148856 -260.206744)
			(xy 121.399533 -260.457421) (xy 121.732538 -260.457421) (xy 121.732538 -260.404123) (xy 121.740481 -260.351419)
			(xy 121.756191 -260.300489) (xy 121.779317 -260.252468) (xy 121.809341 -260.208431) (xy 121.845593 -260.16936)
			(xy 121.887264 -260.136129) (xy 121.933422 -260.10948) (xy 121.983036 -260.090008) (xy 122.034998 -260.078148)
			(xy 122.088148 -260.074165) (xy 122.141298 -260.078148) (xy 122.19326 -260.090008) (xy 122.242874 -260.10948)
			(xy 122.289032 -260.136129) (xy 122.330703 -260.16936) (xy 122.366955 -260.208431) (xy 122.396979 -260.252468)
			(xy 122.420105 -260.300489) (xy 122.435815 -260.351419) (xy 122.443758 -260.404123) (xy 122.444256 -260.430772)
			(xy 122.443758 -260.457421) (xy 122.672338 -260.457421) (xy 122.672338 -260.404123) (xy 122.680281 -260.351419)
			(xy 122.695991 -260.300489) (xy 122.719117 -260.252468) (xy 122.749141 -260.208431) (xy 122.785393 -260.16936)
			(xy 122.827064 -260.136129) (xy 122.873222 -260.10948) (xy 122.922836 -260.090008) (xy 122.974798 -260.078148)
			(xy 123.027948 -260.074165) (xy 123.081098 -260.078148) (xy 123.13306 -260.090008) (xy 123.182674 -260.10948)
			(xy 123.228832 -260.136129) (xy 123.270503 -260.16936) (xy 123.306755 -260.208431) (xy 123.336779 -260.252468)
			(xy 123.359905 -260.300489) (xy 123.375615 -260.351419) (xy 123.383558 -260.404123) (xy 123.384056 -260.430772)
			(xy 123.383558 -260.457421) (xy 123.612138 -260.457421) (xy 123.612138 -260.404123) (xy 123.620081 -260.351419)
			(xy 123.635791 -260.300489) (xy 123.658917 -260.252468) (xy 123.688941 -260.208431) (xy 123.725193 -260.16936)
			(xy 123.766864 -260.136129) (xy 123.813022 -260.10948) (xy 123.862636 -260.090008) (xy 123.914598 -260.078148)
			(xy 123.967748 -260.074165) (xy 124.020898 -260.078148) (xy 124.07286 -260.090008) (xy 124.122474 -260.10948)
			(xy 124.168632 -260.136129) (xy 124.210303 -260.16936) (xy 124.246555 -260.208431) (xy 124.276579 -260.252468)
			(xy 124.299705 -260.300489) (xy 124.315415 -260.351419) (xy 124.323358 -260.404123) (xy 124.323856 -260.430772)
			(xy 124.323358 -260.457421) (xy 124.551938 -260.457421) (xy 124.551938 -260.404123) (xy 124.559881 -260.351419)
			(xy 124.575591 -260.300489) (xy 124.598717 -260.252468) (xy 124.628741 -260.208431) (xy 124.664993 -260.16936)
			(xy 124.706664 -260.136129) (xy 124.752822 -260.10948) (xy 124.802436 -260.090008) (xy 124.854398 -260.078148)
			(xy 124.907548 -260.074165) (xy 124.960698 -260.078148) (xy 125.01266 -260.090008) (xy 125.062274 -260.10948)
			(xy 125.108432 -260.136129) (xy 125.150103 -260.16936) (xy 125.186355 -260.208431) (xy 125.216379 -260.252468)
			(xy 125.239505 -260.300489) (xy 125.255215 -260.351419) (xy 125.263158 -260.404123) (xy 125.263656 -260.430772)
			(xy 125.263158 -260.457421) (xy 125.491738 -260.457421) (xy 125.491738 -260.404123) (xy 125.499681 -260.351419)
			(xy 125.515391 -260.300489) (xy 125.538517 -260.252468) (xy 125.568541 -260.208431) (xy 125.604793 -260.16936)
			(xy 125.646464 -260.136129) (xy 125.692622 -260.10948) (xy 125.742236 -260.090008) (xy 125.794198 -260.078148)
			(xy 125.847348 -260.074165) (xy 125.900498 -260.078148) (xy 125.95246 -260.090008) (xy 126.002074 -260.10948)
			(xy 126.048232 -260.136129) (xy 126.089903 -260.16936) (xy 126.126155 -260.208431) (xy 126.156179 -260.252468)
			(xy 126.179305 -260.300489) (xy 126.195015 -260.351419) (xy 126.202958 -260.404123) (xy 126.203456 -260.430772)
			(xy 126.202958 -260.457421) (xy 126.431284 -260.457421) (xy 126.431284 -260.404123) (xy 126.439227 -260.351419)
			(xy 126.454937 -260.300489) (xy 126.478063 -260.252468) (xy 126.508087 -260.208431) (xy 126.544339 -260.16936)
			(xy 126.58601 -260.136129) (xy 126.632168 -260.10948) (xy 126.681782 -260.090008) (xy 126.733744 -260.078148)
			(xy 126.786894 -260.074165) (xy 126.840044 -260.078148) (xy 126.892006 -260.090008) (xy 126.94162 -260.10948)
			(xy 126.987778 -260.136129) (xy 127.029449 -260.16936) (xy 127.065701 -260.208431) (xy 127.095725 -260.252468)
			(xy 127.118851 -260.300489) (xy 127.134561 -260.351419) (xy 127.142504 -260.404123) (xy 127.143002 -260.430772)
			(xy 127.142504 -260.457421) (xy 127.371338 -260.457421) (xy 127.371338 -260.404123) (xy 127.379281 -260.351419)
			(xy 127.394991 -260.300489) (xy 127.418117 -260.252468) (xy 127.448141 -260.208431) (xy 127.484393 -260.16936)
			(xy 127.526064 -260.136129) (xy 127.572222 -260.10948) (xy 127.621836 -260.090008) (xy 127.673798 -260.078148)
			(xy 127.726948 -260.074165) (xy 127.780098 -260.078148) (xy 127.83206 -260.090008) (xy 127.881674 -260.10948)
			(xy 127.927832 -260.136129) (xy 127.969503 -260.16936) (xy 128.005755 -260.208431) (xy 128.035779 -260.252468)
			(xy 128.058905 -260.300489) (xy 128.074615 -260.351419) (xy 128.082558 -260.404123) (xy 128.083056 -260.430772)
			(xy 128.082558 -260.457421) (xy 128.311138 -260.457421) (xy 128.311138 -260.404123) (xy 128.319081 -260.351419)
			(xy 128.334791 -260.300489) (xy 128.357917 -260.252468) (xy 128.387941 -260.208431) (xy 128.424193 -260.16936)
			(xy 128.465864 -260.136129) (xy 128.512022 -260.10948) (xy 128.561636 -260.090008) (xy 128.613598 -260.078148)
			(xy 128.666748 -260.074165) (xy 128.719898 -260.078148) (xy 128.77186 -260.090008) (xy 128.821474 -260.10948)
			(xy 128.867632 -260.136129) (xy 128.909303 -260.16936) (xy 128.945555 -260.208431) (xy 128.975579 -260.252468)
			(xy 128.998705 -260.300489) (xy 129.014415 -260.351419) (xy 129.022358 -260.404123) (xy 129.022856 -260.430772)
			(xy 129.022358 -260.457421) (xy 129.250938 -260.457421) (xy 129.250938 -260.404123) (xy 129.258881 -260.351419)
			(xy 129.274591 -260.300489) (xy 129.297717 -260.252468) (xy 129.327741 -260.208431) (xy 129.363993 -260.16936)
			(xy 129.405664 -260.136129) (xy 129.451822 -260.10948) (xy 129.501436 -260.090008) (xy 129.553398 -260.078148)
			(xy 129.606548 -260.074165) (xy 129.659698 -260.078148) (xy 129.71166 -260.090008) (xy 129.761274 -260.10948)
			(xy 129.807432 -260.136129) (xy 129.849103 -260.16936) (xy 129.885355 -260.208431) (xy 129.915379 -260.252468)
			(xy 129.938505 -260.300489) (xy 129.954215 -260.351419) (xy 129.962158 -260.404123) (xy 129.962656 -260.430772)
			(xy 129.962158 -260.457421) (xy 130.190738 -260.457421) (xy 130.190738 -260.404123) (xy 130.198681 -260.351419)
			(xy 130.214391 -260.300489) (xy 130.237517 -260.252468) (xy 130.267541 -260.208431) (xy 130.303793 -260.16936)
			(xy 130.345464 -260.136129) (xy 130.391622 -260.10948) (xy 130.441236 -260.090008) (xy 130.493198 -260.078148)
			(xy 130.546348 -260.074165) (xy 130.599498 -260.078148) (xy 130.65146 -260.090008) (xy 130.701074 -260.10948)
			(xy 130.747232 -260.136129) (xy 130.788903 -260.16936) (xy 130.825155 -260.208431) (xy 130.855179 -260.252468)
			(xy 130.878305 -260.300489) (xy 130.894015 -260.351419) (xy 130.901958 -260.404123) (xy 130.902456 -260.430772)
			(xy 130.901958 -260.457421) (xy 131.130538 -260.457421) (xy 131.130538 -260.404123) (xy 131.138481 -260.351419)
			(xy 131.154191 -260.300489) (xy 131.177317 -260.252468) (xy 131.207341 -260.208431) (xy 131.243593 -260.16936)
			(xy 131.285264 -260.136129) (xy 131.331422 -260.10948) (xy 131.381036 -260.090008) (xy 131.432998 -260.078148)
			(xy 131.486148 -260.074165) (xy 131.539298 -260.078148) (xy 131.59126 -260.090008) (xy 131.640874 -260.10948)
			(xy 131.687032 -260.136129) (xy 131.728703 -260.16936) (xy 131.764955 -260.208431) (xy 131.794979 -260.252468)
			(xy 131.818105 -260.300489) (xy 131.833815 -260.351419) (xy 131.841758 -260.404123) (xy 131.842256 -260.430772)
			(xy 131.841758 -260.457421) (xy 132.070338 -260.457421) (xy 132.070338 -260.404123) (xy 132.078281 -260.351419)
			(xy 132.093991 -260.300489) (xy 132.117117 -260.252468) (xy 132.147141 -260.208431) (xy 132.183393 -260.16936)
			(xy 132.225064 -260.136129) (xy 132.271222 -260.10948) (xy 132.320836 -260.090008) (xy 132.372798 -260.078148)
			(xy 132.425948 -260.074165) (xy 132.479098 -260.078148) (xy 132.53106 -260.090008) (xy 132.580674 -260.10948)
			(xy 132.626832 -260.136129) (xy 132.668503 -260.16936) (xy 132.704755 -260.208431) (xy 132.734779 -260.252468)
			(xy 132.757905 -260.300489) (xy 132.773615 -260.351419) (xy 132.781558 -260.404123) (xy 132.782056 -260.430772)
			(xy 132.781558 -260.457421) (xy 133.009884 -260.457421) (xy 133.009884 -260.404123) (xy 133.017827 -260.351419)
			(xy 133.033537 -260.300489) (xy 133.056663 -260.252468) (xy 133.086687 -260.208431) (xy 133.122939 -260.16936)
			(xy 133.16461 -260.136129) (xy 133.210768 -260.10948) (xy 133.260382 -260.090008) (xy 133.312344 -260.078148)
			(xy 133.365494 -260.074165) (xy 133.418644 -260.078148) (xy 133.470606 -260.090008) (xy 133.52022 -260.10948)
			(xy 133.566378 -260.136129) (xy 133.608049 -260.16936) (xy 133.644301 -260.208431) (xy 133.674325 -260.252468)
			(xy 133.697451 -260.300489) (xy 133.713161 -260.351419) (xy 133.721104 -260.404123) (xy 133.721602 -260.430772)
			(xy 133.721104 -260.457421) (xy 133.949938 -260.457421) (xy 133.949938 -260.404123) (xy 133.957881 -260.351419)
			(xy 133.973591 -260.300489) (xy 133.996717 -260.252468) (xy 134.026741 -260.208431) (xy 134.062993 -260.16936)
			(xy 134.104664 -260.136129) (xy 134.150822 -260.10948) (xy 134.200436 -260.090008) (xy 134.252398 -260.078148)
			(xy 134.305548 -260.074165) (xy 134.358698 -260.078148) (xy 134.41066 -260.090008) (xy 134.460274 -260.10948)
			(xy 134.506432 -260.136129) (xy 134.548103 -260.16936) (xy 134.584355 -260.208431) (xy 134.614379 -260.252468)
			(xy 134.637505 -260.300489) (xy 134.653215 -260.351419) (xy 134.661158 -260.404123) (xy 134.661656 -260.430772)
			(xy 134.661158 -260.457421) (xy 134.653215 -260.510125) (xy 134.637505 -260.561055) (xy 134.614379 -260.609076)
			(xy 134.584355 -260.653113) (xy 134.548103 -260.692184) (xy 134.506432 -260.725415) (xy 134.460274 -260.752064)
			(xy 134.41066 -260.771536) (xy 134.358698 -260.783396) (xy 134.305548 -260.78738) (xy 134.252398 -260.783396)
			(xy 134.200436 -260.771536) (xy 134.150822 -260.752064) (xy 134.104664 -260.725415) (xy 134.062993 -260.692184)
			(xy 134.026741 -260.653113) (xy 133.996717 -260.609076) (xy 133.973591 -260.561055) (xy 133.957881 -260.510125)
			(xy 133.949938 -260.457421) (xy 133.721104 -260.457421) (xy 133.713161 -260.510125) (xy 133.697451 -260.561055)
			(xy 133.674325 -260.609076) (xy 133.644301 -260.653113) (xy 133.608049 -260.692184) (xy 133.566378 -260.725415)
			(xy 133.52022 -260.752064) (xy 133.470606 -260.771536) (xy 133.418644 -260.783396) (xy 133.365494 -260.78738)
			(xy 133.312344 -260.783396) (xy 133.260382 -260.771536) (xy 133.210768 -260.752064) (xy 133.16461 -260.725415)
			(xy 133.122939 -260.692184) (xy 133.086687 -260.653113) (xy 133.056663 -260.609076) (xy 133.033537 -260.561055)
			(xy 133.017827 -260.510125) (xy 133.009884 -260.457421) (xy 132.781558 -260.457421) (xy 132.773615 -260.510125)
			(xy 132.757905 -260.561055) (xy 132.734779 -260.609076) (xy 132.704755 -260.653113) (xy 132.668503 -260.692184)
			(xy 132.626832 -260.725415) (xy 132.580674 -260.752064) (xy 132.53106 -260.771536) (xy 132.479098 -260.783396)
			(xy 132.425948 -260.78738) (xy 132.372798 -260.783396) (xy 132.320836 -260.771536) (xy 132.271222 -260.752064)
			(xy 132.225064 -260.725415) (xy 132.183393 -260.692184) (xy 132.147141 -260.653113) (xy 132.117117 -260.609076)
			(xy 132.093991 -260.561055) (xy 132.078281 -260.510125) (xy 132.070338 -260.457421) (xy 131.841758 -260.457421)
			(xy 131.833815 -260.510125) (xy 131.818105 -260.561055) (xy 131.794979 -260.609076) (xy 131.764955 -260.653113)
			(xy 131.728703 -260.692184) (xy 131.687032 -260.725415) (xy 131.640874 -260.752064) (xy 131.59126 -260.771536)
			(xy 131.539298 -260.783396) (xy 131.486148 -260.78738) (xy 131.432998 -260.783396) (xy 131.381036 -260.771536)
			(xy 131.331422 -260.752064) (xy 131.285264 -260.725415) (xy 131.243593 -260.692184) (xy 131.207341 -260.653113)
			(xy 131.177317 -260.609076) (xy 131.154191 -260.561055) (xy 131.138481 -260.510125) (xy 131.130538 -260.457421)
			(xy 130.901958 -260.457421) (xy 130.894015 -260.510125) (xy 130.878305 -260.561055) (xy 130.855179 -260.609076)
			(xy 130.825155 -260.653113) (xy 130.788903 -260.692184) (xy 130.747232 -260.725415) (xy 130.701074 -260.752064)
			(xy 130.65146 -260.771536) (xy 130.599498 -260.783396) (xy 130.546348 -260.78738) (xy 130.493198 -260.783396)
			(xy 130.441236 -260.771536) (xy 130.391622 -260.752064) (xy 130.345464 -260.725415) (xy 130.303793 -260.692184)
			(xy 130.267541 -260.653113) (xy 130.237517 -260.609076) (xy 130.214391 -260.561055) (xy 130.198681 -260.510125)
			(xy 130.190738 -260.457421) (xy 129.962158 -260.457421) (xy 129.954215 -260.510125) (xy 129.938505 -260.561055)
			(xy 129.915379 -260.609076) (xy 129.885355 -260.653113) (xy 129.849103 -260.692184) (xy 129.807432 -260.725415)
			(xy 129.761274 -260.752064) (xy 129.71166 -260.771536) (xy 129.659698 -260.783396) (xy 129.606548 -260.78738)
			(xy 129.553398 -260.783396) (xy 129.501436 -260.771536) (xy 129.451822 -260.752064) (xy 129.405664 -260.725415)
			(xy 129.363993 -260.692184) (xy 129.327741 -260.653113) (xy 129.297717 -260.609076) (xy 129.274591 -260.561055)
			(xy 129.258881 -260.510125) (xy 129.250938 -260.457421) (xy 129.022358 -260.457421) (xy 129.014415 -260.510125)
			(xy 128.998705 -260.561055) (xy 128.975579 -260.609076) (xy 128.945555 -260.653113) (xy 128.909303 -260.692184)
			(xy 128.867632 -260.725415) (xy 128.821474 -260.752064) (xy 128.77186 -260.771536) (xy 128.719898 -260.783396)
			(xy 128.666748 -260.78738) (xy 128.613598 -260.783396) (xy 128.561636 -260.771536) (xy 128.512022 -260.752064)
			(xy 128.465864 -260.725415) (xy 128.424193 -260.692184) (xy 128.387941 -260.653113) (xy 128.357917 -260.609076)
			(xy 128.334791 -260.561055) (xy 128.319081 -260.510125) (xy 128.311138 -260.457421) (xy 128.082558 -260.457421)
			(xy 128.074615 -260.510125) (xy 128.058905 -260.561055) (xy 128.035779 -260.609076) (xy 128.005755 -260.653113)
			(xy 127.969503 -260.692184) (xy 127.927832 -260.725415) (xy 127.881674 -260.752064) (xy 127.83206 -260.771536)
			(xy 127.780098 -260.783396) (xy 127.726948 -260.78738) (xy 127.673798 -260.783396) (xy 127.621836 -260.771536)
			(xy 127.572222 -260.752064) (xy 127.526064 -260.725415) (xy 127.484393 -260.692184) (xy 127.448141 -260.653113)
			(xy 127.418117 -260.609076) (xy 127.394991 -260.561055) (xy 127.379281 -260.510125) (xy 127.371338 -260.457421)
			(xy 127.142504 -260.457421) (xy 127.134561 -260.510125) (xy 127.118851 -260.561055) (xy 127.095725 -260.609076)
			(xy 127.065701 -260.653113) (xy 127.029449 -260.692184) (xy 126.987778 -260.725415) (xy 126.94162 -260.752064)
			(xy 126.892006 -260.771536) (xy 126.840044 -260.783396) (xy 126.786894 -260.78738) (xy 126.733744 -260.783396)
			(xy 126.681782 -260.771536) (xy 126.632168 -260.752064) (xy 126.58601 -260.725415) (xy 126.544339 -260.692184)
			(xy 126.508087 -260.653113) (xy 126.478063 -260.609076) (xy 126.454937 -260.561055) (xy 126.439227 -260.510125)
			(xy 126.431284 -260.457421) (xy 126.202958 -260.457421) (xy 126.195015 -260.510125) (xy 126.179305 -260.561055)
			(xy 126.156179 -260.609076) (xy 126.126155 -260.653113) (xy 126.089903 -260.692184) (xy 126.048232 -260.725415)
			(xy 126.002074 -260.752064) (xy 125.95246 -260.771536) (xy 125.900498 -260.783396) (xy 125.847348 -260.78738)
			(xy 125.794198 -260.783396) (xy 125.742236 -260.771536) (xy 125.692622 -260.752064) (xy 125.646464 -260.725415)
			(xy 125.604793 -260.692184) (xy 125.568541 -260.653113) (xy 125.538517 -260.609076) (xy 125.515391 -260.561055)
			(xy 125.499681 -260.510125) (xy 125.491738 -260.457421) (xy 125.263158 -260.457421) (xy 125.255215 -260.510125)
			(xy 125.239505 -260.561055) (xy 125.216379 -260.609076) (xy 125.186355 -260.653113) (xy 125.150103 -260.692184)
			(xy 125.108432 -260.725415) (xy 125.062274 -260.752064) (xy 125.01266 -260.771536) (xy 124.960698 -260.783396)
			(xy 124.907548 -260.78738) (xy 124.854398 -260.783396) (xy 124.802436 -260.771536) (xy 124.752822 -260.752064)
			(xy 124.706664 -260.725415) (xy 124.664993 -260.692184) (xy 124.628741 -260.653113) (xy 124.598717 -260.609076)
			(xy 124.575591 -260.561055) (xy 124.559881 -260.510125) (xy 124.551938 -260.457421) (xy 124.323358 -260.457421)
			(xy 124.315415 -260.510125) (xy 124.299705 -260.561055) (xy 124.276579 -260.609076) (xy 124.246555 -260.653113)
			(xy 124.210303 -260.692184) (xy 124.168632 -260.725415) (xy 124.122474 -260.752064) (xy 124.07286 -260.771536)
			(xy 124.020898 -260.783396) (xy 123.967748 -260.78738) (xy 123.914598 -260.783396) (xy 123.862636 -260.771536)
			(xy 123.813022 -260.752064) (xy 123.766864 -260.725415) (xy 123.725193 -260.692184) (xy 123.688941 -260.653113)
			(xy 123.658917 -260.609076) (xy 123.635791 -260.561055) (xy 123.620081 -260.510125) (xy 123.612138 -260.457421)
			(xy 123.383558 -260.457421) (xy 123.375615 -260.510125) (xy 123.359905 -260.561055) (xy 123.336779 -260.609076)
			(xy 123.306755 -260.653113) (xy 123.270503 -260.692184) (xy 123.228832 -260.725415) (xy 123.182674 -260.752064)
			(xy 123.13306 -260.771536) (xy 123.081098 -260.783396) (xy 123.027948 -260.78738) (xy 122.974798 -260.783396)
			(xy 122.922836 -260.771536) (xy 122.873222 -260.752064) (xy 122.827064 -260.725415) (xy 122.785393 -260.692184)
			(xy 122.749141 -260.653113) (xy 122.719117 -260.609076) (xy 122.695991 -260.561055) (xy 122.680281 -260.510125)
			(xy 122.672338 -260.457421) (xy 122.443758 -260.457421) (xy 122.435815 -260.510125) (xy 122.420105 -260.561055)
			(xy 122.396979 -260.609076) (xy 122.366955 -260.653113) (xy 122.330703 -260.692184) (xy 122.289032 -260.725415)
			(xy 122.242874 -260.752064) (xy 122.19326 -260.771536) (xy 122.141298 -260.783396) (xy 122.088148 -260.78738)
			(xy 122.034998 -260.783396) (xy 121.983036 -260.771536) (xy 121.933422 -260.752064) (xy 121.887264 -260.725415)
			(xy 121.845593 -260.692184) (xy 121.809341 -260.653113) (xy 121.779317 -260.609076) (xy 121.756191 -260.561055)
			(xy 121.740481 -260.510125) (xy 121.732538 -260.457421) (xy 121.399533 -260.457421) (xy 121.42343 -260.481318)
			(xy 121.42343 -260.596634) (xy 121.600468 -260.773418) (xy 121.600468 -261.271491) (xy 122.202184 -261.271491)
			(xy 122.202184 -261.218193) (xy 122.210127 -261.165489) (xy 122.225837 -261.114559) (xy 122.248963 -261.066538)
			(xy 122.278987 -261.022501) (xy 122.315239 -260.98343) (xy 122.35691 -260.950199) (xy 122.403068 -260.92355)
			(xy 122.452682 -260.904078) (xy 122.504644 -260.892218) (xy 122.557794 -260.888235) (xy 122.610944 -260.892218)
			(xy 122.662906 -260.904078) (xy 122.71252 -260.92355) (xy 122.758678 -260.950199) (xy 122.800349 -260.98343)
			(xy 122.836601 -261.022501) (xy 122.866625 -261.066538) (xy 122.889751 -261.114559) (xy 122.905461 -261.165489)
			(xy 122.913404 -261.218193) (xy 122.913902 -261.244842) (xy 122.913404 -261.271491) (xy 123.141984 -261.271491)
			(xy 123.141984 -261.218193) (xy 123.149927 -261.165489) (xy 123.165637 -261.114559) (xy 123.188763 -261.066538)
			(xy 123.218787 -261.022501) (xy 123.255039 -260.98343) (xy 123.29671 -260.950199) (xy 123.342868 -260.92355)
			(xy 123.392482 -260.904078) (xy 123.444444 -260.892218) (xy 123.497594 -260.888235) (xy 123.550744 -260.892218)
			(xy 123.602706 -260.904078) (xy 123.65232 -260.92355) (xy 123.698478 -260.950199) (xy 123.740149 -260.98343)
			(xy 123.776401 -261.022501) (xy 123.806425 -261.066538) (xy 123.829551 -261.114559) (xy 123.845261 -261.165489)
			(xy 123.853204 -261.218193) (xy 123.853702 -261.244842) (xy 123.853204 -261.271491) (xy 124.081784 -261.271491)
			(xy 124.081784 -261.218193) (xy 124.089727 -261.165489) (xy 124.105437 -261.114559) (xy 124.128563 -261.066538)
			(xy 124.158587 -261.022501) (xy 124.194839 -260.98343) (xy 124.23651 -260.950199) (xy 124.282668 -260.92355)
			(xy 124.332282 -260.904078) (xy 124.384244 -260.892218) (xy 124.437394 -260.888235) (xy 124.490544 -260.892218)
			(xy 124.542506 -260.904078) (xy 124.59212 -260.92355) (xy 124.638278 -260.950199) (xy 124.679949 -260.98343)
			(xy 124.716201 -261.022501) (xy 124.746225 -261.066538) (xy 124.769351 -261.114559) (xy 124.785061 -261.165489)
			(xy 124.793004 -261.218193) (xy 124.793502 -261.244842) (xy 124.793004 -261.271491) (xy 125.021584 -261.271491)
			(xy 125.021584 -261.218193) (xy 125.029527 -261.165489) (xy 125.045237 -261.114559) (xy 125.068363 -261.066538)
			(xy 125.098387 -261.022501) (xy 125.134639 -260.98343) (xy 125.17631 -260.950199) (xy 125.222468 -260.92355)
			(xy 125.272082 -260.904078) (xy 125.324044 -260.892218) (xy 125.377194 -260.888235) (xy 125.430344 -260.892218)
			(xy 125.482306 -260.904078) (xy 125.53192 -260.92355) (xy 125.578078 -260.950199) (xy 125.619749 -260.98343)
			(xy 125.656001 -261.022501) (xy 125.686025 -261.066538) (xy 125.709151 -261.114559) (xy 125.724861 -261.165489)
			(xy 125.732804 -261.218193) (xy 125.733302 -261.244842) (xy 125.732804 -261.271491) (xy 125.961384 -261.271491)
			(xy 125.961384 -261.218193) (xy 125.969327 -261.165489) (xy 125.985037 -261.114559) (xy 126.008163 -261.066538)
			(xy 126.038187 -261.022501) (xy 126.074439 -260.98343) (xy 126.11611 -260.950199) (xy 126.162268 -260.92355)
			(xy 126.211882 -260.904078) (xy 126.263844 -260.892218) (xy 126.316994 -260.888235) (xy 126.370144 -260.892218)
			(xy 126.422106 -260.904078) (xy 126.47172 -260.92355) (xy 126.517878 -260.950199) (xy 126.559549 -260.98343)
			(xy 126.595801 -261.022501) (xy 126.625825 -261.066538) (xy 126.648951 -261.114559) (xy 126.664661 -261.165489)
			(xy 126.672604 -261.218193) (xy 126.673102 -261.244842) (xy 126.672604 -261.271491) (xy 126.901184 -261.271491)
			(xy 126.901184 -261.218193) (xy 126.909127 -261.165489) (xy 126.924837 -261.114559) (xy 126.947963 -261.066538)
			(xy 126.977987 -261.022501) (xy 127.014239 -260.98343) (xy 127.05591 -260.950199) (xy 127.102068 -260.92355)
			(xy 127.151682 -260.904078) (xy 127.203644 -260.892218) (xy 127.256794 -260.888235) (xy 127.309944 -260.892218)
			(xy 127.361906 -260.904078) (xy 127.41152 -260.92355) (xy 127.457678 -260.950199) (xy 127.499349 -260.98343)
			(xy 127.535601 -261.022501) (xy 127.565625 -261.066538) (xy 127.588751 -261.114559) (xy 127.604461 -261.165489)
			(xy 127.612404 -261.218193) (xy 127.612902 -261.244842) (xy 127.612404 -261.271491) (xy 127.840984 -261.271491)
			(xy 127.840984 -261.218193) (xy 127.848927 -261.165489) (xy 127.864637 -261.114559) (xy 127.887763 -261.066538)
			(xy 127.917787 -261.022501) (xy 127.954039 -260.98343) (xy 127.99571 -260.950199) (xy 128.041868 -260.92355)
			(xy 128.091482 -260.904078) (xy 128.143444 -260.892218) (xy 128.196594 -260.888235) (xy 128.249744 -260.892218)
			(xy 128.301706 -260.904078) (xy 128.35132 -260.92355) (xy 128.397478 -260.950199) (xy 128.439149 -260.98343)
			(xy 128.475401 -261.022501) (xy 128.505425 -261.066538) (xy 128.528551 -261.114559) (xy 128.544261 -261.165489)
			(xy 128.552204 -261.218193) (xy 128.552702 -261.244842) (xy 128.552204 -261.271491) (xy 128.780784 -261.271491)
			(xy 128.780784 -261.218193) (xy 128.788727 -261.165489) (xy 128.804437 -261.114559) (xy 128.827563 -261.066538)
			(xy 128.857587 -261.022501) (xy 128.893839 -260.98343) (xy 128.93551 -260.950199) (xy 128.981668 -260.92355)
			(xy 129.031282 -260.904078) (xy 129.083244 -260.892218) (xy 129.136394 -260.888235) (xy 129.189544 -260.892218)
			(xy 129.241506 -260.904078) (xy 129.29112 -260.92355) (xy 129.337278 -260.950199) (xy 129.378949 -260.98343)
			(xy 129.415201 -261.022501) (xy 129.445225 -261.066538) (xy 129.468351 -261.114559) (xy 129.484061 -261.165489)
			(xy 129.492004 -261.218193) (xy 129.492502 -261.244842) (xy 129.492004 -261.271491) (xy 129.720584 -261.271491)
			(xy 129.720584 -261.218193) (xy 129.728527 -261.165489) (xy 129.744237 -261.114559) (xy 129.767363 -261.066538)
			(xy 129.797387 -261.022501) (xy 129.833639 -260.98343) (xy 129.87531 -260.950199) (xy 129.921468 -260.92355)
			(xy 129.971082 -260.904078) (xy 130.023044 -260.892218) (xy 130.076194 -260.888235) (xy 130.129344 -260.892218)
			(xy 130.181306 -260.904078) (xy 130.23092 -260.92355) (xy 130.277078 -260.950199) (xy 130.318749 -260.98343)
			(xy 130.355001 -261.022501) (xy 130.385025 -261.066538) (xy 130.408151 -261.114559) (xy 130.423861 -261.165489)
			(xy 130.431804 -261.218193) (xy 130.432302 -261.244842) (xy 130.431804 -261.271491) (xy 130.660384 -261.271491)
			(xy 130.660384 -261.218193) (xy 130.668327 -261.165489) (xy 130.684037 -261.114559) (xy 130.707163 -261.066538)
			(xy 130.737187 -261.022501) (xy 130.773439 -260.98343) (xy 130.81511 -260.950199) (xy 130.861268 -260.92355)
			(xy 130.910882 -260.904078) (xy 130.962844 -260.892218) (xy 131.015994 -260.888235) (xy 131.069144 -260.892218)
			(xy 131.121106 -260.904078) (xy 131.17072 -260.92355) (xy 131.216878 -260.950199) (xy 131.258549 -260.98343)
			(xy 131.294801 -261.022501) (xy 131.324825 -261.066538) (xy 131.347951 -261.114559) (xy 131.363661 -261.165489)
			(xy 131.371604 -261.218193) (xy 131.372102 -261.244842) (xy 131.371604 -261.271491) (xy 131.600184 -261.271491)
			(xy 131.600184 -261.218193) (xy 131.608127 -261.165489) (xy 131.623837 -261.114559) (xy 131.646963 -261.066538)
			(xy 131.676987 -261.022501) (xy 131.713239 -260.98343) (xy 131.75491 -260.950199) (xy 131.801068 -260.92355)
			(xy 131.850682 -260.904078) (xy 131.902644 -260.892218) (xy 131.955794 -260.888235) (xy 132.008944 -260.892218)
			(xy 132.060906 -260.904078) (xy 132.11052 -260.92355) (xy 132.156678 -260.950199) (xy 132.198349 -260.98343)
			(xy 132.234601 -261.022501) (xy 132.264625 -261.066538) (xy 132.287751 -261.114559) (xy 132.303461 -261.165489)
			(xy 132.311404 -261.218193) (xy 132.311902 -261.244842) (xy 132.311404 -261.271491) (xy 132.539984 -261.271491)
			(xy 132.539984 -261.218193) (xy 132.547927 -261.165489) (xy 132.563637 -261.114559) (xy 132.586763 -261.066538)
			(xy 132.616787 -261.022501) (xy 132.653039 -260.98343) (xy 132.69471 -260.950199) (xy 132.740868 -260.92355)
			(xy 132.790482 -260.904078) (xy 132.842444 -260.892218) (xy 132.895594 -260.888235) (xy 132.948744 -260.892218)
			(xy 133.000706 -260.904078) (xy 133.05032 -260.92355) (xy 133.096478 -260.950199) (xy 133.138149 -260.98343)
			(xy 133.174401 -261.022501) (xy 133.204425 -261.066538) (xy 133.227551 -261.114559) (xy 133.243261 -261.165489)
			(xy 133.251204 -261.218193) (xy 133.251702 -261.244842) (xy 133.251204 -261.271491) (xy 133.479784 -261.271491)
			(xy 133.479784 -261.218193) (xy 133.487727 -261.165489) (xy 133.503437 -261.114559) (xy 133.526563 -261.066538)
			(xy 133.556587 -261.022501) (xy 133.592839 -260.98343) (xy 133.63451 -260.950199) (xy 133.680668 -260.92355)
			(xy 133.730282 -260.904078) (xy 133.782244 -260.892218) (xy 133.835394 -260.888235) (xy 133.888544 -260.892218)
			(xy 133.940506 -260.904078) (xy 133.99012 -260.92355) (xy 134.036278 -260.950199) (xy 134.077949 -260.98343)
			(xy 134.114201 -261.022501) (xy 134.144225 -261.066538) (xy 134.167351 -261.114559) (xy 134.183061 -261.165489)
			(xy 134.191004 -261.218193) (xy 134.191502 -261.244842) (xy 134.191004 -261.271491) (xy 134.183061 -261.324195)
			(xy 134.167351 -261.375125) (xy 134.144225 -261.423146) (xy 134.114201 -261.467183) (xy 134.077949 -261.506254)
			(xy 134.036278 -261.539485) (xy 133.99012 -261.566134) (xy 133.940506 -261.585606) (xy 133.888544 -261.597466)
			(xy 133.835394 -261.60145) (xy 133.782244 -261.597466) (xy 133.730282 -261.585606) (xy 133.680668 -261.566134)
			(xy 133.63451 -261.539485) (xy 133.592839 -261.506254) (xy 133.556587 -261.467183) (xy 133.526563 -261.423146)
			(xy 133.503437 -261.375125) (xy 133.487727 -261.324195) (xy 133.479784 -261.271491) (xy 133.251204 -261.271491)
			(xy 133.243261 -261.324195) (xy 133.227551 -261.375125) (xy 133.204425 -261.423146) (xy 133.174401 -261.467183)
			(xy 133.138149 -261.506254) (xy 133.096478 -261.539485) (xy 133.05032 -261.566134) (xy 133.000706 -261.585606)
			(xy 132.948744 -261.597466) (xy 132.895594 -261.60145) (xy 132.842444 -261.597466) (xy 132.790482 -261.585606)
			(xy 132.740868 -261.566134) (xy 132.69471 -261.539485) (xy 132.653039 -261.506254) (xy 132.616787 -261.467183)
			(xy 132.586763 -261.423146) (xy 132.563637 -261.375125) (xy 132.547927 -261.324195) (xy 132.539984 -261.271491)
			(xy 132.311404 -261.271491) (xy 132.303461 -261.324195) (xy 132.287751 -261.375125) (xy 132.264625 -261.423146)
			(xy 132.234601 -261.467183) (xy 132.198349 -261.506254) (xy 132.156678 -261.539485) (xy 132.11052 -261.566134)
			(xy 132.060906 -261.585606) (xy 132.008944 -261.597466) (xy 131.955794 -261.60145) (xy 131.902644 -261.597466)
			(xy 131.850682 -261.585606) (xy 131.801068 -261.566134) (xy 131.75491 -261.539485) (xy 131.713239 -261.506254)
			(xy 131.676987 -261.467183) (xy 131.646963 -261.423146) (xy 131.623837 -261.375125) (xy 131.608127 -261.324195)
			(xy 131.600184 -261.271491) (xy 131.371604 -261.271491) (xy 131.363661 -261.324195) (xy 131.347951 -261.375125)
			(xy 131.324825 -261.423146) (xy 131.294801 -261.467183) (xy 131.258549 -261.506254) (xy 131.216878 -261.539485)
			(xy 131.17072 -261.566134) (xy 131.121106 -261.585606) (xy 131.069144 -261.597466) (xy 131.015994 -261.60145)
			(xy 130.962844 -261.597466) (xy 130.910882 -261.585606) (xy 130.861268 -261.566134) (xy 130.81511 -261.539485)
			(xy 130.773439 -261.506254) (xy 130.737187 -261.467183) (xy 130.707163 -261.423146) (xy 130.684037 -261.375125)
			(xy 130.668327 -261.324195) (xy 130.660384 -261.271491) (xy 130.431804 -261.271491) (xy 130.423861 -261.324195)
			(xy 130.408151 -261.375125) (xy 130.385025 -261.423146) (xy 130.355001 -261.467183) (xy 130.318749 -261.506254)
			(xy 130.277078 -261.539485) (xy 130.23092 -261.566134) (xy 130.181306 -261.585606) (xy 130.129344 -261.597466)
			(xy 130.076194 -261.60145) (xy 130.023044 -261.597466) (xy 129.971082 -261.585606) (xy 129.921468 -261.566134)
			(xy 129.87531 -261.539485) (xy 129.833639 -261.506254) (xy 129.797387 -261.467183) (xy 129.767363 -261.423146)
			(xy 129.744237 -261.375125) (xy 129.728527 -261.324195) (xy 129.720584 -261.271491) (xy 129.492004 -261.271491)
			(xy 129.484061 -261.324195) (xy 129.468351 -261.375125) (xy 129.445225 -261.423146) (xy 129.415201 -261.467183)
			(xy 129.378949 -261.506254) (xy 129.337278 -261.539485) (xy 129.29112 -261.566134) (xy 129.241506 -261.585606)
			(xy 129.189544 -261.597466) (xy 129.136394 -261.60145) (xy 129.083244 -261.597466) (xy 129.031282 -261.585606)
			(xy 128.981668 -261.566134) (xy 128.93551 -261.539485) (xy 128.893839 -261.506254) (xy 128.857587 -261.467183)
			(xy 128.827563 -261.423146) (xy 128.804437 -261.375125) (xy 128.788727 -261.324195) (xy 128.780784 -261.271491)
			(xy 128.552204 -261.271491) (xy 128.544261 -261.324195) (xy 128.528551 -261.375125) (xy 128.505425 -261.423146)
			(xy 128.475401 -261.467183) (xy 128.439149 -261.506254) (xy 128.397478 -261.539485) (xy 128.35132 -261.566134)
			(xy 128.301706 -261.585606) (xy 128.249744 -261.597466) (xy 128.196594 -261.60145) (xy 128.143444 -261.597466)
			(xy 128.091482 -261.585606) (xy 128.041868 -261.566134) (xy 127.99571 -261.539485) (xy 127.954039 -261.506254)
			(xy 127.917787 -261.467183) (xy 127.887763 -261.423146) (xy 127.864637 -261.375125) (xy 127.848927 -261.324195)
			(xy 127.840984 -261.271491) (xy 127.612404 -261.271491) (xy 127.604461 -261.324195) (xy 127.588751 -261.375125)
			(xy 127.565625 -261.423146) (xy 127.535601 -261.467183) (xy 127.499349 -261.506254) (xy 127.457678 -261.539485)
			(xy 127.41152 -261.566134) (xy 127.361906 -261.585606) (xy 127.309944 -261.597466) (xy 127.256794 -261.60145)
			(xy 127.203644 -261.597466) (xy 127.151682 -261.585606) (xy 127.102068 -261.566134) (xy 127.05591 -261.539485)
			(xy 127.014239 -261.506254) (xy 126.977987 -261.467183) (xy 126.947963 -261.423146) (xy 126.924837 -261.375125)
			(xy 126.909127 -261.324195) (xy 126.901184 -261.271491) (xy 126.672604 -261.271491) (xy 126.664661 -261.324195)
			(xy 126.648951 -261.375125) (xy 126.625825 -261.423146) (xy 126.595801 -261.467183) (xy 126.559549 -261.506254)
			(xy 126.517878 -261.539485) (xy 126.47172 -261.566134) (xy 126.422106 -261.585606) (xy 126.370144 -261.597466)
			(xy 126.316994 -261.60145) (xy 126.263844 -261.597466) (xy 126.211882 -261.585606) (xy 126.162268 -261.566134)
			(xy 126.11611 -261.539485) (xy 126.074439 -261.506254) (xy 126.038187 -261.467183) (xy 126.008163 -261.423146)
			(xy 125.985037 -261.375125) (xy 125.969327 -261.324195) (xy 125.961384 -261.271491) (xy 125.732804 -261.271491)
			(xy 125.724861 -261.324195) (xy 125.709151 -261.375125) (xy 125.686025 -261.423146) (xy 125.656001 -261.467183)
			(xy 125.619749 -261.506254) (xy 125.578078 -261.539485) (xy 125.53192 -261.566134) (xy 125.482306 -261.585606)
			(xy 125.430344 -261.597466) (xy 125.377194 -261.60145) (xy 125.324044 -261.597466) (xy 125.272082 -261.585606)
			(xy 125.222468 -261.566134) (xy 125.17631 -261.539485) (xy 125.134639 -261.506254) (xy 125.098387 -261.467183)
			(xy 125.068363 -261.423146) (xy 125.045237 -261.375125) (xy 125.029527 -261.324195) (xy 125.021584 -261.271491)
			(xy 124.793004 -261.271491) (xy 124.785061 -261.324195) (xy 124.769351 -261.375125) (xy 124.746225 -261.423146)
			(xy 124.716201 -261.467183) (xy 124.679949 -261.506254) (xy 124.638278 -261.539485) (xy 124.59212 -261.566134)
			(xy 124.542506 -261.585606) (xy 124.490544 -261.597466) (xy 124.437394 -261.60145) (xy 124.384244 -261.597466)
			(xy 124.332282 -261.585606) (xy 124.282668 -261.566134) (xy 124.23651 -261.539485) (xy 124.194839 -261.506254)
			(xy 124.158587 -261.467183) (xy 124.128563 -261.423146) (xy 124.105437 -261.375125) (xy 124.089727 -261.324195)
			(xy 124.081784 -261.271491) (xy 123.853204 -261.271491) (xy 123.845261 -261.324195) (xy 123.829551 -261.375125)
			(xy 123.806425 -261.423146) (xy 123.776401 -261.467183) (xy 123.740149 -261.506254) (xy 123.698478 -261.539485)
			(xy 123.65232 -261.566134) (xy 123.602706 -261.585606) (xy 123.550744 -261.597466) (xy 123.497594 -261.60145)
			(xy 123.444444 -261.597466) (xy 123.392482 -261.585606) (xy 123.342868 -261.566134) (xy 123.29671 -261.539485)
			(xy 123.255039 -261.506254) (xy 123.218787 -261.467183) (xy 123.188763 -261.423146) (xy 123.165637 -261.375125)
			(xy 123.149927 -261.324195) (xy 123.141984 -261.271491) (xy 122.913404 -261.271491) (xy 122.905461 -261.324195)
			(xy 122.889751 -261.375125) (xy 122.866625 -261.423146) (xy 122.836601 -261.467183) (xy 122.800349 -261.506254)
			(xy 122.758678 -261.539485) (xy 122.71252 -261.566134) (xy 122.662906 -261.585606) (xy 122.610944 -261.597466)
			(xy 122.557794 -261.60145) (xy 122.504644 -261.597466) (xy 122.452682 -261.585606) (xy 122.403068 -261.566134)
			(xy 122.35691 -261.539485) (xy 122.315239 -261.506254) (xy 122.278987 -261.467183) (xy 122.248963 -261.423146)
			(xy 122.225837 -261.375125) (xy 122.210127 -261.324195) (xy 122.202184 -261.271491) (xy 121.600468 -261.271491)
			(xy 121.600468 -261.568438) (xy 121.835672 -261.803642) (xy 121.870978 -261.776464) (xy 121.894489 -261.759114)
			(xy 121.945986 -261.731515) (xy 122.001295 -261.712685) (xy 122.058935 -261.70313) (xy 122.088148 -261.70255)
			(xy 122.115109 -261.703043) (xy 122.168416 -261.711166) (xy 122.219888 -261.727234) (xy 122.268349 -261.75088)
			(xy 122.31269 -261.781563) (xy 122.351897 -261.818582) (xy 122.385075 -261.861089) (xy 122.411463 -261.908113)
			(xy 122.421396 -261.933182) (xy 122.433842 -261.965948) (xy 122.682 -261.965948)
		)
		(stroke
			(width 0)
			(type solid)
		)
		(fill yes)
		(layer "In13.Cu")
		(net "PVCCD_HV_CPU1")
	)
	(gr_poly
		(pts
			(xy 230.38054 -434.93182)
			(arc
				(start 230.38054 -423.4688)
				(mid 230.404693 -423.347284)
				(end 230.473504 -423.244264)
			)
			(arc
				(start 232.983024 -420.734744)
				(mid 233.086056 -420.665963)
				(end 233.20756 -420.64178)
			)
			(xy 270.363188 -420.64178)
			(arc
				(start 275.408898 -415.59607)
				(mid 275.524699 -415.483433)
				(end 275.680932 -415.4424)
			)
			(xy 279.79624 -415.4424) (xy 280.19756 -415.04108) (xy 280.19756 -408.29992) (xy 279.96896 -408.07132)
			(xy 239.84458 -408.07132)
			(arc
				(start 233.163364 -414.752536)
				(mid 233.060332 -414.821317)
				(end 232.938828 -414.8455)
			)
			(xy 207.34528 -414.8455) (xy 206.49184 -415.69894) (xy 206.49184 -435.39156) (xy 207.63484 -436.53456)
			(xy 228.7778 -436.53456)
		)
		(stroke
			(width 0)
			(type solid)
		)
		(fill yes)
		(layer "In14.Cu")
		(net "P12V_PSU")
	)
	(gr_poly
		(pts
			(xy 531.7998 -462.520284) (xy 531.855607 -462.519775) (xy 531.96691 -462.511434) (xy 532.077278 -462.494798)
			(xy 532.186094 -462.469962) (xy 532.29275 -462.437062) (xy 532.396649 -462.396285) (xy 532.49721 -462.347857)
			(xy 532.593871 -462.292049) (xy 532.686092 -462.229174) (xy 532.773355 -462.159583) (xy 532.855174 -462.083666)
			(xy 532.931091 -462.001846) (xy 533.000681 -461.914582) (xy 533.063556 -461.822361) (xy 533.119362 -461.7257)
			(xy 533.16779 -461.625138) (xy 533.208566 -461.521239) (xy 533.241465 -461.414583) (xy 533.266301 -461.305766)
			(xy 533.282935 -461.195398) (xy 533.291275 -461.084095) (xy 533.291796 -461.028288) (xy 533.291796 -455.0283)
			(xy 533.291274 -454.972493) (xy 533.282933 -454.861191) (xy 533.266298 -454.750824) (xy 533.241462 -454.642008)
			(xy 533.208563 -454.535353) (xy 533.167786 -454.431454) (xy 533.119358 -454.330893) (xy 533.063551 -454.234233)
			(xy 533.000677 -454.142013) (xy 532.931086 -454.054749) (xy 532.85517 -453.97293) (xy 532.773351 -453.897014)
			(xy 532.686087 -453.827423) (xy 532.593867 -453.764549) (xy 532.497207 -453.708742) (xy 532.396646 -453.660314)
			(xy 532.292747 -453.619537) (xy 532.186092 -453.586638) (xy 532.077276 -453.561802) (xy 531.966909 -453.545167)
			(xy 531.855607 -453.536826) (xy 531.7998 -453.536304) (xy 516.019796 -453.536304) (xy 515.949442 -453.535811)
			(xy 515.808956 -453.527921) (xy 515.669133 -453.512166) (xy 515.530414 -453.488597) (xy 515.393234 -453.457286)
			(xy 515.258026 -453.418334) (xy 515.125215 -453.371861) (xy 514.995218 -453.318014) (xy 514.868445 -453.256963)
			(xy 514.745294 -453.188901) (xy 514.626154 -453.11404) (xy 514.511398 -453.032616) (xy 514.401389 -452.944887)
			(xy 514.296471 -452.851127) (xy 514.196976 -452.751632) (xy 514.103216 -452.646714) (xy 514.015486 -452.536705)
			(xy 513.934063 -452.421949) (xy 513.859201 -452.302809) (xy 513.791138 -452.179659) (xy 513.730087 -452.052886)
			(xy 513.676241 -451.922889) (xy 513.629768 -451.790078) (xy 513.590815 -451.65487) (xy 513.559504 -451.51769)
			(xy 513.535934 -451.378971) (xy 513.520179 -451.239148) (xy 513.512289 -451.098662) (xy 513.5118 -451.028308)
			(xy 513.5118 -312.408316) (xy 513.512284 -312.337962) (xy 513.520173 -312.197474) (xy 513.535926 -312.05765)
			(xy 513.559495 -311.91893) (xy 513.590805 -311.781749) (xy 513.629757 -311.646539) (xy 513.676229 -311.513726)
			(xy 513.730076 -311.383728) (xy 513.791126 -311.256954) (xy 513.859189 -311.133802) (xy 513.93405 -311.01466)
			(xy 514.015474 -310.899903) (xy 514.103203 -310.789893) (xy 514.196964 -310.684974) (xy 514.296459 -310.585477)
			(xy 514.401377 -310.491716) (xy 514.511387 -310.403986) (xy 514.626144 -310.322561) (xy 514.745285 -310.247699)
			(xy 514.868436 -310.179635) (xy 514.99521 -310.118584) (xy 515.125208 -310.064737) (xy 515.25802 -310.018263)
			(xy 515.393229 -309.97931) (xy 515.53041 -309.947999) (xy 515.669131 -309.924429) (xy 515.808954 -309.908674)
			(xy 515.949442 -309.900784) (xy 516.019796 -309.90032) (xy 531.7998 -309.90032) (xy 531.855607 -309.899798)
			(xy 531.96691 -309.891457) (xy 532.077278 -309.874822) (xy 532.186094 -309.849986) (xy 532.292751 -309.817087)
			(xy 532.39665 -309.77631) (xy 532.497211 -309.727883) (xy 532.593873 -309.672076) (xy 532.686094 -309.609202)
			(xy 532.773358 -309.539612) (xy 532.855178 -309.463695) (xy 532.931096 -309.381876) (xy 533.000687 -309.294613)
			(xy 533.063563 -309.202393) (xy 533.119372 -309.105733) (xy 533.167801 -309.005172) (xy 533.208579 -308.901273)
			(xy 533.24148 -308.794618) (xy 533.266318 -308.685802) (xy 533.282955 -308.575434) (xy 533.291297 -308.464131)
			(xy 533.291796 -308.408324) (xy 533.291796 10.40003) (xy 533.291273 10.455836) (xy 533.28293 10.567137)
			(xy 533.266293 10.677502) (xy 533.241455 10.786316) (xy 533.208555 10.89297) (xy 533.167777 10.996866)
			(xy 533.119348 11.097425) (xy 533.063541 11.194084) (xy 533.000666 11.286302) (xy 532.931076 11.373563)
			(xy 532.855159 11.45538) (xy 532.77334 11.531295) (xy 532.686078 11.600884) (xy 532.593858 11.663757)
			(xy 532.497199 11.719562) (xy 532.396639 11.767989) (xy 532.292741 11.808765) (xy 532.186087 11.841663)
			(xy 532.077273 11.866499) (xy 531.966907 11.883134) (xy 531.855606 11.891474) (xy 531.7998 11.892026)
			(xy 475.799912 11.892026) (xy 475.744104 11.891505) (xy 475.632801 11.883165) (xy 475.522432 11.86653)
			(xy 475.413615 11.841695) (xy 475.306958 11.808796) (xy 475.203057 11.76802) (xy 475.102495 11.719593)
			(xy 475.005832 11.663786) (xy 474.91361 11.600912) (xy 474.826345 11.531322) (xy 474.744524 11.455406)
			(xy 474.668605 11.373587) (xy 474.599013 11.286323) (xy 474.536136 11.194103) (xy 474.480327 11.097442)
			(xy 474.431897 10.996881) (xy 474.391117 10.892982) (xy 474.358216 10.786326) (xy 474.333378 10.677509)
			(xy 474.31674 10.567141) (xy 474.308397 10.455838) (xy 474.307916 10.40003) (xy 474.307916 7.335466)
			(xy 526.704041 7.335466) (xy 526.704041 7.464606) (xy 526.711991 7.593501) (xy 526.727861 7.721661)
			(xy 526.75159 7.848602) (xy 526.783089 7.973841) (xy 526.822238 8.096904) (xy 526.868889 8.217323)
			(xy 526.922864 8.334642) (xy 526.983959 8.448416) (xy 527.051942 8.558213) (xy 527.126556 8.663616)
			(xy 527.207517 8.764226) (xy 527.294517 8.859661) (xy 527.387228 8.94956) (xy 527.485298 9.033581)
			(xy 527.588353 9.111405) (xy 527.696004 9.182737) (xy 527.807843 9.247307) (xy 527.923444 9.304869)
			(xy 528.042369 9.355206) (xy 528.164168 9.398126) (xy 528.288378 9.433467) (xy 528.414527 9.461094)
			(xy 528.542139 9.480903) (xy 528.670728 9.492819) (xy 528.799806 9.496796) (xy 528.928884 9.492819)
			(xy 529.057473 9.480903) (xy 529.185085 9.461094) (xy 529.311234 9.433467) (xy 529.435444 9.398126)
			(xy 529.557243 9.355206) (xy 529.676168 9.304869) (xy 529.791769 9.247307) (xy 529.903608 9.182737)
			(xy 530.011259 9.111405) (xy 530.114314 9.033581) (xy 530.212384 8.94956) (xy 530.305095 8.859661)
			(xy 530.392095 8.764226) (xy 530.473056 8.663616) (xy 530.54767 8.558213) (xy 530.615653 8.448416)
			(xy 530.676748 8.334642) (xy 530.730723 8.217323) (xy 530.777374 8.096904) (xy 530.816523 7.973841)
			(xy 530.848022 7.848602) (xy 530.871751 7.721661) (xy 530.887621 7.593501) (xy 530.895571 7.464606)
			(xy 530.896068 7.400036) (xy 530.895571 7.335466) (xy 530.887621 7.206571) (xy 530.871751 7.078411)
			(xy 530.848022 6.95147) (xy 530.816523 6.826231) (xy 530.777374 6.703168) (xy 530.730723 6.582749)
			(xy 530.676748 6.46543) (xy 530.615653 6.351656) (xy 530.54767 6.241859) (xy 530.473056 6.136456)
			(xy 530.392095 6.035846) (xy 530.305095 5.940411) (xy 530.212384 5.850512) (xy 530.114314 5.766491)
			(xy 530.011259 5.688667) (xy 529.903608 5.617335) (xy 529.791769 5.552765) (xy 529.676168 5.495203)
			(xy 529.557243 5.444866) (xy 529.435444 5.401946) (xy 529.311234 5.366605) (xy 529.185085 5.338978)
			(xy 529.057473 5.319169) (xy 528.928884 5.307253) (xy 528.799806 5.303277) (xy 528.670728 5.307253)
			(xy 528.542139 5.319169) (xy 528.414527 5.338978) (xy 528.288378 5.366605) (xy 528.164168 5.401946)
			(xy 528.042369 5.444866) (xy 527.923444 5.495203) (xy 527.807843 5.552765) (xy 527.696004 5.617335)
			(xy 527.588353 5.688667) (xy 527.485298 5.766491) (xy 527.387228 5.850512) (xy 527.294517 5.940411)
			(xy 527.207517 6.035846) (xy 527.126556 6.136456) (xy 527.051942 6.241859) (xy 526.983959 6.351656)
			(xy 526.922864 6.46543) (xy 526.868889 6.582749) (xy 526.822238 6.703168) (xy 526.783089 6.826231)
			(xy 526.75159 6.95147) (xy 526.727861 7.078411) (xy 526.711991 7.206571) (xy 526.704041 7.335466)
			(xy 474.307916 7.335466) (xy 474.307916 -77.67193) (xy 474.307428 -77.765094) (xy 474.299715 -77.951262)
			(xy 474.284317 -78.136953) (xy 474.261258 -78.321849) (xy 474.23058 -78.505634) (xy 474.192333 -78.687994)
			(xy 474.146584 -78.868619) (xy 474.093411 -79.047199) (xy 474.032904 -79.223429) (xy 473.965167 -79.397008)
			(xy 473.890315 -79.56764) (xy 473.808477 -79.735034) (xy 473.719792 -79.898903) (xy 473.624411 -80.058968)
			(xy 473.522498 -80.214955) (xy 473.414227 -80.366597) (xy 473.299782 -80.513637) (xy 473.17936 -80.655821)
			(xy 473.053165 -80.792909) (xy 472.987624 -80.859122) (xy 471.245184 -82.601562) (xy 471.207836 -82.63956)
			(xy 471.138049 -82.720082) (xy 471.074185 -82.805378) (xy 471.01657 -82.895014) (xy 470.965496 -82.988531)
			(xy 470.921226 -83.085455) (xy 470.883983 -83.18529) (xy 470.853958 -83.287527) (xy 470.831304 -83.391646)
			(xy 470.816136 -83.497117) (xy 470.808532 -83.6034) (xy 470.80805 -83.656678) (xy 470.80805 -404.871936)
			(xy 470.807562 -404.9651) (xy 470.799849 -405.151268) (xy 470.78445 -405.336959) (xy 470.761392 -405.521855)
			(xy 470.730713 -405.70564) (xy 470.692467 -405.888001) (xy 470.646718 -406.068625) (xy 470.593544 -406.247205)
			(xy 470.533038 -406.423435) (xy 470.465301 -406.597015) (xy 470.39045 -406.767647) (xy 470.308612 -406.935041)
			(xy 470.219927 -407.098911) (xy 470.124547 -407.258976) (xy 470.022634 -407.414963) (xy 469.914363 -407.566606)
			(xy 469.799919 -407.713645) (xy 469.679497 -407.855831) (xy 469.553302 -407.992919) (xy 469.487758 -408.059128)
			(xy 468.244936 -409.30195) (xy 468.207612 -409.339964) (xy 468.137859 -409.4205) (xy 468.074028 -409.505805)
			(xy 468.016443 -409.595446) (xy 467.965398 -409.688966) (xy 467.921153 -409.785888) (xy 467.883933 -409.885719)
			(xy 467.853928 -409.98795) (xy 467.831291 -410.092061) (xy 467.816137 -410.197522) (xy 467.808543 -410.303794)
			(xy 467.808056 -410.357066) (xy 467.808056 -439.989976) (xy 467.808577 -440.045784) (xy 467.816916 -440.157089)
			(xy 467.83355 -440.267459) (xy 467.858385 -440.376277) (xy 467.891282 -440.482936) (xy 467.932058 -440.586837)
			(xy 467.980485 -440.687401) (xy 468.036291 -440.784065) (xy 468.099165 -440.876289) (xy 468.168754 -440.963556)
			(xy 468.244671 -441.045378) (xy 468.32649 -441.121299) (xy 468.413753 -441.190893) (xy 468.505974 -441.253771)
			(xy 468.602635 -441.309582) (xy 468.703197 -441.358013) (xy 468.807096 -441.398794) (xy 468.913753 -441.431697)
			(xy 469.02257 -441.456537) (xy 469.13294 -441.473176) (xy 469.244244 -441.48152) (xy 469.300052 -441.481972)
			(xy 471.79992 -441.481972) (xy 471.870274 -441.482466) (xy 472.01076 -441.490356) (xy 472.150582 -441.506112)
			(xy 472.289302 -441.529682) (xy 472.426481 -441.560993) (xy 472.561689 -441.599946) (xy 472.6945 -441.646419)
			(xy 472.824497 -441.700266) (xy 472.95127 -441.761317) (xy 473.07442 -441.82938) (xy 473.19356 -441.904241)
			(xy 473.308316 -441.985664) (xy 473.418325 -442.073394) (xy 473.523243 -442.167153) (xy 473.622738 -442.266648)
			(xy 473.716499 -442.371565) (xy 473.804229 -442.481575) (xy 473.885652 -442.59633) (xy 473.960514 -442.71547)
			(xy 474.028578 -442.83862) (xy 474.089629 -442.965392) (xy 474.143476 -443.095389) (xy 474.18995 -443.2282)
			(xy 474.228904 -443.363407) (xy 474.260216 -443.500587) (xy 474.283787 -443.639306) (xy 474.299543 -443.779128)
			(xy 474.307434 -443.919614) (xy 474.307916 -443.989968) (xy 474.307916 -458.092864) (xy 526.704041 -458.092864)
			(xy 526.704041 -457.963724) (xy 526.711991 -457.834829) (xy 526.727861 -457.706669) (xy 526.75159 -457.579728)
			(xy 526.783089 -457.454489) (xy 526.822238 -457.331426) (xy 526.868889 -457.211007) (xy 526.922864 -457.093688)
			(xy 526.983959 -456.979914) (xy 527.051942 -456.870117) (xy 527.126556 -456.764714) (xy 527.207517 -456.664104)
			(xy 527.294517 -456.568669) (xy 527.387228 -456.47877) (xy 527.485298 -456.394749) (xy 527.588353 -456.316925)
			(xy 527.696004 -456.245593) (xy 527.807843 -456.181023) (xy 527.923444 -456.123461) (xy 528.042369 -456.073124)
			(xy 528.164168 -456.030204) (xy 528.288378 -455.994863) (xy 528.414527 -455.967236) (xy 528.542139 -455.947427)
			(xy 528.670728 -455.935511) (xy 528.799806 -455.931535) (xy 528.928884 -455.935511) (xy 529.057473 -455.947427)
			(xy 529.185085 -455.967236) (xy 529.311234 -455.994863) (xy 529.435444 -456.030204) (xy 529.557243 -456.073124)
			(xy 529.676168 -456.123461) (xy 529.791769 -456.181023) (xy 529.903608 -456.245593) (xy 530.011259 -456.316925)
			(xy 530.114314 -456.394749) (xy 530.212384 -456.47877) (xy 530.305095 -456.568669) (xy 530.392095 -456.664104)
			(xy 530.473056 -456.764714) (xy 530.54767 -456.870117) (xy 530.615653 -456.979914) (xy 530.676748 -457.093688)
			(xy 530.730723 -457.211007) (xy 530.777374 -457.331426) (xy 530.816523 -457.454489) (xy 530.848022 -457.579728)
			(xy 530.871751 -457.706669) (xy 530.887621 -457.834829) (xy 530.895571 -457.963724) (xy 530.896068 -458.028294)
			(xy 530.895571 -458.092864) (xy 530.887621 -458.221759) (xy 530.871751 -458.349919) (xy 530.848022 -458.47686)
			(xy 530.816523 -458.602099) (xy 530.777374 -458.725162) (xy 530.730723 -458.845581) (xy 530.676748 -458.9629)
			(xy 530.615653 -459.076674) (xy 530.54767 -459.186471) (xy 530.473056 -459.291874) (xy 530.392095 -459.392484)
			(xy 530.305095 -459.487919) (xy 530.212384 -459.577818) (xy 530.114314 -459.661839) (xy 530.011259 -459.739663)
			(xy 529.903608 -459.810995) (xy 529.791769 -459.875565) (xy 529.676168 -459.933127) (xy 529.557243 -459.983464)
			(xy 529.435444 -460.026384) (xy 529.311234 -460.061725) (xy 529.185085 -460.089352) (xy 529.057473 -460.109161)
			(xy 528.928884 -460.121077) (xy 528.799806 -460.125054) (xy 528.670728 -460.121077) (xy 528.542139 -460.109161)
			(xy 528.414527 -460.089352) (xy 528.288378 -460.061725) (xy 528.164168 -460.026384) (xy 528.042369 -459.983464)
			(xy 527.923444 -459.933127) (xy 527.807843 -459.875565) (xy 527.696004 -459.810995) (xy 527.588353 -459.739663)
			(xy 527.485298 -459.661839) (xy 527.387228 -459.577818) (xy 527.294517 -459.487919) (xy 527.207517 -459.392484)
			(xy 527.126556 -459.291874) (xy 527.051942 -459.186471) (xy 526.983959 -459.076674) (xy 526.922864 -458.9629)
			(xy 526.868889 -458.845581) (xy 526.822238 -458.725162) (xy 526.783089 -458.602099) (xy 526.75159 -458.47686)
			(xy 526.727861 -458.349919) (xy 526.711991 -458.221759) (xy 526.704041 -458.092864) (xy 474.307916 -458.092864)
			(xy 474.307916 -461.028288) (xy 474.308425 -461.084096) (xy 474.316765 -461.195399) (xy 474.3334 -461.305768)
			(xy 474.358236 -461.414584) (xy 474.391134 -461.521241) (xy 474.431912 -461.625141) (xy 474.480339 -461.725703)
			(xy 474.536147 -461.822365) (xy 474.599022 -461.914586) (xy 474.668612 -462.00185) (xy 474.74453 -462.08367)
			(xy 474.82635 -462.159588) (xy 474.913614 -462.229178) (xy 475.005835 -462.292053) (xy 475.102497 -462.347861)
			(xy 475.203059 -462.396288) (xy 475.306959 -462.437066) (xy 475.413616 -462.469964) (xy 475.522432 -462.4948)
			(xy 475.632801 -462.511435) (xy 475.744104 -462.519775) (xy 475.799912 -462.520284)
		)
		(stroke
			(width 0)
			(type solid)
		)
		(fill yes)
		(layer "In14.Cu")
		(net "T1_GND")
	)
	(gr_poly
		(pts
			(xy 256.292096 -31.120588) (xy 256.292096 -11.780012) (xy 256.29258 -11.709658) (xy 256.300469 -11.56917)
			(xy 256.316223 -11.429347) (xy 256.339792 -11.290626) (xy 256.371101 -11.153445) (xy 256.410054 -11.018236)
			(xy 256.456527 -10.885423) (xy 256.510373 -10.755425) (xy 256.571423 -10.628651) (xy 256.639486 -10.505499)
			(xy 256.714347 -10.386357) (xy 256.795771 -10.2716) (xy 256.883501 -10.16159) (xy 256.977261 -10.056671)
			(xy 257.076757 -9.957175) (xy 257.181674 -9.863414) (xy 257.291684 -9.775683) (xy 257.406441 -9.694258)
			(xy 257.525582 -9.619396) (xy 257.648733 -9.551333) (xy 257.775507 -9.490281) (xy 257.905504 -9.436434)
			(xy 258.038317 -9.38996) (xy 258.173526 -9.351006) (xy 258.310706 -9.319695) (xy 258.449427 -9.296125)
			(xy 258.589251 -9.280371) (xy 258.729738 -9.272481) (xy 258.800092 -9.272016) (xy 383.601976 -9.272016)
			(xy 383.657784 -9.271508) (xy 383.769089 -9.263168) (xy 383.879459 -9.246534) (xy 383.988278 -9.221699)
			(xy 384.094936 -9.188801) (xy 384.198838 -9.148025) (xy 384.299402 -9.099598) (xy 384.396066 -9.043791)
			(xy 384.488289 -8.980916) (xy 384.575555 -8.911326) (xy 384.657377 -8.835408) (xy 384.733297 -8.753588)
			(xy 384.80289 -8.666324) (xy 384.865767 -8.574103) (xy 384.921577 -8.477441) (xy 384.970007 -8.376878)
			(xy 385.010787 -8.272978) (xy 385.043688 -8.16632) (xy 385.068526 -8.057503) (xy 385.085163 -7.947133)
			(xy 385.093506 -7.835828) (xy 385.093972 -7.78002) (xy 385.093972 0.999998) (xy 385.094465 1.070352)
			(xy 385.102355 1.210839) (xy 385.118109 1.350662) (xy 385.141678 1.489383) (xy 385.172988 1.626563)
			(xy 385.211941 1.761772) (xy 385.258413 1.894584) (xy 385.312259 2.024582) (xy 385.37331 2.151356)
			(xy 385.441373 2.274507) (xy 385.516233 2.393649) (xy 385.597656 2.508405) (xy 385.685386 2.618416)
			(xy 385.779146 2.723335) (xy 385.878641 2.822831) (xy 385.983558 2.916592) (xy 386.093567 3.004323)
			(xy 386.208323 3.085748) (xy 386.327463 3.16061) (xy 386.450614 3.228674) (xy 386.577387 3.289727)
			(xy 386.707384 3.343575) (xy 386.840195 3.390049) (xy 386.975404 3.429003) (xy 387.112584 3.460315)
			(xy 387.251304 3.483887) (xy 387.391127 3.499643) (xy 387.531614 3.507534) (xy 387.601968 3.507994)
			(xy 456.202034 3.507994) (xy 456.272387 3.5075) (xy 456.412872 3.499608) (xy 456.552693 3.483853)
			(xy 456.691411 3.460282) (xy 456.828589 3.42897) (xy 456.963796 3.390016) (xy 457.096605 3.343542)
			(xy 457.226601 3.289695) (xy 457.353372 3.228644) (xy 457.476521 3.16058) (xy 457.595659 3.085719)
			(xy 457.710413 3.004295) (xy 457.820421 2.916565) (xy 457.925337 2.822806) (xy 458.02483 2.723311)
			(xy 458.118589 2.618393) (xy 458.206317 2.508384) (xy 458.287739 2.393629) (xy 458.362598 2.27449)
			(xy 458.43066 2.15134) (xy 458.49171 2.024568) (xy 458.545555 1.894572) (xy 458.592027 1.761761)
			(xy 458.630979 1.626554) (xy 458.662289 1.489376) (xy 458.685858 1.350658) (xy 458.701612 1.210836)
			(xy 458.709501 1.070351) (xy 458.71003 0.999998) (xy 458.71003 -7.78002) (xy 458.71054 -7.835827)
			(xy 458.718882 -7.947128) (xy 458.735519 -8.057494) (xy 458.760357 -8.166309) (xy 458.793257 -8.272963)
			(xy 458.834035 -8.37686) (xy 458.882464 -8.47742) (xy 458.938272 -8.574079) (xy 459.001148 -8.666297)
			(xy 459.070739 -8.753559) (xy 459.146656 -8.835376) (xy 459.228476 -8.911291) (xy 459.31574 -8.98088)
			(xy 459.40796 -9.043752) (xy 459.504621 -9.099557) (xy 459.605182 -9.147983) (xy 459.70908 -9.188758)
			(xy 459.815736 -9.221655) (xy 459.924551 -9.24649) (xy 460.034918 -9.263123) (xy 460.146219 -9.271462)
			(xy 460.202026 -9.272016) (xy 464.327748 -9.272016) (xy 464.332574 -9.271) (xy 464.357024 -9.266474)
			(xy 464.406516 -9.261643) (xy 464.43138 -9.261348) (xy 464.456244 -9.26164) (xy 464.505735 -9.266479)
			(xy 464.530186 -9.271) (xy 464.535012 -9.272016) (xy 469.799924 -9.272016) (xy 469.855731 -9.271493)
			(xy 469.967032 -9.263151) (xy 470.077399 -9.246514) (xy 470.186213 -9.221677) (xy 470.292868 -9.188777)
			(xy 470.396765 -9.147999) (xy 470.497325 -9.099571) (xy 470.593985 -9.043764) (xy 470.686204 -8.980889)
			(xy 470.773467 -8.911299) (xy 470.855285 -8.835382) (xy 470.931202 -8.753564) (xy 471.000791 -8.666301)
			(xy 471.063666 -8.574082) (xy 471.119473 -8.477422) (xy 471.167901 -8.376862) (xy 471.208678 -8.272964)
			(xy 471.241578 -8.166309) (xy 471.266415 -8.057495) (xy 471.283051 -7.947128) (xy 471.291394 -7.835827)
			(xy 471.29192 -7.78002) (xy 471.29192 10.40003) (xy 471.291397 10.455837) (xy 471.283054 10.567138)
			(xy 471.266417 10.677504) (xy 471.241579 10.786319) (xy 471.208679 10.892973) (xy 471.167901 10.99687)
			(xy 471.119473 11.09743) (xy 471.063666 11.194089) (xy 471.000791 11.286308) (xy 470.931201 11.373571)
			(xy 470.855284 11.455389) (xy 470.773466 11.531305) (xy 470.686203 11.600895) (xy 470.593984 11.663769)
			(xy 470.497324 11.719576) (xy 470.396765 11.768004) (xy 470.292867 11.808781) (xy 470.186213 11.841681)
			(xy 470.077398 11.866518) (xy 469.967032 11.883155) (xy 469.855731 11.891497) (xy 469.799924 11.892026)
			(xy 1.999996 11.892026) (xy 1.944189 11.891504) (xy 1.832887 11.883163) (xy 1.72252 11.866527) (xy 1.613705 11.841691)
			(xy 1.50705 11.808792) (xy 1.403151 11.768014) (xy 1.302591 11.719587) (xy 1.20593 11.66378) (xy 1.113711 11.600905)
			(xy 1.026448 11.531315) (xy 0.944629 11.455398) (xy 0.868712 11.373579) (xy 0.799122 11.286316) (xy 0.736248 11.194096)
			(xy 0.680441 11.097436) (xy 0.632014 10.996875) (xy 0.591237 10.892977) (xy 0.558338 10.786321) (xy 0.533502 10.677506)
			(xy 0.516867 10.567139) (xy 0.508526 10.455837) (xy 0.508 10.40003) (xy 0.508 7.335466) (xy 2.904225 7.335466)
			(xy 2.904225 7.464606) (xy 2.912175 7.593501) (xy 2.928045 7.721661) (xy 2.951774 7.848602) (xy 2.983273 7.973841)
			(xy 3.022422 8.096904) (xy 3.069073 8.217323) (xy 3.123048 8.334642) (xy 3.184143 8.448416) (xy 3.252126 8.558213)
			(xy 3.32674 8.663616) (xy 3.407701 8.764226) (xy 3.494701 8.859661) (xy 3.587412 8.94956) (xy 3.685482 9.033581)
			(xy 3.788537 9.111405) (xy 3.896188 9.182737) (xy 4.008027 9.247307) (xy 4.123628 9.304869) (xy 4.242553 9.355206)
			(xy 4.364352 9.398126) (xy 4.488562 9.433467) (xy 4.614711 9.461094) (xy 4.742323 9.480903) (xy 4.870912 9.492819)
			(xy 4.99999 9.496796) (xy 5.129068 9.492819) (xy 5.257657 9.480903) (xy 5.385269 9.461094) (xy 5.511418 9.433467)
			(xy 5.635628 9.398126) (xy 5.757427 9.355206) (xy 5.876352 9.304869) (xy 5.991953 9.247307) (xy 6.020338 9.230919)
			(xy 256.921241 9.230919) (xy 256.921241 9.316669) (xy 256.929153 9.402052) (xy 256.944909 9.486342)
			(xy 256.968376 9.568818) (xy 256.999352 9.648777) (xy 257.037574 9.725537) (xy 257.082715 9.798443)
			(xy 257.134391 9.866872) (xy 257.19216 9.930242) (xy 257.25553 9.988011) (xy 257.323959 10.039687)
			(xy 257.396865 10.084828) (xy 257.473625 10.12305) (xy 257.553584 10.154026) (xy 257.63606 10.177493)
			(xy 257.72035 10.193249) (xy 257.805733 10.201161) (xy 257.891483 10.201161) (xy 257.976866 10.193249)
			(xy 258.061156 10.177493) (xy 258.143632 10.154026) (xy 258.223591 10.12305) (xy 258.300351 10.084828)
			(xy 258.373257 10.039687) (xy 258.441686 9.988011) (xy 258.505056 9.930242) (xy 258.562825 9.866872)
			(xy 258.614501 9.798443) (xy 258.659642 9.725537) (xy 258.697864 9.648777) (xy 258.72884 9.568818)
			(xy 258.752307 9.486342) (xy 258.768063 9.402052) (xy 258.775975 9.316669) (xy 258.77647 9.273794)
			(xy 258.775975 9.230919) (xy 263.271241 9.230919) (xy 263.271241 9.316669) (xy 263.279153 9.402052)
			(xy 263.294909 9.486342) (xy 263.318376 9.568818) (xy 263.349352 9.648777) (xy 263.387574 9.725537)
			(xy 263.432715 9.798443) (xy 263.484391 9.866872) (xy 263.54216 9.930242) (xy 263.60553 9.988011)
			(xy 263.673959 10.039687) (xy 263.746865 10.084828) (xy 263.823625 10.12305) (xy 263.903584 10.154026)
			(xy 263.98606 10.177493) (xy 264.07035 10.193249) (xy 264.155733 10.201161) (xy 264.241483 10.201161)
			(xy 264.326866 10.193249) (xy 264.411156 10.177493) (xy 264.493632 10.154026) (xy 264.573591 10.12305)
			(xy 264.650351 10.084828) (xy 264.723257 10.039687) (xy 264.791686 9.988011) (xy 264.855056 9.930242)
			(xy 264.912825 9.866872) (xy 264.964501 9.798443) (xy 265.009642 9.725537) (xy 265.047864 9.648777)
			(xy 265.07884 9.568818) (xy 265.102307 9.486342) (xy 265.118063 9.402052) (xy 265.125975 9.316669)
			(xy 265.12647 9.273794) (xy 265.125975 9.230919) (xy 324.845921 9.230919) (xy 324.845921 9.316669)
			(xy 324.853833 9.402052) (xy 324.869589 9.486342) (xy 324.893056 9.568818) (xy 324.924032 9.648777)
			(xy 324.962254 9.725537) (xy 325.007395 9.798443) (xy 325.059071 9.866872) (xy 325.11684 9.930242)
			(xy 325.18021 9.988011) (xy 325.248639 10.039687) (xy 325.321545 10.084828) (xy 325.398305 10.12305)
			(xy 325.478264 10.154026) (xy 325.56074 10.177493) (xy 325.64503 10.193249) (xy 325.730413 10.201161)
			(xy 325.816163 10.201161) (xy 325.901546 10.193249) (xy 325.985836 10.177493) (xy 326.068312 10.154026)
			(xy 326.148271 10.12305) (xy 326.225031 10.084828) (xy 326.297937 10.039687) (xy 326.366366 9.988011)
			(xy 326.429736 9.930242) (xy 326.487505 9.866872) (xy 326.539181 9.798443) (xy 326.584322 9.725537)
			(xy 326.622544 9.648777) (xy 326.65352 9.568818) (xy 326.676987 9.486342) (xy 326.692743 9.402052)
			(xy 326.700655 9.316669) (xy 326.70115 9.273794) (xy 326.700655 9.230919) (xy 331.195921 9.230919)
			(xy 331.195921 9.316669) (xy 331.203833 9.402052) (xy 331.219589 9.486342) (xy 331.243056 9.568818)
			(xy 331.274032 9.648777) (xy 331.312254 9.725537) (xy 331.357395 9.798443) (xy 331.409071 9.866872)
			(xy 331.46684 9.930242) (xy 331.53021 9.988011) (xy 331.598639 10.039687) (xy 331.671545 10.084828)
			(xy 331.748305 10.12305) (xy 331.828264 10.154026) (xy 331.91074 10.177493) (xy 331.99503 10.193249)
			(xy 332.080413 10.201161) (xy 332.166163 10.201161) (xy 332.251546 10.193249) (xy 332.335836 10.177493)
			(xy 332.418312 10.154026) (xy 332.498271 10.12305) (xy 332.575031 10.084828) (xy 332.647937 10.039687)
			(xy 332.716366 9.988011) (xy 332.779736 9.930242) (xy 332.837505 9.866872) (xy 332.889181 9.798443)
			(xy 332.934322 9.725537) (xy 332.972544 9.648777) (xy 333.00352 9.568818) (xy 333.026987 9.486342)
			(xy 333.042743 9.402052) (xy 333.050655 9.316669) (xy 333.05115 9.273794) (xy 333.050655 9.230919)
			(xy 335.488267 9.230919) (xy 335.488267 9.316669) (xy 335.496179 9.402052) (xy 335.511935 9.486342)
			(xy 335.535402 9.568818) (xy 335.566378 9.648777) (xy 335.6046 9.725537) (xy 335.649741 9.798443)
			(xy 335.701417 9.866872) (xy 335.759186 9.930242) (xy 335.822556 9.988011) (xy 335.890985 10.039687)
			(xy 335.963891 10.084828) (xy 336.040651 10.12305) (xy 336.12061 10.154026) (xy 336.203086 10.177493)
			(xy 336.287376 10.193249) (xy 336.372759 10.201161) (xy 336.458509 10.201161) (xy 336.543892 10.193249)
			(xy 336.628182 10.177493) (xy 336.710658 10.154026) (xy 336.790617 10.12305) (xy 336.867377 10.084828)
			(xy 336.940283 10.039687) (xy 337.008712 9.988011) (xy 337.072082 9.930242) (xy 337.129851 9.866872)
			(xy 337.181527 9.798443) (xy 337.226668 9.725537) (xy 337.26489 9.648777) (xy 337.295866 9.568818)
			(xy 337.319333 9.486342) (xy 337.335089 9.402052) (xy 337.343001 9.316669) (xy 337.343496 9.273794)
			(xy 337.343001 9.230919) (xy 341.838267 9.230919) (xy 341.838267 9.316669) (xy 341.846179 9.402052)
			(xy 341.861935 9.486342) (xy 341.885402 9.568818) (xy 341.916378 9.648777) (xy 341.9546 9.725537)
			(xy 341.999741 9.798443) (xy 342.051417 9.866872) (xy 342.109186 9.930242) (xy 342.172556 9.988011)
			(xy 342.240985 10.039687) (xy 342.313891 10.084828) (xy 342.390651 10.12305) (xy 342.47061 10.154026)
			(xy 342.553086 10.177493) (xy 342.637376 10.193249) (xy 342.722759 10.201161) (xy 342.808509 10.201161)
			(xy 342.893892 10.193249) (xy 342.978182 10.177493) (xy 343.060658 10.154026) (xy 343.140617 10.12305)
			(xy 343.217377 10.084828) (xy 343.290283 10.039687) (xy 343.358712 9.988011) (xy 343.422082 9.930242)
			(xy 343.479851 9.866872) (xy 343.531527 9.798443) (xy 343.576668 9.725537) (xy 343.61489 9.648777)
			(xy 343.645866 9.568818) (xy 343.669333 9.486342) (xy 343.685089 9.402052) (xy 343.693001 9.316669)
			(xy 343.693496 9.273794) (xy 343.693001 9.230919) (xy 373.705107 9.230919) (xy 373.705107 9.316669)
			(xy 373.713019 9.402052) (xy 373.728775 9.486342) (xy 373.752242 9.568818) (xy 373.783218 9.648777)
			(xy 373.82144 9.725537) (xy 373.866581 9.798443) (xy 373.918257 9.866872) (xy 373.976026 9.930242)
			(xy 374.039396 9.988011) (xy 374.107825 10.039687) (xy 374.180731 10.084828) (xy 374.257491 10.12305)
			(xy 374.33745 10.154026) (xy 374.419926 10.177493) (xy 374.504216 10.193249) (xy 374.589599 10.201161)
			(xy 374.675349 10.201161) (xy 374.760732 10.193249) (xy 374.845022 10.177493) (xy 374.927498 10.154026)
			(xy 375.007457 10.12305) (xy 375.084217 10.084828) (xy 375.157123 10.039687) (xy 375.225552 9.988011)
			(xy 375.288922 9.930242) (xy 375.346691 9.866872) (xy 375.398367 9.798443) (xy 375.443508 9.725537)
			(xy 375.48173 9.648777) (xy 375.512706 9.568818) (xy 375.536173 9.486342) (xy 375.551929 9.402052)
			(xy 375.559841 9.316669) (xy 375.560336 9.273794) (xy 375.559841 9.230919) (xy 380.055107 9.230919)
			(xy 380.055107 9.316669) (xy 380.063019 9.402052) (xy 380.078775 9.486342) (xy 380.102242 9.568818)
			(xy 380.133218 9.648777) (xy 380.17144 9.725537) (xy 380.216581 9.798443) (xy 380.268257 9.866872)
			(xy 380.326026 9.930242) (xy 380.389396 9.988011) (xy 380.457825 10.039687) (xy 380.530731 10.084828)
			(xy 380.607491 10.12305) (xy 380.68745 10.154026) (xy 380.769926 10.177493) (xy 380.854216 10.193249)
			(xy 380.939599 10.201161) (xy 381.025349 10.201161) (xy 381.110732 10.193249) (xy 381.195022 10.177493)
			(xy 381.277498 10.154026) (xy 381.357457 10.12305) (xy 381.434217 10.084828) (xy 381.507123 10.039687)
			(xy 381.575552 9.988011) (xy 381.638922 9.930242) (xy 381.696691 9.866872) (xy 381.748367 9.798443)
			(xy 381.793508 9.725537) (xy 381.83173 9.648777) (xy 381.862706 9.568818) (xy 381.886173 9.486342)
			(xy 381.901929 9.402052) (xy 381.909841 9.316669) (xy 381.910336 9.273794) (xy 381.909841 9.230919)
			(xy 381.901929 9.145536) (xy 381.886173 9.061246) (xy 381.862706 8.97877) (xy 381.83173 8.898811)
			(xy 381.793508 8.822051) (xy 381.748367 8.749145) (xy 381.696691 8.680716) (xy 381.638922 8.617346)
			(xy 381.575552 8.559577) (xy 381.507123 8.507901) (xy 381.434217 8.46276) (xy 381.357457 8.424538)
			(xy 381.277498 8.393562) (xy 381.195022 8.370095) (xy 381.110732 8.354339) (xy 381.025349 8.346427)
			(xy 380.939599 8.346427) (xy 380.854216 8.354339) (xy 380.769926 8.370095) (xy 380.68745 8.393562)
			(xy 380.607491 8.424538) (xy 380.530731 8.46276) (xy 380.457825 8.507901) (xy 380.389396 8.559577)
			(xy 380.326026 8.617346) (xy 380.268257 8.680716) (xy 380.216581 8.749145) (xy 380.17144 8.822051)
			(xy 380.133218 8.898811) (xy 380.102242 8.97877) (xy 380.078775 9.061246) (xy 380.063019 9.145536)
			(xy 380.055107 9.230919) (xy 375.559841 9.230919) (xy 375.551929 9.145536) (xy 375.536173 9.061246)
			(xy 375.512706 8.97877) (xy 375.48173 8.898811) (xy 375.443508 8.822051) (xy 375.398367 8.749145)
			(xy 375.346691 8.680716) (xy 375.288922 8.617346) (xy 375.225552 8.559577) (xy 375.157123 8.507901)
			(xy 375.084217 8.46276) (xy 375.007457 8.424538) (xy 374.927498 8.393562) (xy 374.845022 8.370095)
			(xy 374.760732 8.354339) (xy 374.675349 8.346427) (xy 374.589599 8.346427) (xy 374.504216 8.354339)
			(xy 374.419926 8.370095) (xy 374.33745 8.393562) (xy 374.257491 8.424538) (xy 374.180731 8.46276)
			(xy 374.107825 8.507901) (xy 374.039396 8.559577) (xy 373.976026 8.617346) (xy 373.918257 8.680716)
			(xy 373.866581 8.749145) (xy 373.82144 8.822051) (xy 373.783218 8.898811) (xy 373.752242 8.97877)
			(xy 373.728775 9.061246) (xy 373.713019 9.145536) (xy 373.705107 9.230919) (xy 343.693001 9.230919)
			(xy 343.685089 9.145536) (xy 343.669333 9.061246) (xy 343.645866 8.97877) (xy 343.61489 8.898811)
			(xy 343.576668 8.822051) (xy 343.531527 8.749145) (xy 343.479851 8.680716) (xy 343.422082 8.617346)
			(xy 343.358712 8.559577) (xy 343.290283 8.507901) (xy 343.217377 8.46276) (xy 343.140617 8.424538)
			(xy 343.060658 8.393562) (xy 342.978182 8.370095) (xy 342.893892 8.354339) (xy 342.808509 8.346427)
			(xy 342.722759 8.346427) (xy 342.637376 8.354339) (xy 342.553086 8.370095) (xy 342.47061 8.393562)
			(xy 342.390651 8.424538) (xy 342.313891 8.46276) (xy 342.240985 8.507901) (xy 342.172556 8.559577)
			(xy 342.109186 8.617346) (xy 342.051417 8.680716) (xy 341.999741 8.749145) (xy 341.9546 8.822051)
			(xy 341.916378 8.898811) (xy 341.885402 8.97877) (xy 341.861935 9.061246) (xy 341.846179 9.145536)
			(xy 341.838267 9.230919) (xy 337.343001 9.230919) (xy 337.335089 9.145536) (xy 337.319333 9.061246)
			(xy 337.295866 8.97877) (xy 337.26489 8.898811) (xy 337.226668 8.822051) (xy 337.181527 8.749145)
			(xy 337.129851 8.680716) (xy 337.072082 8.617346) (xy 337.008712 8.559577) (xy 336.940283 8.507901)
			(xy 336.867377 8.46276) (xy 336.790617 8.424538) (xy 336.710658 8.393562) (xy 336.628182 8.370095)
			(xy 336.543892 8.354339) (xy 336.458509 8.346427) (xy 336.372759 8.346427) (xy 336.287376 8.354339)
			(xy 336.203086 8.370095) (xy 336.12061 8.393562) (xy 336.040651 8.424538) (xy 335.963891 8.46276)
			(xy 335.890985 8.507901) (xy 335.822556 8.559577) (xy 335.759186 8.617346) (xy 335.701417 8.680716)
			(xy 335.649741 8.749145) (xy 335.6046 8.822051) (xy 335.566378 8.898811) (xy 335.535402 8.97877)
			(xy 335.511935 9.061246) (xy 335.496179 9.145536) (xy 335.488267 9.230919) (xy 333.050655 9.230919)
			(xy 333.042743 9.145536) (xy 333.026987 9.061246) (xy 333.00352 8.97877) (xy 332.972544 8.898811)
			(xy 332.934322 8.822051) (xy 332.889181 8.749145) (xy 332.837505 8.680716) (xy 332.779736 8.617346)
			(xy 332.716366 8.559577) (xy 332.647937 8.507901) (xy 332.575031 8.46276) (xy 332.498271 8.424538)
			(xy 332.418312 8.393562) (xy 332.335836 8.370095) (xy 332.251546 8.354339) (xy 332.166163 8.346427)
			(xy 332.080413 8.346427) (xy 331.99503 8.354339) (xy 331.91074 8.370095) (xy 331.828264 8.393562)
			(xy 331.748305 8.424538) (xy 331.671545 8.46276) (xy 331.598639 8.507901) (xy 331.53021 8.559577)
			(xy 331.46684 8.617346) (xy 331.409071 8.680716) (xy 331.357395 8.749145) (xy 331.312254 8.822051)
			(xy 331.274032 8.898811) (xy 331.243056 8.97877) (xy 331.219589 9.061246) (xy 331.203833 9.145536)
			(xy 331.195921 9.230919) (xy 326.700655 9.230919) (xy 326.692743 9.145536) (xy 326.676987 9.061246)
			(xy 326.65352 8.97877) (xy 326.622544 8.898811) (xy 326.584322 8.822051) (xy 326.539181 8.749145)
			(xy 326.487505 8.680716) (xy 326.429736 8.617346) (xy 326.366366 8.559577) (xy 326.297937 8.507901)
			(xy 326.225031 8.46276) (xy 326.148271 8.424538) (xy 326.068312 8.393562) (xy 325.985836 8.370095)
			(xy 325.901546 8.354339) (xy 325.816163 8.346427) (xy 325.730413 8.346427) (xy 325.64503 8.354339)
			(xy 325.56074 8.370095) (xy 325.478264 8.393562) (xy 325.398305 8.424538) (xy 325.321545 8.46276)
			(xy 325.248639 8.507901) (xy 325.18021 8.559577) (xy 325.11684 8.617346) (xy 325.059071 8.680716)
			(xy 325.007395 8.749145) (xy 324.962254 8.822051) (xy 324.924032 8.898811) (xy 324.893056 8.97877)
			(xy 324.869589 9.061246) (xy 324.853833 9.145536) (xy 324.845921 9.230919) (xy 265.125975 9.230919)
			(xy 265.118063 9.145536) (xy 265.102307 9.061246) (xy 265.07884 8.97877) (xy 265.047864 8.898811)
			(xy 265.009642 8.822051) (xy 264.964501 8.749145) (xy 264.912825 8.680716) (xy 264.855056 8.617346)
			(xy 264.791686 8.559577) (xy 264.723257 8.507901) (xy 264.650351 8.46276) (xy 264.573591 8.424538)
			(xy 264.493632 8.393562) (xy 264.411156 8.370095) (xy 264.326866 8.354339) (xy 264.241483 8.346427)
			(xy 264.155733 8.346427) (xy 264.07035 8.354339) (xy 263.98606 8.370095) (xy 263.903584 8.393562)
			(xy 263.823625 8.424538) (xy 263.746865 8.46276) (xy 263.673959 8.507901) (xy 263.60553 8.559577)
			(xy 263.54216 8.617346) (xy 263.484391 8.680716) (xy 263.432715 8.749145) (xy 263.387574 8.822051)
			(xy 263.349352 8.898811) (xy 263.318376 8.97877) (xy 263.294909 9.061246) (xy 263.279153 9.145536)
			(xy 263.271241 9.230919) (xy 258.775975 9.230919) (xy 258.768063 9.145536) (xy 258.752307 9.061246)
			(xy 258.72884 8.97877) (xy 258.697864 8.898811) (xy 258.659642 8.822051) (xy 258.614501 8.749145)
			(xy 258.562825 8.680716) (xy 258.505056 8.617346) (xy 258.441686 8.559577) (xy 258.373257 8.507901)
			(xy 258.300351 8.46276) (xy 258.223591 8.424538) (xy 258.143632 8.393562) (xy 258.061156 8.370095)
			(xy 257.976866 8.354339) (xy 257.891483 8.346427) (xy 257.805733 8.346427) (xy 257.72035 8.354339)
			(xy 257.63606 8.370095) (xy 257.553584 8.393562) (xy 257.473625 8.424538) (xy 257.396865 8.46276)
			(xy 257.323959 8.507901) (xy 257.25553 8.559577) (xy 257.19216 8.617346) (xy 257.134391 8.680716)
			(xy 257.082715 8.749145) (xy 257.037574 8.822051) (xy 256.999352 8.898811) (xy 256.968376 8.97877)
			(xy 256.944909 9.061246) (xy 256.929153 9.145536) (xy 256.921241 9.230919) (xy 6.020338 9.230919)
			(xy 6.103792 9.182737) (xy 6.211443 9.111405) (xy 6.314498 9.033581) (xy 6.412568 8.94956) (xy 6.505279 8.859661)
			(xy 6.592279 8.764226) (xy 6.67324 8.663616) (xy 6.747854 8.558213) (xy 6.815837 8.448416) (xy 6.876932 8.334642)
			(xy 6.930907 8.217323) (xy 6.977558 8.096904) (xy 7.016707 7.973841) (xy 7.048206 7.848602) (xy 7.071935 7.721661)
			(xy 7.087805 7.593501) (xy 7.095755 7.464606) (xy 7.096252 7.400036) (xy 7.095755 7.335466) (xy 7.087805 7.206571)
			(xy 7.071935 7.078411) (xy 7.048206 6.95147) (xy 7.016707 6.826231) (xy 6.977558 6.703168) (xy 6.97173 6.688125)
			(xy 178.335673 6.688125) (xy 178.335673 6.773875) (xy 178.343585 6.859258) (xy 178.359341 6.943548)
			(xy 178.382808 7.026024) (xy 178.413784 7.105983) (xy 178.452006 7.182743) (xy 178.497147 7.255649)
			(xy 178.548823 7.324078) (xy 178.606592 7.387448) (xy 178.669962 7.445217) (xy 178.738391 7.496893)
			(xy 178.811297 7.542034) (xy 178.888057 7.580256) (xy 178.968016 7.611232) (xy 179.050492 7.634699)
			(xy 179.134782 7.650455) (xy 179.220165 7.658367) (xy 179.305915 7.658367) (xy 179.391298 7.650455)
			(xy 179.475588 7.634699) (xy 179.558064 7.611232) (xy 179.638023 7.580256) (xy 179.714783 7.542034)
			(xy 179.787689 7.496893) (xy 179.856118 7.445217) (xy 179.919488 7.387448) (xy 179.977257 7.324078)
			(xy 180.028933 7.255649) (xy 180.074074 7.182743) (xy 180.112296 7.105983) (xy 180.143272 7.026024)
			(xy 180.166739 6.943548) (xy 180.182495 6.859258) (xy 180.190407 6.773875) (xy 180.190902 6.731)
			(xy 180.190407 6.688125) (xy 184.685673 6.688125) (xy 184.685673 6.773875) (xy 184.693585 6.859258)
			(xy 184.709341 6.943548) (xy 184.732808 7.026024) (xy 184.763784 7.105983) (xy 184.802006 7.182743)
			(xy 184.847147 7.255649) (xy 184.898823 7.324078) (xy 184.956592 7.387448) (xy 185.019962 7.445217)
			(xy 185.088391 7.496893) (xy 185.161297 7.542034) (xy 185.238057 7.580256) (xy 185.318016 7.611232)
			(xy 185.400492 7.634699) (xy 185.484782 7.650455) (xy 185.570165 7.658367) (xy 185.655915 7.658367)
			(xy 185.741298 7.650455) (xy 185.825588 7.634699) (xy 185.908064 7.611232) (xy 185.988023 7.580256)
			(xy 186.064783 7.542034) (xy 186.137689 7.496893) (xy 186.206118 7.445217) (xy 186.269488 7.387448)
			(xy 186.327257 7.324078) (xy 186.378933 7.255649) (xy 186.424074 7.182743) (xy 186.462296 7.105983)
			(xy 186.493272 7.026024) (xy 186.516739 6.943548) (xy 186.532495 6.859258) (xy 186.540407 6.773875)
			(xy 186.540902 6.731) (xy 186.540407 6.688125) (xy 246.260353 6.688125) (xy 246.260353 6.773875)
			(xy 246.268265 6.859258) (xy 246.284021 6.943548) (xy 246.307488 7.026024) (xy 246.338464 7.105983)
			(xy 246.376686 7.182743) (xy 246.421827 7.255649) (xy 246.473503 7.324078) (xy 246.531272 7.387448)
			(xy 246.594642 7.445217) (xy 246.663071 7.496893) (xy 246.735977 7.542034) (xy 246.812737 7.580256)
			(xy 246.892696 7.611232) (xy 246.975172 7.634699) (xy 247.059462 7.650455) (xy 247.144845 7.658367)
			(xy 247.230595 7.658367) (xy 247.315978 7.650455) (xy 247.400268 7.634699) (xy 247.482744 7.611232)
			(xy 247.562703 7.580256) (xy 247.639463 7.542034) (xy 247.712369 7.496893) (xy 247.780798 7.445217)
			(xy 247.844168 7.387448) (xy 247.901937 7.324078) (xy 247.953613 7.255649) (xy 247.998754 7.182743)
			(xy 248.036976 7.105983) (xy 248.067952 7.026024) (xy 248.091419 6.943548) (xy 248.107175 6.859258)
			(xy 248.115087 6.773875) (xy 248.115582 6.731) (xy 248.115087 6.688125) (xy 252.610353 6.688125)
			(xy 252.610353 6.773875) (xy 252.618265 6.859258) (xy 252.634021 6.943548) (xy 252.657488 7.026024)
			(xy 252.688464 7.105983) (xy 252.726686 7.182743) (xy 252.771827 7.255649) (xy 252.823503 7.324078)
			(xy 252.881272 7.387448) (xy 252.944642 7.445217) (xy 253.013071 7.496893) (xy 253.085977 7.542034)
			(xy 253.162737 7.580256) (xy 253.242696 7.611232) (xy 253.325172 7.634699) (xy 253.409462 7.650455)
			(xy 253.494845 7.658367) (xy 253.580595 7.658367) (xy 253.665978 7.650455) (xy 253.750268 7.634699)
			(xy 253.832744 7.611232) (xy 253.912703 7.580256) (xy 253.989463 7.542034) (xy 254.062369 7.496893)
			(xy 254.130798 7.445217) (xy 254.194168 7.387448) (xy 254.251937 7.324078) (xy 254.303613 7.255649)
			(xy 254.348754 7.182743) (xy 254.386976 7.105983) (xy 254.417952 7.026024) (xy 254.441419 6.943548)
			(xy 254.457175 6.859258) (xy 254.465087 6.773875) (xy 254.465582 6.731) (xy 254.465119 6.690919)
			(xy 256.921241 6.690919) (xy 256.921241 6.776669) (xy 256.929153 6.862052) (xy 256.944909 6.946342)
			(xy 256.968376 7.028818) (xy 256.999352 7.108777) (xy 257.037574 7.185537) (xy 257.082715 7.258443)
			(xy 257.134391 7.326872) (xy 257.19216 7.390242) (xy 257.25553 7.448011) (xy 257.323959 7.499687)
			(xy 257.396865 7.544828) (xy 257.473625 7.58305) (xy 257.553584 7.614026) (xy 257.63606 7.637493)
			(xy 257.72035 7.653249) (xy 257.805733 7.661161) (xy 257.891483 7.661161) (xy 257.976866 7.653249)
			(xy 258.061156 7.637493) (xy 258.143632 7.614026) (xy 258.223591 7.58305) (xy 258.245794 7.571994)
			(xy 261.85622 7.571994) (xy 261.85622 8.435594) (xy 261.856706 8.462863) (xy 261.864468 8.516847)
			(xy 261.879833 8.569177) (xy 261.90249 8.618787) (xy 261.931976 8.664668) (xy 261.967691 8.705885)
			(xy 262.008908 8.7416) (xy 262.054789 8.771086) (xy 262.104399 8.793743) (xy 262.156729 8.809108)
			(xy 262.210713 8.81687) (xy 262.265251 8.81687) (xy 262.319235 8.809108) (xy 262.371565 8.793743)
			(xy 262.421175 8.771086) (xy 262.467056 8.7416) (xy 262.508273 8.705885) (xy 262.543988 8.664668)
			(xy 262.573474 8.618787) (xy 262.596131 8.569177) (xy 262.611496 8.516847) (xy 262.619258 8.462863)
			(xy 262.619744 8.435594) (xy 262.619744 7.571994) (xy 262.619258 7.544725) (xy 262.611496 7.490741)
			(xy 262.596131 7.438411) (xy 262.573474 7.388801) (xy 262.543988 7.34292) (xy 262.508273 7.301703)
			(xy 262.467056 7.265988) (xy 262.421175 7.236502) (xy 262.371565 7.213845) (xy 262.319235 7.19848)
			(xy 262.265251 7.190718) (xy 262.210713 7.190718) (xy 262.156729 7.19848) (xy 262.104399 7.213845)
			(xy 262.054789 7.236502) (xy 262.008908 7.265988) (xy 261.967691 7.301703) (xy 261.931976 7.34292)
			(xy 261.90249 7.388801) (xy 261.879833 7.438411) (xy 261.864468 7.490741) (xy 261.856706 7.544725)
			(xy 261.85622 7.571994) (xy 258.245794 7.571994) (xy 258.300351 7.544828) (xy 258.373257 7.499687)
			(xy 258.441686 7.448011) (xy 258.505056 7.390242) (xy 258.562825 7.326872) (xy 258.614501 7.258443)
			(xy 258.659642 7.185537) (xy 258.697864 7.108777) (xy 258.72884 7.028818) (xy 258.752307 6.946342)
			(xy 258.768063 6.862052) (xy 258.775975 6.776669) (xy 258.77647 6.733794) (xy 258.775975 6.690919)
			(xy 263.271241 6.690919) (xy 263.271241 6.776669) (xy 263.279153 6.862052) (xy 263.294909 6.946342)
			(xy 263.318376 7.028818) (xy 263.349352 7.108777) (xy 263.387574 7.185537) (xy 263.432715 7.258443)
			(xy 263.484391 7.326872) (xy 263.54216 7.390242) (xy 263.60553 7.448011) (xy 263.673959 7.499687)
			(xy 263.746865 7.544828) (xy 263.823625 7.58305) (xy 263.903584 7.614026) (xy 263.98606 7.637493)
			(xy 264.07035 7.653249) (xy 264.155733 7.661161) (xy 264.241483 7.661161) (xy 264.326866 7.653249)
			(xy 264.411156 7.637493) (xy 264.493632 7.614026) (xy 264.573591 7.58305) (xy 264.650351 7.544828)
			(xy 264.723257 7.499687) (xy 264.791686 7.448011) (xy 264.855056 7.390242) (xy 264.912825 7.326872)
			(xy 264.964501 7.258443) (xy 265.009642 7.185537) (xy 265.047864 7.108777) (xy 265.07884 7.028818)
			(xy 265.102307 6.946342) (xy 265.118063 6.862052) (xy 265.125975 6.776669) (xy 265.12647 6.733794)
			(xy 265.125975 6.690919) (xy 324.845921 6.690919) (xy 324.845921 6.776669) (xy 324.853833 6.862052)
			(xy 324.869589 6.946342) (xy 324.893056 7.028818) (xy 324.924032 7.108777) (xy 324.962254 7.185537)
			(xy 325.007395 7.258443) (xy 325.059071 7.326872) (xy 325.11684 7.390242) (xy 325.18021 7.448011)
			(xy 325.248639 7.499687) (xy 325.321545 7.544828) (xy 325.398305 7.58305) (xy 325.478264 7.614026)
			(xy 325.56074 7.637493) (xy 325.64503 7.653249) (xy 325.730413 7.661161) (xy 325.816163 7.661161)
			(xy 325.901546 7.653249) (xy 325.985836 7.637493) (xy 326.068312 7.614026) (xy 326.148271 7.58305)
			(xy 326.170474 7.571994) (xy 327.352152 7.571994) (xy 327.352152 8.435594) (xy 327.352638 8.462863)
			(xy 327.3604 8.516847) (xy 327.375765 8.569177) (xy 327.398422 8.618787) (xy 327.427908 8.664668)
			(xy 327.463623 8.705885) (xy 327.50484 8.7416) (xy 327.550721 8.771086) (xy 327.600331 8.793743)
			(xy 327.652661 8.809108) (xy 327.706645 8.81687) (xy 327.761183 8.81687) (xy 327.815167 8.809108)
			(xy 327.867497 8.793743) (xy 327.917107 8.771086) (xy 327.962988 8.7416) (xy 328.004205 8.705885)
			(xy 328.03992 8.664668) (xy 328.069406 8.618787) (xy 328.092063 8.569177) (xy 328.107428 8.516847)
			(xy 328.11519 8.462863) (xy 328.115676 8.435594) (xy 328.115676 7.571994) (xy 328.11519 7.544725)
			(xy 328.107428 7.490741) (xy 328.092063 7.438411) (xy 328.069406 7.388801) (xy 328.03992 7.34292)
			(xy 328.004205 7.301703) (xy 327.962988 7.265988) (xy 327.917107 7.236502) (xy 327.867497 7.213845)
			(xy 327.815167 7.19848) (xy 327.761183 7.190718) (xy 327.706645 7.190718) (xy 327.652661 7.19848)
			(xy 327.600331 7.213845) (xy 327.550721 7.236502) (xy 327.50484 7.265988) (xy 327.463623 7.301703)
			(xy 327.427908 7.34292) (xy 327.398422 7.388801) (xy 327.375765 7.438411) (xy 327.3604 7.490741)
			(xy 327.352638 7.544725) (xy 327.352152 7.571994) (xy 326.170474 7.571994) (xy 326.225031 7.544828)
			(xy 326.297937 7.499687) (xy 326.366366 7.448011) (xy 326.429736 7.390242) (xy 326.487505 7.326872)
			(xy 326.539181 7.258443) (xy 326.584322 7.185537) (xy 326.622544 7.108777) (xy 326.65352 7.028818)
			(xy 326.676987 6.946342) (xy 326.692743 6.862052) (xy 326.700655 6.776669) (xy 326.70115 6.733794)
			(xy 326.700655 6.690919) (xy 331.195921 6.690919) (xy 331.195921 6.776669) (xy 331.203833 6.862052)
			(xy 331.219589 6.946342) (xy 331.243056 7.028818) (xy 331.274032 7.108777) (xy 331.312254 7.185537)
			(xy 331.357395 7.258443) (xy 331.409071 7.326872) (xy 331.46684 7.390242) (xy 331.53021 7.448011)
			(xy 331.598639 7.499687) (xy 331.671545 7.544828) (xy 331.748305 7.58305) (xy 331.828264 7.614026)
			(xy 331.91074 7.637493) (xy 331.99503 7.653249) (xy 332.080413 7.661161) (xy 332.166163 7.661161)
			(xy 332.251546 7.653249) (xy 332.335836 7.637493) (xy 332.418312 7.614026) (xy 332.498271 7.58305)
			(xy 332.575031 7.544828) (xy 332.647937 7.499687) (xy 332.716366 7.448011) (xy 332.779736 7.390242)
			(xy 332.837505 7.326872) (xy 332.889181 7.258443) (xy 332.934322 7.185537) (xy 332.972544 7.108777)
			(xy 333.00352 7.028818) (xy 333.026987 6.946342) (xy 333.042743 6.862052) (xy 333.050655 6.776669)
			(xy 333.05115 6.733794) (xy 333.050655 6.690919) (xy 335.488267 6.690919) (xy 335.488267 6.776669)
			(xy 335.496179 6.862052) (xy 335.511935 6.946342) (xy 335.535402 7.028818) (xy 335.566378 7.108777)
			(xy 335.6046 7.185537) (xy 335.649741 7.258443) (xy 335.701417 7.326872) (xy 335.759186 7.390242)
			(xy 335.822556 7.448011) (xy 335.890985 7.499687) (xy 335.963891 7.544828) (xy 336.040651 7.58305)
			(xy 336.12061 7.614026) (xy 336.203086 7.637493) (xy 336.287376 7.653249) (xy 336.372759 7.661161)
			(xy 336.458509 7.661161) (xy 336.543892 7.653249) (xy 336.628182 7.637493) (xy 336.710658 7.614026)
			(xy 336.790617 7.58305) (xy 336.81282 7.571994) (xy 340.4235 7.571994) (xy 340.4235 8.435594) (xy 340.423986 8.462845)
			(xy 340.431742 8.516793) (xy 340.447097 8.569088) (xy 340.469739 8.618665) (xy 340.499205 8.664515)
			(xy 340.534896 8.705706) (xy 340.576087 8.741397) (xy 340.621937 8.770863) (xy 340.671514 8.793505)
			(xy 340.723809 8.80886) (xy 340.777757 8.816616) (xy 340.832259 8.816616) (xy 340.886207 8.80886)
			(xy 340.938502 8.793505) (xy 340.988079 8.770863) (xy 341.033929 8.741397) (xy 341.07512 8.705706)
			(xy 341.110811 8.664515) (xy 341.140277 8.618665) (xy 341.162919 8.569088) (xy 341.178274 8.516793)
			(xy 341.18603 8.462845) (xy 341.186516 8.435594) (xy 341.186516 7.571994) (xy 341.18603 7.544743)
			(xy 341.178274 7.490795) (xy 341.162919 7.4385) (xy 341.140277 7.388923) (xy 341.110811 7.343073)
			(xy 341.07512 7.301882) (xy 341.033929 7.266191) (xy 340.988079 7.236725) (xy 340.938502 7.214083)
			(xy 340.886207 7.198728) (xy 340.832259 7.190972) (xy 340.777757 7.190972) (xy 340.723809 7.198728)
			(xy 340.671514 7.214083) (xy 340.621937 7.236725) (xy 340.576087 7.266191) (xy 340.534896 7.301882)
			(xy 340.499205 7.343073) (xy 340.469739 7.388923) (xy 340.447097 7.4385) (xy 340.431742 7.490795)
			(xy 340.423986 7.544743) (xy 340.4235 7.571994) (xy 336.81282 7.571994) (xy 336.867377 7.544828)
			(xy 336.940283 7.499687) (xy 337.008712 7.448011) (xy 337.072082 7.390242) (xy 337.129851 7.326872)
			(xy 337.181527 7.258443) (xy 337.226668 7.185537) (xy 337.26489 7.108777) (xy 337.295866 7.028818)
			(xy 337.319333 6.946342) (xy 337.335089 6.862052) (xy 337.343001 6.776669) (xy 337.343496 6.733794)
			(xy 337.343001 6.690919) (xy 341.838267 6.690919) (xy 341.838267 6.776669) (xy 341.846179 6.862052)
			(xy 341.861935 6.946342) (xy 341.885402 7.028818) (xy 341.916378 7.108777) (xy 341.9546 7.185537)
			(xy 341.999741 7.258443) (xy 342.051417 7.326872) (xy 342.109186 7.390242) (xy 342.172556 7.448011)
			(xy 342.240985 7.499687) (xy 342.313891 7.544828) (xy 342.390651 7.58305) (xy 342.47061 7.614026)
			(xy 342.553086 7.637493) (xy 342.637376 7.653249) (xy 342.722759 7.661161) (xy 342.808509 7.661161)
			(xy 342.893892 7.653249) (xy 342.978182 7.637493) (xy 343.060658 7.614026) (xy 343.140617 7.58305)
			(xy 343.217377 7.544828) (xy 343.290283 7.499687) (xy 343.358712 7.448011) (xy 343.422082 7.390242)
			(xy 343.479851 7.326872) (xy 343.531527 7.258443) (xy 343.576668 7.185537) (xy 343.61489 7.108777)
			(xy 343.645866 7.028818) (xy 343.669333 6.946342) (xy 343.685089 6.862052) (xy 343.693001 6.776669)
			(xy 343.693496 6.733794) (xy 343.693001 6.690919) (xy 373.705107 6.690919) (xy 373.705107 6.776669)
			(xy 373.713019 6.862052) (xy 373.728775 6.946342) (xy 373.752242 7.028818) (xy 373.783218 7.108777)
			(xy 373.82144 7.185537) (xy 373.866581 7.258443) (xy 373.918257 7.326872) (xy 373.976026 7.390242)
			(xy 374.039396 7.448011) (xy 374.107825 7.499687) (xy 374.180731 7.544828) (xy 374.257491 7.58305)
			(xy 374.33745 7.614026) (xy 374.419926 7.637493) (xy 374.504216 7.653249) (xy 374.589599 7.661161)
			(xy 374.675349 7.661161) (xy 374.760732 7.653249) (xy 374.845022 7.637493) (xy 374.927498 7.614026)
			(xy 375.007457 7.58305) (xy 375.02966 7.571994) (xy 376.211592 7.571994) (xy 376.211592 8.435594)
			(xy 376.212078 8.462845) (xy 376.219834 8.516793) (xy 376.235189 8.569088) (xy 376.257831 8.618665)
			(xy 376.287297 8.664515) (xy 376.322988 8.705706) (xy 376.364179 8.741397) (xy 376.410029 8.770863)
			(xy 376.459606 8.793505) (xy 376.511901 8.80886) (xy 376.565849 8.816616) (xy 376.620351 8.816616)
			(xy 376.674299 8.80886) (xy 376.726594 8.793505) (xy 376.776171 8.770863) (xy 376.822021 8.741397)
			(xy 376.863212 8.705706) (xy 376.898903 8.664515) (xy 376.928369 8.618665) (xy 376.951011 8.569088)
			(xy 376.966366 8.516793) (xy 376.974122 8.462845) (xy 376.974608 8.435594) (xy 376.974608 7.571994)
			(xy 376.974122 7.544743) (xy 376.966366 7.490795) (xy 376.951011 7.4385) (xy 376.928369 7.388923)
			(xy 376.898903 7.343073) (xy 376.863212 7.301882) (xy 376.822021 7.266191) (xy 376.776171 7.236725)
			(xy 376.726594 7.214083) (xy 376.674299 7.198728) (xy 376.620351 7.190972) (xy 376.565849 7.190972)
			(xy 376.511901 7.198728) (xy 376.459606 7.214083) (xy 376.410029 7.236725) (xy 376.364179 7.266191)
			(xy 376.322988 7.301882) (xy 376.287297 7.343073) (xy 376.257831 7.388923) (xy 376.235189 7.4385)
			(xy 376.219834 7.490795) (xy 376.212078 7.544743) (xy 376.211592 7.571994) (xy 375.02966 7.571994)
			(xy 375.084217 7.544828) (xy 375.157123 7.499687) (xy 375.225552 7.448011) (xy 375.288922 7.390242)
			(xy 375.346691 7.326872) (xy 375.398367 7.258443) (xy 375.443508 7.185537) (xy 375.48173 7.108777)
			(xy 375.512706 7.028818) (xy 375.536173 6.946342) (xy 375.551929 6.862052) (xy 375.559841 6.776669)
			(xy 375.560336 6.733794) (xy 375.559841 6.690919) (xy 380.055107 6.690919) (xy 380.055107 6.776669)
			(xy 380.063019 6.862052) (xy 380.078775 6.946342) (xy 380.102242 7.028818) (xy 380.133218 7.108777)
			(xy 380.17144 7.185537) (xy 380.216581 7.258443) (xy 380.268257 7.326872) (xy 380.326026 7.390242)
			(xy 380.389396 7.448011) (xy 380.457825 7.499687) (xy 380.530731 7.544828) (xy 380.607491 7.58305)
			(xy 380.68745 7.614026) (xy 380.769926 7.637493) (xy 380.854216 7.653249) (xy 380.939599 7.661161)
			(xy 381.025349 7.661161) (xy 381.110732 7.653249) (xy 381.195022 7.637493) (xy 381.277498 7.614026)
			(xy 381.357457 7.58305) (xy 381.434217 7.544828) (xy 381.507123 7.499687) (xy 381.575552 7.448011)
			(xy 381.638922 7.390242) (xy 381.688857 7.335466) (xy 464.704165 7.335466) (xy 464.704165 7.464606)
			(xy 464.712115 7.593501) (xy 464.727985 7.721661) (xy 464.751714 7.848602) (xy 464.783213 7.973841)
			(xy 464.822362 8.096904) (xy 464.869013 8.217323) (xy 464.922988 8.334642) (xy 464.984083 8.448416)
			(xy 465.052066 8.558213) (xy 465.12668 8.663616) (xy 465.207641 8.764226) (xy 465.294641 8.859661)
			(xy 465.387352 8.94956) (xy 465.485422 9.033581) (xy 465.588477 9.111405) (xy 465.696128 9.182737)
			(xy 465.807967 9.247307) (xy 465.923568 9.304869) (xy 466.042493 9.355206) (xy 466.164292 9.398126)
			(xy 466.288502 9.433467) (xy 466.414651 9.461094) (xy 466.542263 9.480903) (xy 466.670852 9.492819)
			(xy 466.79993 9.496796) (xy 466.929008 9.492819) (xy 467.057597 9.480903) (xy 467.185209 9.461094)
			(xy 467.311358 9.433467) (xy 467.435568 9.398126) (xy 467.557367 9.355206) (xy 467.676292 9.304869)
			(xy 467.791893 9.247307) (xy 467.903732 9.182737) (xy 468.011383 9.111405) (xy 468.114438 9.033581)
			(xy 468.212508 8.94956) (xy 468.305219 8.859661) (xy 468.392219 8.764226) (xy 468.47318 8.663616)
			(xy 468.547794 8.558213) (xy 468.615777 8.448416) (xy 468.676872 8.334642) (xy 468.730847 8.217323)
			(xy 468.777498 8.096904) (xy 468.816647 7.973841) (xy 468.848146 7.848602) (xy 468.871875 7.721661)
			(xy 468.887745 7.593501) (xy 468.895695 7.464606) (xy 468.896192 7.400036) (xy 468.895695 7.335466)
			(xy 468.887745 7.206571) (xy 468.871875 7.078411) (xy 468.848146 6.95147) (xy 468.816647 6.826231)
			(xy 468.777498 6.703168) (xy 468.730847 6.582749) (xy 468.676872 6.46543) (xy 468.615777 6.351656)
			(xy 468.547794 6.241859) (xy 468.47318 6.136456) (xy 468.392219 6.035846) (xy 468.305219 5.940411)
			(xy 468.212508 5.850512) (xy 468.114438 5.766491) (xy 468.011383 5.688667) (xy 467.903732 5.617335)
			(xy 467.791893 5.552765) (xy 467.676292 5.495203) (xy 467.557367 5.444866) (xy 467.435568 5.401946)
			(xy 467.311358 5.366605) (xy 467.185209 5.338978) (xy 467.057597 5.319169) (xy 466.929008 5.307253)
			(xy 466.79993 5.303277) (xy 466.670852 5.307253) (xy 466.542263 5.319169) (xy 466.414651 5.338978)
			(xy 466.288502 5.366605) (xy 466.164292 5.401946) (xy 466.042493 5.444866) (xy 465.923568 5.495203)
			(xy 465.807967 5.552765) (xy 465.696128 5.617335) (xy 465.588477 5.688667) (xy 465.485422 5.766491)
			(xy 465.387352 5.850512) (xy 465.294641 5.940411) (xy 465.207641 6.035846) (xy 465.12668 6.136456)
			(xy 465.052066 6.241859) (xy 464.984083 6.351656) (xy 464.922988 6.46543) (xy 464.869013 6.582749)
			(xy 464.822362 6.703168) (xy 464.783213 6.826231) (xy 464.751714 6.95147) (xy 464.727985 7.078411)
			(xy 464.712115 7.206571) (xy 464.704165 7.335466) (xy 381.688857 7.335466) (xy 381.696691 7.326872)
			(xy 381.748367 7.258443) (xy 381.793508 7.185537) (xy 381.83173 7.108777) (xy 381.862706 7.028818)
			(xy 381.886173 6.946342) (xy 381.901929 6.862052) (xy 381.909841 6.776669) (xy 381.910336 6.733794)
			(xy 381.909841 6.690919) (xy 381.901929 6.605536) (xy 381.886173 6.521246) (xy 381.862706 6.43877)
			(xy 381.83173 6.358811) (xy 381.793508 6.282051) (xy 381.748367 6.209145) (xy 381.696691 6.140716)
			(xy 381.638922 6.077346) (xy 381.575552 6.019577) (xy 381.507123 5.967901) (xy 381.434217 5.92276)
			(xy 381.357457 5.884538) (xy 381.277498 5.853562) (xy 381.195022 5.830095) (xy 381.110732 5.814339)
			(xy 381.025349 5.806427) (xy 380.939599 5.806427) (xy 380.854216 5.814339) (xy 380.769926 5.830095)
			(xy 380.68745 5.853562) (xy 380.607491 5.884538) (xy 380.530731 5.92276) (xy 380.457825 5.967901)
			(xy 380.389396 6.019577) (xy 380.326026 6.077346) (xy 380.268257 6.140716) (xy 380.216581 6.209145)
			(xy 380.17144 6.282051) (xy 380.133218 6.358811) (xy 380.102242 6.43877) (xy 380.078775 6.521246)
			(xy 380.063019 6.605536) (xy 380.055107 6.690919) (xy 375.559841 6.690919) (xy 375.551929 6.605536)
			(xy 375.536173 6.521246) (xy 375.512706 6.43877) (xy 375.48173 6.358811) (xy 375.443508 6.282051)
			(xy 375.398367 6.209145) (xy 375.346691 6.140716) (xy 375.288922 6.077346) (xy 375.225552 6.019577)
			(xy 375.157123 5.967901) (xy 375.084217 5.92276) (xy 375.007457 5.884538) (xy 374.927498 5.853562)
			(xy 374.845022 5.830095) (xy 374.760732 5.814339) (xy 374.675349 5.806427) (xy 374.589599 5.806427)
			(xy 374.504216 5.814339) (xy 374.419926 5.830095) (xy 374.33745 5.853562) (xy 374.257491 5.884538)
			(xy 374.180731 5.92276) (xy 374.107825 5.967901) (xy 374.039396 6.019577) (xy 373.976026 6.077346)
			(xy 373.918257 6.140716) (xy 373.866581 6.209145) (xy 373.82144 6.282051) (xy 373.783218 6.358811)
			(xy 373.752242 6.43877) (xy 373.728775 6.521246) (xy 373.713019 6.605536) (xy 373.705107 6.690919)
			(xy 343.693001 6.690919) (xy 343.685089 6.605536) (xy 343.669333 6.521246) (xy 343.645866 6.43877)
			(xy 343.61489 6.358811) (xy 343.576668 6.282051) (xy 343.531527 6.209145) (xy 343.479851 6.140716)
			(xy 343.422082 6.077346) (xy 343.358712 6.019577) (xy 343.290283 5.967901) (xy 343.217377 5.92276)
			(xy 343.140617 5.884538) (xy 343.060658 5.853562) (xy 342.978182 5.830095) (xy 342.893892 5.814339)
			(xy 342.808509 5.806427) (xy 342.722759 5.806427) (xy 342.637376 5.814339) (xy 342.553086 5.830095)
			(xy 342.47061 5.853562) (xy 342.390651 5.884538) (xy 342.313891 5.92276) (xy 342.240985 5.967901)
			(xy 342.172556 6.019577) (xy 342.109186 6.077346) (xy 342.051417 6.140716) (xy 341.999741 6.209145)
			(xy 341.9546 6.282051) (xy 341.916378 6.358811) (xy 341.885402 6.43877) (xy 341.861935 6.521246)
			(xy 341.846179 6.605536) (xy 341.838267 6.690919) (xy 337.343001 6.690919) (xy 337.335089 6.605536)
			(xy 337.319333 6.521246) (xy 337.295866 6.43877) (xy 337.26489 6.358811) (xy 337.226668 6.282051)
			(xy 337.181527 6.209145) (xy 337.129851 6.140716) (xy 337.072082 6.077346) (xy 337.008712 6.019577)
			(xy 336.940283 5.967901) (xy 336.867377 5.92276) (xy 336.790617 5.884538) (xy 336.710658 5.853562)
			(xy 336.628182 5.830095) (xy 336.543892 5.814339) (xy 336.458509 5.806427) (xy 336.372759 5.806427)
			(xy 336.287376 5.814339) (xy 336.203086 5.830095) (xy 336.12061 5.853562) (xy 336.040651 5.884538)
			(xy 335.963891 5.92276) (xy 335.890985 5.967901) (xy 335.822556 6.019577) (xy 335.759186 6.077346)
			(xy 335.701417 6.140716) (xy 335.649741 6.209145) (xy 335.6046 6.282051) (xy 335.566378 6.358811)
			(xy 335.535402 6.43877) (xy 335.511935 6.521246) (xy 335.496179 6.605536) (xy 335.488267 6.690919)
			(xy 333.050655 6.690919) (xy 333.042743 6.605536) (xy 333.026987 6.521246) (xy 333.00352 6.43877)
			(xy 332.972544 6.358811) (xy 332.934322 6.282051) (xy 332.889181 6.209145) (xy 332.837505 6.140716)
			(xy 332.779736 6.077346) (xy 332.716366 6.019577) (xy 332.647937 5.967901) (xy 332.575031 5.92276)
			(xy 332.498271 5.884538) (xy 332.418312 5.853562) (xy 332.335836 5.830095) (xy 332.251546 5.814339)
			(xy 332.166163 5.806427) (xy 332.080413 5.806427) (xy 331.99503 5.814339) (xy 331.91074 5.830095)
			(xy 331.828264 5.853562) (xy 331.748305 5.884538) (xy 331.671545 5.92276) (xy 331.598639 5.967901)
			(xy 331.53021 6.019577) (xy 331.46684 6.077346) (xy 331.409071 6.140716) (xy 331.357395 6.209145)
			(xy 331.312254 6.282051) (xy 331.274032 6.358811) (xy 331.243056 6.43877) (xy 331.219589 6.521246)
			(xy 331.203833 6.605536) (xy 331.195921 6.690919) (xy 326.700655 6.690919) (xy 326.692743 6.605536)
			(xy 326.676987 6.521246) (xy 326.65352 6.43877) (xy 326.622544 6.358811) (xy 326.584322 6.282051)
			(xy 326.539181 6.209145) (xy 326.487505 6.140716) (xy 326.429736 6.077346) (xy 326.366366 6.019577)
			(xy 326.297937 5.967901) (xy 326.225031 5.92276) (xy 326.148271 5.884538) (xy 326.068312 5.853562)
			(xy 325.985836 5.830095) (xy 325.901546 5.814339) (xy 325.816163 5.806427) (xy 325.730413 5.806427)
			(xy 325.64503 5.814339) (xy 325.56074 5.830095) (xy 325.478264 5.853562) (xy 325.398305 5.884538)
			(xy 325.321545 5.92276) (xy 325.248639 5.967901) (xy 325.18021 6.019577) (xy 325.11684 6.077346)
			(xy 325.059071 6.140716) (xy 325.007395 6.209145) (xy 324.962254 6.282051) (xy 324.924032 6.358811)
			(xy 324.893056 6.43877) (xy 324.869589 6.521246) (xy 324.853833 6.605536) (xy 324.845921 6.690919)
			(xy 265.125975 6.690919) (xy 265.118063 6.605536) (xy 265.102307 6.521246) (xy 265.07884 6.43877)
			(xy 265.047864 6.358811) (xy 265.009642 6.282051) (xy 264.964501 6.209145) (xy 264.912825 6.140716)
			(xy 264.855056 6.077346) (xy 264.791686 6.019577) (xy 264.723257 5.967901) (xy 264.650351 5.92276)
			(xy 264.573591 5.884538) (xy 264.493632 5.853562) (xy 264.411156 5.830095) (xy 264.326866 5.814339)
			(xy 264.241483 5.806427) (xy 264.155733 5.806427) (xy 264.07035 5.814339) (xy 263.98606 5.830095)
			(xy 263.903584 5.853562) (xy 263.823625 5.884538) (xy 263.746865 5.92276) (xy 263.673959 5.967901)
			(xy 263.60553 6.019577) (xy 263.54216 6.077346) (xy 263.484391 6.140716) (xy 263.432715 6.209145)
			(xy 263.387574 6.282051) (xy 263.349352 6.358811) (xy 263.318376 6.43877) (xy 263.294909 6.521246)
			(xy 263.279153 6.605536) (xy 263.271241 6.690919) (xy 258.775975 6.690919) (xy 258.768063 6.605536)
			(xy 258.752307 6.521246) (xy 258.72884 6.43877) (xy 258.697864 6.358811) (xy 258.659642 6.282051)
			(xy 258.614501 6.209145) (xy 258.562825 6.140716) (xy 258.505056 6.077346) (xy 258.441686 6.019577)
			(xy 258.373257 5.967901) (xy 258.300351 5.92276) (xy 258.223591 5.884538) (xy 258.143632 5.853562)
			(xy 258.061156 5.830095) (xy 257.976866 5.814339) (xy 257.891483 5.806427) (xy 257.805733 5.806427)
			(xy 257.72035 5.814339) (xy 257.63606 5.830095) (xy 257.553584 5.853562) (xy 257.473625 5.884538)
			(xy 257.396865 5.92276) (xy 257.323959 5.967901) (xy 257.25553 6.019577) (xy 257.19216 6.077346)
			(xy 257.134391 6.140716) (xy 257.082715 6.209145) (xy 257.037574 6.282051) (xy 256.999352 6.358811)
			(xy 256.968376 6.43877) (xy 256.944909 6.521246) (xy 256.929153 6.605536) (xy 256.921241 6.690919)
			(xy 254.465119 6.690919) (xy 254.465087 6.688125) (xy 254.457175 6.602742) (xy 254.441419 6.518452)
			(xy 254.417952 6.435976) (xy 254.386976 6.356017) (xy 254.348754 6.279257) (xy 254.303613 6.206351)
			(xy 254.251937 6.137922) (xy 254.194168 6.074552) (xy 254.130798 6.016783) (xy 254.062369 5.965107)
			(xy 253.989463 5.919966) (xy 253.912703 5.881744) (xy 253.832744 5.850768) (xy 253.750268 5.827301)
			(xy 253.665978 5.811545) (xy 253.580595 5.803633) (xy 253.494845 5.803633) (xy 253.409462 5.811545)
			(xy 253.325172 5.827301) (xy 253.242696 5.850768) (xy 253.162737 5.881744) (xy 253.085977 5.919966)
			(xy 253.013071 5.965107) (xy 252.944642 6.016783) (xy 252.881272 6.074552) (xy 252.823503 6.137922)
			(xy 252.771827 6.206351) (xy 252.726686 6.279257) (xy 252.688464 6.356017) (xy 252.657488 6.435976)
			(xy 252.634021 6.518452) (xy 252.618265 6.602742) (xy 252.610353 6.688125) (xy 248.115087 6.688125)
			(xy 248.107175 6.602742) (xy 248.091419 6.518452) (xy 248.067952 6.435976) (xy 248.036976 6.356017)
			(xy 247.998754 6.279257) (xy 247.953613 6.206351) (xy 247.901937 6.137922) (xy 247.844168 6.074552)
			(xy 247.780798 6.016783) (xy 247.712369 5.965107) (xy 247.639463 5.919966) (xy 247.562703 5.881744)
			(xy 247.482744 5.850768) (xy 247.400268 5.827301) (xy 247.315978 5.811545) (xy 247.230595 5.803633)
			(xy 247.144845 5.803633) (xy 247.059462 5.811545) (xy 246.975172 5.827301) (xy 246.892696 5.850768)
			(xy 246.812737 5.881744) (xy 246.735977 5.919966) (xy 246.663071 5.965107) (xy 246.594642 6.016783)
			(xy 246.531272 6.074552) (xy 246.473503 6.137922) (xy 246.421827 6.206351) (xy 246.376686 6.279257)
			(xy 246.338464 6.356017) (xy 246.307488 6.435976) (xy 246.284021 6.518452) (xy 246.268265 6.602742)
			(xy 246.260353 6.688125) (xy 186.540407 6.688125) (xy 186.532495 6.602742) (xy 186.516739 6.518452)
			(xy 186.493272 6.435976) (xy 186.462296 6.356017) (xy 186.424074 6.279257) (xy 186.378933 6.206351)
			(xy 186.327257 6.137922) (xy 186.269488 6.074552) (xy 186.206118 6.016783) (xy 186.137689 5.965107)
			(xy 186.064783 5.919966) (xy 185.988023 5.881744) (xy 185.908064 5.850768) (xy 185.825588 5.827301)
			(xy 185.741298 5.811545) (xy 185.655915 5.803633) (xy 185.570165 5.803633) (xy 185.484782 5.811545)
			(xy 185.400492 5.827301) (xy 185.318016 5.850768) (xy 185.238057 5.881744) (xy 185.161297 5.919966)
			(xy 185.088391 5.965107) (xy 185.019962 6.016783) (xy 184.956592 6.074552) (xy 184.898823 6.137922)
			(xy 184.847147 6.206351) (xy 184.802006 6.279257) (xy 184.763784 6.356017) (xy 184.732808 6.435976)
			(xy 184.709341 6.518452) (xy 184.693585 6.602742) (xy 184.685673 6.688125) (xy 180.190407 6.688125)
			(xy 180.182495 6.602742) (xy 180.166739 6.518452) (xy 180.143272 6.435976) (xy 180.112296 6.356017)
			(xy 180.074074 6.279257) (xy 180.028933 6.206351) (xy 179.977257 6.137922) (xy 179.919488 6.074552)
			(xy 179.856118 6.016783) (xy 179.787689 5.965107) (xy 179.714783 5.919966) (xy 179.638023 5.881744)
			(xy 179.558064 5.850768) (xy 179.475588 5.827301) (xy 179.391298 5.811545) (xy 179.305915 5.803633)
			(xy 179.220165 5.803633) (xy 179.134782 5.811545) (xy 179.050492 5.827301) (xy 178.968016 5.850768)
			(xy 178.888057 5.881744) (xy 178.811297 5.919966) (xy 178.738391 5.965107) (xy 178.669962 6.016783)
			(xy 178.606592 6.074552) (xy 178.548823 6.137922) (xy 178.497147 6.206351) (xy 178.452006 6.279257)
			(xy 178.413784 6.356017) (xy 178.382808 6.435976) (xy 178.359341 6.518452) (xy 178.343585 6.602742)
			(xy 178.335673 6.688125) (xy 6.97173 6.688125) (xy 6.930907 6.582749) (xy 6.876932 6.46543) (xy 6.815837 6.351656)
			(xy 6.747854 6.241859) (xy 6.67324 6.136456) (xy 6.592279 6.035846) (xy 6.505279 5.940411) (xy 6.412568 5.850512)
			(xy 6.314498 5.766491) (xy 6.211443 5.688667) (xy 6.103792 5.617335) (xy 5.991953 5.552765) (xy 5.876352 5.495203)
			(xy 5.757427 5.444866) (xy 5.635628 5.401946) (xy 5.511418 5.366605) (xy 5.385269 5.338978) (xy 5.257657 5.319169)
			(xy 5.129068 5.307253) (xy 4.99999 5.303277) (xy 4.870912 5.307253) (xy 4.742323 5.319169) (xy 4.614711 5.338978)
			(xy 4.488562 5.366605) (xy 4.364352 5.401946) (xy 4.242553 5.444866) (xy 4.123628 5.495203) (xy 4.008027 5.552765)
			(xy 3.896188 5.617335) (xy 3.788537 5.688667) (xy 3.685482 5.766491) (xy 3.587412 5.850512) (xy 3.494701 5.940411)
			(xy 3.407701 6.035846) (xy 3.32674 6.136456) (xy 3.252126 6.241859) (xy 3.184143 6.351656) (xy 3.123048 6.46543)
			(xy 3.069073 6.582749) (xy 3.022422 6.703168) (xy 2.983273 6.826231) (xy 2.951774 6.95147) (xy 2.928045 7.078411)
			(xy 2.912175 7.206571) (xy 2.904225 7.335466) (xy 0.508 7.335466) (xy 0.508 4.148125) (xy 178.335673 4.148125)
			(xy 178.335673 4.233875) (xy 178.343585 4.319258) (xy 178.359341 4.403548) (xy 178.382808 4.486024)
			(xy 178.413784 4.565983) (xy 178.452006 4.642743) (xy 178.497147 4.715649) (xy 178.548823 4.784078)
			(xy 178.606592 4.847448) (xy 178.669962 4.905217) (xy 178.738391 4.956893) (xy 178.811297 5.002034)
			(xy 178.888057 5.040256) (xy 178.968016 5.071232) (xy 179.050492 5.094699) (xy 179.134782 5.110455)
			(xy 179.220165 5.118367) (xy 179.305915 5.118367) (xy 179.391298 5.110455) (xy 179.475588 5.094699)
			(xy 179.558064 5.071232) (xy 179.638023 5.040256) (xy 179.660226 5.0292) (xy 183.270652 5.0292) (xy 183.270652 5.8928)
			(xy 183.271138 5.920069) (xy 183.2789 5.974053) (xy 183.294265 6.026383) (xy 183.316922 6.075993)
			(xy 183.346408 6.121874) (xy 183.382123 6.163091) (xy 183.42334 6.198806) (xy 183.469221 6.228292)
			(xy 183.518831 6.250949) (xy 183.571161 6.266314) (xy 183.625145 6.274076) (xy 183.679683 6.274076)
			(xy 183.733667 6.266314) (xy 183.785997 6.250949) (xy 183.835607 6.228292) (xy 183.881488 6.198806)
			(xy 183.922705 6.163091) (xy 183.95842 6.121874) (xy 183.987906 6.075993) (xy 184.010563 6.026383)
			(xy 184.025928 5.974053) (xy 184.03369 5.920069) (xy 184.034176 5.8928) (xy 184.034176 5.0292) (xy 184.03369 5.001931)
			(xy 184.025928 4.947947) (xy 184.010563 4.895617) (xy 183.987906 4.846007) (xy 183.95842 4.800126)
			(xy 183.922705 4.758909) (xy 183.881488 4.723194) (xy 183.835607 4.693708) (xy 183.785997 4.671051)
			(xy 183.733667 4.655686) (xy 183.679683 4.647924) (xy 183.625145 4.647924) (xy 183.571161 4.655686)
			(xy 183.518831 4.671051) (xy 183.469221 4.693708) (xy 183.42334 4.723194) (xy 183.382123 4.758909)
			(xy 183.346408 4.800126) (xy 183.316922 4.846007) (xy 183.294265 4.895617) (xy 183.2789 4.947947)
			(xy 183.271138 5.001931) (xy 183.270652 5.0292) (xy 179.660226 5.0292) (xy 179.714783 5.002034) (xy 179.787689 4.956893)
			(xy 179.856118 4.905217) (xy 179.919488 4.847448) (xy 179.977257 4.784078) (xy 180.028933 4.715649)
			(xy 180.074074 4.642743) (xy 180.112296 4.565983) (xy 180.143272 4.486024) (xy 180.166739 4.403548)
			(xy 180.182495 4.319258) (xy 180.190407 4.233875) (xy 180.190902 4.191) (xy 180.190407 4.148125)
			(xy 184.685673 4.148125) (xy 184.685673 4.233875) (xy 184.693585 4.319258) (xy 184.709341 4.403548)
			(xy 184.732808 4.486024) (xy 184.763784 4.565983) (xy 184.802006 4.642743) (xy 184.847147 4.715649)
			(xy 184.898823 4.784078) (xy 184.956592 4.847448) (xy 185.019962 4.905217) (xy 185.088391 4.956893)
			(xy 185.161297 5.002034) (xy 185.238057 5.040256) (xy 185.318016 5.071232) (xy 185.400492 5.094699)
			(xy 185.484782 5.110455) (xy 185.570165 5.118367) (xy 185.655915 5.118367) (xy 185.741298 5.110455)
			(xy 185.825588 5.094699) (xy 185.908064 5.071232) (xy 185.988023 5.040256) (xy 186.064783 5.002034)
			(xy 186.137689 4.956893) (xy 186.206118 4.905217) (xy 186.269488 4.847448) (xy 186.327257 4.784078)
			(xy 186.378933 4.715649) (xy 186.424074 4.642743) (xy 186.462296 4.565983) (xy 186.493272 4.486024)
			(xy 186.516739 4.403548) (xy 186.532495 4.319258) (xy 186.540407 4.233875) (xy 186.540902 4.191)
			(xy 186.540407 4.148125) (xy 246.260353 4.148125) (xy 246.260353 4.233875) (xy 246.268265 4.319258)
			(xy 246.284021 4.403548) (xy 246.307488 4.486024) (xy 246.338464 4.565983) (xy 246.376686 4.642743)
			(xy 246.421827 4.715649) (xy 246.473503 4.784078) (xy 246.531272 4.847448) (xy 246.594642 4.905217)
			(xy 246.663071 4.956893) (xy 246.735977 5.002034) (xy 246.812737 5.040256) (xy 246.892696 5.071232)
			(xy 246.975172 5.094699) (xy 247.059462 5.110455) (xy 247.144845 5.118367) (xy 247.230595 5.118367)
			(xy 247.315978 5.110455) (xy 247.400268 5.094699) (xy 247.482744 5.071232) (xy 247.562703 5.040256)
			(xy 247.584906 5.0292) (xy 248.766584 5.0292) (xy 248.766584 5.8928) (xy 248.76707 5.920069) (xy 248.774832 5.974053)
			(xy 248.790197 6.026383) (xy 248.812854 6.075993) (xy 248.84234 6.121874) (xy 248.878055 6.163091)
			(xy 248.919272 6.198806) (xy 248.965153 6.228292) (xy 249.014763 6.250949) (xy 249.067093 6.266314)
			(xy 249.121077 6.274076) (xy 249.175615 6.274076) (xy 249.229599 6.266314) (xy 249.281929 6.250949)
			(xy 249.331539 6.228292) (xy 249.37742 6.198806) (xy 249.418637 6.163091) (xy 249.454352 6.121874)
			(xy 249.483838 6.075993) (xy 249.506495 6.026383) (xy 249.52186 5.974053) (xy 249.529622 5.920069)
			(xy 249.530108 5.8928) (xy 249.530108 5.0292) (xy 249.529622 5.001931) (xy 249.52186 4.947947) (xy 249.506495 4.895617)
			(xy 249.483838 4.846007) (xy 249.454352 4.800126) (xy 249.418637 4.758909) (xy 249.37742 4.723194)
			(xy 249.331539 4.693708) (xy 249.281929 4.671051) (xy 249.229599 4.655686) (xy 249.175615 4.647924)
			(xy 249.121077 4.647924) (xy 249.067093 4.655686) (xy 249.014763 4.671051) (xy 248.965153 4.693708)
			(xy 248.919272 4.723194) (xy 248.878055 4.758909) (xy 248.84234 4.800126) (xy 248.812854 4.846007)
			(xy 248.790197 4.895617) (xy 248.774832 4.947947) (xy 248.76707 5.001931) (xy 248.766584 5.0292)
			(xy 247.584906 5.0292) (xy 247.639463 5.002034) (xy 247.712369 4.956893) (xy 247.780798 4.905217)
			(xy 247.844168 4.847448) (xy 247.901937 4.784078) (xy 247.953613 4.715649) (xy 247.998754 4.642743)
			(xy 248.036976 4.565983) (xy 248.067952 4.486024) (xy 248.091419 4.403548) (xy 248.107175 4.319258)
			(xy 248.115087 4.233875) (xy 248.115582 4.191) (xy 248.115087 4.148125) (xy 252.610353 4.148125)
			(xy 252.610353 4.233875) (xy 252.618265 4.319258) (xy 252.634021 4.403548) (xy 252.657488 4.486024)
			(xy 252.688464 4.565983) (xy 252.726686 4.642743) (xy 252.771827 4.715649) (xy 252.823503 4.784078)
			(xy 252.881272 4.847448) (xy 252.944642 4.905217) (xy 253.013071 4.956893) (xy 253.085977 5.002034)
			(xy 253.162737 5.040256) (xy 253.242696 5.071232) (xy 253.325172 5.094699) (xy 253.409462 5.110455)
			(xy 253.494845 5.118367) (xy 253.580595 5.118367) (xy 253.665978 5.110455) (xy 253.750268 5.094699)
			(xy 253.832744 5.071232) (xy 253.912703 5.040256) (xy 253.989463 5.002034) (xy 254.062369 4.956893)
			(xy 254.130798 4.905217) (xy 254.194168 4.847448) (xy 254.251937 4.784078) (xy 254.303613 4.715649)
			(xy 254.348754 4.642743) (xy 254.386976 4.565983) (xy 254.417952 4.486024) (xy 254.441419 4.403548)
			(xy 254.457175 4.319258) (xy 254.465087 4.233875) (xy 254.465582 4.191) (xy 254.465119 4.150919)
			(xy 256.921241 4.150919) (xy 256.921241 4.236669) (xy 256.929153 4.322052) (xy 256.944909 4.406342)
			(xy 256.968376 4.488818) (xy 256.999352 4.568777) (xy 257.037574 4.645537) (xy 257.082715 4.718443)
			(xy 257.134391 4.786872) (xy 257.19216 4.850242) (xy 257.25553 4.908011) (xy 257.323959 4.959687)
			(xy 257.396865 5.004828) (xy 257.473625 5.04305) (xy 257.553584 5.074026) (xy 257.63606 5.097493)
			(xy 257.72035 5.113249) (xy 257.805733 5.121161) (xy 257.891483 5.121161) (xy 257.976866 5.113249)
			(xy 258.061156 5.097493) (xy 258.143632 5.074026) (xy 258.223591 5.04305) (xy 258.245794 5.031994)
			(xy 261.85622 5.031994) (xy 261.85622 5.895594) (xy 261.856706 5.922863) (xy 261.864468 5.976847)
			(xy 261.879833 6.029177) (xy 261.90249 6.078787) (xy 261.931976 6.124668) (xy 261.967691 6.165885)
			(xy 262.008908 6.2016) (xy 262.054789 6.231086) (xy 262.104399 6.253743) (xy 262.156729 6.269108)
			(xy 262.210713 6.27687) (xy 262.265251 6.27687) (xy 262.319235 6.269108) (xy 262.371565 6.253743)
			(xy 262.421175 6.231086) (xy 262.467056 6.2016) (xy 262.508273 6.165885) (xy 262.543988 6.124668)
			(xy 262.573474 6.078787) (xy 262.596131 6.029177) (xy 262.611496 5.976847) (xy 262.619258 5.922863)
			(xy 262.619744 5.895594) (xy 262.619744 5.031994) (xy 262.619258 5.004725) (xy 262.611496 4.950741)
			(xy 262.596131 4.898411) (xy 262.573474 4.848801) (xy 262.543988 4.80292) (xy 262.508273 4.761703)
			(xy 262.467056 4.725988) (xy 262.421175 4.696502) (xy 262.371565 4.673845) (xy 262.319235 4.65848)
			(xy 262.265251 4.650718) (xy 262.210713 4.650718) (xy 262.156729 4.65848) (xy 262.104399 4.673845)
			(xy 262.054789 4.696502) (xy 262.008908 4.725988) (xy 261.967691 4.761703) (xy 261.931976 4.80292)
			(xy 261.90249 4.848801) (xy 261.879833 4.898411) (xy 261.864468 4.950741) (xy 261.856706 5.004725)
			(xy 261.85622 5.031994) (xy 258.245794 5.031994) (xy 258.300351 5.004828) (xy 258.373257 4.959687)
			(xy 258.441686 4.908011) (xy 258.505056 4.850242) (xy 258.562825 4.786872) (xy 258.614501 4.718443)
			(xy 258.659642 4.645537) (xy 258.697864 4.568777) (xy 258.72884 4.488818) (xy 258.752307 4.406342)
			(xy 258.768063 4.322052) (xy 258.775975 4.236669) (xy 258.77647 4.193794) (xy 258.775975 4.150919)
			(xy 263.271241 4.150919) (xy 263.271241 4.236669) (xy 263.279153 4.322052) (xy 263.294909 4.406342)
			(xy 263.318376 4.488818) (xy 263.349352 4.568777) (xy 263.387574 4.645537) (xy 263.432715 4.718443)
			(xy 263.484391 4.786872) (xy 263.54216 4.850242) (xy 263.60553 4.908011) (xy 263.673959 4.959687)
			(xy 263.746865 5.004828) (xy 263.823625 5.04305) (xy 263.903584 5.074026) (xy 263.98606 5.097493)
			(xy 264.07035 5.113249) (xy 264.155733 5.121161) (xy 264.241483 5.121161) (xy 264.326866 5.113249)
			(xy 264.411156 5.097493) (xy 264.493632 5.074026) (xy 264.573591 5.04305) (xy 264.650351 5.004828)
			(xy 264.723257 4.959687) (xy 264.791686 4.908011) (xy 264.855056 4.850242) (xy 264.912825 4.786872)
			(xy 264.964501 4.718443) (xy 265.009642 4.645537) (xy 265.047864 4.568777) (xy 265.07884 4.488818)
			(xy 265.102307 4.406342) (xy 265.118063 4.322052) (xy 265.125975 4.236669) (xy 265.12647 4.193794)
			(xy 265.125975 4.150919) (xy 324.845921 4.150919) (xy 324.845921 4.236669) (xy 324.853833 4.322052)
			(xy 324.869589 4.406342) (xy 324.893056 4.488818) (xy 324.924032 4.568777) (xy 324.962254 4.645537)
			(xy 325.007395 4.718443) (xy 325.059071 4.786872) (xy 325.11684 4.850242) (xy 325.18021 4.908011)
			(xy 325.248639 4.959687) (xy 325.321545 5.004828) (xy 325.398305 5.04305) (xy 325.478264 5.074026)
			(xy 325.56074 5.097493) (xy 325.64503 5.113249) (xy 325.730413 5.121161) (xy 325.816163 5.121161)
			(xy 325.901546 5.113249) (xy 325.985836 5.097493) (xy 326.068312 5.074026) (xy 326.148271 5.04305)
			(xy 326.170474 5.031994) (xy 327.352152 5.031994) (xy 327.352152 5.895594) (xy 327.352638 5.922863)
			(xy 327.3604 5.976847) (xy 327.375765 6.029177) (xy 327.398422 6.078787) (xy 327.427908 6.124668)
			(xy 327.463623 6.165885) (xy 327.50484 6.2016) (xy 327.550721 6.231086) (xy 327.600331 6.253743)
			(xy 327.652661 6.269108) (xy 327.706645 6.27687) (xy 327.761183 6.27687) (xy 327.815167 6.269108)
			(xy 327.867497 6.253743) (xy 327.917107 6.231086) (xy 327.962988 6.2016) (xy 328.004205 6.165885)
			(xy 328.03992 6.124668) (xy 328.069406 6.078787) (xy 328.092063 6.029177) (xy 328.107428 5.976847)
			(xy 328.11519 5.922863) (xy 328.115676 5.895594) (xy 328.115676 5.031994) (xy 328.11519 5.004725)
			(xy 328.107428 4.950741) (xy 328.092063 4.898411) (xy 328.069406 4.848801) (xy 328.03992 4.80292)
			(xy 328.004205 4.761703) (xy 327.962988 4.725988) (xy 327.917107 4.696502) (xy 327.867497 4.673845)
			(xy 327.815167 4.65848) (xy 327.761183 4.650718) (xy 327.706645 4.650718) (xy 327.652661 4.65848)
			(xy 327.600331 4.673845) (xy 327.550721 4.696502) (xy 327.50484 4.725988) (xy 327.463623 4.761703)
			(xy 327.427908 4.80292) (xy 327.398422 4.848801) (xy 327.375765 4.898411) (xy 327.3604 4.950741)
			(xy 327.352638 5.004725) (xy 327.352152 5.031994) (xy 326.170474 5.031994) (xy 326.225031 5.004828)
			(xy 326.297937 4.959687) (xy 326.366366 4.908011) (xy 326.429736 4.850242) (xy 326.487505 4.786872)
			(xy 326.539181 4.718443) (xy 326.584322 4.645537) (xy 326.622544 4.568777) (xy 326.65352 4.488818)
			(xy 326.676987 4.406342) (xy 326.692743 4.322052) (xy 326.700655 4.236669) (xy 326.70115 4.193794)
			(xy 326.700655 4.150919) (xy 331.195921 4.150919) (xy 331.195921 4.236669) (xy 331.203833 4.322052)
			(xy 331.219589 4.406342) (xy 331.243056 4.488818) (xy 331.274032 4.568777) (xy 331.312254 4.645537)
			(xy 331.357395 4.718443) (xy 331.409071 4.786872) (xy 331.46684 4.850242) (xy 331.53021 4.908011)
			(xy 331.598639 4.959687) (xy 331.671545 5.004828) (xy 331.748305 5.04305) (xy 331.828264 5.074026)
			(xy 331.91074 5.097493) (xy 331.99503 5.113249) (xy 332.080413 5.121161) (xy 332.166163 5.121161)
			(xy 332.251546 5.113249) (xy 332.335836 5.097493) (xy 332.418312 5.074026) (xy 332.498271 5.04305)
			(xy 332.575031 5.004828) (xy 332.647937 4.959687) (xy 332.716366 4.908011) (xy 332.779736 4.850242)
			(xy 332.837505 4.786872) (xy 332.889181 4.718443) (xy 332.934322 4.645537) (xy 332.972544 4.568777)
			(xy 333.00352 4.488818) (xy 333.026987 4.406342) (xy 333.042743 4.322052) (xy 333.050655 4.236669)
			(xy 333.05115 4.193794) (xy 333.050655 4.150919) (xy 335.488267 4.150919) (xy 335.488267 4.236669)
			(xy 335.496179 4.322052) (xy 335.511935 4.406342) (xy 335.535402 4.488818) (xy 335.566378 4.568777)
			(xy 335.6046 4.645537) (xy 335.649741 4.718443) (xy 335.701417 4.786872) (xy 335.759186 4.850242)
			(xy 335.822556 4.908011) (xy 335.890985 4.959687) (xy 335.963891 5.004828) (xy 336.040651 5.04305)
			(xy 336.12061 5.074026) (xy 336.203086 5.097493) (xy 336.287376 5.113249) (xy 336.372759 5.121161)
			(xy 336.458509 5.121161) (xy 336.543892 5.113249) (xy 336.628182 5.097493) (xy 336.710658 5.074026)
			(xy 336.790617 5.04305) (xy 336.81282 5.031994) (xy 340.4235 5.031994) (xy 340.4235 5.895594) (xy 340.423986 5.922845)
			(xy 340.431742 5.976793) (xy 340.447097 6.029088) (xy 340.469739 6.078665) (xy 340.499205 6.124515)
			(xy 340.534896 6.165706) (xy 340.576087 6.201397) (xy 340.621937 6.230863) (xy 340.671514 6.253505)
			(xy 340.723809 6.26886) (xy 340.777757 6.276616) (xy 340.832259 6.276616) (xy 340.886207 6.26886)
			(xy 340.938502 6.253505) (xy 340.988079 6.230863) (xy 341.033929 6.201397) (xy 341.07512 6.165706)
			(xy 341.110811 6.124515) (xy 341.140277 6.078665) (xy 341.162919 6.029088) (xy 341.178274 5.976793)
			(xy 341.18603 5.922845) (xy 341.186516 5.895594) (xy 341.186516 5.031994) (xy 341.18603 5.004743)
			(xy 341.178274 4.950795) (xy 341.162919 4.8985) (xy 341.140277 4.848923) (xy 341.110811 4.803073)
			(xy 341.07512 4.761882) (xy 341.033929 4.726191) (xy 340.988079 4.696725) (xy 340.938502 4.674083)
			(xy 340.886207 4.658728) (xy 340.832259 4.650972) (xy 340.777757 4.650972) (xy 340.723809 4.658728)
			(xy 340.671514 4.674083) (xy 340.621937 4.696725) (xy 340.576087 4.726191) (xy 340.534896 4.761882)
			(xy 340.499205 4.803073) (xy 340.469739 4.848923) (xy 340.447097 4.8985) (xy 340.431742 4.950795)
			(xy 340.423986 5.004743) (xy 340.4235 5.031994) (xy 336.81282 5.031994) (xy 336.867377 5.004828)
			(xy 336.940283 4.959687) (xy 337.008712 4.908011) (xy 337.072082 4.850242) (xy 337.129851 4.786872)
			(xy 337.181527 4.718443) (xy 337.226668 4.645537) (xy 337.26489 4.568777) (xy 337.295866 4.488818)
			(xy 337.319333 4.406342) (xy 337.335089 4.322052) (xy 337.343001 4.236669) (xy 337.343496 4.193794)
			(xy 337.343001 4.150919) (xy 341.838267 4.150919) (xy 341.838267 4.236669) (xy 341.846179 4.322052)
			(xy 341.861935 4.406342) (xy 341.885402 4.488818) (xy 341.916378 4.568777) (xy 341.9546 4.645537)
			(xy 341.999741 4.718443) (xy 342.051417 4.786872) (xy 342.109186 4.850242) (xy 342.172556 4.908011)
			(xy 342.240985 4.959687) (xy 342.313891 5.004828) (xy 342.390651 5.04305) (xy 342.47061 5.074026)
			(xy 342.553086 5.097493) (xy 342.637376 5.113249) (xy 342.722759 5.121161) (xy 342.808509 5.121161)
			(xy 342.893892 5.113249) (xy 342.978182 5.097493) (xy 343.060658 5.074026) (xy 343.140617 5.04305)
			(xy 343.217377 5.004828) (xy 343.290283 4.959687) (xy 343.358712 4.908011) (xy 343.422082 4.850242)
			(xy 343.479851 4.786872) (xy 343.531527 4.718443) (xy 343.576668 4.645537) (xy 343.61489 4.568777)
			(xy 343.645866 4.488818) (xy 343.669333 4.406342) (xy 343.685089 4.322052) (xy 343.693001 4.236669)
			(xy 343.693496 4.193794) (xy 343.693001 4.150919) (xy 373.705107 4.150919) (xy 373.705107 4.236669)
			(xy 373.713019 4.322052) (xy 373.728775 4.406342) (xy 373.752242 4.488818) (xy 373.783218 4.568777)
			(xy 373.82144 4.645537) (xy 373.866581 4.718443) (xy 373.918257 4.786872) (xy 373.976026 4.850242)
			(xy 374.039396 4.908011) (xy 374.107825 4.959687) (xy 374.180731 5.004828) (xy 374.257491 5.04305)
			(xy 374.33745 5.074026) (xy 374.419926 5.097493) (xy 374.504216 5.113249) (xy 374.589599 5.121161)
			(xy 374.675349 5.121161) (xy 374.760732 5.113249) (xy 374.845022 5.097493) (xy 374.927498 5.074026)
			(xy 375.007457 5.04305) (xy 375.02966 5.031994) (xy 376.211592 5.031994) (xy 376.211592 5.895594)
			(xy 376.212078 5.922845) (xy 376.219834 5.976793) (xy 376.235189 6.029088) (xy 376.257831 6.078665)
			(xy 376.287297 6.124515) (xy 376.322988 6.165706) (xy 376.364179 6.201397) (xy 376.410029 6.230863)
			(xy 376.459606 6.253505) (xy 376.511901 6.26886) (xy 376.565849 6.276616) (xy 376.620351 6.276616)
			(xy 376.674299 6.26886) (xy 376.726594 6.253505) (xy 376.776171 6.230863) (xy 376.822021 6.201397)
			(xy 376.863212 6.165706) (xy 376.898903 6.124515) (xy 376.928369 6.078665) (xy 376.951011 6.029088)
			(xy 376.966366 5.976793) (xy 376.974122 5.922845) (xy 376.974608 5.895594) (xy 376.974608 5.031994)
			(xy 376.974122 5.004743) (xy 376.966366 4.950795) (xy 376.951011 4.8985) (xy 376.928369 4.848923)
			(xy 376.898903 4.803073) (xy 376.863212 4.761882) (xy 376.822021 4.726191) (xy 376.776171 4.696725)
			(xy 376.726594 4.674083) (xy 376.674299 4.658728) (xy 376.620351 4.650972) (xy 376.565849 4.650972)
			(xy 376.511901 4.658728) (xy 376.459606 4.674083) (xy 376.410029 4.696725) (xy 376.364179 4.726191)
			(xy 376.322988 4.761882) (xy 376.287297 4.803073) (xy 376.257831 4.848923) (xy 376.235189 4.8985)
			(xy 376.219834 4.950795) (xy 376.212078 5.004743) (xy 376.211592 5.031994) (xy 375.02966 5.031994)
			(xy 375.084217 5.004828) (xy 375.157123 4.959687) (xy 375.225552 4.908011) (xy 375.288922 4.850242)
			(xy 375.346691 4.786872) (xy 375.398367 4.718443) (xy 375.443508 4.645537) (xy 375.48173 4.568777)
			(xy 375.512706 4.488818) (xy 375.536173 4.406342) (xy 375.551929 4.322052) (xy 375.559841 4.236669)
			(xy 375.560336 4.193794) (xy 375.559841 4.150919) (xy 380.055107 4.150919) (xy 380.055107 4.236669)
			(xy 380.063019 4.322052) (xy 380.078775 4.406342) (xy 380.102242 4.488818) (xy 380.133218 4.568777)
			(xy 380.17144 4.645537) (xy 380.216581 4.718443) (xy 380.268257 4.786872) (xy 380.326026 4.850242)
			(xy 380.389396 4.908011) (xy 380.457825 4.959687) (xy 380.530731 5.004828) (xy 380.607491 5.04305)
			(xy 380.68745 5.074026) (xy 380.769926 5.097493) (xy 380.854216 5.113249) (xy 380.939599 5.121161)
			(xy 381.025349 5.121161) (xy 381.110732 5.113249) (xy 381.195022 5.097493) (xy 381.277498 5.074026)
			(xy 381.357457 5.04305) (xy 381.434217 5.004828) (xy 381.507123 4.959687) (xy 381.575552 4.908011)
			(xy 381.638922 4.850242) (xy 381.696691 4.786872) (xy 381.748367 4.718443) (xy 381.793508 4.645537)
			(xy 381.83173 4.568777) (xy 381.862706 4.488818) (xy 381.886173 4.406342) (xy 381.901929 4.322052)
			(xy 381.909841 4.236669) (xy 381.910336 4.193794) (xy 381.909841 4.150919) (xy 381.901929 4.065536)
			(xy 381.886173 3.981246) (xy 381.862706 3.89877) (xy 381.83173 3.818811) (xy 381.793508 3.742051)
			(xy 381.748367 3.669145) (xy 381.696691 3.600716) (xy 381.638922 3.537346) (xy 381.575552 3.479577)
			(xy 381.507123 3.427901) (xy 381.434217 3.38276) (xy 381.357457 3.344538) (xy 381.277498 3.313562)
			(xy 381.195022 3.290095) (xy 381.110732 3.274339) (xy 381.025349 3.266427) (xy 380.939599 3.266427)
			(xy 380.854216 3.274339) (xy 380.769926 3.290095) (xy 380.68745 3.313562) (xy 380.607491 3.344538)
			(xy 380.530731 3.38276) (xy 380.457825 3.427901) (xy 380.389396 3.479577) (xy 380.326026 3.537346)
			(xy 380.268257 3.600716) (xy 380.216581 3.669145) (xy 380.17144 3.742051) (xy 380.133218 3.818811)
			(xy 380.102242 3.89877) (xy 380.078775 3.981246) (xy 380.063019 4.065536) (xy 380.055107 4.150919)
			(xy 375.559841 4.150919) (xy 375.551929 4.065536) (xy 375.536173 3.981246) (xy 375.512706 3.89877)
			(xy 375.48173 3.818811) (xy 375.443508 3.742051) (xy 375.398367 3.669145) (xy 375.346691 3.600716)
			(xy 375.288922 3.537346) (xy 375.225552 3.479577) (xy 375.157123 3.427901) (xy 375.084217 3.38276)
			(xy 375.007457 3.344538) (xy 374.927498 3.313562) (xy 374.845022 3.290095) (xy 374.760732 3.274339)
			(xy 374.675349 3.266427) (xy 374.589599 3.266427) (xy 374.504216 3.274339) (xy 374.419926 3.290095)
			(xy 374.33745 3.313562) (xy 374.257491 3.344538) (xy 374.180731 3.38276) (xy 374.107825 3.427901)
			(xy 374.039396 3.479577) (xy 373.976026 3.537346) (xy 373.918257 3.600716) (xy 373.866581 3.669145)
			(xy 373.82144 3.742051) (xy 373.783218 3.818811) (xy 373.752242 3.89877) (xy 373.728775 3.981246)
			(xy 373.713019 4.065536) (xy 373.705107 4.150919) (xy 343.693001 4.150919) (xy 343.685089 4.065536)
			(xy 343.669333 3.981246) (xy 343.645866 3.89877) (xy 343.61489 3.818811) (xy 343.576668 3.742051)
			(xy 343.531527 3.669145) (xy 343.479851 3.600716) (xy 343.422082 3.537346) (xy 343.358712 3.479577)
			(xy 343.290283 3.427901) (xy 343.217377 3.38276) (xy 343.140617 3.344538) (xy 343.060658 3.313562)
			(xy 342.978182 3.290095) (xy 342.893892 3.274339) (xy 342.808509 3.266427) (xy 342.722759 3.266427)
			(xy 342.637376 3.274339) (xy 342.553086 3.290095) (xy 342.47061 3.313562) (xy 342.390651 3.344538)
			(xy 342.313891 3.38276) (xy 342.240985 3.427901) (xy 342.172556 3.479577) (xy 342.109186 3.537346)
			(xy 342.051417 3.600716) (xy 341.999741 3.669145) (xy 341.9546 3.742051) (xy 341.916378 3.818811)
			(xy 341.885402 3.89877) (xy 341.861935 3.981246) (xy 341.846179 4.065536) (xy 341.838267 4.150919)
			(xy 337.343001 4.150919) (xy 337.335089 4.065536) (xy 337.319333 3.981246) (xy 337.295866 3.89877)
			(xy 337.26489 3.818811) (xy 337.226668 3.742051) (xy 337.181527 3.669145) (xy 337.129851 3.600716)
			(xy 337.072082 3.537346) (xy 337.008712 3.479577) (xy 336.940283 3.427901) (xy 336.867377 3.38276)
			(xy 336.790617 3.344538) (xy 336.710658 3.313562) (xy 336.628182 3.290095) (xy 336.543892 3.274339)
			(xy 336.458509 3.266427) (xy 336.372759 3.266427) (xy 336.287376 3.274339) (xy 336.203086 3.290095)
			(xy 336.12061 3.313562) (xy 336.040651 3.344538) (xy 335.963891 3.38276) (xy 335.890985 3.427901)
			(xy 335.822556 3.479577) (xy 335.759186 3.537346) (xy 335.701417 3.600716) (xy 335.649741 3.669145)
			(xy 335.6046 3.742051) (xy 335.566378 3.818811) (xy 335.535402 3.89877) (xy 335.511935 3.981246)
			(xy 335.496179 4.065536) (xy 335.488267 4.150919) (xy 333.050655 4.150919) (xy 333.042743 4.065536)
			(xy 333.026987 3.981246) (xy 333.00352 3.89877) (xy 332.972544 3.818811) (xy 332.934322 3.742051)
			(xy 332.889181 3.669145) (xy 332.837505 3.600716) (xy 332.779736 3.537346) (xy 332.716366 3.479577)
			(xy 332.647937 3.427901) (xy 332.575031 3.38276) (xy 332.498271 3.344538) (xy 332.418312 3.313562)
			(xy 332.335836 3.290095) (xy 332.251546 3.274339) (xy 332.166163 3.266427) (xy 332.080413 3.266427)
			(xy 331.99503 3.274339) (xy 331.91074 3.290095) (xy 331.828264 3.313562) (xy 331.748305 3.344538)
			(xy 331.671545 3.38276) (xy 331.598639 3.427901) (xy 331.53021 3.479577) (xy 331.46684 3.537346)
			(xy 331.409071 3.600716) (xy 331.357395 3.669145) (xy 331.312254 3.742051) (xy 331.274032 3.818811)
			(xy 331.243056 3.89877) (xy 331.219589 3.981246) (xy 331.203833 4.065536) (xy 331.195921 4.150919)
			(xy 326.700655 4.150919) (xy 326.692743 4.065536) (xy 326.676987 3.981246) (xy 326.65352 3.89877)
			(xy 326.622544 3.818811) (xy 326.584322 3.742051) (xy 326.539181 3.669145) (xy 326.487505 3.600716)
			(xy 326.429736 3.537346) (xy 326.366366 3.479577) (xy 326.297937 3.427901) (xy 326.225031 3.38276)
			(xy 326.148271 3.344538) (xy 326.068312 3.313562) (xy 325.985836 3.290095) (xy 325.901546 3.274339)
			(xy 325.816163 3.266427) (xy 325.730413 3.266427) (xy 325.64503 3.274339) (xy 325.56074 3.290095)
			(xy 325.478264 3.313562) (xy 325.398305 3.344538) (xy 325.321545 3.38276) (xy 325.248639 3.427901)
			(xy 325.18021 3.479577) (xy 325.11684 3.537346) (xy 325.059071 3.600716) (xy 325.007395 3.669145)
			(xy 324.962254 3.742051) (xy 324.924032 3.818811) (xy 324.893056 3.89877) (xy 324.869589 3.981246)
			(xy 324.853833 4.065536) (xy 324.845921 4.150919) (xy 265.125975 4.150919) (xy 265.118063 4.065536)
			(xy 265.102307 3.981246) (xy 265.07884 3.89877) (xy 265.047864 3.818811) (xy 265.009642 3.742051)
			(xy 264.964501 3.669145) (xy 264.912825 3.600716) (xy 264.855056 3.537346) (xy 264.791686 3.479577)
			(xy 264.723257 3.427901) (xy 264.650351 3.38276) (xy 264.573591 3.344538) (xy 264.493632 3.313562)
			(xy 264.411156 3.290095) (xy 264.326866 3.274339) (xy 264.241483 3.266427) (xy 264.155733 3.266427)
			(xy 264.07035 3.274339) (xy 263.98606 3.290095) (xy 263.903584 3.313562) (xy 263.823625 3.344538)
			(xy 263.746865 3.38276) (xy 263.673959 3.427901) (xy 263.60553 3.479577) (xy 263.54216 3.537346)
			(xy 263.484391 3.600716) (xy 263.432715 3.669145) (xy 263.387574 3.742051) (xy 263.349352 3.818811)
			(xy 263.318376 3.89877) (xy 263.294909 3.981246) (xy 263.279153 4.065536) (xy 263.271241 4.150919)
			(xy 258.775975 4.150919) (xy 258.768063 4.065536) (xy 258.752307 3.981246) (xy 258.72884 3.89877)
			(xy 258.697864 3.818811) (xy 258.659642 3.742051) (xy 258.614501 3.669145) (xy 258.562825 3.600716)
			(xy 258.505056 3.537346) (xy 258.441686 3.479577) (xy 258.373257 3.427901) (xy 258.300351 3.38276)
			(xy 258.223591 3.344538) (xy 258.143632 3.313562) (xy 258.061156 3.290095) (xy 257.976866 3.274339)
			(xy 257.891483 3.266427) (xy 257.805733 3.266427) (xy 257.72035 3.274339) (xy 257.63606 3.290095)
			(xy 257.553584 3.313562) (xy 257.473625 3.344538) (xy 257.396865 3.38276) (xy 257.323959 3.427901)
			(xy 257.25553 3.479577) (xy 257.19216 3.537346) (xy 257.134391 3.600716) (xy 257.082715 3.669145)
			(xy 257.037574 3.742051) (xy 256.999352 3.818811) (xy 256.968376 3.89877) (xy 256.944909 3.981246)
			(xy 256.929153 4.065536) (xy 256.921241 4.150919) (xy 254.465119 4.150919) (xy 254.465087 4.148125)
			(xy 254.457175 4.062742) (xy 254.441419 3.978452) (xy 254.417952 3.895976) (xy 254.386976 3.816017)
			(xy 254.348754 3.739257) (xy 254.303613 3.666351) (xy 254.251937 3.597922) (xy 254.194168 3.534552)
			(xy 254.130798 3.476783) (xy 254.062369 3.425107) (xy 253.989463 3.379966) (xy 253.912703 3.341744)
			(xy 253.832744 3.310768) (xy 253.750268 3.287301) (xy 253.665978 3.271545) (xy 253.580595 3.263633)
			(xy 253.494845 3.263633) (xy 253.409462 3.271545) (xy 253.325172 3.287301) (xy 253.242696 3.310768)
			(xy 253.162737 3.341744) (xy 253.085977 3.379966) (xy 253.013071 3.425107) (xy 252.944642 3.476783)
			(xy 252.881272 3.534552) (xy 252.823503 3.597922) (xy 252.771827 3.666351) (xy 252.726686 3.739257)
			(xy 252.688464 3.816017) (xy 252.657488 3.895976) (xy 252.634021 3.978452) (xy 252.618265 4.062742)
			(xy 252.610353 4.148125) (xy 248.115087 4.148125) (xy 248.107175 4.062742) (xy 248.091419 3.978452)
			(xy 248.067952 3.895976) (xy 248.036976 3.816017) (xy 247.998754 3.739257) (xy 247.953613 3.666351)
			(xy 247.901937 3.597922) (xy 247.844168 3.534552) (xy 247.780798 3.476783) (xy 247.712369 3.425107)
			(xy 247.639463 3.379966) (xy 247.562703 3.341744) (xy 247.482744 3.310768) (xy 247.400268 3.287301)
			(xy 247.315978 3.271545) (xy 247.230595 3.263633) (xy 247.144845 3.263633) (xy 247.059462 3.271545)
			(xy 246.975172 3.287301) (xy 246.892696 3.310768) (xy 246.812737 3.341744) (xy 246.735977 3.379966)
			(xy 246.663071 3.425107) (xy 246.594642 3.476783) (xy 246.531272 3.534552) (xy 246.473503 3.597922)
			(xy 246.421827 3.666351) (xy 246.376686 3.739257) (xy 246.338464 3.816017) (xy 246.307488 3.895976)
			(xy 246.284021 3.978452) (xy 246.268265 4.062742) (xy 246.260353 4.148125) (xy 186.540407 4.148125)
			(xy 186.532495 4.062742) (xy 186.516739 3.978452) (xy 186.493272 3.895976) (xy 186.462296 3.816017)
			(xy 186.424074 3.739257) (xy 186.378933 3.666351) (xy 186.327257 3.597922) (xy 186.269488 3.534552)
			(xy 186.206118 3.476783) (xy 186.137689 3.425107) (xy 186.064783 3.379966) (xy 185.988023 3.341744)
			(xy 185.908064 3.310768) (xy 185.825588 3.287301) (xy 185.741298 3.271545) (xy 185.655915 3.263633)
			(xy 185.570165 3.263633) (xy 185.484782 3.271545) (xy 185.400492 3.287301) (xy 185.318016 3.310768)
			(xy 185.238057 3.341744) (xy 185.161297 3.379966) (xy 185.088391 3.425107) (xy 185.019962 3.476783)
			(xy 184.956592 3.534552) (xy 184.898823 3.597922) (xy 184.847147 3.666351) (xy 184.802006 3.739257)
			(xy 184.763784 3.816017) (xy 184.732808 3.895976) (xy 184.709341 3.978452) (xy 184.693585 4.062742)
			(xy 184.685673 4.148125) (xy 180.190407 4.148125) (xy 180.182495 4.062742) (xy 180.166739 3.978452)
			(xy 180.143272 3.895976) (xy 180.112296 3.816017) (xy 180.074074 3.739257) (xy 180.028933 3.666351)
			(xy 179.977257 3.597922) (xy 179.919488 3.534552) (xy 179.856118 3.476783) (xy 179.787689 3.425107)
			(xy 179.714783 3.379966) (xy 179.638023 3.341744) (xy 179.558064 3.310768) (xy 179.475588 3.287301)
			(xy 179.391298 3.271545) (xy 179.305915 3.263633) (xy 179.220165 3.263633) (xy 179.134782 3.271545)
			(xy 179.050492 3.287301) (xy 178.968016 3.310768) (xy 178.888057 3.341744) (xy 178.811297 3.379966)
			(xy 178.738391 3.425107) (xy 178.669962 3.476783) (xy 178.606592 3.534552) (xy 178.548823 3.597922)
			(xy 178.497147 3.666351) (xy 178.452006 3.739257) (xy 178.413784 3.816017) (xy 178.382808 3.895976)
			(xy 178.359341 3.978452) (xy 178.343585 4.062742) (xy 178.335673 4.148125) (xy 0.508 4.148125) (xy 0.508 -7.78002)
			(xy 0.508522 -7.835827) (xy 0.516863 -7.947129) (xy 0.533498 -8.057497) (xy 0.558334 -8.166312) (xy 0.591233 -8.272968)
			(xy 0.63201 -8.376867) (xy 0.680438 -8.477428) (xy 0.736245 -8.574088) (xy 0.799119 -8.666308) (xy 0.868709 -8.753572)
			(xy 0.944626 -8.835391) (xy 1.026445 -8.911308) (xy 1.113708 -8.980898) (xy 1.205928 -9.043773) (xy 1.302589 -9.09958)
			(xy 1.40315 -9.148008) (xy 1.507048 -9.188786) (xy 1.613704 -9.221685) (xy 1.722519 -9.246521) (xy 1.832887 -9.263157)
			(xy 1.944189 -9.271498) (xy 1.999996 -9.272016) (xy 9.10209 -9.272016) (xy 9.157898 -9.271495) (xy 9.269201 -9.263154)
			(xy 9.379569 -9.24652) (xy 9.488386 -9.221684) (xy 9.595043 -9.188786) (xy 9.698942 -9.148009) (xy 9.799505 -9.099582)
			(xy 9.896167 -9.043775) (xy 9.988388 -8.980901) (xy 10.075653 -8.911311) (xy 10.157473 -8.835394)
			(xy 10.233392 -8.753575) (xy 10.302983 -8.666312) (xy 10.365859 -8.574092) (xy 10.421668 -8.477431)
			(xy 10.470097 -8.37687) (xy 10.510876 -8.272971) (xy 10.543776 -8.166315) (xy 10.568614 -8.057499)
			(xy 10.585251 -7.94713) (xy 10.593594 -7.835828) (xy 10.594086 -7.78002) (xy 10.594086 0.999998)
			(xy 10.59457 1.070352) (xy 10.60246 1.210839) (xy 10.618214 1.350662) (xy 10.641783 1.489382) (xy 10.673094 1.626562)
			(xy 10.712047 1.761771) (xy 10.758519 1.894583) (xy 10.812366 2.02458) (xy 10.873417 2.151354) (xy 10.94148 2.274505)
			(xy 11.016341 2.393646) (xy 11.097765 2.508402) (xy 11.185495 2.618411) (xy 11.279255 2.723329) (xy 11.378751 2.822825)
			(xy 11.483669 2.916585) (xy 11.593678 3.004315) (xy 11.708434 3.085739) (xy 11.827575 3.1606) (xy 11.950726 3.228663)
			(xy 12.0775 3.289714) (xy 12.207497 3.343561) (xy 12.340309 3.390033) (xy 12.475518 3.428986) (xy 12.612698 3.460297)
			(xy 12.751418 3.483866) (xy 12.891241 3.49962) (xy 13.031728 3.50751) (xy 13.102082 3.507994) (xy 81.701894 3.507994)
			(xy 81.772248 3.50751) (xy 81.912735 3.499621) (xy 82.052558 3.483867) (xy 82.191278 3.460297) (xy 82.328459 3.428987)
			(xy 82.463668 3.390034) (xy 82.59648 3.343562) (xy 82.726477 3.289715) (xy 82.853251 3.228664) (xy 82.976402 3.160601)
			(xy 83.095543 3.08574) (xy 83.2103 3.004317) (xy 83.32031 2.916587) (xy 83.425228 2.822826) (xy 83.524724 2.723331)
			(xy 83.618484 2.618413) (xy 83.706214 2.508403) (xy 83.787638 2.393647) (xy 83.862499 2.274506) (xy 83.930563 2.151355)
			(xy 83.991614 2.024581) (xy 84.04546 1.894584) (xy 84.091933 1.761772) (xy 84.130886 1.626563) (xy 84.135094 1.608125)
			(xy 178.335673 1.608125) (xy 178.335673 1.693875) (xy 178.343585 1.779258) (xy 178.359341 1.863548)
			(xy 178.382808 1.946024) (xy 178.413784 2.025983) (xy 178.452006 2.102743) (xy 178.497147 2.175649)
			(xy 178.548823 2.244078) (xy 178.606592 2.307448) (xy 178.669962 2.365217) (xy 178.738391 2.416893)
			(xy 178.811297 2.462034) (xy 178.888057 2.500256) (xy 178.968016 2.531232) (xy 179.050492 2.554699)
			(xy 179.134782 2.570455) (xy 179.220165 2.578367) (xy 179.305915 2.578367) (xy 179.391298 2.570455)
			(xy 179.475588 2.554699) (xy 179.558064 2.531232) (xy 179.638023 2.500256) (xy 179.660226 2.4892)
			(xy 183.270652 2.4892) (xy 183.270652 3.3528) (xy 183.271138 3.380069) (xy 183.2789 3.434053) (xy 183.294265 3.486383)
			(xy 183.316922 3.535993) (xy 183.346408 3.581874) (xy 183.382123 3.623091) (xy 183.42334 3.658806)
			(xy 183.469221 3.688292) (xy 183.518831 3.710949) (xy 183.571161 3.726314) (xy 183.625145 3.734076)
			(xy 183.679683 3.734076) (xy 183.733667 3.726314) (xy 183.785997 3.710949) (xy 183.835607 3.688292)
			(xy 183.881488 3.658806) (xy 183.922705 3.623091) (xy 183.95842 3.581874) (xy 183.987906 3.535993)
			(xy 184.010563 3.486383) (xy 184.025928 3.434053) (xy 184.03369 3.380069) (xy 184.034176 3.3528)
			(xy 184.034176 2.4892) (xy 184.03369 2.461931) (xy 184.025928 2.407947) (xy 184.010563 2.355617)
			(xy 183.987906 2.306007) (xy 183.95842 2.260126) (xy 183.922705 2.218909) (xy 183.881488 2.183194)
			(xy 183.835607 2.153708) (xy 183.785997 2.131051) (xy 183.733667 2.115686) (xy 183.679683 2.107924)
			(xy 183.625145 2.107924) (xy 183.571161 2.115686) (xy 183.518831 2.131051) (xy 183.469221 2.153708)
			(xy 183.42334 2.183194) (xy 183.382123 2.218909) (xy 183.346408 2.260126) (xy 183.316922 2.306007)
			(xy 183.294265 2.355617) (xy 183.2789 2.407947) (xy 183.271138 2.461931) (xy 183.270652 2.4892) (xy 179.660226 2.4892)
			(xy 179.714783 2.462034) (xy 179.787689 2.416893) (xy 179.856118 2.365217) (xy 179.919488 2.307448)
			(xy 179.977257 2.244078) (xy 180.028933 2.175649) (xy 180.074074 2.102743) (xy 180.112296 2.025983)
			(xy 180.143272 1.946024) (xy 180.166739 1.863548) (xy 180.182495 1.779258) (xy 180.190407 1.693875)
			(xy 180.190902 1.651) (xy 180.190407 1.608125) (xy 184.685673 1.608125) (xy 184.685673 1.693875)
			(xy 184.693585 1.779258) (xy 184.709341 1.863548) (xy 184.732808 1.946024) (xy 184.763784 2.025983)
			(xy 184.802006 2.102743) (xy 184.847147 2.175649) (xy 184.898823 2.244078) (xy 184.956592 2.307448)
			(xy 185.019962 2.365217) (xy 185.088391 2.416893) (xy 185.161297 2.462034) (xy 185.238057 2.500256)
			(xy 185.318016 2.531232) (xy 185.400492 2.554699) (xy 185.484782 2.570455) (xy 185.570165 2.578367)
			(xy 185.655915 2.578367) (xy 185.741298 2.570455) (xy 185.825588 2.554699) (xy 185.908064 2.531232)
			(xy 185.988023 2.500256) (xy 186.064783 2.462034) (xy 186.137689 2.416893) (xy 186.206118 2.365217)
			(xy 186.269488 2.307448) (xy 186.327257 2.244078) (xy 186.378933 2.175649) (xy 186.424074 2.102743)
			(xy 186.462296 2.025983) (xy 186.493272 1.946024) (xy 186.516739 1.863548) (xy 186.532495 1.779258)
			(xy 186.540407 1.693875) (xy 186.540902 1.651) (xy 186.540407 1.608125) (xy 246.260353 1.608125)
			(xy 246.260353 1.693875) (xy 246.268265 1.779258) (xy 246.284021 1.863548) (xy 246.307488 1.946024)
			(xy 246.338464 2.025983) (xy 246.376686 2.102743) (xy 246.421827 2.175649) (xy 246.473503 2.244078)
			(xy 246.531272 2.307448) (xy 246.594642 2.365217) (xy 246.663071 2.416893) (xy 246.735977 2.462034)
			(xy 246.812737 2.500256) (xy 246.892696 2.531232) (xy 246.975172 2.554699) (xy 247.059462 2.570455)
			(xy 247.144845 2.578367) (xy 247.230595 2.578367) (xy 247.315978 2.570455) (xy 247.400268 2.554699)
			(xy 247.482744 2.531232) (xy 247.562703 2.500256) (xy 247.584906 2.4892) (xy 248.766584 2.4892) (xy 248.766584 3.3528)
			(xy 248.76707 3.380069) (xy 248.774832 3.434053) (xy 248.790197 3.486383) (xy 248.812854 3.535993)
			(xy 248.84234 3.581874) (xy 248.878055 3.623091) (xy 248.919272 3.658806) (xy 248.965153 3.688292)
			(xy 249.014763 3.710949) (xy 249.067093 3.726314) (xy 249.121077 3.734076) (xy 249.175615 3.734076)
			(xy 249.229599 3.726314) (xy 249.281929 3.710949) (xy 249.331539 3.688292) (xy 249.37742 3.658806)
			(xy 249.418637 3.623091) (xy 249.454352 3.581874) (xy 249.483838 3.535993) (xy 249.506495 3.486383)
			(xy 249.52186 3.434053) (xy 249.529622 3.380069) (xy 249.530108 3.3528) (xy 249.530108 2.4892) (xy 249.529622 2.461931)
			(xy 249.52186 2.407947) (xy 249.506495 2.355617) (xy 249.483838 2.306007) (xy 249.454352 2.260126)
			(xy 249.418637 2.218909) (xy 249.37742 2.183194) (xy 249.331539 2.153708) (xy 249.281929 2.131051)
			(xy 249.229599 2.115686) (xy 249.175615 2.107924) (xy 249.121077 2.107924) (xy 249.067093 2.115686)
			(xy 249.014763 2.131051) (xy 248.965153 2.153708) (xy 248.919272 2.183194) (xy 248.878055 2.218909)
			(xy 248.84234 2.260126) (xy 248.812854 2.306007) (xy 248.790197 2.355617) (xy 248.774832 2.407947)
			(xy 248.76707 2.461931) (xy 248.766584 2.4892) (xy 247.584906 2.4892) (xy 247.639463 2.462034) (xy 247.712369 2.416893)
			(xy 247.780798 2.365217) (xy 247.844168 2.307448) (xy 247.901937 2.244078) (xy 247.953613 2.175649)
			(xy 247.998754 2.102743) (xy 248.036976 2.025983) (xy 248.067952 1.946024) (xy 248.091419 1.863548)
			(xy 248.107175 1.779258) (xy 248.115087 1.693875) (xy 248.115582 1.651) (xy 248.115087 1.608125)
			(xy 252.610353 1.608125) (xy 252.610353 1.693875) (xy 252.618265 1.779258) (xy 252.634021 1.863548)
			(xy 252.657488 1.946024) (xy 252.688464 2.025983) (xy 252.726686 2.102743) (xy 252.771827 2.175649)
			(xy 252.823503 2.244078) (xy 252.881272 2.307448) (xy 252.944642 2.365217) (xy 253.013071 2.416893)
			(xy 253.085977 2.462034) (xy 253.162737 2.500256) (xy 253.242696 2.531232) (xy 253.325172 2.554699)
			(xy 253.409462 2.570455) (xy 253.494845 2.578367) (xy 253.580595 2.578367) (xy 253.665978 2.570455)
			(xy 253.750268 2.554699) (xy 253.832744 2.531232) (xy 253.912703 2.500256) (xy 253.989463 2.462034)
			(xy 254.062369 2.416893) (xy 254.130798 2.365217) (xy 254.194168 2.307448) (xy 254.251937 2.244078)
			(xy 254.303613 2.175649) (xy 254.348754 2.102743) (xy 254.386976 2.025983) (xy 254.417952 1.946024)
			(xy 254.441419 1.863548) (xy 254.457175 1.779258) (xy 254.465087 1.693875) (xy 254.465582 1.651)
			(xy 254.465119 1.610919) (xy 256.921241 1.610919) (xy 256.921241 1.696669) (xy 256.929153 1.782052)
			(xy 256.944909 1.866342) (xy 256.968376 1.948818) (xy 256.999352 2.028777) (xy 257.037574 2.105537)
			(xy 257.082715 2.178443) (xy 257.134391 2.246872) (xy 257.19216 2.310242) (xy 257.25553 2.368011)
			(xy 257.323959 2.419687) (xy 257.396865 2.464828) (xy 257.473625 2.50305) (xy 257.553584 2.534026)
			(xy 257.63606 2.557493) (xy 257.72035 2.573249) (xy 257.805733 2.581161) (xy 257.891483 2.581161)
			(xy 257.976866 2.573249) (xy 258.061156 2.557493) (xy 258.143632 2.534026) (xy 258.223591 2.50305)
			(xy 258.245794 2.491994) (xy 261.85622 2.491994) (xy 261.85622 3.355594) (xy 261.856706 3.382863)
			(xy 261.864468 3.436847) (xy 261.879833 3.489177) (xy 261.90249 3.538787) (xy 261.931976 3.584668)
			(xy 261.967691 3.625885) (xy 262.008908 3.6616) (xy 262.054789 3.691086) (xy 262.104399 3.713743)
			(xy 262.156729 3.729108) (xy 262.210713 3.73687) (xy 262.265251 3.73687) (xy 262.319235 3.729108)
			(xy 262.371565 3.713743) (xy 262.421175 3.691086) (xy 262.467056 3.6616) (xy 262.508273 3.625885)
			(xy 262.543988 3.584668) (xy 262.573474 3.538787) (xy 262.596131 3.489177) (xy 262.611496 3.436847)
			(xy 262.619258 3.382863) (xy 262.619744 3.355594) (xy 262.619744 2.491994) (xy 262.619258 2.464725)
			(xy 262.611496 2.410741) (xy 262.596131 2.358411) (xy 262.573474 2.308801) (xy 262.543988 2.26292)
			(xy 262.508273 2.221703) (xy 262.467056 2.185988) (xy 262.421175 2.156502) (xy 262.371565 2.133845)
			(xy 262.319235 2.11848) (xy 262.265251 2.110718) (xy 262.210713 2.110718) (xy 262.156729 2.11848)
			(xy 262.104399 2.133845) (xy 262.054789 2.156502) (xy 262.008908 2.185988) (xy 261.967691 2.221703)
			(xy 261.931976 2.26292) (xy 261.90249 2.308801) (xy 261.879833 2.358411) (xy 261.864468 2.410741)
			(xy 261.856706 2.464725) (xy 261.85622 2.491994) (xy 258.245794 2.491994) (xy 258.300351 2.464828)
			(xy 258.373257 2.419687) (xy 258.441686 2.368011) (xy 258.505056 2.310242) (xy 258.562825 2.246872)
			(xy 258.614501 2.178443) (xy 258.659642 2.105537) (xy 258.697864 2.028777) (xy 258.72884 1.948818)
			(xy 258.752307 1.866342) (xy 258.768063 1.782052) (xy 258.775975 1.696669) (xy 258.77647 1.653794)
			(xy 258.775975 1.610919) (xy 263.271241 1.610919) (xy 263.271241 1.696669) (xy 263.279153 1.782052)
			(xy 263.294909 1.866342) (xy 263.318376 1.948818) (xy 263.349352 2.028777) (xy 263.387574 2.105537)
			(xy 263.432715 2.178443) (xy 263.484391 2.246872) (xy 263.54216 2.310242) (xy 263.60553 2.368011)
			(xy 263.673959 2.419687) (xy 263.746865 2.464828) (xy 263.823625 2.50305) (xy 263.903584 2.534026)
			(xy 263.98606 2.557493) (xy 264.07035 2.573249) (xy 264.155733 2.581161) (xy 264.241483 2.581161)
			(xy 264.326866 2.573249) (xy 264.411156 2.557493) (xy 264.493632 2.534026) (xy 264.573591 2.50305)
			(xy 264.650351 2.464828) (xy 264.723257 2.419687) (xy 264.791686 2.368011) (xy 264.855056 2.310242)
			(xy 264.912825 2.246872) (xy 264.964501 2.178443) (xy 265.009642 2.105537) (xy 265.047864 2.028777)
			(xy 265.07884 1.948818) (xy 265.102307 1.866342) (xy 265.118063 1.782052) (xy 265.125975 1.696669)
			(xy 265.12647 1.653794) (xy 265.125975 1.610919) (xy 324.845921 1.610919) (xy 324.845921 1.696669)
			(xy 324.853833 1.782052) (xy 324.869589 1.866342) (xy 324.893056 1.948818) (xy 324.924032 2.028777)
			(xy 324.962254 2.105537) (xy 325.007395 2.178443) (xy 325.059071 2.246872) (xy 325.11684 2.310242)
			(xy 325.18021 2.368011) (xy 325.248639 2.419687) (xy 325.321545 2.464828) (xy 325.398305 2.50305)
			(xy 325.478264 2.534026) (xy 325.56074 2.557493) (xy 325.64503 2.573249) (xy 325.730413 2.581161)
			(xy 325.816163 2.581161) (xy 325.901546 2.573249) (xy 325.985836 2.557493) (xy 326.068312 2.534026)
			(xy 326.148271 2.50305) (xy 326.170474 2.491994) (xy 327.352152 2.491994) (xy 327.352152 3.355594)
			(xy 327.352638 3.382863) (xy 327.3604 3.436847) (xy 327.375765 3.489177) (xy 327.398422 3.538787)
			(xy 327.427908 3.584668) (xy 327.463623 3.625885) (xy 327.50484 3.6616) (xy 327.550721 3.691086)
			(xy 327.600331 3.713743) (xy 327.652661 3.729108) (xy 327.706645 3.73687) (xy 327.761183 3.73687)
			(xy 327.815167 3.729108) (xy 327.867497 3.713743) (xy 327.917107 3.691086) (xy 327.962988 3.6616)
			(xy 328.004205 3.625885) (xy 328.03992 3.584668) (xy 328.069406 3.538787) (xy 328.092063 3.489177)
			(xy 328.107428 3.436847) (xy 328.11519 3.382863) (xy 328.115676 3.355594) (xy 328.115676 2.491994)
			(xy 328.11519 2.464725) (xy 328.107428 2.410741) (xy 328.092063 2.358411) (xy 328.069406 2.308801)
			(xy 328.03992 2.26292) (xy 328.004205 2.221703) (xy 327.962988 2.185988) (xy 327.917107 2.156502)
			(xy 327.867497 2.133845) (xy 327.815167 2.11848) (xy 327.761183 2.110718) (xy 327.706645 2.110718)
			(xy 327.652661 2.11848) (xy 327.600331 2.133845) (xy 327.550721 2.156502) (xy 327.50484 2.185988)
			(xy 327.463623 2.221703) (xy 327.427908 2.26292) (xy 327.398422 2.308801) (xy 327.375765 2.358411)
			(xy 327.3604 2.410741) (xy 327.352638 2.464725) (xy 327.352152 2.491994) (xy 326.170474 2.491994)
			(xy 326.225031 2.464828) (xy 326.297937 2.419687) (xy 326.366366 2.368011) (xy 326.429736 2.310242)
			(xy 326.487505 2.246872) (xy 326.539181 2.178443) (xy 326.584322 2.105537) (xy 326.622544 2.028777)
			(xy 326.65352 1.948818) (xy 326.676987 1.866342) (xy 326.692743 1.782052) (xy 326.700655 1.696669)
			(xy 326.70115 1.653794) (xy 326.700655 1.610919) (xy 331.195921 1.610919) (xy 331.195921 1.696669)
			(xy 331.203833 1.782052) (xy 331.219589 1.866342) (xy 331.243056 1.948818) (xy 331.274032 2.028777)
			(xy 331.312254 2.105537) (xy 331.357395 2.178443) (xy 331.409071 2.246872) (xy 331.46684 2.310242)
			(xy 331.53021 2.368011) (xy 331.598639 2.419687) (xy 331.671545 2.464828) (xy 331.748305 2.50305)
			(xy 331.828264 2.534026) (xy 331.91074 2.557493) (xy 331.99503 2.573249) (xy 332.080413 2.581161)
			(xy 332.166163 2.581161) (xy 332.251546 2.573249) (xy 332.335836 2.557493) (xy 332.418312 2.534026)
			(xy 332.498271 2.50305) (xy 332.575031 2.464828) (xy 332.647937 2.419687) (xy 332.716366 2.368011)
			(xy 332.779736 2.310242) (xy 332.837505 2.246872) (xy 332.889181 2.178443) (xy 332.934322 2.105537)
			(xy 332.972544 2.028777) (xy 333.00352 1.948818) (xy 333.026987 1.866342) (xy 333.042743 1.782052)
			(xy 333.050655 1.696669) (xy 333.05115 1.653794) (xy 333.050655 1.610919) (xy 335.488267 1.610919)
			(xy 335.488267 1.696669) (xy 335.496179 1.782052) (xy 335.511935 1.866342) (xy 335.535402 1.948818)
			(xy 335.566378 2.028777) (xy 335.6046 2.105537) (xy 335.649741 2.178443) (xy 335.701417 2.246872)
			(xy 335.759186 2.310242) (xy 335.822556 2.368011) (xy 335.890985 2.419687) (xy 335.963891 2.464828)
			(xy 336.040651 2.50305) (xy 336.12061 2.534026) (xy 336.203086 2.557493) (xy 336.287376 2.573249)
			(xy 336.372759 2.581161) (xy 336.458509 2.581161) (xy 336.543892 2.573249) (xy 336.628182 2.557493)
			(xy 336.710658 2.534026) (xy 336.790617 2.50305) (xy 336.81282 2.491994) (xy 340.4235 2.491994) (xy 340.4235 3.355594)
			(xy 340.423986 3.382845) (xy 340.431742 3.436793) (xy 340.447097 3.489088) (xy 340.469739 3.538665)
			(xy 340.499205 3.584515) (xy 340.534896 3.625706) (xy 340.576087 3.661397) (xy 340.621937 3.690863)
			(xy 340.671514 3.713505) (xy 340.723809 3.72886) (xy 340.777757 3.736616) (xy 340.832259 3.736616)
			(xy 340.886207 3.72886) (xy 340.938502 3.713505) (xy 340.988079 3.690863) (xy 341.033929 3.661397)
			(xy 341.07512 3.625706) (xy 341.110811 3.584515) (xy 341.140277 3.538665) (xy 341.162919 3.489088)
			(xy 341.178274 3.436793) (xy 341.18603 3.382845) (xy 341.186516 3.355594) (xy 341.186516 2.491994)
			(xy 341.18603 2.464743) (xy 341.178274 2.410795) (xy 341.162919 2.3585) (xy 341.140277 2.308923)
			(xy 341.110811 2.263073) (xy 341.07512 2.221882) (xy 341.033929 2.186191) (xy 340.988079 2.156725)
			(xy 340.938502 2.134083) (xy 340.886207 2.118728) (xy 340.832259 2.110972) (xy 340.777757 2.110972)
			(xy 340.723809 2.118728) (xy 340.671514 2.134083) (xy 340.621937 2.156725) (xy 340.576087 2.186191)
			(xy 340.534896 2.221882) (xy 340.499205 2.263073) (xy 340.469739 2.308923) (xy 340.447097 2.3585)
			(xy 340.431742 2.410795) (xy 340.423986 2.464743) (xy 340.4235 2.491994) (xy 336.81282 2.491994)
			(xy 336.867377 2.464828) (xy 336.940283 2.419687) (xy 337.008712 2.368011) (xy 337.072082 2.310242)
			(xy 337.129851 2.246872) (xy 337.181527 2.178443) (xy 337.226668 2.105537) (xy 337.26489 2.028777)
			(xy 337.295866 1.948818) (xy 337.319333 1.866342) (xy 337.335089 1.782052) (xy 337.343001 1.696669)
			(xy 337.343496 1.653794) (xy 337.343001 1.610919) (xy 341.838267 1.610919) (xy 341.838267 1.696669)
			(xy 341.846179 1.782052) (xy 341.861935 1.866342) (xy 341.885402 1.948818) (xy 341.916378 2.028777)
			(xy 341.9546 2.105537) (xy 341.999741 2.178443) (xy 342.051417 2.246872) (xy 342.109186 2.310242)
			(xy 342.172556 2.368011) (xy 342.240985 2.419687) (xy 342.313891 2.464828) (xy 342.390651 2.50305)
			(xy 342.47061 2.534026) (xy 342.553086 2.557493) (xy 342.637376 2.573249) (xy 342.722759 2.581161)
			(xy 342.808509 2.581161) (xy 342.893892 2.573249) (xy 342.978182 2.557493) (xy 343.060658 2.534026)
			(xy 343.140617 2.50305) (xy 343.217377 2.464828) (xy 343.290283 2.419687) (xy 343.358712 2.368011)
			(xy 343.422082 2.310242) (xy 343.479851 2.246872) (xy 343.531527 2.178443) (xy 343.576668 2.105537)
			(xy 343.61489 2.028777) (xy 343.645866 1.948818) (xy 343.669333 1.866342) (xy 343.685089 1.782052)
			(xy 343.693001 1.696669) (xy 343.693496 1.653794) (xy 343.693001 1.610919) (xy 373.705107 1.610919)
			(xy 373.705107 1.696669) (xy 373.713019 1.782052) (xy 373.728775 1.866342) (xy 373.752242 1.948818)
			(xy 373.783218 2.028777) (xy 373.82144 2.105537) (xy 373.866581 2.178443) (xy 373.918257 2.246872)
			(xy 373.976026 2.310242) (xy 374.039396 2.368011) (xy 374.107825 2.419687) (xy 374.180731 2.464828)
			(xy 374.257491 2.50305) (xy 374.33745 2.534026) (xy 374.419926 2.557493) (xy 374.504216 2.573249)
			(xy 374.589599 2.581161) (xy 374.675349 2.581161) (xy 374.760732 2.573249) (xy 374.845022 2.557493)
			(xy 374.927498 2.534026) (xy 375.007457 2.50305) (xy 375.02966 2.491994) (xy 376.211592 2.491994)
			(xy 376.211592 3.355594) (xy 376.212078 3.382845) (xy 376.219834 3.436793) (xy 376.235189 3.489088)
			(xy 376.257831 3.538665) (xy 376.287297 3.584515) (xy 376.322988 3.625706) (xy 376.364179 3.661397)
			(xy 376.410029 3.690863) (xy 376.459606 3.713505) (xy 376.511901 3.72886) (xy 376.565849 3.736616)
			(xy 376.620351 3.736616) (xy 376.674299 3.72886) (xy 376.726594 3.713505) (xy 376.776171 3.690863)
			(xy 376.822021 3.661397) (xy 376.863212 3.625706) (xy 376.898903 3.584515) (xy 376.928369 3.538665)
			(xy 376.951011 3.489088) (xy 376.966366 3.436793) (xy 376.974122 3.382845) (xy 376.974608 3.355594)
			(xy 376.974608 2.491994) (xy 376.974122 2.464743) (xy 376.966366 2.410795) (xy 376.951011 2.3585)
			(xy 376.928369 2.308923) (xy 376.898903 2.263073) (xy 376.863212 2.221882) (xy 376.822021 2.186191)
			(xy 376.776171 2.156725) (xy 376.726594 2.134083) (xy 376.674299 2.118728) (xy 376.620351 2.110972)
			(xy 376.565849 2.110972) (xy 376.511901 2.118728) (xy 376.459606 2.134083) (xy 376.410029 2.156725)
			(xy 376.364179 2.186191) (xy 376.322988 2.221882) (xy 376.287297 2.263073) (xy 376.257831 2.308923)
			(xy 376.235189 2.3585) (xy 376.219834 2.410795) (xy 376.212078 2.464743) (xy 376.211592 2.491994)
			(xy 375.02966 2.491994) (xy 375.084217 2.464828) (xy 375.157123 2.419687) (xy 375.225552 2.368011)
			(xy 375.288922 2.310242) (xy 375.346691 2.246872) (xy 375.398367 2.178443) (xy 375.443508 2.105537)
			(xy 375.48173 2.028777) (xy 375.512706 1.948818) (xy 375.536173 1.866342) (xy 375.551929 1.782052)
			(xy 375.559841 1.696669) (xy 375.560336 1.653794) (xy 375.559841 1.610919) (xy 380.055107 1.610919)
			(xy 380.055107 1.696669) (xy 380.063019 1.782052) (xy 380.078775 1.866342) (xy 380.102242 1.948818)
			(xy 380.133218 2.028777) (xy 380.17144 2.105537) (xy 380.216581 2.178443) (xy 380.268257 2.246872)
			(xy 380.326026 2.310242) (xy 380.389396 2.368011) (xy 380.457825 2.419687) (xy 380.530731 2.464828)
			(xy 380.607491 2.50305) (xy 380.68745 2.534026) (xy 380.769926 2.557493) (xy 380.854216 2.573249)
			(xy 380.939599 2.581161) (xy 381.025349 2.581161) (xy 381.110732 2.573249) (xy 381.195022 2.557493)
			(xy 381.277498 2.534026) (xy 381.357457 2.50305) (xy 381.434217 2.464828) (xy 381.507123 2.419687)
			(xy 381.575552 2.368011) (xy 381.638922 2.310242) (xy 381.696691 2.246872) (xy 381.748367 2.178443)
			(xy 381.793508 2.105537) (xy 381.83173 2.028777) (xy 381.862706 1.948818) (xy 381.886173 1.866342)
			(xy 381.901929 1.782052) (xy 381.909841 1.696669) (xy 381.910336 1.653794) (xy 381.909841 1.610919)
			(xy 381.901929 1.525536) (xy 381.886173 1.441246) (xy 381.862706 1.35877) (xy 381.83173 1.278811)
			(xy 381.793508 1.202051) (xy 381.748367 1.129145) (xy 381.696691 1.060716) (xy 381.638922 0.997346)
			(xy 381.575552 0.939577) (xy 381.507123 0.887901) (xy 381.434217 0.84276) (xy 381.357457 0.804538)
			(xy 381.277498 0.773562) (xy 381.195022 0.750095) (xy 381.110732 0.734339) (xy 381.025349 0.726427)
			(xy 380.939599 0.726427) (xy 380.854216 0.734339) (xy 380.769926 0.750095) (xy 380.68745 0.773562)
			(xy 380.607491 0.804538) (xy 380.530731 0.84276) (xy 380.457825 0.887901) (xy 380.389396 0.939577)
			(xy 380.326026 0.997346) (xy 380.268257 1.060716) (xy 380.216581 1.129145) (xy 380.17144 1.202051)
			(xy 380.133218 1.278811) (xy 380.102242 1.35877) (xy 380.078775 1.441246) (xy 380.063019 1.525536)
			(xy 380.055107 1.610919) (xy 375.559841 1.610919) (xy 375.551929 1.525536) (xy 375.536173 1.441246)
			(xy 375.512706 1.35877) (xy 375.48173 1.278811) (xy 375.443508 1.202051) (xy 375.398367 1.129145)
			(xy 375.346691 1.060716) (xy 375.288922 0.997346) (xy 375.225552 0.939577) (xy 375.157123 0.887901)
			(xy 375.084217 0.84276) (xy 375.007457 0.804538) (xy 374.927498 0.773562) (xy 374.845022 0.750095)
			(xy 374.760732 0.734339) (xy 374.675349 0.726427) (xy 374.589599 0.726427) (xy 374.504216 0.734339)
			(xy 374.419926 0.750095) (xy 374.33745 0.773562) (xy 374.257491 0.804538) (xy 374.180731 0.84276)
			(xy 374.107825 0.887901) (xy 374.039396 0.939577) (xy 373.976026 0.997346) (xy 373.918257 1.060716)
			(xy 373.866581 1.129145) (xy 373.82144 1.202051) (xy 373.783218 1.278811) (xy 373.752242 1.35877)
			(xy 373.728775 1.441246) (xy 373.713019 1.525536) (xy 373.705107 1.610919) (xy 343.693001 1.610919)
			(xy 343.685089 1.525536) (xy 343.669333 1.441246) (xy 343.645866 1.35877) (xy 343.61489 1.278811)
			(xy 343.576668 1.202051) (xy 343.531527 1.129145) (xy 343.479851 1.060716) (xy 343.422082 0.997346)
			(xy 343.358712 0.939577) (xy 343.290283 0.887901) (xy 343.217377 0.84276) (xy 343.140617 0.804538)
			(xy 343.060658 0.773562) (xy 342.978182 0.750095) (xy 342.893892 0.734339) (xy 342.808509 0.726427)
			(xy 342.722759 0.726427) (xy 342.637376 0.734339) (xy 342.553086 0.750095) (xy 342.47061 0.773562)
			(xy 342.390651 0.804538) (xy 342.313891 0.84276) (xy 342.240985 0.887901) (xy 342.172556 0.939577)
			(xy 342.109186 0.997346) (xy 342.051417 1.060716) (xy 341.999741 1.129145) (xy 341.9546 1.202051)
			(xy 341.916378 1.278811) (xy 341.885402 1.35877) (xy 341.861935 1.441246) (xy 341.846179 1.525536)
			(xy 341.838267 1.610919) (xy 337.343001 1.610919) (xy 337.335089 1.525536) (xy 337.319333 1.441246)
			(xy 337.295866 1.35877) (xy 337.26489 1.278811) (xy 337.226668 1.202051) (xy 337.181527 1.129145)
			(xy 337.129851 1.060716) (xy 337.072082 0.997346) (xy 337.008712 0.939577) (xy 336.940283 0.887901)
			(xy 336.867377 0.84276) (xy 336.790617 0.804538) (xy 336.710658 0.773562) (xy 336.628182 0.750095)
			(xy 336.543892 0.734339) (xy 336.458509 0.726427) (xy 336.372759 0.726427) (xy 336.287376 0.734339)
			(xy 336.203086 0.750095) (xy 336.12061 0.773562) (xy 336.040651 0.804538) (xy 335.963891 0.84276)
			(xy 335.890985 0.887901) (xy 335.822556 0.939577) (xy 335.759186 0.997346) (xy 335.701417 1.060716)
			(xy 335.649741 1.129145) (xy 335.6046 1.202051) (xy 335.566378 1.278811) (xy 335.535402 1.35877)
			(xy 335.511935 1.441246) (xy 335.496179 1.525536) (xy 335.488267 1.610919) (xy 333.050655 1.610919)
			(xy 333.042743 1.525536) (xy 333.026987 1.441246) (xy 333.00352 1.35877) (xy 332.972544 1.278811)
			(xy 332.934322 1.202051) (xy 332.889181 1.129145) (xy 332.837505 1.060716) (xy 332.779736 0.997346)
			(xy 332.716366 0.939577) (xy 332.647937 0.887901) (xy 332.575031 0.84276) (xy 332.498271 0.804538)
			(xy 332.418312 0.773562) (xy 332.335836 0.750095) (xy 332.251546 0.734339) (xy 332.166163 0.726427)
			(xy 332.080413 0.726427) (xy 331.99503 0.734339) (xy 331.91074 0.750095) (xy 331.828264 0.773562)
			(xy 331.748305 0.804538) (xy 331.671545 0.84276) (xy 331.598639 0.887901) (xy 331.53021 0.939577)
			(xy 331.46684 0.997346) (xy 331.409071 1.060716) (xy 331.357395 1.129145) (xy 331.312254 1.202051)
			(xy 331.274032 1.278811) (xy 331.243056 1.35877) (xy 331.219589 1.441246) (xy 331.203833 1.525536)
			(xy 331.195921 1.610919) (xy 326.700655 1.610919) (xy 326.692743 1.525536) (xy 326.676987 1.441246)
			(xy 326.65352 1.35877) (xy 326.622544 1.278811) (xy 326.584322 1.202051) (xy 326.539181 1.129145)
			(xy 326.487505 1.060716) (xy 326.429736 0.997346) (xy 326.366366 0.939577) (xy 326.297937 0.887901)
			(xy 326.225031 0.84276) (xy 326.148271 0.804538) (xy 326.068312 0.773562) (xy 325.985836 0.750095)
			(xy 325.901546 0.734339) (xy 325.816163 0.726427) (xy 325.730413 0.726427) (xy 325.64503 0.734339)
			(xy 325.56074 0.750095) (xy 325.478264 0.773562) (xy 325.398305 0.804538) (xy 325.321545 0.84276)
			(xy 325.248639 0.887901) (xy 325.18021 0.939577) (xy 325.11684 0.997346) (xy 325.059071 1.060716)
			(xy 325.007395 1.129145) (xy 324.962254 1.202051) (xy 324.924032 1.278811) (xy 324.893056 1.35877)
			(xy 324.869589 1.441246) (xy 324.853833 1.525536) (xy 324.845921 1.610919) (xy 265.125975 1.610919)
			(xy 265.118063 1.525536) (xy 265.102307 1.441246) (xy 265.07884 1.35877) (xy 265.047864 1.278811)
			(xy 265.009642 1.202051) (xy 264.964501 1.129145) (xy 264.912825 1.060716) (xy 264.855056 0.997346)
			(xy 264.791686 0.939577) (xy 264.723257 0.887901) (xy 264.650351 0.84276) (xy 264.573591 0.804538)
			(xy 264.493632 0.773562) (xy 264.411156 0.750095) (xy 264.326866 0.734339) (xy 264.241483 0.726427)
			(xy 264.155733 0.726427) (xy 264.07035 0.734339) (xy 263.98606 0.750095) (xy 263.903584 0.773562)
			(xy 263.823625 0.804538) (xy 263.746865 0.84276) (xy 263.673959 0.887901) (xy 263.60553 0.939577)
			(xy 263.54216 0.997346) (xy 263.484391 1.060716) (xy 263.432715 1.129145) (xy 263.387574 1.202051)
			(xy 263.349352 1.278811) (xy 263.318376 1.35877) (xy 263.294909 1.441246) (xy 263.279153 1.525536)
			(xy 263.271241 1.610919) (xy 258.775975 1.610919) (xy 258.768063 1.525536) (xy 258.752307 1.441246)
			(xy 258.72884 1.35877) (xy 258.697864 1.278811) (xy 258.659642 1.202051) (xy 258.614501 1.129145)
			(xy 258.562825 1.060716) (xy 258.505056 0.997346) (xy 258.441686 0.939577) (xy 258.373257 0.887901)
			(xy 258.300351 0.84276) (xy 258.223591 0.804538) (xy 258.143632 0.773562) (xy 258.061156 0.750095)
			(xy 257.976866 0.734339) (xy 257.891483 0.726427) (xy 257.805733 0.726427) (xy 257.72035 0.734339)
			(xy 257.63606 0.750095) (xy 257.553584 0.773562) (xy 257.473625 0.804538) (xy 257.396865 0.84276)
			(xy 257.323959 0.887901) (xy 257.25553 0.939577) (xy 257.19216 0.997346) (xy 257.134391 1.060716)
			(xy 257.082715 1.129145) (xy 257.037574 1.202051) (xy 256.999352 1.278811) (xy 256.968376 1.35877)
			(xy 256.944909 1.441246) (xy 256.929153 1.525536) (xy 256.921241 1.610919) (xy 254.465119 1.610919)
			(xy 254.465087 1.608125) (xy 254.457175 1.522742) (xy 254.441419 1.438452) (xy 254.417952 1.355976)
			(xy 254.386976 1.276017) (xy 254.348754 1.199257) (xy 254.303613 1.126351) (xy 254.251937 1.057922)
			(xy 254.194168 0.994552) (xy 254.130798 0.936783) (xy 254.062369 0.885107) (xy 253.989463 0.839966)
			(xy 253.912703 0.801744) (xy 253.832744 0.770768) (xy 253.750268 0.747301) (xy 253.665978 0.731545)
			(xy 253.580595 0.723633) (xy 253.494845 0.723633) (xy 253.409462 0.731545) (xy 253.325172 0.747301)
			(xy 253.242696 0.770768) (xy 253.162737 0.801744) (xy 253.085977 0.839966) (xy 253.013071 0.885107)
			(xy 252.944642 0.936783) (xy 252.881272 0.994552) (xy 252.823503 1.057922) (xy 252.771827 1.126351)
			(xy 252.726686 1.199257) (xy 252.688464 1.276017) (xy 252.657488 1.355976) (xy 252.634021 1.438452)
			(xy 252.618265 1.522742) (xy 252.610353 1.608125) (xy 248.115087 1.608125) (xy 248.107175 1.522742)
			(xy 248.091419 1.438452) (xy 248.067952 1.355976) (xy 248.036976 1.276017) (xy 247.998754 1.199257)
			(xy 247.953613 1.126351) (xy 247.901937 1.057922) (xy 247.844168 0.994552) (xy 247.780798 0.936783)
			(xy 247.712369 0.885107) (xy 247.639463 0.839966) (xy 247.562703 0.801744) (xy 247.482744 0.770768)
			(xy 247.400268 0.747301) (xy 247.315978 0.731545) (xy 247.230595 0.723633) (xy 247.144845 0.723633)
			(xy 247.059462 0.731545) (xy 246.975172 0.747301) (xy 246.892696 0.770768) (xy 246.812737 0.801744)
			(xy 246.735977 0.839966) (xy 246.663071 0.885107) (xy 246.594642 0.936783) (xy 246.531272 0.994552)
			(xy 246.473503 1.057922) (xy 246.421827 1.126351) (xy 246.376686 1.199257) (xy 246.338464 1.276017)
			(xy 246.307488 1.355976) (xy 246.284021 1.438452) (xy 246.268265 1.522742) (xy 246.260353 1.608125)
			(xy 186.540407 1.608125) (xy 186.532495 1.522742) (xy 186.516739 1.438452) (xy 186.493272 1.355976)
			(xy 186.462296 1.276017) (xy 186.424074 1.199257) (xy 186.378933 1.126351) (xy 186.327257 1.057922)
			(xy 186.269488 0.994552) (xy 186.206118 0.936783) (xy 186.137689 0.885107) (xy 186.064783 0.839966)
			(xy 185.988023 0.801744) (xy 185.908064 0.770768) (xy 185.825588 0.747301) (xy 185.741298 0.731545)
			(xy 185.655915 0.723633) (xy 185.570165 0.723633) (xy 185.484782 0.731545) (xy 185.400492 0.747301)
			(xy 185.318016 0.770768) (xy 185.238057 0.801744) (xy 185.161297 0.839966) (xy 185.088391 0.885107)
			(xy 185.019962 0.936783) (xy 184.956592 0.994552) (xy 184.898823 1.057922) (xy 184.847147 1.126351)
			(xy 184.802006 1.199257) (xy 184.763784 1.276017) (xy 184.732808 1.355976) (xy 184.709341 1.438452)
			(xy 184.693585 1.522742) (xy 184.685673 1.608125) (xy 180.190407 1.608125) (xy 180.182495 1.522742)
			(xy 180.166739 1.438452) (xy 180.143272 1.355976) (xy 180.112296 1.276017) (xy 180.074074 1.199257)
			(xy 180.028933 1.126351) (xy 179.977257 1.057922) (xy 179.919488 0.994552) (xy 179.856118 0.936783)
			(xy 179.787689 0.885107) (xy 179.714783 0.839966) (xy 179.638023 0.801744) (xy 179.558064 0.770768)
			(xy 179.475588 0.747301) (xy 179.391298 0.731545) (xy 179.305915 0.723633) (xy 179.220165 0.723633)
			(xy 179.134782 0.731545) (xy 179.050492 0.747301) (xy 178.968016 0.770768) (xy 178.888057 0.801744)
			(xy 178.811297 0.839966) (xy 178.738391 0.885107) (xy 178.669962 0.936783) (xy 178.606592 0.994552)
			(xy 178.548823 1.057922) (xy 178.497147 1.126351) (xy 178.452006 1.199257) (xy 178.413784 1.276017)
			(xy 178.382808 1.355976) (xy 178.359341 1.438452) (xy 178.343585 1.522742) (xy 178.335673 1.608125)
			(xy 84.135094 1.608125) (xy 84.162197 1.489382) (xy 84.185766 1.350662) (xy 84.20152 1.210839) (xy 84.20941 1.070352)
			(xy 84.20989 0.999998) (xy 84.20989 -0.931875) (xy 208.043513 -0.931875) (xy 208.043513 -0.846125)
			(xy 208.051425 -0.760742) (xy 208.067181 -0.676452) (xy 208.090648 -0.593976) (xy 208.121624 -0.514017)
			(xy 208.159846 -0.437257) (xy 208.204987 -0.364351) (xy 208.256663 -0.295922) (xy 208.314432 -0.232552)
			(xy 208.377802 -0.174783) (xy 208.446231 -0.123107) (xy 208.519137 -0.077966) (xy 208.595897 -0.039744)
			(xy 208.675856 -0.008768) (xy 208.758332 0.014699) (xy 208.842622 0.030455) (xy 208.928005 0.038367)
			(xy 209.013755 0.038367) (xy 209.099138 0.030455) (xy 209.183428 0.014699) (xy 209.265904 -0.008768)
			(xy 209.345863 -0.039744) (xy 209.422623 -0.077966) (xy 209.495529 -0.123107) (xy 209.563958 -0.174783)
			(xy 209.627328 -0.232552) (xy 209.685097 -0.295922) (xy 209.736773 -0.364351) (xy 209.781914 -0.437257)
			(xy 209.820136 -0.514017) (xy 209.851112 -0.593976) (xy 209.874579 -0.676452) (xy 209.890335 -0.760742)
			(xy 209.898247 -0.846125) (xy 209.898742 -0.889) (xy 209.898247 -0.931875) (xy 214.393513 -0.931875)
			(xy 214.393513 -0.846125) (xy 214.401425 -0.760742) (xy 214.417181 -0.676452) (xy 214.440648 -0.593976)
			(xy 214.471624 -0.514017) (xy 214.509846 -0.437257) (xy 214.554987 -0.364351) (xy 214.606663 -0.295922)
			(xy 214.664432 -0.232552) (xy 214.727802 -0.174783) (xy 214.796231 -0.123107) (xy 214.869137 -0.077966)
			(xy 214.945897 -0.039744) (xy 215.025856 -0.008768) (xy 215.108332 0.014699) (xy 215.192622 0.030455)
			(xy 215.278005 0.038367) (xy 215.363755 0.038367) (xy 215.449138 0.030455) (xy 215.533428 0.014699)
			(xy 215.615904 -0.008768) (xy 215.695863 -0.039744) (xy 215.772623 -0.077966) (xy 215.845529 -0.123107)
			(xy 215.913958 -0.174783) (xy 215.977328 -0.232552) (xy 216.035097 -0.295922) (xy 216.086773 -0.364351)
			(xy 216.131914 -0.437257) (xy 216.170136 -0.514017) (xy 216.201112 -0.593976) (xy 216.224579 -0.676452)
			(xy 216.240335 -0.760742) (xy 216.248247 -0.846125) (xy 216.248742 -0.889) (xy 216.248247 -0.931875)
			(xy 246.260353 -0.931875) (xy 246.260353 -0.846125) (xy 246.268265 -0.760742) (xy 246.284021 -0.676452)
			(xy 246.307488 -0.593976) (xy 246.338464 -0.514017) (xy 246.376686 -0.437257) (xy 246.421827 -0.364351)
			(xy 246.473503 -0.295922) (xy 246.531272 -0.232552) (xy 246.594642 -0.174783) (xy 246.663071 -0.123107)
			(xy 246.735977 -0.077966) (xy 246.812737 -0.039744) (xy 246.892696 -0.008768) (xy 246.975172 0.014699)
			(xy 247.059462 0.030455) (xy 247.144845 0.038367) (xy 247.230595 0.038367) (xy 247.315978 0.030455)
			(xy 247.400268 0.014699) (xy 247.482744 -0.008768) (xy 247.562703 -0.039744) (xy 247.639463 -0.077966)
			(xy 247.712369 -0.123107) (xy 247.780798 -0.174783) (xy 247.844168 -0.232552) (xy 247.901937 -0.295922)
			(xy 247.953613 -0.364351) (xy 247.998754 -0.437257) (xy 248.036976 -0.514017) (xy 248.067952 -0.593976)
			(xy 248.091419 -0.676452) (xy 248.107175 -0.760742) (xy 248.115087 -0.846125) (xy 248.115582 -0.889)
			(xy 248.115087 -0.931875) (xy 252.610353 -0.931875) (xy 252.610353 -0.846125) (xy 252.618265 -0.760742)
			(xy 252.634021 -0.676452) (xy 252.657488 -0.593976) (xy 252.688464 -0.514017) (xy 252.726686 -0.437257)
			(xy 252.771827 -0.364351) (xy 252.823503 -0.295922) (xy 252.881272 -0.232552) (xy 252.944642 -0.174783)
			(xy 253.013071 -0.123107) (xy 253.085977 -0.077966) (xy 253.162737 -0.039744) (xy 253.242696 -0.008768)
			(xy 253.325172 0.014699) (xy 253.409462 0.030455) (xy 253.494845 0.038367) (xy 253.580595 0.038367)
			(xy 253.665978 0.030455) (xy 253.750268 0.014699) (xy 253.832744 -0.008768) (xy 253.912703 -0.039744)
			(xy 253.989463 -0.077966) (xy 254.062369 -0.123107) (xy 254.130798 -0.174783) (xy 254.194168 -0.232552)
			(xy 254.251937 -0.295922) (xy 254.303613 -0.364351) (xy 254.348754 -0.437257) (xy 254.386976 -0.514017)
			(xy 254.417952 -0.593976) (xy 254.441419 -0.676452) (xy 254.457175 -0.760742) (xy 254.465087 -0.846125)
			(xy 254.465582 -0.889) (xy 254.465119 -0.929081) (xy 256.921241 -0.929081) (xy 256.921241 -0.843331)
			(xy 256.929153 -0.757948) (xy 256.944909 -0.673658) (xy 256.968376 -0.591182) (xy 256.999352 -0.511223)
			(xy 257.037574 -0.434463) (xy 257.082715 -0.361557) (xy 257.134391 -0.293128) (xy 257.19216 -0.229758)
			(xy 257.25553 -0.171989) (xy 257.323959 -0.120313) (xy 257.396865 -0.075172) (xy 257.473625 -0.03695)
			(xy 257.553584 -0.005974) (xy 257.63606 0.017493) (xy 257.72035 0.033249) (xy 257.805733 0.041161)
			(xy 257.891483 0.041161) (xy 257.976866 0.033249) (xy 258.061156 0.017493) (xy 258.143632 -0.005974)
			(xy 258.223591 -0.03695) (xy 258.245794 -0.048006) (xy 261.85622 -0.048006) (xy 261.85622 0.815594)
			(xy 261.856706 0.842863) (xy 261.864468 0.896847) (xy 261.879833 0.949177) (xy 261.90249 0.998787)
			(xy 261.931976 1.044668) (xy 261.967691 1.085885) (xy 262.008908 1.1216) (xy 262.054789 1.151086)
			(xy 262.104399 1.173743) (xy 262.156729 1.189108) (xy 262.210713 1.19687) (xy 262.265251 1.19687)
			(xy 262.319235 1.189108) (xy 262.371565 1.173743) (xy 262.421175 1.151086) (xy 262.467056 1.1216)
			(xy 262.508273 1.085885) (xy 262.543988 1.044668) (xy 262.573474 0.998787) (xy 262.596131 0.949177)
			(xy 262.611496 0.896847) (xy 262.619258 0.842863) (xy 262.619744 0.815594) (xy 262.619744 -0.048006)
			(xy 262.619258 -0.075275) (xy 262.611496 -0.129259) (xy 262.596131 -0.181589) (xy 262.573474 -0.231199)
			(xy 262.543988 -0.27708) (xy 262.508273 -0.318297) (xy 262.467056 -0.354012) (xy 262.421175 -0.383498)
			(xy 262.371565 -0.406155) (xy 262.319235 -0.42152) (xy 262.265251 -0.429282) (xy 262.210713 -0.429282)
			(xy 262.156729 -0.42152) (xy 262.104399 -0.406155) (xy 262.054789 -0.383498) (xy 262.008908 -0.354012)
			(xy 261.967691 -0.318297) (xy 261.931976 -0.27708) (xy 261.90249 -0.231199) (xy 261.879833 -0.181589)
			(xy 261.864468 -0.129259) (xy 261.856706 -0.075275) (xy 261.85622 -0.048006) (xy 258.245794 -0.048006)
			(xy 258.300351 -0.075172) (xy 258.373257 -0.120313) (xy 258.441686 -0.171989) (xy 258.505056 -0.229758)
			(xy 258.562825 -0.293128) (xy 258.614501 -0.361557) (xy 258.659642 -0.434463) (xy 258.697864 -0.511223)
			(xy 258.72884 -0.591182) (xy 258.752307 -0.673658) (xy 258.768063 -0.757948) (xy 258.775975 -0.843331)
			(xy 258.77647 -0.886206) (xy 258.775975 -0.929081) (xy 263.271241 -0.929081) (xy 263.271241 -0.843331)
			(xy 263.279153 -0.757948) (xy 263.294909 -0.673658) (xy 263.318376 -0.591182) (xy 263.349352 -0.511223)
			(xy 263.387574 -0.434463) (xy 263.432715 -0.361557) (xy 263.484391 -0.293128) (xy 263.54216 -0.229758)
			(xy 263.60553 -0.171989) (xy 263.673959 -0.120313) (xy 263.746865 -0.075172) (xy 263.823625 -0.03695)
			(xy 263.903584 -0.005974) (xy 263.98606 0.017493) (xy 264.07035 0.033249) (xy 264.155733 0.041161)
			(xy 264.241483 0.041161) (xy 264.326866 0.033249) (xy 264.411156 0.017493) (xy 264.493632 -0.005974)
			(xy 264.573591 -0.03695) (xy 264.650351 -0.075172) (xy 264.723257 -0.120313) (xy 264.791686 -0.171989)
			(xy 264.855056 -0.229758) (xy 264.912825 -0.293128) (xy 264.964501 -0.361557) (xy 265.009642 -0.434463)
			(xy 265.047864 -0.511223) (xy 265.07884 -0.591182) (xy 265.102307 -0.673658) (xy 265.118063 -0.757948)
			(xy 265.125975 -0.843331) (xy 265.12647 -0.886206) (xy 265.125975 -0.929081) (xy 324.845921 -0.929081)
			(xy 324.845921 -0.843331) (xy 324.853833 -0.757948) (xy 324.869589 -0.673658) (xy 324.893056 -0.591182)
			(xy 324.924032 -0.511223) (xy 324.962254 -0.434463) (xy 325.007395 -0.361557) (xy 325.059071 -0.293128)
			(xy 325.11684 -0.229758) (xy 325.18021 -0.171989) (xy 325.248639 -0.120313) (xy 325.321545 -0.075172)
			(xy 325.398305 -0.03695) (xy 325.478264 -0.005974) (xy 325.56074 0.017493) (xy 325.64503 0.033249)
			(xy 325.730413 0.041161) (xy 325.816163 0.041161) (xy 325.901546 0.033249) (xy 325.985836 0.017493)
			(xy 326.068312 -0.005974) (xy 326.148271 -0.03695) (xy 326.170474 -0.048006) (xy 327.352152 -0.048006)
			(xy 327.352152 0.815594) (xy 327.352638 0.842863) (xy 327.3604 0.896847) (xy 327.375765 0.949177)
			(xy 327.398422 0.998787) (xy 327.427908 1.044668) (xy 327.463623 1.085885) (xy 327.50484 1.1216)
			(xy 327.550721 1.151086) (xy 327.600331 1.173743) (xy 327.652661 1.189108) (xy 327.706645 1.19687)
			(xy 327.761183 1.19687) (xy 327.815167 1.189108) (xy 327.867497 1.173743) (xy 327.917107 1.151086)
			(xy 327.962988 1.1216) (xy 328.004205 1.085885) (xy 328.03992 1.044668) (xy 328.069406 0.998787)
			(xy 328.092063 0.949177) (xy 328.107428 0.896847) (xy 328.11519 0.842863) (xy 328.115676 0.815594)
			(xy 328.115676 -0.048006) (xy 328.11519 -0.075275) (xy 328.107428 -0.129259) (xy 328.092063 -0.181589)
			(xy 328.069406 -0.231199) (xy 328.03992 -0.27708) (xy 328.004205 -0.318297) (xy 327.962988 -0.354012)
			(xy 327.917107 -0.383498) (xy 327.867497 -0.406155) (xy 327.815167 -0.42152) (xy 327.761183 -0.429282)
			(xy 327.706645 -0.429282) (xy 327.652661 -0.42152) (xy 327.600331 -0.406155) (xy 327.550721 -0.383498)
			(xy 327.50484 -0.354012) (xy 327.463623 -0.318297) (xy 327.427908 -0.27708) (xy 327.398422 -0.231199)
			(xy 327.375765 -0.181589) (xy 327.3604 -0.129259) (xy 327.352638 -0.075275) (xy 327.352152 -0.048006)
			(xy 326.170474 -0.048006) (xy 326.225031 -0.075172) (xy 326.297937 -0.120313) (xy 326.366366 -0.171989)
			(xy 326.429736 -0.229758) (xy 326.487505 -0.293128) (xy 326.539181 -0.361557) (xy 326.584322 -0.434463)
			(xy 326.622544 -0.511223) (xy 326.65352 -0.591182) (xy 326.676987 -0.673658) (xy 326.692743 -0.757948)
			(xy 326.700655 -0.843331) (xy 326.70115 -0.886206) (xy 326.700655 -0.929081) (xy 331.195921 -0.929081)
			(xy 331.195921 -0.843331) (xy 331.203833 -0.757948) (xy 331.219589 -0.673658) (xy 331.243056 -0.591182)
			(xy 331.274032 -0.511223) (xy 331.312254 -0.434463) (xy 331.357395 -0.361557) (xy 331.409071 -0.293128)
			(xy 331.46684 -0.229758) (xy 331.53021 -0.171989) (xy 331.598639 -0.120313) (xy 331.671545 -0.075172)
			(xy 331.748305 -0.03695) (xy 331.828264 -0.005974) (xy 331.91074 0.017493) (xy 331.99503 0.033249)
			(xy 332.080413 0.041161) (xy 332.166163 0.041161) (xy 332.251546 0.033249) (xy 332.335836 0.017493)
			(xy 332.418312 -0.005974) (xy 332.498271 -0.03695) (xy 332.575031 -0.075172) (xy 332.647937 -0.120313)
			(xy 332.716366 -0.171989) (xy 332.779736 -0.229758) (xy 332.837505 -0.293128) (xy 332.889181 -0.361557)
			(xy 332.934322 -0.434463) (xy 332.972544 -0.511223) (xy 333.00352 -0.591182) (xy 333.026987 -0.673658)
			(xy 333.042743 -0.757948) (xy 333.050655 -0.843331) (xy 333.05115 -0.886206) (xy 333.050655 -0.929081)
			(xy 335.488267 -0.929081) (xy 335.488267 -0.843331) (xy 335.496179 -0.757948) (xy 335.511935 -0.673658)
			(xy 335.535402 -0.591182) (xy 335.566378 -0.511223) (xy 335.6046 -0.434463) (xy 335.649741 -0.361557)
			(xy 335.701417 -0.293128) (xy 335.759186 -0.229758) (xy 335.822556 -0.171989) (xy 335.890985 -0.120313)
			(xy 335.963891 -0.075172) (xy 336.040651 -0.03695) (xy 336.12061 -0.005974) (xy 336.203086 0.017493)
			(xy 336.287376 0.033249) (xy 336.372759 0.041161) (xy 336.458509 0.041161) (xy 336.543892 0.033249)
			(xy 336.628182 0.017493) (xy 336.710658 -0.005974) (xy 336.790617 -0.03695) (xy 336.81282 -0.048006)
			(xy 340.4235 -0.048006) (xy 340.4235 0.815594) (xy 340.423986 0.842845) (xy 340.431742 0.896793)
			(xy 340.447097 0.949088) (xy 340.469739 0.998665) (xy 340.499205 1.044515) (xy 340.534896 1.085706)
			(xy 340.576087 1.121397) (xy 340.621937 1.150863) (xy 340.671514 1.173505) (xy 340.723809 1.18886)
			(xy 340.777757 1.196616) (xy 340.832259 1.196616) (xy 340.886207 1.18886) (xy 340.938502 1.173505)
			(xy 340.988079 1.150863) (xy 341.033929 1.121397) (xy 341.07512 1.085706) (xy 341.110811 1.044515)
			(xy 341.140277 0.998665) (xy 341.162919 0.949088) (xy 341.178274 0.896793) (xy 341.18603 0.842845)
			(xy 341.186516 0.815594) (xy 341.186516 -0.048006) (xy 341.18603 -0.075257) (xy 341.178274 -0.129205)
			(xy 341.162919 -0.1815) (xy 341.140277 -0.231077) (xy 341.110811 -0.276927) (xy 341.07512 -0.318118)
			(xy 341.033929 -0.353809) (xy 340.988079 -0.383275) (xy 340.938502 -0.405917) (xy 340.886207 -0.421272)
			(xy 340.832259 -0.429028) (xy 340.777757 -0.429028) (xy 340.723809 -0.421272) (xy 340.671514 -0.405917)
			(xy 340.621937 -0.383275) (xy 340.576087 -0.353809) (xy 340.534896 -0.318118) (xy 340.499205 -0.276927)
			(xy 340.469739 -0.231077) (xy 340.447097 -0.1815) (xy 340.431742 -0.129205) (xy 340.423986 -0.075257)
			(xy 340.4235 -0.048006) (xy 336.81282 -0.048006) (xy 336.867377 -0.075172) (xy 336.940283 -0.120313)
			(xy 337.008712 -0.171989) (xy 337.072082 -0.229758) (xy 337.129851 -0.293128) (xy 337.181527 -0.361557)
			(xy 337.226668 -0.434463) (xy 337.26489 -0.511223) (xy 337.295866 -0.591182) (xy 337.319333 -0.673658)
			(xy 337.335089 -0.757948) (xy 337.343001 -0.843331) (xy 337.343496 -0.886206) (xy 337.343001 -0.929081)
			(xy 341.838267 -0.929081) (xy 341.838267 -0.843331) (xy 341.846179 -0.757948) (xy 341.861935 -0.673658)
			(xy 341.885402 -0.591182) (xy 341.916378 -0.511223) (xy 341.9546 -0.434463) (xy 341.999741 -0.361557)
			(xy 342.051417 -0.293128) (xy 342.109186 -0.229758) (xy 342.172556 -0.171989) (xy 342.240985 -0.120313)
			(xy 342.313891 -0.075172) (xy 342.390651 -0.03695) (xy 342.47061 -0.005974) (xy 342.553086 0.017493)
			(xy 342.637376 0.033249) (xy 342.722759 0.041161) (xy 342.808509 0.041161) (xy 342.893892 0.033249)
			(xy 342.978182 0.017493) (xy 343.060658 -0.005974) (xy 343.140617 -0.03695) (xy 343.217377 -0.075172)
			(xy 343.290283 -0.120313) (xy 343.358712 -0.171989) (xy 343.422082 -0.229758) (xy 343.479851 -0.293128)
			(xy 343.531527 -0.361557) (xy 343.576668 -0.434463) (xy 343.61489 -0.511223) (xy 343.645866 -0.591182)
			(xy 343.669333 -0.673658) (xy 343.685089 -0.757948) (xy 343.693001 -0.843331) (xy 343.693496 -0.886206)
			(xy 343.693001 -0.929081) (xy 373.705107 -0.929081) (xy 373.705107 -0.843331) (xy 373.713019 -0.757948)
			(xy 373.728775 -0.673658) (xy 373.752242 -0.591182) (xy 373.783218 -0.511223) (xy 373.82144 -0.434463)
			(xy 373.866581 -0.361557) (xy 373.918257 -0.293128) (xy 373.976026 -0.229758) (xy 374.039396 -0.171989)
			(xy 374.107825 -0.120313) (xy 374.180731 -0.075172) (xy 374.257491 -0.03695) (xy 374.33745 -0.005974)
			(xy 374.419926 0.017493) (xy 374.504216 0.033249) (xy 374.589599 0.041161) (xy 374.675349 0.041161)
			(xy 374.760732 0.033249) (xy 374.845022 0.017493) (xy 374.927498 -0.005974) (xy 375.007457 -0.03695)
			(xy 375.02966 -0.048006) (xy 376.211592 -0.048006) (xy 376.211592 0.815594) (xy 376.212078 0.842845)
			(xy 376.219834 0.896793) (xy 376.235189 0.949088) (xy 376.257831 0.998665) (xy 376.287297 1.044515)
			(xy 376.322988 1.085706) (xy 376.364179 1.121397) (xy 376.410029 1.150863) (xy 376.459606 1.173505)
			(xy 376.511901 1.18886) (xy 376.565849 1.196616) (xy 376.620351 1.196616) (xy 376.674299 1.18886)
			(xy 376.726594 1.173505) (xy 376.776171 1.150863) (xy 376.822021 1.121397) (xy 376.863212 1.085706)
			(xy 376.898903 1.044515) (xy 376.928369 0.998665) (xy 376.951011 0.949088) (xy 376.966366 0.896793)
			(xy 376.974122 0.842845) (xy 376.974608 0.815594) (xy 376.974608 -0.048006) (xy 376.974122 -0.075257)
			(xy 376.966366 -0.129205) (xy 376.951011 -0.1815) (xy 376.928369 -0.231077) (xy 376.898903 -0.276927)
			(xy 376.863212 -0.318118) (xy 376.822021 -0.353809) (xy 376.776171 -0.383275) (xy 376.726594 -0.405917)
			(xy 376.674299 -0.421272) (xy 376.620351 -0.429028) (xy 376.565849 -0.429028) (xy 376.511901 -0.421272)
			(xy 376.459606 -0.405917) (xy 376.410029 -0.383275) (xy 376.364179 -0.353809) (xy 376.322988 -0.318118)
			(xy 376.287297 -0.276927) (xy 376.257831 -0.231077) (xy 376.235189 -0.1815) (xy 376.219834 -0.129205)
			(xy 376.212078 -0.075257) (xy 376.211592 -0.048006) (xy 375.02966 -0.048006) (xy 375.084217 -0.075172)
			(xy 375.157123 -0.120313) (xy 375.225552 -0.171989) (xy 375.288922 -0.229758) (xy 375.346691 -0.293128)
			(xy 375.398367 -0.361557) (xy 375.443508 -0.434463) (xy 375.48173 -0.511223) (xy 375.512706 -0.591182)
			(xy 375.536173 -0.673658) (xy 375.551929 -0.757948) (xy 375.559841 -0.843331) (xy 375.560336 -0.886206)
			(xy 375.559841 -0.929081) (xy 380.055107 -0.929081) (xy 380.055107 -0.843331) (xy 380.063019 -0.757948)
			(xy 380.078775 -0.673658) (xy 380.102242 -0.591182) (xy 380.133218 -0.511223) (xy 380.17144 -0.434463)
			(xy 380.216581 -0.361557) (xy 380.268257 -0.293128) (xy 380.326026 -0.229758) (xy 380.389396 -0.171989)
			(xy 380.457825 -0.120313) (xy 380.530731 -0.075172) (xy 380.607491 -0.03695) (xy 380.68745 -0.005974)
			(xy 380.769926 0.017493) (xy 380.854216 0.033249) (xy 380.939599 0.041161) (xy 381.025349 0.041161)
			(xy 381.110732 0.033249) (xy 381.195022 0.017493) (xy 381.277498 -0.005974) (xy 381.357457 -0.03695)
			(xy 381.434217 -0.075172) (xy 381.507123 -0.120313) (xy 381.575552 -0.171989) (xy 381.638922 -0.229758)
			(xy 381.696691 -0.293128) (xy 381.748367 -0.361557) (xy 381.793508 -0.434463) (xy 381.83173 -0.511223)
			(xy 381.862706 -0.591182) (xy 381.886173 -0.673658) (xy 381.901929 -0.757948) (xy 381.909841 -0.843331)
			(xy 381.910336 -0.886206) (xy 381.909841 -0.929081) (xy 381.901929 -1.014464) (xy 381.886173 -1.098754)
			(xy 381.862706 -1.18123) (xy 381.83173 -1.261189) (xy 381.793508 -1.337949) (xy 381.748367 -1.410855)
			(xy 381.696691 -1.479284) (xy 381.638922 -1.542654) (xy 381.575552 -1.600423) (xy 381.507123 -1.652099)
			(xy 381.434217 -1.69724) (xy 381.357457 -1.735462) (xy 381.277498 -1.766438) (xy 381.195022 -1.789905)
			(xy 381.110732 -1.805661) (xy 381.025349 -1.813573) (xy 380.939599 -1.813573) (xy 380.854216 -1.805661)
			(xy 380.769926 -1.789905) (xy 380.68745 -1.766438) (xy 380.607491 -1.735462) (xy 380.530731 -1.69724)
			(xy 380.457825 -1.652099) (xy 380.389396 -1.600423) (xy 380.326026 -1.542654) (xy 380.268257 -1.479284)
			(xy 380.216581 -1.410855) (xy 380.17144 -1.337949) (xy 380.133218 -1.261189) (xy 380.102242 -1.18123)
			(xy 380.078775 -1.098754) (xy 380.063019 -1.014464) (xy 380.055107 -0.929081) (xy 375.559841 -0.929081)
			(xy 375.551929 -1.014464) (xy 375.536173 -1.098754) (xy 375.512706 -1.18123) (xy 375.48173 -1.261189)
			(xy 375.443508 -1.337949) (xy 375.398367 -1.410855) (xy 375.346691 -1.479284) (xy 375.288922 -1.542654)
			(xy 375.225552 -1.600423) (xy 375.157123 -1.652099) (xy 375.084217 -1.69724) (xy 375.007457 -1.735462)
			(xy 374.927498 -1.766438) (xy 374.845022 -1.789905) (xy 374.760732 -1.805661) (xy 374.675349 -1.813573)
			(xy 374.589599 -1.813573) (xy 374.504216 -1.805661) (xy 374.419926 -1.789905) (xy 374.33745 -1.766438)
			(xy 374.257491 -1.735462) (xy 374.180731 -1.69724) (xy 374.107825 -1.652099) (xy 374.039396 -1.600423)
			(xy 373.976026 -1.542654) (xy 373.918257 -1.479284) (xy 373.866581 -1.410855) (xy 373.82144 -1.337949)
			(xy 373.783218 -1.261189) (xy 373.752242 -1.18123) (xy 373.728775 -1.098754) (xy 373.713019 -1.014464)
			(xy 373.705107 -0.929081) (xy 343.693001 -0.929081) (xy 343.685089 -1.014464) (xy 343.669333 -1.098754)
			(xy 343.645866 -1.18123) (xy 343.61489 -1.261189) (xy 343.576668 -1.337949) (xy 343.531527 -1.410855)
			(xy 343.479851 -1.479284) (xy 343.422082 -1.542654) (xy 343.358712 -1.600423) (xy 343.290283 -1.652099)
			(xy 343.217377 -1.69724) (xy 343.140617 -1.735462) (xy 343.060658 -1.766438) (xy 342.978182 -1.789905)
			(xy 342.893892 -1.805661) (xy 342.808509 -1.813573) (xy 342.722759 -1.813573) (xy 342.637376 -1.805661)
			(xy 342.553086 -1.789905) (xy 342.47061 -1.766438) (xy 342.390651 -1.735462) (xy 342.313891 -1.69724)
			(xy 342.240985 -1.652099) (xy 342.172556 -1.600423) (xy 342.109186 -1.542654) (xy 342.051417 -1.479284)
			(xy 341.999741 -1.410855) (xy 341.9546 -1.337949) (xy 341.916378 -1.261189) (xy 341.885402 -1.18123)
			(xy 341.861935 -1.098754) (xy 341.846179 -1.014464) (xy 341.838267 -0.929081) (xy 337.343001 -0.929081)
			(xy 337.335089 -1.014464) (xy 337.319333 -1.098754) (xy 337.295866 -1.18123) (xy 337.26489 -1.261189)
			(xy 337.226668 -1.337949) (xy 337.181527 -1.410855) (xy 337.129851 -1.479284) (xy 337.072082 -1.542654)
			(xy 337.008712 -1.600423) (xy 336.940283 -1.652099) (xy 336.867377 -1.69724) (xy 336.790617 -1.735462)
			(xy 336.710658 -1.766438) (xy 336.628182 -1.789905) (xy 336.543892 -1.805661) (xy 336.458509 -1.813573)
			(xy 336.372759 -1.813573) (xy 336.287376 -1.805661) (xy 336.203086 -1.789905) (xy 336.12061 -1.766438)
			(xy 336.040651 -1.735462) (xy 335.963891 -1.69724) (xy 335.890985 -1.652099) (xy 335.822556 -1.600423)
			(xy 335.759186 -1.542654) (xy 335.701417 -1.479284) (xy 335.649741 -1.410855) (xy 335.6046 -1.337949)
			(xy 335.566378 -1.261189) (xy 335.535402 -1.18123) (xy 335.511935 -1.098754) (xy 335.496179 -1.014464)
			(xy 335.488267 -0.929081) (xy 333.050655 -0.929081) (xy 333.042743 -1.014464) (xy 333.026987 -1.098754)
			(xy 333.00352 -1.18123) (xy 332.972544 -1.261189) (xy 332.934322 -1.337949) (xy 332.889181 -1.410855)
			(xy 332.837505 -1.479284) (xy 332.779736 -1.542654) (xy 332.716366 -1.600423) (xy 332.647937 -1.652099)
			(xy 332.575031 -1.69724) (xy 332.498271 -1.735462) (xy 332.418312 -1.766438) (xy 332.335836 -1.789905)
			(xy 332.251546 -1.805661) (xy 332.166163 -1.813573) (xy 332.080413 -1.813573) (xy 331.99503 -1.805661)
			(xy 331.91074 -1.789905) (xy 331.828264 -1.766438) (xy 331.748305 -1.735462) (xy 331.671545 -1.69724)
			(xy 331.598639 -1.652099) (xy 331.53021 -1.600423) (xy 331.46684 -1.542654) (xy 331.409071 -1.479284)
			(xy 331.357395 -1.410855) (xy 331.312254 -1.337949) (xy 331.274032 -1.261189) (xy 331.243056 -1.18123)
			(xy 331.219589 -1.098754) (xy 331.203833 -1.014464) (xy 331.195921 -0.929081) (xy 326.700655 -0.929081)
			(xy 326.692743 -1.014464) (xy 326.676987 -1.098754) (xy 326.65352 -1.18123) (xy 326.622544 -1.261189)
			(xy 326.584322 -1.337949) (xy 326.539181 -1.410855) (xy 326.487505 -1.479284) (xy 326.429736 -1.542654)
			(xy 326.366366 -1.600423) (xy 326.297937 -1.652099) (xy 326.225031 -1.69724) (xy 326.148271 -1.735462)
			(xy 326.068312 -1.766438) (xy 325.985836 -1.789905) (xy 325.901546 -1.805661) (xy 325.816163 -1.813573)
			(xy 325.730413 -1.813573) (xy 325.64503 -1.805661) (xy 325.56074 -1.789905) (xy 325.478264 -1.766438)
			(xy 325.398305 -1.735462) (xy 325.321545 -1.69724) (xy 325.248639 -1.652099) (xy 325.18021 -1.600423)
			(xy 325.11684 -1.542654) (xy 325.059071 -1.479284) (xy 325.007395 -1.410855) (xy 324.962254 -1.337949)
			(xy 324.924032 -1.261189) (xy 324.893056 -1.18123) (xy 324.869589 -1.098754) (xy 324.853833 -1.014464)
			(xy 324.845921 -0.929081) (xy 265.125975 -0.929081) (xy 265.118063 -1.014464) (xy 265.102307 -1.098754)
			(xy 265.07884 -1.18123) (xy 265.047864 -1.261189) (xy 265.009642 -1.337949) (xy 264.964501 -1.410855)
			(xy 264.912825 -1.479284) (xy 264.855056 -1.542654) (xy 264.791686 -1.600423) (xy 264.723257 -1.652099)
			(xy 264.650351 -1.69724) (xy 264.573591 -1.735462) (xy 264.493632 -1.766438) (xy 264.411156 -1.789905)
			(xy 264.326866 -1.805661) (xy 264.241483 -1.813573) (xy 264.155733 -1.813573) (xy 264.07035 -1.805661)
			(xy 263.98606 -1.789905) (xy 263.903584 -1.766438) (xy 263.823625 -1.735462) (xy 263.746865 -1.69724)
			(xy 263.673959 -1.652099) (xy 263.60553 -1.600423) (xy 263.54216 -1.542654) (xy 263.484391 -1.479284)
			(xy 263.432715 -1.410855) (xy 263.387574 -1.337949) (xy 263.349352 -1.261189) (xy 263.318376 -1.18123)
			(xy 263.294909 -1.098754) (xy 263.279153 -1.014464) (xy 263.271241 -0.929081) (xy 258.775975 -0.929081)
			(xy 258.768063 -1.014464) (xy 258.752307 -1.098754) (xy 258.72884 -1.18123) (xy 258.697864 -1.261189)
			(xy 258.659642 -1.337949) (xy 258.614501 -1.410855) (xy 258.562825 -1.479284) (xy 258.505056 -1.542654)
			(xy 258.441686 -1.600423) (xy 258.373257 -1.652099) (xy 258.300351 -1.69724) (xy 258.223591 -1.735462)
			(xy 258.143632 -1.766438) (xy 258.061156 -1.789905) (xy 257.976866 -1.805661) (xy 257.891483 -1.813573)
			(xy 257.805733 -1.813573) (xy 257.72035 -1.805661) (xy 257.63606 -1.789905) (xy 257.553584 -1.766438)
			(xy 257.473625 -1.735462) (xy 257.396865 -1.69724) (xy 257.323959 -1.652099) (xy 257.25553 -1.600423)
			(xy 257.19216 -1.542654) (xy 257.134391 -1.479284) (xy 257.082715 -1.410855) (xy 257.037574 -1.337949)
			(xy 256.999352 -1.261189) (xy 256.968376 -1.18123) (xy 256.944909 -1.098754) (xy 256.929153 -1.014464)
			(xy 256.921241 -0.929081) (xy 254.465119 -0.929081) (xy 254.465087 -0.931875) (xy 254.457175 -1.017258)
			(xy 254.441419 -1.101548) (xy 254.417952 -1.184024) (xy 254.386976 -1.263983) (xy 254.348754 -1.340743)
			(xy 254.303613 -1.413649) (xy 254.251937 -1.482078) (xy 254.194168 -1.545448) (xy 254.130798 -1.603217)
			(xy 254.062369 -1.654893) (xy 253.989463 -1.700034) (xy 253.912703 -1.738256) (xy 253.832744 -1.769232)
			(xy 253.750268 -1.792699) (xy 253.665978 -1.808455) (xy 253.580595 -1.816367) (xy 253.494845 -1.816367)
			(xy 253.409462 -1.808455) (xy 253.325172 -1.792699) (xy 253.242696 -1.769232) (xy 253.162737 -1.738256)
			(xy 253.085977 -1.700034) (xy 253.013071 -1.654893) (xy 252.944642 -1.603217) (xy 252.881272 -1.545448)
			(xy 252.823503 -1.482078) (xy 252.771827 -1.413649) (xy 252.726686 -1.340743) (xy 252.688464 -1.263983)
			(xy 252.657488 -1.184024) (xy 252.634021 -1.101548) (xy 252.618265 -1.017258) (xy 252.610353 -0.931875)
			(xy 248.115087 -0.931875) (xy 248.107175 -1.017258) (xy 248.091419 -1.101548) (xy 248.067952 -1.184024)
			(xy 248.036976 -1.263983) (xy 247.998754 -1.340743) (xy 247.953613 -1.413649) (xy 247.901937 -1.482078)
			(xy 247.844168 -1.545448) (xy 247.780798 -1.603217) (xy 247.712369 -1.654893) (xy 247.639463 -1.700034)
			(xy 247.562703 -1.738256) (xy 247.482744 -1.769232) (xy 247.400268 -1.792699) (xy 247.315978 -1.808455)
			(xy 247.230595 -1.816367) (xy 247.144845 -1.816367) (xy 247.059462 -1.808455) (xy 246.975172 -1.792699)
			(xy 246.892696 -1.769232) (xy 246.812737 -1.738256) (xy 246.735977 -1.700034) (xy 246.663071 -1.654893)
			(xy 246.594642 -1.603217) (xy 246.531272 -1.545448) (xy 246.473503 -1.482078) (xy 246.421827 -1.413649)
			(xy 246.376686 -1.340743) (xy 246.338464 -1.263983) (xy 246.307488 -1.184024) (xy 246.284021 -1.101548)
			(xy 246.268265 -1.017258) (xy 246.260353 -0.931875) (xy 216.248247 -0.931875) (xy 216.240335 -1.017258)
			(xy 216.224579 -1.101548) (xy 216.201112 -1.184024) (xy 216.170136 -1.263983) (xy 216.131914 -1.340743)
			(xy 216.086773 -1.413649) (xy 216.035097 -1.482078) (xy 215.977328 -1.545448) (xy 215.913958 -1.603217)
			(xy 215.845529 -1.654893) (xy 215.772623 -1.700034) (xy 215.695863 -1.738256) (xy 215.615904 -1.769232)
			(xy 215.533428 -1.792699) (xy 215.449138 -1.808455) (xy 215.363755 -1.816367) (xy 215.278005 -1.816367)
			(xy 215.192622 -1.808455) (xy 215.108332 -1.792699) (xy 215.025856 -1.769232) (xy 214.945897 -1.738256)
			(xy 214.869137 -1.700034) (xy 214.796231 -1.654893) (xy 214.727802 -1.603217) (xy 214.664432 -1.545448)
			(xy 214.606663 -1.482078) (xy 214.554987 -1.413649) (xy 214.509846 -1.340743) (xy 214.471624 -1.263983)
			(xy 214.440648 -1.184024) (xy 214.417181 -1.101548) (xy 214.401425 -1.017258) (xy 214.393513 -0.931875)
			(xy 209.898247 -0.931875) (xy 209.890335 -1.017258) (xy 209.874579 -1.101548) (xy 209.851112 -1.184024)
			(xy 209.820136 -1.263983) (xy 209.781914 -1.340743) (xy 209.736773 -1.413649) (xy 209.685097 -1.482078)
			(xy 209.627328 -1.545448) (xy 209.563958 -1.603217) (xy 209.495529 -1.654893) (xy 209.422623 -1.700034)
			(xy 209.345863 -1.738256) (xy 209.265904 -1.769232) (xy 209.183428 -1.792699) (xy 209.099138 -1.808455)
			(xy 209.013755 -1.816367) (xy 208.928005 -1.816367) (xy 208.842622 -1.808455) (xy 208.758332 -1.792699)
			(xy 208.675856 -1.769232) (xy 208.595897 -1.738256) (xy 208.519137 -1.700034) (xy 208.446231 -1.654893)
			(xy 208.377802 -1.603217) (xy 208.314432 -1.545448) (xy 208.256663 -1.482078) (xy 208.204987 -1.413649)
			(xy 208.159846 -1.340743) (xy 208.121624 -1.263983) (xy 208.090648 -1.184024) (xy 208.067181 -1.101548)
			(xy 208.051425 -1.017258) (xy 208.043513 -0.931875) (xy 84.20989 -0.931875) (xy 84.20989 -7.78002)
			(xy 84.210412 -7.835827) (xy 84.218755 -7.947128) (xy 84.235391 -8.057495) (xy 84.260229 -8.16631)
			(xy 84.293128 -8.272964) (xy 84.333906 -8.376862) (xy 84.382334 -8.477422) (xy 84.438141 -8.574082)
			(xy 84.501016 -8.666301) (xy 84.570606 -8.753563) (xy 84.646523 -8.835382) (xy 84.728341 -8.911298)
			(xy 84.815604 -8.980888) (xy 84.907824 -9.043762) (xy 85.004484 -9.099569) (xy 85.105044 -9.147996)
			(xy 85.208942 -9.188774) (xy 85.315596 -9.221673) (xy 85.424411 -9.24651) (xy 85.534778 -9.263146)
			(xy 85.646079 -9.271488) (xy 85.701886 -9.272016) (xy 122.102118 -9.272016) (xy 122.157925 -9.271494)
			(xy 122.269226 -9.263152) (xy 122.379593 -9.246515) (xy 122.488409 -9.221678) (xy 122.595063 -9.188778)
			(xy 122.698961 -9.148001) (xy 122.799522 -9.099573) (xy 122.896182 -9.043766) (xy 122.988401 -8.980891)
			(xy 123.075664 -8.911301) (xy 123.157483 -8.835384) (xy 123.2334 -8.753566) (xy 123.30299 -8.666303)
			(xy 123.365865 -8.574084) (xy 123.421672 -8.477423) (xy 123.4701 -8.376863) (xy 123.510878 -8.272965)
			(xy 123.543777 -8.16631) (xy 123.568615 -8.057495) (xy 123.585251 -7.947128) (xy 123.593594 -7.835827)
			(xy 123.594114 -7.78002) (xy 123.594114 -4.2799) (xy 123.594598 -4.209546) (xy 123.602488 -4.06906)
			(xy 123.618242 -3.929237) (xy 123.641812 -3.790517) (xy 123.673122 -3.653337) (xy 123.712075 -3.518129)
			(xy 123.758548 -3.385317) (xy 123.812395 -3.25532) (xy 123.873446 -3.128547) (xy 123.941509 -3.005396)
			(xy 124.01637 -2.886255) (xy 124.097794 -2.7715) (xy 124.185524 -2.66149) (xy 124.279284 -2.556573)
			(xy 124.37878 -2.457077) (xy 124.483698 -2.363317) (xy 124.593708 -2.275588) (xy 124.708464 -2.194165)
			(xy 124.827605 -2.119304) (xy 124.950755 -2.051241) (xy 125.077529 -1.990191) (xy 125.207526 -1.936345)
			(xy 125.340338 -1.889872) (xy 125.475547 -1.85092) (xy 125.612727 -1.81961) (xy 125.751447 -1.796041)
			(xy 125.89127 -1.780287) (xy 126.031756 -1.772398) (xy 126.10211 -1.771904) (xy 194.701922 -1.771904)
			(xy 194.772275 -1.772398) (xy 194.912761 -1.780289) (xy 195.052582 -1.796044) (xy 195.191301 -1.819614)
			(xy 195.32848 -1.850925) (xy 195.463687 -1.889879) (xy 195.596497 -1.936352) (xy 195.726493 -1.990199)
			(xy 195.853265 -2.05125) (xy 195.976414 -2.119314) (xy 196.095554 -2.194175) (xy 196.210308 -2.275598)
			(xy 196.320316 -2.363328) (xy 196.425233 -2.457088) (xy 196.524727 -2.556583) (xy 196.618486 -2.6615)
			(xy 196.706215 -2.77151) (xy 196.787637 -2.886265) (xy 196.862497 -3.005405) (xy 196.93056 -3.128555)
			(xy 196.99161 -3.255327) (xy 197.045455 -3.385323) (xy 197.075741 -3.471875) (xy 208.043513 -3.471875)
			(xy 208.043513 -3.386125) (xy 208.051425 -3.300742) (xy 208.067181 -3.216452) (xy 208.090648 -3.133976)
			(xy 208.121624 -3.054017) (xy 208.159846 -2.977257) (xy 208.204987 -2.904351) (xy 208.256663 -2.835922)
			(xy 208.314432 -2.772552) (xy 208.377802 -2.714783) (xy 208.446231 -2.663107) (xy 208.519137 -2.617966)
			(xy 208.595897 -2.579744) (xy 208.675856 -2.548768) (xy 208.758332 -2.525301) (xy 208.842622 -2.509545)
			(xy 208.928005 -2.501633) (xy 209.013755 -2.501633) (xy 209.099138 -2.509545) (xy 209.183428 -2.525301)
			(xy 209.265904 -2.548768) (xy 209.345863 -2.579744) (xy 209.368066 -2.5908) (xy 212.978492 -2.5908)
			(xy 212.978492 -1.7272) (xy 212.978978 -1.699931) (xy 212.98674 -1.645947) (xy 213.002105 -1.593617)
			(xy 213.024762 -1.544007) (xy 213.054248 -1.498126) (xy 213.089963 -1.456909) (xy 213.13118 -1.421194)
			(xy 213.177061 -1.391708) (xy 213.226671 -1.369051) (xy 213.279001 -1.353686) (xy 213.332985 -1.345924)
			(xy 213.387523 -1.345924) (xy 213.441507 -1.353686) (xy 213.493837 -1.369051) (xy 213.543447 -1.391708)
			(xy 213.589328 -1.421194) (xy 213.630545 -1.456909) (xy 213.66626 -1.498126) (xy 213.695746 -1.544007)
			(xy 213.718403 -1.593617) (xy 213.733768 -1.645947) (xy 213.74153 -1.699931) (xy 213.742016 -1.7272)
			(xy 213.742016 -2.5908) (xy 213.74153 -2.618069) (xy 213.733768 -2.672053) (xy 213.718403 -2.724383)
			(xy 213.695746 -2.773993) (xy 213.66626 -2.819874) (xy 213.630545 -2.861091) (xy 213.589328 -2.896806)
			(xy 213.543447 -2.926292) (xy 213.493837 -2.948949) (xy 213.441507 -2.964314) (xy 213.387523 -2.972076)
			(xy 213.332985 -2.972076) (xy 213.279001 -2.964314) (xy 213.226671 -2.948949) (xy 213.177061 -2.926292)
			(xy 213.13118 -2.896806) (xy 213.089963 -2.861091) (xy 213.054248 -2.819874) (xy 213.024762 -2.773993)
			(xy 213.002105 -2.724383) (xy 212.98674 -2.672053) (xy 212.978978 -2.618069) (xy 212.978492 -2.5908)
			(xy 209.368066 -2.5908) (xy 209.422623 -2.617966) (xy 209.495529 -2.663107) (xy 209.563958 -2.714783)
			(xy 209.627328 -2.772552) (xy 209.685097 -2.835922) (xy 209.736773 -2.904351) (xy 209.781914 -2.977257)
			(xy 209.820136 -3.054017) (xy 209.851112 -3.133976) (xy 209.874579 -3.216452) (xy 209.890335 -3.300742)
			(xy 209.898247 -3.386125) (xy 209.898742 -3.429) (xy 209.898247 -3.471875) (xy 214.393513 -3.471875)
			(xy 214.393513 -3.386125) (xy 214.401425 -3.300742) (xy 214.417181 -3.216452) (xy 214.440648 -3.133976)
			(xy 214.471624 -3.054017) (xy 214.509846 -2.977257) (xy 214.554987 -2.904351) (xy 214.606663 -2.835922)
			(xy 214.664432 -2.772552) (xy 214.727802 -2.714783) (xy 214.796231 -2.663107) (xy 214.869137 -2.617966)
			(xy 214.945897 -2.579744) (xy 215.025856 -2.548768) (xy 215.108332 -2.525301) (xy 215.192622 -2.509545)
			(xy 215.278005 -2.501633) (xy 215.363755 -2.501633) (xy 215.449138 -2.509545) (xy 215.533428 -2.525301)
			(xy 215.615904 -2.548768) (xy 215.695863 -2.579744) (xy 215.772623 -2.617966) (xy 215.845529 -2.663107)
			(xy 215.913958 -2.714783) (xy 215.977328 -2.772552) (xy 216.035097 -2.835922) (xy 216.086773 -2.904351)
			(xy 216.131914 -2.977257) (xy 216.170136 -3.054017) (xy 216.201112 -3.133976) (xy 216.224579 -3.216452)
			(xy 216.240335 -3.300742) (xy 216.248247 -3.386125) (xy 216.248742 -3.429) (xy 216.248247 -3.471875)
			(xy 246.260353 -3.471875) (xy 246.260353 -3.386125) (xy 246.268265 -3.300742) (xy 246.284021 -3.216452)
			(xy 246.307488 -3.133976) (xy 246.338464 -3.054017) (xy 246.376686 -2.977257) (xy 246.421827 -2.904351)
			(xy 246.473503 -2.835922) (xy 246.531272 -2.772552) (xy 246.594642 -2.714783) (xy 246.663071 -2.663107)
			(xy 246.735977 -2.617966) (xy 246.812737 -2.579744) (xy 246.892696 -2.548768) (xy 246.975172 -2.525301)
			(xy 247.059462 -2.509545) (xy 247.144845 -2.501633) (xy 247.230595 -2.501633) (xy 247.315978 -2.509545)
			(xy 247.400268 -2.525301) (xy 247.482744 -2.548768) (xy 247.562703 -2.579744) (xy 247.584906 -2.5908)
			(xy 248.766584 -2.5908) (xy 248.766584 -1.7272) (xy 248.76707 -1.699931) (xy 248.774832 -1.645947)
			(xy 248.790197 -1.593617) (xy 248.812854 -1.544007) (xy 248.84234 -1.498126) (xy 248.878055 -1.456909)
			(xy 248.919272 -1.421194) (xy 248.965153 -1.391708) (xy 249.014763 -1.369051) (xy 249.067093 -1.353686)
			(xy 249.121077 -1.345924) (xy 249.175615 -1.345924) (xy 249.229599 -1.353686) (xy 249.281929 -1.369051)
			(xy 249.331539 -1.391708) (xy 249.37742 -1.421194) (xy 249.418637 -1.456909) (xy 249.454352 -1.498126)
			(xy 249.483838 -1.544007) (xy 249.506495 -1.593617) (xy 249.52186 -1.645947) (xy 249.529622 -1.699931)
			(xy 249.530108 -1.7272) (xy 249.530108 -2.5908) (xy 249.529622 -2.618069) (xy 249.52186 -2.672053)
			(xy 249.506495 -2.724383) (xy 249.483838 -2.773993) (xy 249.454352 -2.819874) (xy 249.418637 -2.861091)
			(xy 249.37742 -2.896806) (xy 249.331539 -2.926292) (xy 249.281929 -2.948949) (xy 249.229599 -2.964314)
			(xy 249.175615 -2.972076) (xy 249.121077 -2.972076) (xy 249.067093 -2.964314) (xy 249.014763 -2.948949)
			(xy 248.965153 -2.926292) (xy 248.919272 -2.896806) (xy 248.878055 -2.861091) (xy 248.84234 -2.819874)
			(xy 248.812854 -2.773993) (xy 248.790197 -2.724383) (xy 248.774832 -2.672053) (xy 248.76707 -2.618069)
			(xy 248.766584 -2.5908) (xy 247.584906 -2.5908) (xy 247.639463 -2.617966) (xy 247.712369 -2.663107)
			(xy 247.780798 -2.714783) (xy 247.844168 -2.772552) (xy 247.901937 -2.835922) (xy 247.953613 -2.904351)
			(xy 247.998754 -2.977257) (xy 248.036976 -3.054017) (xy 248.067952 -3.133976) (xy 248.091419 -3.216452)
			(xy 248.107175 -3.300742) (xy 248.115087 -3.386125) (xy 248.115582 -3.429) (xy 248.115087 -3.471875)
			(xy 252.610353 -3.471875) (xy 252.610353 -3.386125) (xy 252.618265 -3.300742) (xy 252.634021 -3.216452)
			(xy 252.657488 -3.133976) (xy 252.688464 -3.054017) (xy 252.726686 -2.977257) (xy 252.771827 -2.904351)
			(xy 252.823503 -2.835922) (xy 252.881272 -2.772552) (xy 252.944642 -2.714783) (xy 253.013071 -2.663107)
			(xy 253.085977 -2.617966) (xy 253.162737 -2.579744) (xy 253.242696 -2.548768) (xy 253.325172 -2.525301)
			(xy 253.409462 -2.509545) (xy 253.494845 -2.501633) (xy 253.580595 -2.501633) (xy 253.665978 -2.509545)
			(xy 253.750268 -2.525301) (xy 253.832744 -2.548768) (xy 253.912703 -2.579744) (xy 253.989463 -2.617966)
			(xy 254.062369 -2.663107) (xy 254.130798 -2.714783) (xy 254.194168 -2.772552) (xy 254.251937 -2.835922)
			(xy 254.303613 -2.904351) (xy 254.348754 -2.977257) (xy 254.386976 -3.054017) (xy 254.417952 -3.133976)
			(xy 254.441419 -3.216452) (xy 254.457175 -3.300742) (xy 254.465087 -3.386125) (xy 254.465582 -3.429)
			(xy 254.465119 -3.469081) (xy 256.921241 -3.469081) (xy 256.921241 -3.383331) (xy 256.929153 -3.297948)
			(xy 256.944909 -3.213658) (xy 256.968376 -3.131182) (xy 256.999352 -3.051223) (xy 257.037574 -2.974463)
			(xy 257.082715 -2.901557) (xy 257.134391 -2.833128) (xy 257.19216 -2.769758) (xy 257.25553 -2.711989)
			(xy 257.323959 -2.660313) (xy 257.396865 -2.615172) (xy 257.473625 -2.57695) (xy 257.553584 -2.545974)
			(xy 257.63606 -2.522507) (xy 257.72035 -2.506751) (xy 257.805733 -2.498839) (xy 257.891483 -2.498839)
			(xy 257.976866 -2.506751) (xy 258.061156 -2.522507) (xy 258.143632 -2.545974) (xy 258.223591 -2.57695)
			(xy 258.300351 -2.615172) (xy 258.373257 -2.660313) (xy 258.441686 -2.711989) (xy 258.505056 -2.769758)
			(xy 258.562825 -2.833128) (xy 258.614501 -2.901557) (xy 258.659642 -2.974463) (xy 258.697864 -3.051223)
			(xy 258.72884 -3.131182) (xy 258.752307 -3.213658) (xy 258.768063 -3.297948) (xy 258.775975 -3.383331)
			(xy 258.77647 -3.426206) (xy 258.775975 -3.469081) (xy 263.271241 -3.469081) (xy 263.271241 -3.383331)
			(xy 263.279153 -3.297948) (xy 263.294909 -3.213658) (xy 263.318376 -3.131182) (xy 263.349352 -3.051223)
			(xy 263.387574 -2.974463) (xy 263.432715 -2.901557) (xy 263.484391 -2.833128) (xy 263.54216 -2.769758)
			(xy 263.60553 -2.711989) (xy 263.673959 -2.660313) (xy 263.746865 -2.615172) (xy 263.823625 -2.57695)
			(xy 263.903584 -2.545974) (xy 263.98606 -2.522507) (xy 264.07035 -2.506751) (xy 264.155733 -2.498839)
			(xy 264.241483 -2.498839) (xy 264.326866 -2.506751) (xy 264.411156 -2.522507) (xy 264.493632 -2.545974)
			(xy 264.573591 -2.57695) (xy 264.650351 -2.615172) (xy 264.723257 -2.660313) (xy 264.791686 -2.711989)
			(xy 264.855056 -2.769758) (xy 264.912825 -2.833128) (xy 264.964501 -2.901557) (xy 265.009642 -2.974463)
			(xy 265.047864 -3.051223) (xy 265.07884 -3.131182) (xy 265.102307 -3.213658) (xy 265.118063 -3.297948)
			(xy 265.125975 -3.383331) (xy 265.12647 -3.426206) (xy 265.125975 -3.469081) (xy 324.845921 -3.469081)
			(xy 324.845921 -3.383331) (xy 324.853833 -3.297948) (xy 324.869589 -3.213658) (xy 324.893056 -3.131182)
			(xy 324.924032 -3.051223) (xy 324.962254 -2.974463) (xy 325.007395 -2.901557) (xy 325.059071 -2.833128)
			(xy 325.11684 -2.769758) (xy 325.18021 -2.711989) (xy 325.248639 -2.660313) (xy 325.321545 -2.615172)
			(xy 325.398305 -2.57695) (xy 325.478264 -2.545974) (xy 325.56074 -2.522507) (xy 325.64503 -2.506751)
			(xy 325.730413 -2.498839) (xy 325.816163 -2.498839) (xy 325.901546 -2.506751) (xy 325.985836 -2.522507)
			(xy 326.068312 -2.545974) (xy 326.148271 -2.57695) (xy 326.225031 -2.615172) (xy 326.297937 -2.660313)
			(xy 326.366366 -2.711989) (xy 326.429736 -2.769758) (xy 326.487505 -2.833128) (xy 326.539181 -2.901557)
			(xy 326.584322 -2.974463) (xy 326.622544 -3.051223) (xy 326.65352 -3.131182) (xy 326.676987 -3.213658)
			(xy 326.692743 -3.297948) (xy 326.700655 -3.383331) (xy 326.70115 -3.426206) (xy 326.700655 -3.469081)
			(xy 331.195921 -3.469081) (xy 331.195921 -3.383331) (xy 331.203833 -3.297948) (xy 331.219589 -3.213658)
			(xy 331.243056 -3.131182) (xy 331.274032 -3.051223) (xy 331.312254 -2.974463) (xy 331.357395 -2.901557)
			(xy 331.409071 -2.833128) (xy 331.46684 -2.769758) (xy 331.53021 -2.711989) (xy 331.598639 -2.660313)
			(xy 331.671545 -2.615172) (xy 331.748305 -2.57695) (xy 331.828264 -2.545974) (xy 331.91074 -2.522507)
			(xy 331.99503 -2.506751) (xy 332.080413 -2.498839) (xy 332.166163 -2.498839) (xy 332.251546 -2.506751)
			(xy 332.335836 -2.522507) (xy 332.418312 -2.545974) (xy 332.498271 -2.57695) (xy 332.575031 -2.615172)
			(xy 332.647937 -2.660313) (xy 332.716366 -2.711989) (xy 332.779736 -2.769758) (xy 332.837505 -2.833128)
			(xy 332.889181 -2.901557) (xy 332.934322 -2.974463) (xy 332.972544 -3.051223) (xy 333.00352 -3.131182)
			(xy 333.026987 -3.213658) (xy 333.042743 -3.297948) (xy 333.050655 -3.383331) (xy 333.05115 -3.426206)
			(xy 333.050655 -3.469081) (xy 335.488267 -3.469081) (xy 335.488267 -3.383331) (xy 335.496179 -3.297948)
			(xy 335.511935 -3.213658) (xy 335.535402 -3.131182) (xy 335.566378 -3.051223) (xy 335.6046 -2.974463)
			(xy 335.649741 -2.901557) (xy 335.701417 -2.833128) (xy 335.759186 -2.769758) (xy 335.822556 -2.711989)
			(xy 335.890985 -2.660313) (xy 335.963891 -2.615172) (xy 336.040651 -2.57695) (xy 336.12061 -2.545974)
			(xy 336.203086 -2.522507) (xy 336.287376 -2.506751) (xy 336.372759 -2.498839) (xy 336.458509 -2.498839)
			(xy 336.543892 -2.506751) (xy 336.628182 -2.522507) (xy 336.710658 -2.545974) (xy 336.790617 -2.57695)
			(xy 336.867377 -2.615172) (xy 336.940283 -2.660313) (xy 337.008712 -2.711989) (xy 337.072082 -2.769758)
			(xy 337.129851 -2.833128) (xy 337.181527 -2.901557) (xy 337.226668 -2.974463) (xy 337.26489 -3.051223)
			(xy 337.295866 -3.131182) (xy 337.319333 -3.213658) (xy 337.335089 -3.297948) (xy 337.343001 -3.383331)
			(xy 337.343496 -3.426206) (xy 337.343001 -3.469081) (xy 341.838267 -3.469081) (xy 341.838267 -3.383331)
			(xy 341.846179 -3.297948) (xy 341.861935 -3.213658) (xy 341.885402 -3.131182) (xy 341.916378 -3.051223)
			(xy 341.9546 -2.974463) (xy 341.999741 -2.901557) (xy 342.051417 -2.833128) (xy 342.109186 -2.769758)
			(xy 342.172556 -2.711989) (xy 342.240985 -2.660313) (xy 342.313891 -2.615172) (xy 342.390651 -2.57695)
			(xy 342.47061 -2.545974) (xy 342.553086 -2.522507) (xy 342.637376 -2.506751) (xy 342.722759 -2.498839)
			(xy 342.808509 -2.498839) (xy 342.893892 -2.506751) (xy 342.978182 -2.522507) (xy 343.060658 -2.545974)
			(xy 343.140617 -2.57695) (xy 343.217377 -2.615172) (xy 343.290283 -2.660313) (xy 343.358712 -2.711989)
			(xy 343.422082 -2.769758) (xy 343.479851 -2.833128) (xy 343.531527 -2.901557) (xy 343.576668 -2.974463)
			(xy 343.61489 -3.051223) (xy 343.645866 -3.131182) (xy 343.669333 -3.213658) (xy 343.685089 -3.297948)
			(xy 343.693001 -3.383331) (xy 343.693496 -3.426206) (xy 343.693001 -3.469081) (xy 373.705107 -3.469081)
			(xy 373.705107 -3.383331) (xy 373.713019 -3.297948) (xy 373.728775 -3.213658) (xy 373.752242 -3.131182)
			(xy 373.783218 -3.051223) (xy 373.82144 -2.974463) (xy 373.866581 -2.901557) (xy 373.918257 -2.833128)
			(xy 373.976026 -2.769758) (xy 374.039396 -2.711989) (xy 374.107825 -2.660313) (xy 374.180731 -2.615172)
			(xy 374.257491 -2.57695) (xy 374.33745 -2.545974) (xy 374.419926 -2.522507) (xy 374.504216 -2.506751)
			(xy 374.589599 -2.498839) (xy 374.675349 -2.498839) (xy 374.760732 -2.506751) (xy 374.845022 -2.522507)
			(xy 374.927498 -2.545974) (xy 375.007457 -2.57695) (xy 375.084217 -2.615172) (xy 375.157123 -2.660313)
			(xy 375.225552 -2.711989) (xy 375.288922 -2.769758) (xy 375.346691 -2.833128) (xy 375.398367 -2.901557)
			(xy 375.443508 -2.974463) (xy 375.48173 -3.051223) (xy 375.512706 -3.131182) (xy 375.536173 -3.213658)
			(xy 375.551929 -3.297948) (xy 375.559841 -3.383331) (xy 375.560336 -3.426206) (xy 375.559841 -3.469081)
			(xy 380.055107 -3.469081) (xy 380.055107 -3.383331) (xy 380.063019 -3.297948) (xy 380.078775 -3.213658)
			(xy 380.102242 -3.131182) (xy 380.133218 -3.051223) (xy 380.17144 -2.974463) (xy 380.216581 -2.901557)
			(xy 380.268257 -2.833128) (xy 380.326026 -2.769758) (xy 380.389396 -2.711989) (xy 380.457825 -2.660313)
			(xy 380.530731 -2.615172) (xy 380.607491 -2.57695) (xy 380.68745 -2.545974) (xy 380.769926 -2.522507)
			(xy 380.854216 -2.506751) (xy 380.939599 -2.498839) (xy 381.025349 -2.498839) (xy 381.110732 -2.506751)
			(xy 381.195022 -2.522507) (xy 381.277498 -2.545974) (xy 381.357457 -2.57695) (xy 381.434217 -2.615172)
			(xy 381.507123 -2.660313) (xy 381.575552 -2.711989) (xy 381.638922 -2.769758) (xy 381.696691 -2.833128)
			(xy 381.748367 -2.901557) (xy 381.793508 -2.974463) (xy 381.83173 -3.051223) (xy 381.862706 -3.131182)
			(xy 381.886173 -3.213658) (xy 381.901929 -3.297948) (xy 381.909841 -3.383331) (xy 381.910336 -3.426206)
			(xy 381.909841 -3.469081) (xy 381.901929 -3.554464) (xy 381.886173 -3.638754) (xy 381.862706 -3.72123)
			(xy 381.83173 -3.801189) (xy 381.793508 -3.877949) (xy 381.748367 -3.950855) (xy 381.696691 -4.019284)
			(xy 381.638922 -4.082654) (xy 381.575552 -4.140423) (xy 381.507123 -4.192099) (xy 381.434217 -4.23724)
			(xy 381.357457 -4.275462) (xy 381.277498 -4.306438) (xy 381.195022 -4.329905) (xy 381.110732 -4.345661)
			(xy 381.025349 -4.353573) (xy 380.939599 -4.353573) (xy 380.854216 -4.345661) (xy 380.769926 -4.329905)
			(xy 380.68745 -4.306438) (xy 380.607491 -4.275462) (xy 380.530731 -4.23724) (xy 380.457825 -4.192099)
			(xy 380.389396 -4.140423) (xy 380.326026 -4.082654) (xy 380.268257 -4.019284) (xy 380.216581 -3.950855)
			(xy 380.17144 -3.877949) (xy 380.133218 -3.801189) (xy 380.102242 -3.72123) (xy 380.078775 -3.638754)
			(xy 380.063019 -3.554464) (xy 380.055107 -3.469081) (xy 375.559841 -3.469081) (xy 375.551929 -3.554464)
			(xy 375.536173 -3.638754) (xy 375.512706 -3.72123) (xy 375.48173 -3.801189) (xy 375.443508 -3.877949)
			(xy 375.398367 -3.950855) (xy 375.346691 -4.019284) (xy 375.288922 -4.082654) (xy 375.225552 -4.140423)
			(xy 375.157123 -4.192099) (xy 375.084217 -4.23724) (xy 375.007457 -4.275462) (xy 374.927498 -4.306438)
			(xy 374.845022 -4.329905) (xy 374.760732 -4.345661) (xy 374.675349 -4.353573) (xy 374.589599 -4.353573)
			(xy 374.504216 -4.345661) (xy 374.419926 -4.329905) (xy 374.33745 -4.306438) (xy 374.257491 -4.275462)
			(xy 374.180731 -4.23724) (xy 374.107825 -4.192099) (xy 374.039396 -4.140423) (xy 373.976026 -4.082654)
			(xy 373.918257 -4.019284) (xy 373.866581 -3.950855) (xy 373.82144 -3.877949) (xy 373.783218 -3.801189)
			(xy 373.752242 -3.72123) (xy 373.728775 -3.638754) (xy 373.713019 -3.554464) (xy 373.705107 -3.469081)
			(xy 343.693001 -3.469081) (xy 343.685089 -3.554464) (xy 343.669333 -3.638754) (xy 343.645866 -3.72123)
			(xy 343.61489 -3.801189) (xy 343.576668 -3.877949) (xy 343.531527 -3.950855) (xy 343.479851 -4.019284)
			(xy 343.422082 -4.082654) (xy 343.358712 -4.140423) (xy 343.290283 -4.192099) (xy 343.217377 -4.23724)
			(xy 343.140617 -4.275462) (xy 343.060658 -4.306438) (xy 342.978182 -4.329905) (xy 342.893892 -4.345661)
			(xy 342.808509 -4.353573) (xy 342.722759 -4.353573) (xy 342.637376 -4.345661) (xy 342.553086 -4.329905)
			(xy 342.47061 -4.306438) (xy 342.390651 -4.275462) (xy 342.313891 -4.23724) (xy 342.240985 -4.192099)
			(xy 342.172556 -4.140423) (xy 342.109186 -4.082654) (xy 342.051417 -4.019284) (xy 341.999741 -3.950855)
			(xy 341.9546 -3.877949) (xy 341.916378 -3.801189) (xy 341.885402 -3.72123) (xy 341.861935 -3.638754)
			(xy 341.846179 -3.554464) (xy 341.838267 -3.469081) (xy 337.343001 -3.469081) (xy 337.335089 -3.554464)
			(xy 337.319333 -3.638754) (xy 337.295866 -3.72123) (xy 337.26489 -3.801189) (xy 337.226668 -3.877949)
			(xy 337.181527 -3.950855) (xy 337.129851 -4.019284) (xy 337.072082 -4.082654) (xy 337.008712 -4.140423)
			(xy 336.940283 -4.192099) (xy 336.867377 -4.23724) (xy 336.790617 -4.275462) (xy 336.710658 -4.306438)
			(xy 336.628182 -4.329905) (xy 336.543892 -4.345661) (xy 336.458509 -4.353573) (xy 336.372759 -4.353573)
			(xy 336.287376 -4.345661) (xy 336.203086 -4.329905) (xy 336.12061 -4.306438) (xy 336.040651 -4.275462)
			(xy 335.963891 -4.23724) (xy 335.890985 -4.192099) (xy 335.822556 -4.140423) (xy 335.759186 -4.082654)
			(xy 335.701417 -4.019284) (xy 335.649741 -3.950855) (xy 335.6046 -3.877949) (xy 335.566378 -3.801189)
			(xy 335.535402 -3.72123) (xy 335.511935 -3.638754) (xy 335.496179 -3.554464) (xy 335.488267 -3.469081)
			(xy 333.050655 -3.469081) (xy 333.042743 -3.554464) (xy 333.026987 -3.638754) (xy 333.00352 -3.72123)
			(xy 332.972544 -3.801189) (xy 332.934322 -3.877949) (xy 332.889181 -3.950855) (xy 332.837505 -4.019284)
			(xy 332.779736 -4.082654) (xy 332.716366 -4.140423) (xy 332.647937 -4.192099) (xy 332.575031 -4.23724)
			(xy 332.498271 -4.275462) (xy 332.418312 -4.306438) (xy 332.335836 -4.329905) (xy 332.251546 -4.345661)
			(xy 332.166163 -4.353573) (xy 332.080413 -4.353573) (xy 331.99503 -4.345661) (xy 331.91074 -4.329905)
			(xy 331.828264 -4.306438) (xy 331.748305 -4.275462) (xy 331.671545 -4.23724) (xy 331.598639 -4.192099)
			(xy 331.53021 -4.140423) (xy 331.46684 -4.082654) (xy 331.409071 -4.019284) (xy 331.357395 -3.950855)
			(xy 331.312254 -3.877949) (xy 331.274032 -3.801189) (xy 331.243056 -3.72123) (xy 331.219589 -3.638754)
			(xy 331.203833 -3.554464) (xy 331.195921 -3.469081) (xy 326.700655 -3.469081) (xy 326.692743 -3.554464)
			(xy 326.676987 -3.638754) (xy 326.65352 -3.72123) (xy 326.622544 -3.801189) (xy 326.584322 -3.877949)
			(xy 326.539181 -3.950855) (xy 326.487505 -4.019284) (xy 326.429736 -4.082654) (xy 326.366366 -4.140423)
			(xy 326.297937 -4.192099) (xy 326.225031 -4.23724) (xy 326.148271 -4.275462) (xy 326.068312 -4.306438)
			(xy 325.985836 -4.329905) (xy 325.901546 -4.345661) (xy 325.816163 -4.353573) (xy 325.730413 -4.353573)
			(xy 325.64503 -4.345661) (xy 325.56074 -4.329905) (xy 325.478264 -4.306438) (xy 325.398305 -4.275462)
			(xy 325.321545 -4.23724) (xy 325.248639 -4.192099) (xy 325.18021 -4.140423) (xy 325.11684 -4.082654)
			(xy 325.059071 -4.019284) (xy 325.007395 -3.950855) (xy 324.962254 -3.877949) (xy 324.924032 -3.801189)
			(xy 324.893056 -3.72123) (xy 324.869589 -3.638754) (xy 324.853833 -3.554464) (xy 324.845921 -3.469081)
			(xy 265.125975 -3.469081) (xy 265.118063 -3.554464) (xy 265.102307 -3.638754) (xy 265.07884 -3.72123)
			(xy 265.047864 -3.801189) (xy 265.009642 -3.877949) (xy 264.964501 -3.950855) (xy 264.912825 -4.019284)
			(xy 264.855056 -4.082654) (xy 264.791686 -4.140423) (xy 264.723257 -4.192099) (xy 264.650351 -4.23724)
			(xy 264.573591 -4.275462) (xy 264.493632 -4.306438) (xy 264.411156 -4.329905) (xy 264.326866 -4.345661)
			(xy 264.241483 -4.353573) (xy 264.155733 -4.353573) (xy 264.07035 -4.345661) (xy 263.98606 -4.329905)
			(xy 263.903584 -4.306438) (xy 263.823625 -4.275462) (xy 263.746865 -4.23724) (xy 263.673959 -4.192099)
			(xy 263.60553 -4.140423) (xy 263.54216 -4.082654) (xy 263.484391 -4.019284) (xy 263.432715 -3.950855)
			(xy 263.387574 -3.877949) (xy 263.349352 -3.801189) (xy 263.318376 -3.72123) (xy 263.294909 -3.638754)
			(xy 263.279153 -3.554464) (xy 263.271241 -3.469081) (xy 258.775975 -3.469081) (xy 258.768063 -3.554464)
			(xy 258.752307 -3.638754) (xy 258.72884 -3.72123) (xy 258.697864 -3.801189) (xy 258.659642 -3.877949)
			(xy 258.614501 -3.950855) (xy 258.562825 -4.019284) (xy 258.505056 -4.082654) (xy 258.441686 -4.140423)
			(xy 258.373257 -4.192099) (xy 258.300351 -4.23724) (xy 258.223591 -4.275462) (xy 258.143632 -4.306438)
			(xy 258.061156 -4.329905) (xy 257.976866 -4.345661) (xy 257.891483 -4.353573) (xy 257.805733 -4.353573)
			(xy 257.72035 -4.345661) (xy 257.63606 -4.329905) (xy 257.553584 -4.306438) (xy 257.473625 -4.275462)
			(xy 257.396865 -4.23724) (xy 257.323959 -4.192099) (xy 257.25553 -4.140423) (xy 257.19216 -4.082654)
			(xy 257.134391 -4.019284) (xy 257.082715 -3.950855) (xy 257.037574 -3.877949) (xy 256.999352 -3.801189)
			(xy 256.968376 -3.72123) (xy 256.944909 -3.638754) (xy 256.929153 -3.554464) (xy 256.921241 -3.469081)
			(xy 254.465119 -3.469081) (xy 254.465087 -3.471875) (xy 254.457175 -3.557258) (xy 254.441419 -3.641548)
			(xy 254.417952 -3.724024) (xy 254.386976 -3.803983) (xy 254.348754 -3.880743) (xy 254.303613 -3.953649)
			(xy 254.251937 -4.022078) (xy 254.194168 -4.085448) (xy 254.130798 -4.143217) (xy 254.062369 -4.194893)
			(xy 253.989463 -4.240034) (xy 253.912703 -4.278256) (xy 253.832744 -4.309232) (xy 253.750268 -4.332699)
			(xy 253.665978 -4.348455) (xy 253.580595 -4.356367) (xy 253.494845 -4.356367) (xy 253.409462 -4.348455)
			(xy 253.325172 -4.332699) (xy 253.242696 -4.309232) (xy 253.162737 -4.278256) (xy 253.085977 -4.240034)
			(xy 253.013071 -4.194893) (xy 252.944642 -4.143217) (xy 252.881272 -4.085448) (xy 252.823503 -4.022078)
			(xy 252.771827 -3.953649) (xy 252.726686 -3.880743) (xy 252.688464 -3.803983) (xy 252.657488 -3.724024)
			(xy 252.634021 -3.641548) (xy 252.618265 -3.557258) (xy 252.610353 -3.471875) (xy 248.115087 -3.471875)
			(xy 248.107175 -3.557258) (xy 248.091419 -3.641548) (xy 248.067952 -3.724024) (xy 248.036976 -3.803983)
			(xy 247.998754 -3.880743) (xy 247.953613 -3.953649) (xy 247.901937 -4.022078) (xy 247.844168 -4.085448)
			(xy 247.780798 -4.143217) (xy 247.712369 -4.194893) (xy 247.639463 -4.240034) (xy 247.562703 -4.278256)
			(xy 247.482744 -4.309232) (xy 247.400268 -4.332699) (xy 247.315978 -4.348455) (xy 247.230595 -4.356367)
			(xy 247.144845 -4.356367) (xy 247.059462 -4.348455) (xy 246.975172 -4.332699) (xy 246.892696 -4.309232)
			(xy 246.812737 -4.278256) (xy 246.735977 -4.240034) (xy 246.663071 -4.194893) (xy 246.594642 -4.143217)
			(xy 246.531272 -4.085448) (xy 246.473503 -4.022078) (xy 246.421827 -3.953649) (xy 246.376686 -3.880743)
			(xy 246.338464 -3.803983) (xy 246.307488 -3.724024) (xy 246.284021 -3.641548) (xy 246.268265 -3.557258)
			(xy 246.260353 -3.471875) (xy 216.248247 -3.471875) (xy 216.240335 -3.557258) (xy 216.224579 -3.641548)
			(xy 216.201112 -3.724024) (xy 216.170136 -3.803983) (xy 216.131914 -3.880743) (xy 216.086773 -3.953649)
			(xy 216.035097 -4.022078) (xy 215.977328 -4.085448) (xy 215.913958 -4.143217) (xy 215.845529 -4.194893)
			(xy 215.772623 -4.240034) (xy 215.695863 -4.278256) (xy 215.615904 -4.309232) (xy 215.533428 -4.332699)
			(xy 215.449138 -4.348455) (xy 215.363755 -4.356367) (xy 215.278005 -4.356367) (xy 215.192622 -4.348455)
			(xy 215.108332 -4.332699) (xy 215.025856 -4.309232) (xy 214.945897 -4.278256) (xy 214.869137 -4.240034)
			(xy 214.796231 -4.194893) (xy 214.727802 -4.143217) (xy 214.664432 -4.085448) (xy 214.606663 -4.022078)
			(xy 214.554987 -3.953649) (xy 214.509846 -3.880743) (xy 214.471624 -3.803983) (xy 214.440648 -3.724024)
			(xy 214.417181 -3.641548) (xy 214.401425 -3.557258) (xy 214.393513 -3.471875) (xy 209.898247 -3.471875)
			(xy 209.890335 -3.557258) (xy 209.874579 -3.641548) (xy 209.851112 -3.724024) (xy 209.820136 -3.803983)
			(xy 209.781914 -3.880743) (xy 209.736773 -3.953649) (xy 209.685097 -4.022078) (xy 209.627328 -4.085448)
			(xy 209.563958 -4.143217) (xy 209.495529 -4.194893) (xy 209.422623 -4.240034) (xy 209.345863 -4.278256)
			(xy 209.265904 -4.309232) (xy 209.183428 -4.332699) (xy 209.099138 -4.348455) (xy 209.013755 -4.356367)
			(xy 208.928005 -4.356367) (xy 208.842622 -4.348455) (xy 208.758332 -4.332699) (xy 208.675856 -4.309232)
			(xy 208.595897 -4.278256) (xy 208.519137 -4.240034) (xy 208.446231 -4.194893) (xy 208.377802 -4.143217)
			(xy 208.314432 -4.085448) (xy 208.256663 -4.022078) (xy 208.204987 -3.953649) (xy 208.159846 -3.880743)
			(xy 208.121624 -3.803983) (xy 208.090648 -3.724024) (xy 208.067181 -3.641548) (xy 208.051425 -3.557258)
			(xy 208.043513 -3.471875) (xy 197.075741 -3.471875) (xy 197.091928 -3.518134) (xy 197.13088 -3.653342)
			(xy 197.16219 -3.790521) (xy 197.185759 -3.929239) (xy 197.201513 -4.069061) (xy 197.209403 -4.209547)
			(xy 197.209918 -4.2799) (xy 197.209918 -6.011875) (xy 208.043513 -6.011875) (xy 208.043513 -5.926125)
			(xy 208.051425 -5.840742) (xy 208.067181 -5.756452) (xy 208.090648 -5.673976) (xy 208.121624 -5.594017)
			(xy 208.159846 -5.517257) (xy 208.204987 -5.444351) (xy 208.256663 -5.375922) (xy 208.314432 -5.312552)
			(xy 208.377802 -5.254783) (xy 208.446231 -5.203107) (xy 208.519137 -5.157966) (xy 208.595897 -5.119744)
			(xy 208.675856 -5.088768) (xy 208.758332 -5.065301) (xy 208.842622 -5.049545) (xy 208.928005 -5.041633)
			(xy 209.013755 -5.041633) (xy 209.099138 -5.049545) (xy 209.183428 -5.065301) (xy 209.265904 -5.088768)
			(xy 209.345863 -5.119744) (xy 209.368066 -5.1308) (xy 212.978492 -5.1308) (xy 212.978492 -4.2672)
			(xy 212.978978 -4.239931) (xy 212.98674 -4.185947) (xy 213.002105 -4.133617) (xy 213.024762 -4.084007)
			(xy 213.054248 -4.038126) (xy 213.089963 -3.996909) (xy 213.13118 -3.961194) (xy 213.177061 -3.931708)
			(xy 213.226671 -3.909051) (xy 213.279001 -3.893686) (xy 213.332985 -3.885924) (xy 213.387523 -3.885924)
			(xy 213.441507 -3.893686) (xy 213.493837 -3.909051) (xy 213.543447 -3.931708) (xy 213.589328 -3.961194)
			(xy 213.630545 -3.996909) (xy 213.66626 -4.038126) (xy 213.695746 -4.084007) (xy 213.718403 -4.133617)
			(xy 213.733768 -4.185947) (xy 213.74153 -4.239931) (xy 213.742016 -4.2672) (xy 213.742016 -5.1308)
			(xy 213.74153 -5.158069) (xy 213.733768 -5.212053) (xy 213.718403 -5.264383) (xy 213.695746 -5.313993)
			(xy 213.66626 -5.359874) (xy 213.630545 -5.401091) (xy 213.589328 -5.436806) (xy 213.543447 -5.466292)
			(xy 213.493837 -5.488949) (xy 213.441507 -5.504314) (xy 213.387523 -5.512076) (xy 213.332985 -5.512076)
			(xy 213.279001 -5.504314) (xy 213.226671 -5.488949) (xy 213.177061 -5.466292) (xy 213.13118 -5.436806)
			(xy 213.089963 -5.401091) (xy 213.054248 -5.359874) (xy 213.024762 -5.313993) (xy 213.002105 -5.264383)
			(xy 212.98674 -5.212053) (xy 212.978978 -5.158069) (xy 212.978492 -5.1308) (xy 209.368066 -5.1308)
			(xy 209.422623 -5.157966) (xy 209.495529 -5.203107) (xy 209.563958 -5.254783) (xy 209.627328 -5.312552)
			(xy 209.685097 -5.375922) (xy 209.736773 -5.444351) (xy 209.781914 -5.517257) (xy 209.820136 -5.594017)
			(xy 209.851112 -5.673976) (xy 209.874579 -5.756452) (xy 209.890335 -5.840742) (xy 209.898247 -5.926125)
			(xy 209.898742 -5.969) (xy 209.898247 -6.011875) (xy 214.393513 -6.011875) (xy 214.393513 -5.926125)
			(xy 214.401425 -5.840742) (xy 214.417181 -5.756452) (xy 214.440648 -5.673976) (xy 214.471624 -5.594017)
			(xy 214.509846 -5.517257) (xy 214.554987 -5.444351) (xy 214.606663 -5.375922) (xy 214.664432 -5.312552)
			(xy 214.727802 -5.254783) (xy 214.796231 -5.203107) (xy 214.869137 -5.157966) (xy 214.945897 -5.119744)
			(xy 215.025856 -5.088768) (xy 215.108332 -5.065301) (xy 215.192622 -5.049545) (xy 215.278005 -5.041633)
			(xy 215.363755 -5.041633) (xy 215.449138 -5.049545) (xy 215.533428 -5.065301) (xy 215.615904 -5.088768)
			(xy 215.695863 -5.119744) (xy 215.772623 -5.157966) (xy 215.845529 -5.203107) (xy 215.913958 -5.254783)
			(xy 215.977328 -5.312552) (xy 216.035097 -5.375922) (xy 216.086773 -5.444351) (xy 216.131914 -5.517257)
			(xy 216.170136 -5.594017) (xy 216.201112 -5.673976) (xy 216.224579 -5.756452) (xy 216.240335 -5.840742)
			(xy 216.248247 -5.926125) (xy 216.248742 -5.969) (xy 216.248247 -6.011875) (xy 246.260353 -6.011875)
			(xy 246.260353 -5.926125) (xy 246.268265 -5.840742) (xy 246.284021 -5.756452) (xy 246.307488 -5.673976)
			(xy 246.338464 -5.594017) (xy 246.376686 -5.517257) (xy 246.421827 -5.444351) (xy 246.473503 -5.375922)
			(xy 246.531272 -5.312552) (xy 246.594642 -5.254783) (xy 246.663071 -5.203107) (xy 246.735977 -5.157966)
			(xy 246.812737 -5.119744) (xy 246.892696 -5.088768) (xy 246.975172 -5.065301) (xy 247.059462 -5.049545)
			(xy 247.144845 -5.041633) (xy 247.230595 -5.041633) (xy 247.315978 -5.049545) (xy 247.400268 -5.065301)
			(xy 247.482744 -5.088768) (xy 247.562703 -5.119744) (xy 247.584906 -5.1308) (xy 248.766584 -5.1308)
			(xy 248.766584 -4.2672) (xy 248.76707 -4.239931) (xy 248.774832 -4.185947) (xy 248.790197 -4.133617)
			(xy 248.812854 -4.084007) (xy 248.84234 -4.038126) (xy 248.878055 -3.996909) (xy 248.919272 -3.961194)
			(xy 248.965153 -3.931708) (xy 249.014763 -3.909051) (xy 249.067093 -3.893686) (xy 249.121077 -3.885924)
			(xy 249.175615 -3.885924) (xy 249.229599 -3.893686) (xy 249.281929 -3.909051) (xy 249.331539 -3.931708)
			(xy 249.37742 -3.961194) (xy 249.418637 -3.996909) (xy 249.454352 -4.038126) (xy 249.483838 -4.084007)
			(xy 249.506495 -4.133617) (xy 249.52186 -4.185947) (xy 249.529622 -4.239931) (xy 249.530108 -4.2672)
			(xy 249.530108 -5.1308) (xy 249.529622 -5.158069) (xy 249.52186 -5.212053) (xy 249.506495 -5.264383)
			(xy 249.483838 -5.313993) (xy 249.454352 -5.359874) (xy 249.418637 -5.401091) (xy 249.37742 -5.436806)
			(xy 249.331539 -5.466292) (xy 249.281929 -5.488949) (xy 249.229599 -5.504314) (xy 249.175615 -5.512076)
			(xy 249.121077 -5.512076) (xy 249.067093 -5.504314) (xy 249.014763 -5.488949) (xy 248.965153 -5.466292)
			(xy 248.919272 -5.436806) (xy 248.878055 -5.401091) (xy 248.84234 -5.359874) (xy 248.812854 -5.313993)
			(xy 248.790197 -5.264383) (xy 248.774832 -5.212053) (xy 248.76707 -5.158069) (xy 248.766584 -5.1308)
			(xy 247.584906 -5.1308) (xy 247.639463 -5.157966) (xy 247.712369 -5.203107) (xy 247.780798 -5.254783)
			(xy 247.844168 -5.312552) (xy 247.901937 -5.375922) (xy 247.953613 -5.444351) (xy 247.998754 -5.517257)
			(xy 248.036976 -5.594017) (xy 248.067952 -5.673976) (xy 248.091419 -5.756452) (xy 248.107175 -5.840742)
			(xy 248.115087 -5.926125) (xy 248.115582 -5.969) (xy 248.115087 -6.011875) (xy 252.610353 -6.011875)
			(xy 252.610353 -5.926125) (xy 252.618265 -5.840742) (xy 252.634021 -5.756452) (xy 252.657488 -5.673976)
			(xy 252.688464 -5.594017) (xy 252.726686 -5.517257) (xy 252.771827 -5.444351) (xy 252.823503 -5.375922)
			(xy 252.881272 -5.312552) (xy 252.944642 -5.254783) (xy 253.013071 -5.203107) (xy 253.085977 -5.157966)
			(xy 253.162737 -5.119744) (xy 253.242696 -5.088768) (xy 253.325172 -5.065301) (xy 253.409462 -5.049545)
			(xy 253.494845 -5.041633) (xy 253.580595 -5.041633) (xy 253.665978 -5.049545) (xy 253.750268 -5.065301)
			(xy 253.832744 -5.088768) (xy 253.912703 -5.119744) (xy 253.989463 -5.157966) (xy 254.062369 -5.203107)
			(xy 254.130798 -5.254783) (xy 254.194168 -5.312552) (xy 254.251937 -5.375922) (xy 254.303613 -5.444351)
			(xy 254.348754 -5.517257) (xy 254.386976 -5.594017) (xy 254.417952 -5.673976) (xy 254.441419 -5.756452)
			(xy 254.457175 -5.840742) (xy 254.465087 -5.926125) (xy 254.465582 -5.969) (xy 254.465119 -6.009081)
			(xy 256.921241 -6.009081) (xy 256.921241 -5.923331) (xy 256.929153 -5.837948) (xy 256.944909 -5.753658)
			(xy 256.968376 -5.671182) (xy 256.999352 -5.591223) (xy 257.037574 -5.514463) (xy 257.082715 -5.441557)
			(xy 257.134391 -5.373128) (xy 257.19216 -5.309758) (xy 257.25553 -5.251989) (xy 257.323959 -5.200313)
			(xy 257.396865 -5.155172) (xy 257.473625 -5.11695) (xy 257.553584 -5.085974) (xy 257.63606 -5.062507)
			(xy 257.72035 -5.046751) (xy 257.805733 -5.038839) (xy 257.891483 -5.038839) (xy 257.976866 -5.046751)
			(xy 258.061156 -5.062507) (xy 258.143632 -5.085974) (xy 258.223591 -5.11695) (xy 258.300351 -5.155172)
			(xy 258.373257 -5.200313) (xy 258.441686 -5.251989) (xy 258.505056 -5.309758) (xy 258.562825 -5.373128)
			(xy 258.614501 -5.441557) (xy 258.659642 -5.514463) (xy 258.697864 -5.591223) (xy 258.72884 -5.671182)
			(xy 258.752307 -5.753658) (xy 258.768063 -5.837948) (xy 258.775975 -5.923331) (xy 258.77647 -5.966206)
			(xy 258.775975 -6.009081) (xy 263.271241 -6.009081) (xy 263.271241 -5.923331) (xy 263.279153 -5.837948)
			(xy 263.294909 -5.753658) (xy 263.318376 -5.671182) (xy 263.349352 -5.591223) (xy 263.387574 -5.514463)
			(xy 263.432715 -5.441557) (xy 263.484391 -5.373128) (xy 263.54216 -5.309758) (xy 263.60553 -5.251989)
			(xy 263.673959 -5.200313) (xy 263.746865 -5.155172) (xy 263.823625 -5.11695) (xy 263.903584 -5.085974)
			(xy 263.98606 -5.062507) (xy 264.07035 -5.046751) (xy 264.155733 -5.038839) (xy 264.241483 -5.038839)
			(xy 264.326866 -5.046751) (xy 264.411156 -5.062507) (xy 264.493632 -5.085974) (xy 264.573591 -5.11695)
			(xy 264.650351 -5.155172) (xy 264.723257 -5.200313) (xy 264.791686 -5.251989) (xy 264.855056 -5.309758)
			(xy 264.912825 -5.373128) (xy 264.964501 -5.441557) (xy 265.009642 -5.514463) (xy 265.047864 -5.591223)
			(xy 265.07884 -5.671182) (xy 265.102307 -5.753658) (xy 265.118063 -5.837948) (xy 265.125975 -5.923331)
			(xy 265.12647 -5.966206) (xy 265.125975 -6.009081) (xy 324.845921 -6.009081) (xy 324.845921 -5.923331)
			(xy 324.853833 -5.837948) (xy 324.869589 -5.753658) (xy 324.893056 -5.671182) (xy 324.924032 -5.591223)
			(xy 324.962254 -5.514463) (xy 325.007395 -5.441557) (xy 325.059071 -5.373128) (xy 325.11684 -5.309758)
			(xy 325.18021 -5.251989) (xy 325.248639 -5.200313) (xy 325.321545 -5.155172) (xy 325.398305 -5.11695)
			(xy 325.478264 -5.085974) (xy 325.56074 -5.062507) (xy 325.64503 -5.046751) (xy 325.730413 -5.038839)
			(xy 325.816163 -5.038839) (xy 325.901546 -5.046751) (xy 325.985836 -5.062507) (xy 326.068312 -5.085974)
			(xy 326.148271 -5.11695) (xy 326.225031 -5.155172) (xy 326.297937 -5.200313) (xy 326.366366 -5.251989)
			(xy 326.429736 -5.309758) (xy 326.487505 -5.373128) (xy 326.539181 -5.441557) (xy 326.584322 -5.514463)
			(xy 326.622544 -5.591223) (xy 326.65352 -5.671182) (xy 326.676987 -5.753658) (xy 326.692743 -5.837948)
			(xy 326.700655 -5.923331) (xy 326.70115 -5.966206) (xy 326.700655 -6.009081) (xy 331.195921 -6.009081)
			(xy 331.195921 -5.923331) (xy 331.203833 -5.837948) (xy 331.219589 -5.753658) (xy 331.243056 -5.671182)
			(xy 331.274032 -5.591223) (xy 331.312254 -5.514463) (xy 331.357395 -5.441557) (xy 331.409071 -5.373128)
			(xy 331.46684 -5.309758) (xy 331.53021 -5.251989) (xy 331.598639 -5.200313) (xy 331.671545 -5.155172)
			(xy 331.748305 -5.11695) (xy 331.828264 -5.085974) (xy 331.91074 -5.062507) (xy 331.99503 -5.046751)
			(xy 332.080413 -5.038839) (xy 332.166163 -5.038839) (xy 332.251546 -5.046751) (xy 332.335836 -5.062507)
			(xy 332.418312 -5.085974) (xy 332.498271 -5.11695) (xy 332.575031 -5.155172) (xy 332.647937 -5.200313)
			(xy 332.716366 -5.251989) (xy 332.779736 -5.309758) (xy 332.837505 -5.373128) (xy 332.889181 -5.441557)
			(xy 332.934322 -5.514463) (xy 332.972544 -5.591223) (xy 333.00352 -5.671182) (xy 333.026987 -5.753658)
			(xy 333.042743 -5.837948) (xy 333.050655 -5.923331) (xy 333.05115 -5.966206) (xy 333.050655 -6.009081)
			(xy 335.488267 -6.009081) (xy 335.488267 -5.923331) (xy 335.496179 -5.837948) (xy 335.511935 -5.753658)
			(xy 335.535402 -5.671182) (xy 335.566378 -5.591223) (xy 335.6046 -5.514463) (xy 335.649741 -5.441557)
			(xy 335.701417 -5.373128) (xy 335.759186 -5.309758) (xy 335.822556 -5.251989) (xy 335.890985 -5.200313)
			(xy 335.963891 -5.155172) (xy 336.040651 -5.11695) (xy 336.12061 -5.085974) (xy 336.203086 -5.062507)
			(xy 336.287376 -5.046751) (xy 336.372759 -5.038839) (xy 336.458509 -5.038839) (xy 336.543892 -5.046751)
			(xy 336.628182 -5.062507) (xy 336.710658 -5.085974) (xy 336.790617 -5.11695) (xy 336.867377 -5.155172)
			(xy 336.940283 -5.200313) (xy 337.008712 -5.251989) (xy 337.072082 -5.309758) (xy 337.129851 -5.373128)
			(xy 337.181527 -5.441557) (xy 337.226668 -5.514463) (xy 337.26489 -5.591223) (xy 337.295866 -5.671182)
			(xy 337.319333 -5.753658) (xy 337.335089 -5.837948) (xy 337.343001 -5.923331) (xy 337.343496 -5.966206)
			(xy 337.343001 -6.009081) (xy 341.838267 -6.009081) (xy 341.838267 -5.923331) (xy 341.846179 -5.837948)
			(xy 341.861935 -5.753658) (xy 341.885402 -5.671182) (xy 341.916378 -5.591223) (xy 341.9546 -5.514463)
			(xy 341.999741 -5.441557) (xy 342.051417 -5.373128) (xy 342.109186 -5.309758) (xy 342.172556 -5.251989)
			(xy 342.240985 -5.200313) (xy 342.313891 -5.155172) (xy 342.390651 -5.11695) (xy 342.47061 -5.085974)
			(xy 342.553086 -5.062507) (xy 342.637376 -5.046751) (xy 342.722759 -5.038839) (xy 342.808509 -5.038839)
			(xy 342.893892 -5.046751) (xy 342.978182 -5.062507) (xy 343.060658 -5.085974) (xy 343.140617 -5.11695)
			(xy 343.217377 -5.155172) (xy 343.290283 -5.200313) (xy 343.358712 -5.251989) (xy 343.422082 -5.309758)
			(xy 343.479851 -5.373128) (xy 343.531527 -5.441557) (xy 343.576668 -5.514463) (xy 343.61489 -5.591223)
			(xy 343.645866 -5.671182) (xy 343.669333 -5.753658) (xy 343.685089 -5.837948) (xy 343.693001 -5.923331)
			(xy 343.693496 -5.966206) (xy 343.693001 -6.009081) (xy 373.705107 -6.009081) (xy 373.705107 -5.923331)
			(xy 373.713019 -5.837948) (xy 373.728775 -5.753658) (xy 373.752242 -5.671182) (xy 373.783218 -5.591223)
			(xy 373.82144 -5.514463) (xy 373.866581 -5.441557) (xy 373.918257 -5.373128) (xy 373.976026 -5.309758)
			(xy 374.039396 -5.251989) (xy 374.107825 -5.200313) (xy 374.180731 -5.155172) (xy 374.257491 -5.11695)
			(xy 374.33745 -5.085974) (xy 374.419926 -5.062507) (xy 374.504216 -5.046751) (xy 374.589599 -5.038839)
			(xy 374.675349 -5.038839) (xy 374.760732 -5.046751) (xy 374.845022 -5.062507) (xy 374.927498 -5.085974)
			(xy 375.007457 -5.11695) (xy 375.084217 -5.155172) (xy 375.157123 -5.200313) (xy 375.225552 -5.251989)
			(xy 375.288922 -5.309758) (xy 375.346691 -5.373128) (xy 375.398367 -5.441557) (xy 375.443508 -5.514463)
			(xy 375.48173 -5.591223) (xy 375.512706 -5.671182) (xy 375.536173 -5.753658) (xy 375.551929 -5.837948)
			(xy 375.559841 -5.923331) (xy 375.560336 -5.966206) (xy 375.559841 -6.009081) (xy 380.055107 -6.009081)
			(xy 380.055107 -5.923331) (xy 380.063019 -5.837948) (xy 380.078775 -5.753658) (xy 380.102242 -5.671182)
			(xy 380.133218 -5.591223) (xy 380.17144 -5.514463) (xy 380.216581 -5.441557) (xy 380.268257 -5.373128)
			(xy 380.326026 -5.309758) (xy 380.389396 -5.251989) (xy 380.457825 -5.200313) (xy 380.530731 -5.155172)
			(xy 380.607491 -5.11695) (xy 380.68745 -5.085974) (xy 380.769926 -5.062507) (xy 380.854216 -5.046751)
			(xy 380.939599 -5.038839) (xy 381.025349 -5.038839) (xy 381.110732 -5.046751) (xy 381.195022 -5.062507)
			(xy 381.277498 -5.085974) (xy 381.357457 -5.11695) (xy 381.434217 -5.155172) (xy 381.507123 -5.200313)
			(xy 381.575552 -5.251989) (xy 381.638922 -5.309758) (xy 381.696691 -5.373128) (xy 381.748367 -5.441557)
			(xy 381.793508 -5.514463) (xy 381.83173 -5.591223) (xy 381.862706 -5.671182) (xy 381.886173 -5.753658)
			(xy 381.901929 -5.837948) (xy 381.909841 -5.923331) (xy 381.910336 -5.966206) (xy 381.909841 -6.009081)
			(xy 381.901929 -6.094464) (xy 381.886173 -6.178754) (xy 381.862706 -6.26123) (xy 381.83173 -6.341189)
			(xy 381.793508 -6.417949) (xy 381.748367 -6.490855) (xy 381.696691 -6.559284) (xy 381.638922 -6.622654)
			(xy 381.575552 -6.680423) (xy 381.507123 -6.732099) (xy 381.434217 -6.77724) (xy 381.357457 -6.815462)
			(xy 381.277498 -6.846438) (xy 381.195022 -6.869905) (xy 381.110732 -6.885661) (xy 381.025349 -6.893573)
			(xy 380.939599 -6.893573) (xy 380.854216 -6.885661) (xy 380.769926 -6.869905) (xy 380.68745 -6.846438)
			(xy 380.607491 -6.815462) (xy 380.530731 -6.77724) (xy 380.457825 -6.732099) (xy 380.389396 -6.680423)
			(xy 380.326026 -6.622654) (xy 380.268257 -6.559284) (xy 380.216581 -6.490855) (xy 380.17144 -6.417949)
			(xy 380.133218 -6.341189) (xy 380.102242 -6.26123) (xy 380.078775 -6.178754) (xy 380.063019 -6.094464)
			(xy 380.055107 -6.009081) (xy 375.559841 -6.009081) (xy 375.551929 -6.094464) (xy 375.536173 -6.178754)
			(xy 375.512706 -6.26123) (xy 375.48173 -6.341189) (xy 375.443508 -6.417949) (xy 375.398367 -6.490855)
			(xy 375.346691 -6.559284) (xy 375.288922 -6.622654) (xy 375.225552 -6.680423) (xy 375.157123 -6.732099)
			(xy 375.084217 -6.77724) (xy 375.007457 -6.815462) (xy 374.927498 -6.846438) (xy 374.845022 -6.869905)
			(xy 374.760732 -6.885661) (xy 374.675349 -6.893573) (xy 374.589599 -6.893573) (xy 374.504216 -6.885661)
			(xy 374.419926 -6.869905) (xy 374.33745 -6.846438) (xy 374.257491 -6.815462) (xy 374.180731 -6.77724)
			(xy 374.107825 -6.732099) (xy 374.039396 -6.680423) (xy 373.976026 -6.622654) (xy 373.918257 -6.559284)
			(xy 373.866581 -6.490855) (xy 373.82144 -6.417949) (xy 373.783218 -6.341189) (xy 373.752242 -6.26123)
			(xy 373.728775 -6.178754) (xy 373.713019 -6.094464) (xy 373.705107 -6.009081) (xy 343.693001 -6.009081)
			(xy 343.685089 -6.094464) (xy 343.669333 -6.178754) (xy 343.645866 -6.26123) (xy 343.61489 -6.341189)
			(xy 343.576668 -6.417949) (xy 343.531527 -6.490855) (xy 343.479851 -6.559284) (xy 343.422082 -6.622654)
			(xy 343.358712 -6.680423) (xy 343.290283 -6.732099) (xy 343.217377 -6.77724) (xy 343.140617 -6.815462)
			(xy 343.060658 -6.846438) (xy 342.978182 -6.869905) (xy 342.893892 -6.885661) (xy 342.808509 -6.893573)
			(xy 342.722759 -6.893573) (xy 342.637376 -6.885661) (xy 342.553086 -6.869905) (xy 342.47061 -6.846438)
			(xy 342.390651 -6.815462) (xy 342.313891 -6.77724) (xy 342.240985 -6.732099) (xy 342.172556 -6.680423)
			(xy 342.109186 -6.622654) (xy 342.051417 -6.559284) (xy 341.999741 -6.490855) (xy 341.9546 -6.417949)
			(xy 341.916378 -6.341189) (xy 341.885402 -6.26123) (xy 341.861935 -6.178754) (xy 341.846179 -6.094464)
			(xy 341.838267 -6.009081) (xy 337.343001 -6.009081) (xy 337.335089 -6.094464) (xy 337.319333 -6.178754)
			(xy 337.295866 -6.26123) (xy 337.26489 -6.341189) (xy 337.226668 -6.417949) (xy 337.181527 -6.490855)
			(xy 337.129851 -6.559284) (xy 337.072082 -6.622654) (xy 337.008712 -6.680423) (xy 336.940283 -6.732099)
			(xy 336.867377 -6.77724) (xy 336.790617 -6.815462) (xy 336.710658 -6.846438) (xy 336.628182 -6.869905)
			(xy 336.543892 -6.885661) (xy 336.458509 -6.893573) (xy 336.372759 -6.893573) (xy 336.287376 -6.885661)
			(xy 336.203086 -6.869905) (xy 336.12061 -6.846438) (xy 336.040651 -6.815462) (xy 335.963891 -6.77724)
			(xy 335.890985 -6.732099) (xy 335.822556 -6.680423) (xy 335.759186 -6.622654) (xy 335.701417 -6.559284)
			(xy 335.649741 -6.490855) (xy 335.6046 -6.417949) (xy 335.566378 -6.341189) (xy 335.535402 -6.26123)
			(xy 335.511935 -6.178754) (xy 335.496179 -6.094464) (xy 335.488267 -6.009081) (xy 333.050655 -6.009081)
			(xy 333.042743 -6.094464) (xy 333.026987 -6.178754) (xy 333.00352 -6.26123) (xy 332.972544 -6.341189)
			(xy 332.934322 -6.417949) (xy 332.889181 -6.490855) (xy 332.837505 -6.559284) (xy 332.779736 -6.622654)
			(xy 332.716366 -6.680423) (xy 332.647937 -6.732099) (xy 332.575031 -6.77724) (xy 332.498271 -6.815462)
			(xy 332.418312 -6.846438) (xy 332.335836 -6.869905) (xy 332.251546 -6.885661) (xy 332.166163 -6.893573)
			(xy 332.080413 -6.893573) (xy 331.99503 -6.885661) (xy 331.91074 -6.869905) (xy 331.828264 -6.846438)
			(xy 331.748305 -6.815462) (xy 331.671545 -6.77724) (xy 331.598639 -6.732099) (xy 331.53021 -6.680423)
			(xy 331.46684 -6.622654) (xy 331.409071 -6.559284) (xy 331.357395 -6.490855) (xy 331.312254 -6.417949)
			(xy 331.274032 -6.341189) (xy 331.243056 -6.26123) (xy 331.219589 -6.178754) (xy 331.203833 -6.094464)
			(xy 331.195921 -6.009081) (xy 326.700655 -6.009081) (xy 326.692743 -6.094464) (xy 326.676987 -6.178754)
			(xy 326.65352 -6.26123) (xy 326.622544 -6.341189) (xy 326.584322 -6.417949) (xy 326.539181 -6.490855)
			(xy 326.487505 -6.559284) (xy 326.429736 -6.622654) (xy 326.366366 -6.680423) (xy 326.297937 -6.732099)
			(xy 326.225031 -6.77724) (xy 326.148271 -6.815462) (xy 326.068312 -6.846438) (xy 325.985836 -6.869905)
			(xy 325.901546 -6.885661) (xy 325.816163 -6.893573) (xy 325.730413 -6.893573) (xy 325.64503 -6.885661)
			(xy 325.56074 -6.869905) (xy 325.478264 -6.846438) (xy 325.398305 -6.815462) (xy 325.321545 -6.77724)
			(xy 325.248639 -6.732099) (xy 325.18021 -6.680423) (xy 325.11684 -6.622654) (xy 325.059071 -6.559284)
			(xy 325.007395 -6.490855) (xy 324.962254 -6.417949) (xy 324.924032 -6.341189) (xy 324.893056 -6.26123)
			(xy 324.869589 -6.178754) (xy 324.853833 -6.094464) (xy 324.845921 -6.009081) (xy 265.125975 -6.009081)
			(xy 265.118063 -6.094464) (xy 265.102307 -6.178754) (xy 265.07884 -6.26123) (xy 265.047864 -6.341189)
			(xy 265.009642 -6.417949) (xy 264.964501 -6.490855) (xy 264.912825 -6.559284) (xy 264.855056 -6.622654)
			(xy 264.791686 -6.680423) (xy 264.723257 -6.732099) (xy 264.650351 -6.77724) (xy 264.573591 -6.815462)
			(xy 264.493632 -6.846438) (xy 264.411156 -6.869905) (xy 264.326866 -6.885661) (xy 264.241483 -6.893573)
			(xy 264.155733 -6.893573) (xy 264.07035 -6.885661) (xy 263.98606 -6.869905) (xy 263.903584 -6.846438)
			(xy 263.823625 -6.815462) (xy 263.746865 -6.77724) (xy 263.673959 -6.732099) (xy 263.60553 -6.680423)
			(xy 263.54216 -6.622654) (xy 263.484391 -6.559284) (xy 263.432715 -6.490855) (xy 263.387574 -6.417949)
			(xy 263.349352 -6.341189) (xy 263.318376 -6.26123) (xy 263.294909 -6.178754) (xy 263.279153 -6.094464)
			(xy 263.271241 -6.009081) (xy 258.775975 -6.009081) (xy 258.768063 -6.094464) (xy 258.752307 -6.178754)
			(xy 258.72884 -6.26123) (xy 258.697864 -6.341189) (xy 258.659642 -6.417949) (xy 258.614501 -6.490855)
			(xy 258.562825 -6.559284) (xy 258.505056 -6.622654) (xy 258.441686 -6.680423) (xy 258.373257 -6.732099)
			(xy 258.300351 -6.77724) (xy 258.223591 -6.815462) (xy 258.143632 -6.846438) (xy 258.061156 -6.869905)
			(xy 257.976866 -6.885661) (xy 257.891483 -6.893573) (xy 257.805733 -6.893573) (xy 257.72035 -6.885661)
			(xy 257.63606 -6.869905) (xy 257.553584 -6.846438) (xy 257.473625 -6.815462) (xy 257.396865 -6.77724)
			(xy 257.323959 -6.732099) (xy 257.25553 -6.680423) (xy 257.19216 -6.622654) (xy 257.134391 -6.559284)
			(xy 257.082715 -6.490855) (xy 257.037574 -6.417949) (xy 256.999352 -6.341189) (xy 256.968376 -6.26123)
			(xy 256.944909 -6.178754) (xy 256.929153 -6.094464) (xy 256.921241 -6.009081) (xy 254.465119 -6.009081)
			(xy 254.465087 -6.011875) (xy 254.457175 -6.097258) (xy 254.441419 -6.181548) (xy 254.417952 -6.264024)
			(xy 254.386976 -6.343983) (xy 254.348754 -6.420743) (xy 254.303613 -6.493649) (xy 254.251937 -6.562078)
			(xy 254.194168 -6.625448) (xy 254.130798 -6.683217) (xy 254.062369 -6.734893) (xy 253.989463 -6.780034)
			(xy 253.912703 -6.818256) (xy 253.832744 -6.849232) (xy 253.750268 -6.872699) (xy 253.665978 -6.888455)
			(xy 253.580595 -6.896367) (xy 253.494845 -6.896367) (xy 253.409462 -6.888455) (xy 253.325172 -6.872699)
			(xy 253.242696 -6.849232) (xy 253.162737 -6.818256) (xy 253.085977 -6.780034) (xy 253.013071 -6.734893)
			(xy 252.944642 -6.683217) (xy 252.881272 -6.625448) (xy 252.823503 -6.562078) (xy 252.771827 -6.493649)
			(xy 252.726686 -6.420743) (xy 252.688464 -6.343983) (xy 252.657488 -6.264024) (xy 252.634021 -6.181548)
			(xy 252.618265 -6.097258) (xy 252.610353 -6.011875) (xy 248.115087 -6.011875) (xy 248.107175 -6.097258)
			(xy 248.091419 -6.181548) (xy 248.067952 -6.264024) (xy 248.036976 -6.343983) (xy 247.998754 -6.420743)
			(xy 247.953613 -6.493649) (xy 247.901937 -6.562078) (xy 247.844168 -6.625448) (xy 247.780798 -6.683217)
			(xy 247.712369 -6.734893) (xy 247.639463 -6.780034) (xy 247.562703 -6.818256) (xy 247.482744 -6.849232)
			(xy 247.400268 -6.872699) (xy 247.315978 -6.888455) (xy 247.230595 -6.896367) (xy 247.144845 -6.896367)
			(xy 247.059462 -6.888455) (xy 246.975172 -6.872699) (xy 246.892696 -6.849232) (xy 246.812737 -6.818256)
			(xy 246.735977 -6.780034) (xy 246.663071 -6.734893) (xy 246.594642 -6.683217) (xy 246.531272 -6.625448)
			(xy 246.473503 -6.562078) (xy 246.421827 -6.493649) (xy 246.376686 -6.420743) (xy 246.338464 -6.343983)
			(xy 246.307488 -6.264024) (xy 246.284021 -6.181548) (xy 246.268265 -6.097258) (xy 246.260353 -6.011875)
			(xy 216.248247 -6.011875) (xy 216.240335 -6.097258) (xy 216.224579 -6.181548) (xy 216.201112 -6.264024)
			(xy 216.170136 -6.343983) (xy 216.131914 -6.420743) (xy 216.086773 -6.493649) (xy 216.035097 -6.562078)
			(xy 215.977328 -6.625448) (xy 215.913958 -6.683217) (xy 215.845529 -6.734893) (xy 215.772623 -6.780034)
			(xy 215.695863 -6.818256) (xy 215.615904 -6.849232) (xy 215.533428 -6.872699) (xy 215.449138 -6.888455)
			(xy 215.363755 -6.896367) (xy 215.278005 -6.896367) (xy 215.192622 -6.888455) (xy 215.108332 -6.872699)
			(xy 215.025856 -6.849232) (xy 214.945897 -6.818256) (xy 214.869137 -6.780034) (xy 214.796231 -6.734893)
			(xy 214.727802 -6.683217) (xy 214.664432 -6.625448) (xy 214.606663 -6.562078) (xy 214.554987 -6.493649)
			(xy 214.509846 -6.420743) (xy 214.471624 -6.343983) (xy 214.440648 -6.264024) (xy 214.417181 -6.181548)
			(xy 214.401425 -6.097258) (xy 214.393513 -6.011875) (xy 209.898247 -6.011875) (xy 209.890335 -6.097258)
			(xy 209.874579 -6.181548) (xy 209.851112 -6.264024) (xy 209.820136 -6.343983) (xy 209.781914 -6.420743)
			(xy 209.736773 -6.493649) (xy 209.685097 -6.562078) (xy 209.627328 -6.625448) (xy 209.563958 -6.683217)
			(xy 209.495529 -6.734893) (xy 209.422623 -6.780034) (xy 209.345863 -6.818256) (xy 209.265904 -6.849232)
			(xy 209.183428 -6.872699) (xy 209.099138 -6.888455) (xy 209.013755 -6.896367) (xy 208.928005 -6.896367)
			(xy 208.842622 -6.888455) (xy 208.758332 -6.872699) (xy 208.675856 -6.849232) (xy 208.595897 -6.818256)
			(xy 208.519137 -6.780034) (xy 208.446231 -6.734893) (xy 208.377802 -6.683217) (xy 208.314432 -6.625448)
			(xy 208.256663 -6.562078) (xy 208.204987 -6.493649) (xy 208.159846 -6.420743) (xy 208.121624 -6.343983)
			(xy 208.090648 -6.264024) (xy 208.067181 -6.181548) (xy 208.051425 -6.097258) (xy 208.043513 -6.011875)
			(xy 197.209918 -6.011875) (xy 197.209918 -7.78002) (xy 197.21044 -7.835826) (xy 197.218783 -7.947127)
			(xy 197.235419 -8.057493) (xy 197.260257 -8.166307) (xy 197.293157 -8.27296) (xy 197.333935 -8.376857)
			(xy 197.382363 -8.477416) (xy 197.43817 -8.574075) (xy 197.501045 -8.666293) (xy 197.570635 -8.753555)
			(xy 197.646552 -8.835372) (xy 197.728371 -8.911287) (xy 197.815634 -8.980875) (xy 197.907854 -9.043748)
			(xy 198.004514 -9.099553) (xy 198.105074 -9.147979) (xy 198.208972 -9.188755) (xy 198.315626 -9.221652)
			(xy 198.424441 -9.246487) (xy 198.534807 -9.263121) (xy 198.646108 -9.271461) (xy 198.701914 -9.272016)
			(xy 223.300036 -9.272016) (xy 223.370389 -9.27251) (xy 223.510873 -9.280402) (xy 223.650694 -9.296158)
			(xy 223.789412 -9.319729) (xy 223.92659 -9.35104) (xy 224.061796 -9.389995) (xy 224.194606 -9.436468)
			(xy 224.3246 -9.490316) (xy 224.451371 -9.551367) (xy 224.57452 -9.619431) (xy 224.693658 -9.694292)
			(xy 224.808411 -9.775716) (xy 224.918419 -9.863446) (xy 225.023334 -9.957206) (xy 225.122827 -10.056701)
			(xy 225.216585 -10.161618) (xy 225.304313 -10.271627) (xy 225.385734 -10.386382) (xy 225.460594 -10.505522)
			(xy 225.528655 -10.628671) (xy 225.589704 -10.755444) (xy 225.643549 -10.885439) (xy 225.69002 -11.01825)
			(xy 225.728972 -11.153457) (xy 225.760281 -11.290635) (xy 225.783849 -11.429353) (xy 225.799602 -11.569174)
			(xy 225.807491 -11.709659) (xy 225.808032 -11.780012) (xy 225.808032 -31.197296) (xy 227.377752 -32.767016)
			(xy 254.645668 -32.767016)
		)
		(stroke
			(width 0)
			(type solid)
		)
		(fill yes)
		(layer "In14.Cu")
		(net "DELTA_L_GND_1")
	)
	(gr_poly
		(pts
			(xy 194.495928 -441.17006) (xy 194.49641 -441.126022) (xy 194.50409 -441.03828) (xy 194.519387 -440.951542)
			(xy 194.542185 -440.866466) (xy 194.572311 -440.783702) (xy 194.609536 -440.703878) (xy 194.653576 -440.627602)
			(xy 194.704095 -440.555454) (xy 194.760711 -440.487984) (xy 194.822991 -440.425704) (xy 194.890462 -440.369089)
			(xy 194.96261 -440.31857) (xy 195.038887 -440.274531) (xy 195.118711 -440.237308) (xy 195.201476 -440.207182)
			(xy 195.286551 -440.184385) (xy 195.37329 -440.169088) (xy 195.461032 -440.16141) (xy 195.50507 -440.160918)
			(xy 276.314916 -440.160918) (xy 276.358955 -440.161399) (xy 276.446699 -440.169077) (xy 276.533439 -440.184372)
			(xy 276.618516 -440.207169) (xy 276.701283 -440.237294) (xy 276.781109 -440.274518) (xy 276.857388 -440.318557)
			(xy 276.929538 -440.369076) (xy 276.99701 -440.425692) (xy 277.059292 -440.487972) (xy 277.115909 -440.555443)
			(xy 277.16643 -440.627592) (xy 277.210471 -440.703869) (xy 277.247697 -440.783695) (xy 277.277823 -440.866461)
			(xy 277.300622 -440.951538) (xy 277.31592 -441.038278) (xy 277.3236 -441.126021) (xy 277.324058 -441.17006)
			(xy 277.324058 -441.480956) (xy 463.300064 -441.480956) (xy 463.355834 -441.480449) (xy 463.467062 -441.472116)
			(xy 463.577357 -441.455494) (xy 463.686101 -441.430676) (xy 463.792686 -441.397801) (xy 463.896517 -441.357052)
			(xy 463.997011 -441.308658) (xy 464.093608 -441.252889) (xy 464.185768 -441.190057) (xy 464.272974 -441.120513)
			(xy 464.354739 -441.044647) (xy 464.430606 -440.962883) (xy 464.50015 -440.875677) (xy 464.562982 -440.783519)
			(xy 464.618752 -440.686922) (xy 464.667147 -440.586428) (xy 464.707897 -440.482598) (xy 464.740773 -440.376013)
			(xy 464.765592 -440.267269) (xy 464.782215 -440.156974) (xy 464.790548 -440.045746) (xy 464.791044 -439.989976)
			(xy 464.791044 -419.236652) (xy 464.79206 -419.236652) (xy 464.79206 -419.160198) (xy 464.791552 -419.157912)
			(xy 464.783498 -419.125745) (xy 464.774831 -419.060003) (xy 464.77428 -419.026848) (xy 464.774826 -418.994155)
			(xy 464.783231 -418.929312) (xy 464.791044 -418.897562) (xy 464.791044 -409.528264) (xy 464.791527 -409.457889)
			(xy 464.799416 -409.317359) (xy 464.815173 -409.177493) (xy 464.838748 -409.03873) (xy 464.870067 -408.901508)
			(xy 464.909031 -408.766258) (xy 464.955519 -408.633405) (xy 465.009383 -408.503369) (xy 465.070454 -408.376557)
			(xy 465.138539 -408.25337) (xy 465.213426 -408.134194) (xy 465.294877 -408.019405) (xy 465.382637 -407.909364)
			(xy 465.47643 -407.804418) (xy 465.525866 -407.754328) (xy 467.354412 -405.925782) (xy 467.391723 -405.887821)
			(xy 467.461438 -405.807375) (xy 467.525236 -405.722161) (xy 467.582791 -405.632611) (xy 467.633809 -405.539182)
			(xy 467.678031 -405.442352) (xy 467.715231 -405.342613) (xy 467.74522 -405.240474) (xy 467.767844 -405.136455)
			(xy 467.782988 -405.031087) (xy 467.790575 -404.924907) (xy 467.791038 -404.871682) (xy 467.791038 -82.82813)
			(xy 467.791541 -82.757757) (xy 467.799451 -82.617233) (xy 467.815226 -82.477373) (xy 467.838815 -82.338618)
			(xy 467.870145 -82.201402) (xy 467.909116 -82.066159) (xy 467.955608 -81.933313) (xy 468.009473 -81.803282)
			(xy 468.070541 -81.676474) (xy 468.138622 -81.553289) (xy 468.213501 -81.434114) (xy 468.294942 -81.319323)
			(xy 468.382689 -81.209278) (xy 468.476467 -81.104324) (xy 468.52586 -81.054194) (xy 470.854278 -78.725776)
			(xy 470.891589 -78.687815) (xy 470.961306 -78.60737) (xy 471.025105 -78.522156) (xy 471.082661 -78.432606)
			(xy 471.13368 -78.339178) (xy 471.177903 -78.242348) (xy 471.215103 -78.142608) (xy 471.245092 -78.040469)
			(xy 471.267716 -77.93645) (xy 471.28286 -77.831082) (xy 471.290447 -77.724901) (xy 471.290904 -77.671676)
			(xy 471.290904 -13.780008) (xy 471.290383 -13.724238) (xy 471.282048 -13.613011) (xy 471.265425 -13.502718)
			(xy 471.240606 -13.393975) (xy 471.20773 -13.287391) (xy 471.166981 -13.183562) (xy 471.118587 -13.083068)
			(xy 471.062818 -12.986472) (xy 470.999987 -12.894314) (xy 470.930444 -12.807108) (xy 470.854579 -12.725344)
			(xy 470.772816 -12.649477) (xy 470.685612 -12.579932) (xy 470.593455 -12.517099) (xy 470.49686 -12.461328)
			(xy 470.396367 -12.412932) (xy 470.292539 -12.372181) (xy 470.185956 -12.339303) (xy 470.077214 -12.314481)
			(xy 469.966921 -12.297855) (xy 469.855694 -12.289518) (xy 469.799924 -12.289028) (xy 464.613244 -12.289028)
			(xy 464.613244 -12.288012) (xy 464.272376 -12.288012) (xy 464.272376 -12.289028) (xy 458.20203 -12.289028)
			(xy 458.131647 -12.288544) (xy 457.991102 -12.280653) (xy 457.85122 -12.264894) (xy 457.712443 -12.241316)
			(xy 457.575205 -12.209994) (xy 457.43994 -12.171027) (xy 457.307072 -12.124536) (xy 457.177021 -12.070668)
			(xy 457.050194 -12.009593) (xy 456.926991 -11.941503) (xy 456.8078 -11.866612) (xy 456.692996 -11.785156)
			(xy 456.582939 -11.69739) (xy 456.477977 -11.603592) (xy 456.378439 -11.504056) (xy 456.284639 -11.399096)
			(xy 456.196872 -11.289041) (xy 456.115413 -11.174238) (xy 456.04052 -11.055048) (xy 455.972428 -10.931847)
			(xy 455.911351 -10.805021) (xy 455.857481 -10.674971) (xy 455.810987 -10.542104) (xy 455.772017 -10.406839)
			(xy 455.740693 -10.269603) (xy 455.717113 -10.130825) (xy 455.701351 -9.990944) (xy 455.693457 -9.850399)
			(xy 455.693018 -9.780016) (xy 455.693018 -0.999998) (xy 455.692493 -0.967851) (xy 455.684101 -0.904107)
			(xy 455.667461 -0.842004) (xy 455.642857 -0.782603) (xy 455.610712 -0.726922) (xy 455.571573 -0.675913)
			(xy 455.526112 -0.630449) (xy 455.475106 -0.591307) (xy 455.419427 -0.559158) (xy 455.360029 -0.53455)
			(xy 455.297926 -0.517906) (xy 455.234183 -0.50951) (xy 455.202036 -0.509016) (xy 388.601966 -0.509016)
			(xy 388.569821 -0.509544) (xy 388.506082 -0.517939) (xy 388.443984 -0.534582) (xy 388.384589 -0.559188)
			(xy 388.328914 -0.591335) (xy 388.277911 -0.630474) (xy 388.232453 -0.675936) (xy 388.193318 -0.726941)
			(xy 388.161174 -0.782618) (xy 388.136572 -0.842014) (xy 388.119933 -0.904114) (xy 388.111542 -0.967853)
			(xy 388.110984 -0.999998) (xy 388.110984 -5.169916) (xy 388.850131 -5.169916) (xy 388.854136 -5.082008)
			(xy 388.866119 -4.994828) (xy 388.885979 -4.909099) (xy 388.913554 -4.825531) (xy 388.948613 -4.744817)
			(xy 388.990866 -4.667625) (xy 389.039964 -4.594596) (xy 389.0955 -4.526334) (xy 389.157012 -4.463404)
			(xy 389.223993 -4.40633) (xy 389.295886 -4.355582) (xy 389.372095 -4.311582) (xy 389.45199 -4.274695)
			(xy 389.534909 -4.245226) (xy 389.620164 -4.223419) (xy 389.707048 -4.209455) (xy 389.794842 -4.203449)
			(xy 389.882819 -4.205453) (xy 389.970249 -4.215448) (xy 390.056408 -4.233352) (xy 390.140582 -4.259016)
			(xy 390.222073 -4.292229) (xy 390.300207 -4.332715) (xy 390.374335 -4.380137) (xy 390.443843 -4.434104)
			(xy 390.508157 -4.494169) (xy 390.566741 -4.559833) (xy 390.619112 -4.630552) (xy 390.664835 -4.70574)
			(xy 390.703532 -4.784775) (xy 390.734881 -4.867001) (xy 390.758623 -4.951737) (xy 390.763638 -4.978969)
			(xy 394.947631 -4.978969) (xy 394.947631 -4.924431) (xy 394.955393 -4.870448) (xy 394.970758 -4.81812)
			(xy 394.993414 -4.76851) (xy 395.0229 -4.72263) (xy 395.058614 -4.681413) (xy 395.099832 -4.645698)
			(xy 395.145712 -4.616213) (xy 395.195321 -4.593557) (xy 395.24765 -4.578193) (xy 395.301633 -4.570431)
			(xy 395.328902 -4.569968) (xy 396.192502 -4.569968) (xy 396.219773 -4.570395) (xy 396.273761 -4.578157)
			(xy 396.326094 -4.593524) (xy 396.375708 -4.616182) (xy 396.421593 -4.64567) (xy 396.462813 -4.681388)
			(xy 396.498531 -4.722609) (xy 396.528019 -4.768493) (xy 396.550677 -4.818107) (xy 396.566043 -4.870441)
			(xy 396.573806 -4.924429) (xy 396.573806 -4.978971) (xy 398.547532 -4.978971) (xy 398.547532 -4.924429)
			(xy 398.555294 -4.870443) (xy 398.570661 -4.818111) (xy 398.593321 -4.768498) (xy 398.62281 -4.722616)
			(xy 398.658529 -4.681398) (xy 398.699751 -4.645684) (xy 398.745637 -4.616199) (xy 398.795252 -4.593546)
			(xy 398.847586 -4.578185) (xy 398.901573 -4.570428) (xy 398.928844 -4.569968) (xy 399.792444 -4.569968)
			(xy 399.819713 -4.570398) (xy 399.873697 -4.578165) (xy 399.926025 -4.593535) (xy 399.975633 -4.616196)
			(xy 400.021512 -4.645685) (xy 400.062728 -4.681403) (xy 400.098441 -4.722623) (xy 400.127925 -4.768505)
			(xy 400.15058 -4.818116) (xy 400.165944 -4.870447) (xy 400.173706 -4.92443) (xy 400.173706 -4.978967)
			(xy 402.147554 -4.978967) (xy 402.147554 -4.924433) (xy 402.155315 -4.870455) (xy 402.170678 -4.818131)
			(xy 402.193332 -4.768526) (xy 402.222814 -4.722649) (xy 402.258525 -4.681435) (xy 402.299738 -4.645722)
			(xy 402.345613 -4.616239) (xy 402.395218 -4.593583) (xy 402.447542 -4.578218) (xy 402.501519 -4.570455)
			(xy 402.528786 -4.569968) (xy 403.392386 -4.569968) (xy 403.41966 -4.570371) (xy 403.473652 -4.578132)
			(xy 403.525991 -4.593498) (xy 403.57561 -4.616157) (xy 403.621499 -4.645646) (xy 403.662724 -4.681366)
			(xy 403.698445 -4.72259) (xy 403.727937 -4.768478) (xy 403.750597 -4.818096) (xy 403.765965 -4.870434)
			(xy 403.773728 -4.924426) (xy 403.773728 -4.978966) (xy 405.747754 -4.978966) (xy 405.747754 -4.924434)
			(xy 405.755515 -4.870456) (xy 405.770878 -4.818132) (xy 405.793531 -4.768527) (xy 405.823013 -4.72265)
			(xy 405.858724 -4.681436) (xy 405.899936 -4.645724) (xy 405.945811 -4.61624) (xy 405.995415 -4.593584)
			(xy 406.047738 -4.578219) (xy 406.101716 -4.570456) (xy 406.128982 -4.569968) (xy 406.992582 -4.569968)
			(xy 407.019856 -4.57037) (xy 407.073849 -4.578131) (xy 407.126188 -4.593497) (xy 407.175807 -4.616155)
			(xy 407.221697 -4.645645) (xy 407.262922 -4.681365) (xy 407.298644 -4.722589) (xy 407.328136 -4.768477)
			(xy 407.350797 -4.818095) (xy 407.366165 -4.870433) (xy 407.373928 -4.924426) (xy 407.373928 -4.978971)
			(xy 414.857632 -4.978971) (xy 414.857632 -4.924429) (xy 414.865394 -4.870442) (xy 414.880762 -4.81811)
			(xy 414.903421 -4.768498) (xy 414.93291 -4.722616) (xy 414.96863 -4.681397) (xy 415.009852 -4.645683)
			(xy 415.055738 -4.616199) (xy 415.105353 -4.593546) (xy 415.157687 -4.578184) (xy 415.211675 -4.570428)
			(xy 415.238946 -4.569968) (xy 416.102546 -4.569968) (xy 416.129815 -4.570398) (xy 416.183798 -4.578165)
			(xy 416.236126 -4.593536) (xy 416.285735 -4.616196) (xy 416.331613 -4.645686) (xy 416.372829 -4.681404)
			(xy 416.408542 -4.722624) (xy 416.438026 -4.768506) (xy 416.46068 -4.818117) (xy 416.476045 -4.870447)
			(xy 416.483806 -4.924431) (xy 416.483806 -4.978967) (xy 418.457654 -4.978967) (xy 418.457654 -4.924433)
			(xy 418.465415 -4.870455) (xy 418.480779 -4.818131) (xy 418.503432 -4.768525) (xy 418.532915 -4.722648)
			(xy 418.568626 -4.681434) (xy 418.609839 -4.645722) (xy 418.655715 -4.616238) (xy 418.705319 -4.593583)
			(xy 418.757643 -4.578218) (xy 418.811621 -4.570455) (xy 418.838888 -4.569968) (xy 419.702488 -4.569968)
			(xy 419.729762 -4.570371) (xy 419.783754 -4.578132) (xy 419.836092 -4.593499) (xy 419.885711 -4.616157)
			(xy 419.9316 -4.645647) (xy 419.972824 -4.681367) (xy 420.008546 -4.722591) (xy 420.038037 -4.768479)
			(xy 420.060697 -4.818096) (xy 420.076065 -4.870434) (xy 420.083828 -4.924426) (xy 420.083828 -4.978966)
			(xy 426.067754 -4.978966) (xy 426.067754 -4.924434) (xy 426.075515 -4.870456) (xy 426.090878 -4.818132)
			(xy 426.113531 -4.768527) (xy 426.143013 -4.72265) (xy 426.178724 -4.681436) (xy 426.219936 -4.645724)
			(xy 426.265811 -4.61624) (xy 426.315415 -4.593584) (xy 426.367738 -4.578219) (xy 426.421716 -4.570456)
			(xy 426.448982 -4.569968) (xy 427.312582 -4.569968) (xy 427.339856 -4.57037) (xy 427.393849 -4.578131)
			(xy 427.446188 -4.593497) (xy 427.495807 -4.616155) (xy 427.541697 -4.645645) (xy 427.582922 -4.681365)
			(xy 427.618644 -4.722589) (xy 427.648136 -4.768477) (xy 427.670797 -4.818095) (xy 427.686165 -4.870433)
			(xy 427.693928 -4.924426) (xy 427.693928 -4.97897) (xy 429.667631 -4.97897) (xy 429.667631 -4.92443)
			(xy 429.675394 -4.870445) (xy 429.69076 -4.818115) (xy 429.713417 -4.768504) (xy 429.742905 -4.722623)
			(xy 429.778622 -4.681405) (xy 429.819842 -4.645691) (xy 429.865725 -4.616206) (xy 429.915337 -4.593552)
			(xy 429.967669 -4.578189) (xy 430.021654 -4.57043) (xy 430.048924 -4.569968) (xy 430.912524 -4.569968)
			(xy 430.939794 -4.570396) (xy 430.99378 -4.578161) (xy 431.04611 -4.59353) (xy 431.095721 -4.616189)
			(xy 431.141603 -4.645678) (xy 431.182821 -4.681396) (xy 431.218536 -4.722616) (xy 431.248022 -4.7685)
			(xy 431.270679 -4.818112) (xy 431.286044 -4.870444) (xy 431.293806 -4.92443) (xy 431.293806 -4.97897)
			(xy 431.286044 -5.032956) (xy 431.270679 -5.085288) (xy 431.248022 -5.1349) (xy 431.218536 -5.180784)
			(xy 431.182821 -5.222004) (xy 431.141603 -5.257722) (xy 431.095721 -5.287211) (xy 431.04611 -5.30987)
			(xy 430.99378 -5.325239) (xy 430.939794 -5.333004) (xy 430.912524 -5.333492) (xy 430.048924 -5.333492)
			(xy 430.021654 -5.33297) (xy 429.967669 -5.325211) (xy 429.915337 -5.309848) (xy 429.865725 -5.287194)
			(xy 429.819842 -5.257709) (xy 429.778622 -5.221995) (xy 429.742905 -5.180777) (xy 429.713417 -5.134896)
			(xy 429.69076 -5.085285) (xy 429.675394 -5.032955) (xy 429.667631 -4.97897) (xy 427.693928 -4.97897)
			(xy 427.693928 -4.978974) (xy 427.686165 -5.032967) (xy 427.670797 -5.085305) (xy 427.648136 -5.134923)
			(xy 427.618644 -5.180811) (xy 427.582922 -5.222035) (xy 427.541697 -5.257755) (xy 427.495807 -5.287245)
			(xy 427.446188 -5.309903) (xy 427.393849 -5.325269) (xy 427.339856 -5.33303) (xy 427.312582 -5.333492)
			(xy 426.448982 -5.333492) (xy 426.421716 -5.332944) (xy 426.367738 -5.325181) (xy 426.315415 -5.309816)
			(xy 426.265811 -5.28716) (xy 426.219936 -5.257676) (xy 426.178724 -5.221964) (xy 426.143013 -5.18075)
			(xy 426.113531 -5.134873) (xy 426.090878 -5.085268) (xy 426.075515 -5.032944) (xy 426.067754 -4.978966)
			(xy 420.083828 -4.978966) (xy 420.083828 -4.978974) (xy 420.076065 -5.032966) (xy 420.060697 -5.085304)
			(xy 420.038037 -5.134921) (xy 420.008546 -5.180809) (xy 419.972824 -5.222033) (xy 419.9316 -5.257753)
			(xy 419.885711 -5.287243) (xy 419.836092 -5.309901) (xy 419.783754 -5.325268) (xy 419.729762 -5.333029)
			(xy 419.702488 -5.333492) (xy 418.838888 -5.333492) (xy 418.811621 -5.332945) (xy 418.757643 -5.325182)
			(xy 418.705319 -5.309817) (xy 418.655715 -5.287162) (xy 418.609839 -5.257678) (xy 418.568626 -5.221966)
			(xy 418.532915 -5.180752) (xy 418.503432 -5.134875) (xy 418.480779 -5.085269) (xy 418.465415 -5.032945)
			(xy 418.457654 -4.978967) (xy 416.483806 -4.978967) (xy 416.483806 -4.978969) (xy 416.476045 -5.032953)
			(xy 416.46068 -5.085283) (xy 416.438026 -5.134894) (xy 416.408542 -5.180776) (xy 416.372829 -5.221996)
			(xy 416.331613 -5.257714) (xy 416.285735 -5.287204) (xy 416.236126 -5.309864) (xy 416.183798 -5.325235)
			(xy 416.129815 -5.333002) (xy 416.102546 -5.333492) (xy 415.238946 -5.333492) (xy 415.211675 -5.332972)
			(xy 415.157687 -5.325216) (xy 415.105353 -5.309854) (xy 415.055738 -5.287201) (xy 415.009852 -5.257717)
			(xy 414.96863 -5.222003) (xy 414.93291 -5.180784) (xy 414.903421 -5.134902) (xy 414.880762 -5.08529)
			(xy 414.865394 -5.032958) (xy 414.857632 -4.978971) (xy 407.373928 -4.978971) (xy 407.373928 -4.978974)
			(xy 407.366165 -5.032967) (xy 407.350797 -5.085305) (xy 407.328136 -5.134923) (xy 407.298644 -5.180811)
			(xy 407.262922 -5.222035) (xy 407.221697 -5.257755) (xy 407.175807 -5.287245) (xy 407.126188 -5.309903)
			(xy 407.073849 -5.325269) (xy 407.019856 -5.33303) (xy 406.992582 -5.333492) (xy 406.128982 -5.333492)
			(xy 406.101716 -5.332944) (xy 406.047738 -5.325181) (xy 405.995415 -5.309816) (xy 405.945811 -5.28716)
			(xy 405.899936 -5.257676) (xy 405.858724 -5.221964) (xy 405.823013 -5.18075) (xy 405.793531 -5.134873)
			(xy 405.770878 -5.085268) (xy 405.755515 -5.032944) (xy 405.747754 -4.978966) (xy 403.773728 -4.978966)
			(xy 403.773728 -4.978974) (xy 403.765965 -5.032966) (xy 403.750597 -5.085304) (xy 403.727937 -5.134922)
			(xy 403.698445 -5.18081) (xy 403.662724 -5.222034) (xy 403.621499 -5.257754) (xy 403.57561 -5.287243)
			(xy 403.525991 -5.309902) (xy 403.473652 -5.325268) (xy 403.41966 -5.333029) (xy 403.392386 -5.333492)
			(xy 402.528786 -5.333492) (xy 402.501519 -5.332945) (xy 402.447542 -5.325182) (xy 402.395218 -5.309817)
			(xy 402.345613 -5.287161) (xy 402.299738 -5.257678) (xy 402.258525 -5.221965) (xy 402.222814 -5.180751)
			(xy 402.193332 -5.134874) (xy 402.170678 -5.085269) (xy 402.155315 -5.032945) (xy 402.147554 -4.978967)
			(xy 400.173706 -4.978967) (xy 400.173706 -4.97897) (xy 400.165944 -5.032953) (xy 400.15058 -5.085284)
			(xy 400.127925 -5.134895) (xy 400.098441 -5.180777) (xy 400.062728 -5.221997) (xy 400.021512 -5.257715)
			(xy 399.975633 -5.287204) (xy 399.926025 -5.309865) (xy 399.873697 -5.325235) (xy 399.819713 -5.333002)
			(xy 399.792444 -5.333492) (xy 398.928844 -5.333492) (xy 398.901573 -5.332972) (xy 398.847586 -5.325215)
			(xy 398.795252 -5.309854) (xy 398.745637 -5.287201) (xy 398.699751 -5.257716) (xy 398.658529 -5.222002)
			(xy 398.62281 -5.180784) (xy 398.593321 -5.134902) (xy 398.570661 -5.085289) (xy 398.555294 -5.032957)
			(xy 398.547532 -4.978971) (xy 396.573806 -4.978971) (xy 396.566043 -5.032959) (xy 396.550677 -5.085293)
			(xy 396.528019 -5.134907) (xy 396.498531 -5.180791) (xy 396.462813 -5.222012) (xy 396.421593 -5.25773)
			(xy 396.375708 -5.287218) (xy 396.326094 -5.309876) (xy 396.273761 -5.325243) (xy 396.219773 -5.333005)
			(xy 396.192502 -5.333492) (xy 395.328902 -5.333492) (xy 395.301633 -5.332969) (xy 395.24765 -5.325207)
			(xy 395.195321 -5.309843) (xy 395.145712 -5.287187) (xy 395.099832 -5.257702) (xy 395.058614 -5.221987)
			(xy 395.0229 -5.18077) (xy 394.993414 -5.13489) (xy 394.970758 -5.08528) (xy 394.955393 -5.032952)
			(xy 394.947631 -4.978969) (xy 390.763638 -4.978969) (xy 390.774561 -5.038281) (xy 390.782563 -5.125916)
			(xy 390.783064 -5.169916) (xy 390.782563 -5.213916) (xy 390.774561 -5.301551) (xy 390.758623 -5.388095)
			(xy 390.734881 -5.472831) (xy 390.703532 -5.555057) (xy 390.664835 -5.634092) (xy 390.619112 -5.70928)
			(xy 390.566741 -5.779999) (xy 390.508157 -5.845663) (xy 390.443843 -5.905728) (xy 390.374335 -5.959695)
			(xy 390.300207 -6.007117) (xy 390.222073 -6.047603) (xy 390.140582 -6.080816) (xy 390.056408 -6.10648)
			(xy 389.970249 -6.124384) (xy 389.882819 -6.134379) (xy 389.794842 -6.136383) (xy 389.707048 -6.130377)
			(xy 389.620164 -6.116413) (xy 389.534909 -6.094606) (xy 389.45199 -6.065137) (xy 389.372095 -6.02825)
			(xy 389.295886 -5.98425) (xy 389.223993 -5.933502) (xy 389.157012 -5.876428) (xy 389.0955 -5.813498)
			(xy 389.039964 -5.745236) (xy 388.990866 -5.672207) (xy 388.948613 -5.595015) (xy 388.913554 -5.514301)
			(xy 388.885979 -5.430733) (xy 388.866119 -5.345004) (xy 388.854136 -5.257824) (xy 388.850131 -5.169916)
			(xy 388.110984 -5.169916) (xy 388.110984 -6.169914) (xy 453.015103 -6.169914) (xy 453.019108 -6.082006)
			(xy 453.031091 -5.994826) (xy 453.050951 -5.909097) (xy 453.078526 -5.825529) (xy 453.113585 -5.744815)
			(xy 453.155838 -5.667623) (xy 453.204936 -5.594594) (xy 453.260472 -5.526332) (xy 453.321984 -5.463402)
			(xy 453.388965 -5.406328) (xy 453.460858 -5.35558) (xy 453.537067 -5.31158) (xy 453.616962 -5.274693)
			(xy 453.699881 -5.245224) (xy 453.785136 -5.223417) (xy 453.87202 -5.209453) (xy 453.959814 -5.203447)
			(xy 454.047791 -5.205451) (xy 454.135221 -5.215446) (xy 454.22138 -5.23335) (xy 454.305554 -5.259014)
			(xy 454.387045 -5.292227) (xy 454.465179 -5.332713) (xy 454.539307 -5.380135) (xy 454.608815 -5.434102)
			(xy 454.673129 -5.494167) (xy 454.731713 -5.559831) (xy 454.784084 -5.63055) (xy 454.829807 -5.705738)
			(xy 454.868504 -5.784773) (xy 454.899853 -5.866999) (xy 454.923595 -5.951735) (xy 454.939533 -6.038279)
			(xy 454.947535 -6.125914) (xy 454.948036 -6.169914) (xy 454.947535 -6.213914) (xy 454.939533 -6.301549)
			(xy 454.923595 -6.388093) (xy 454.899853 -6.472829) (xy 454.868504 -6.555055) (xy 454.829807 -6.63409)
			(xy 454.784084 -6.709278) (xy 454.731713 -6.779997) (xy 454.673129 -6.845661) (xy 454.608815 -6.905726)
			(xy 454.539307 -6.959693) (xy 454.465179 -7.007115) (xy 454.387045 -7.047601) (xy 454.305554 -7.080814)
			(xy 454.22138 -7.106478) (xy 454.135221 -7.124382) (xy 454.047791 -7.134377) (xy 453.959814 -7.136381)
			(xy 453.87202 -7.130375) (xy 453.785136 -7.116411) (xy 453.699881 -7.094604) (xy 453.616962 -7.065135)
			(xy 453.537067 -7.028248) (xy 453.460858 -6.984248) (xy 453.388965 -6.9335) (xy 453.321984 -6.876426)
			(xy 453.260472 -6.813496) (xy 453.204936 -6.745234) (xy 453.155838 -6.672205) (xy 453.113585 -6.595013)
			(xy 453.078526 -6.514299) (xy 453.050951 -6.430731) (xy 453.031091 -6.345002) (xy 453.019108 -6.257822)
			(xy 453.015103 -6.169914) (xy 388.110984 -6.169914) (xy 388.110984 -6.740774) (xy 393.142876 -6.740774)
			(xy 393.142876 -6.686226) (xy 393.150639 -6.632232) (xy 393.166008 -6.579894) (xy 393.18867 -6.530275)
			(xy 393.218162 -6.484387) (xy 393.253885 -6.443163) (xy 393.295112 -6.407443) (xy 393.341003 -6.377954)
			(xy 393.390624 -6.355297) (xy 393.442964 -6.339932) (xy 393.496958 -6.332173) (xy 393.524232 -6.331712)
			(xy 394.387832 -6.331712) (xy 394.415098 -6.332253) (xy 394.469074 -6.340017) (xy 394.521397 -6.355384)
			(xy 394.570999 -6.378041) (xy 394.616873 -6.407526) (xy 394.658084 -6.443238) (xy 394.693794 -6.484452)
			(xy 394.723274 -6.530329) (xy 394.745927 -6.579933) (xy 394.761289 -6.632257) (xy 394.76905 -6.686234)
			(xy 394.76905 -6.740766) (xy 394.769049 -6.74077) (xy 396.742898 -6.74077) (xy 396.742898 -6.68623)
			(xy 396.75066 -6.632245) (xy 396.766025 -6.579914) (xy 396.788681 -6.530302) (xy 396.818166 -6.484419)
			(xy 396.853881 -6.4432) (xy 396.895099 -6.407482) (xy 396.940979 -6.377993) (xy 396.99059 -6.355334)
			(xy 397.04292 -6.339965) (xy 397.096904 -6.3322) (xy 397.124174 -6.331712) (xy 397.987774 -6.331712)
			(xy 398.015044 -6.332226) (xy 398.06903 -6.339984) (xy 398.121363 -6.355347) (xy 398.170976 -6.378002)
			(xy 398.216859 -6.407487) (xy 398.25808 -6.443202) (xy 398.293798 -6.48442) (xy 398.323286 -6.530301)
			(xy 398.345944 -6.579913) (xy 398.36131 -6.632244) (xy 398.369072 -6.68623) (xy 398.369072 -6.74077)
			(xy 398.369071 -6.740774) (xy 400.342776 -6.740774) (xy 400.342776 -6.686226) (xy 400.350539 -6.632234)
			(xy 400.365907 -6.579897) (xy 400.388567 -6.530279) (xy 400.418058 -6.484392) (xy 400.45378 -6.443168)
			(xy 400.495005 -6.407449) (xy 400.540893 -6.377959) (xy 400.590512 -6.355301) (xy 400.64285 -6.339935)
			(xy 400.696842 -6.332174) (xy 400.724116 -6.331712) (xy 401.587716 -6.331712) (xy 401.614983 -6.332251)
			(xy 401.668961 -6.340014) (xy 401.721285 -6.35538) (xy 401.77089 -6.378036) (xy 401.816766 -6.40752)
			(xy 401.857978 -6.443233) (xy 401.89369 -6.484447) (xy 401.923172 -6.530324) (xy 401.945825 -6.57993)
			(xy 401.961189 -6.632255) (xy 401.96895 -6.686233) (xy 401.96895 -6.740767) (xy 401.968949 -6.740773)
			(xy 403.942976 -6.740773) (xy 403.942976 -6.686227) (xy 403.950739 -6.632235) (xy 403.966106 -6.579898)
			(xy 403.988766 -6.53028) (xy 404.018257 -6.484393) (xy 404.053978 -6.44317) (xy 404.095203 -6.40745)
			(xy 404.141091 -6.377961) (xy 404.190709 -6.355302) (xy 404.243047 -6.339936) (xy 404.297039 -6.332175)
			(xy 404.324312 -6.331712) (xy 405.187912 -6.331712) (xy 405.215179 -6.332251) (xy 405.269158 -6.340014)
			(xy 405.321482 -6.355379) (xy 405.371087 -6.378034) (xy 405.416964 -6.407519) (xy 405.458177 -6.443231)
			(xy 405.493889 -6.484446) (xy 405.523371 -6.530323) (xy 405.546025 -6.579929) (xy 405.561389 -6.632254)
			(xy 405.56915 -6.686233) (xy 405.56915 -6.740767) (xy 405.56915 -6.74077) (xy 413.052998 -6.74077)
			(xy 413.052998 -6.68623) (xy 413.06076 -6.632245) (xy 413.076125 -6.579914) (xy 413.098781 -6.530302)
			(xy 413.128267 -6.484419) (xy 413.163982 -6.443199) (xy 413.205199 -6.407481) (xy 413.25108 -6.377993)
			(xy 413.300691 -6.355334) (xy 413.353021 -6.339965) (xy 413.407006 -6.3322) (xy 413.434276 -6.331712)
			(xy 414.297876 -6.331712) (xy 414.325146 -6.332226) (xy 414.379132 -6.339985) (xy 414.431464 -6.355348)
			(xy 414.481077 -6.378002) (xy 414.52696 -6.407487) (xy 414.568181 -6.443202) (xy 414.603898 -6.48442)
			(xy 414.633386 -6.530302) (xy 414.656044 -6.579913) (xy 414.67141 -6.632244) (xy 414.679173 -6.68623)
			(xy 414.679173 -6.74077) (xy 414.679172 -6.740774) (xy 416.652876 -6.740774) (xy 416.652876 -6.686226)
			(xy 416.660639 -6.632234) (xy 416.676007 -6.579897) (xy 416.698667 -6.530279) (xy 416.728159 -6.484391)
			(xy 416.763881 -6.443168) (xy 416.805106 -6.407448) (xy 416.850995 -6.377959) (xy 416.900613 -6.355301)
			(xy 416.952952 -6.339935) (xy 417.006944 -6.332174) (xy 417.034218 -6.331712) (xy 417.897818 -6.331712)
			(xy 417.925085 -6.332252) (xy 417.979063 -6.340015) (xy 418.031386 -6.355381) (xy 418.080991 -6.378036)
			(xy 418.126867 -6.407521) (xy 418.168079 -6.443234) (xy 418.20379 -6.484448) (xy 418.233272 -6.530325)
			(xy 418.255926 -6.57993) (xy 418.271289 -6.632255) (xy 418.27905 -6.686233) (xy 418.27905 -6.740767)
			(xy 418.279049 -6.740773) (xy 424.262976 -6.740773) (xy 424.262976 -6.686227) (xy 424.270739 -6.632235)
			(xy 424.286106 -6.579898) (xy 424.308766 -6.53028) (xy 424.338257 -6.484393) (xy 424.373978 -6.44317)
			(xy 424.415203 -6.40745) (xy 424.461091 -6.377961) (xy 424.510709 -6.355302) (xy 424.563047 -6.339936)
			(xy 424.617039 -6.332175) (xy 424.644312 -6.331712) (xy 425.507912 -6.331712) (xy 425.535179 -6.332251)
			(xy 425.589158 -6.340014) (xy 425.641482 -6.355379) (xy 425.691087 -6.378034) (xy 425.736964 -6.407519)
			(xy 425.778177 -6.443231) (xy 425.813889 -6.484446) (xy 425.843371 -6.530323) (xy 425.866025 -6.579929)
			(xy 425.881389 -6.632254) (xy 425.88915 -6.686233) (xy 425.88915 -6.740767) (xy 425.88915 -6.740769)
			(xy 427.862998 -6.740769) (xy 427.862998 -6.686231) (xy 427.870759 -6.632248) (xy 427.886123 -6.579918)
			(xy 427.908778 -6.530308) (xy 427.938261 -6.484426) (xy 427.973974 -6.443207) (xy 428.015189 -6.407489)
			(xy 428.061067 -6.378) (xy 428.110675 -6.35534) (xy 428.163003 -6.339969) (xy 428.216985 -6.332202)
			(xy 428.244254 -6.331712) (xy 429.107854 -6.331712) (xy 429.135125 -6.332224) (xy 429.189113 -6.339981)
			(xy 429.241448 -6.355342) (xy 429.291064 -6.377995) (xy 429.33695 -6.40748) (xy 429.378173 -6.443195)
			(xy 429.413893 -6.484413) (xy 429.443383 -6.530296) (xy 429.466042 -6.579909) (xy 429.48141 -6.632242)
			(xy 429.489172 -6.686229) (xy 429.489172 -6.740771) (xy 429.488151 -6.747873) (xy 431.473788 -6.747873)
			(xy 431.473788 -6.693327) (xy 431.48155 -6.639337) (xy 431.496918 -6.587001) (xy 431.519578 -6.537385)
			(xy 431.549068 -6.491498) (xy 431.584789 -6.450276) (xy 431.626013 -6.414558) (xy 431.6719 -6.385069)
			(xy 431.721518 -6.362412) (xy 431.773854 -6.347047) (xy 431.827845 -6.339286) (xy 431.855118 -6.338824)
			(xy 432.718718 -6.338824) (xy 432.745986 -6.33934) (xy 432.799965 -6.347103) (xy 432.852291 -6.362469)
			(xy 432.901897 -6.385126) (xy 432.947774 -6.414611) (xy 432.988988 -6.450325) (xy 433.0247 -6.491541)
			(xy 433.054183 -6.537419) (xy 433.076837 -6.587026) (xy 433.092201 -6.639352) (xy 433.099962 -6.693332)
			(xy 433.099962 -6.740771) (xy 445.457798 -6.740771) (xy 445.457798 -6.686229) (xy 445.46556 -6.632243)
			(xy 445.480926 -6.579911) (xy 445.503583 -6.530298) (xy 445.53307 -6.484415) (xy 445.568786 -6.443195)
			(xy 445.610005 -6.407477) (xy 445.655888 -6.377989) (xy 445.7055 -6.35533) (xy 445.757831 -6.339963)
			(xy 445.811817 -6.332199) (xy 445.839088 -6.331712) (xy 446.702688 -6.331712) (xy 446.729958 -6.332227)
			(xy 446.783942 -6.339987) (xy 446.836273 -6.355351) (xy 446.885884 -6.378006) (xy 446.931766 -6.407492)
			(xy 446.972985 -6.443207) (xy 447.008701 -6.484424) (xy 447.038188 -6.530305) (xy 447.060845 -6.579916)
			(xy 447.076211 -6.632246) (xy 447.083973 -6.68623) (xy 447.083973 -6.74077) (xy 447.076211 -6.794754)
			(xy 447.060845 -6.847084) (xy 447.038188 -6.896695) (xy 447.008701 -6.942576) (xy 446.972985 -6.983793)
			(xy 446.931766 -7.019508) (xy 446.885884 -7.048994) (xy 446.836273 -7.071649) (xy 446.783942 -7.087013)
			(xy 446.729958 -7.094773) (xy 446.702688 -7.095236) (xy 445.839088 -7.095236) (xy 445.811817 -7.094801)
			(xy 445.757831 -7.087037) (xy 445.7055 -7.07167) (xy 445.655888 -7.049011) (xy 445.610005 -7.019523)
			(xy 445.568786 -6.983805) (xy 445.53307 -6.942585) (xy 445.503583 -6.896702) (xy 445.480926 -6.847089)
			(xy 445.46556 -6.794757) (xy 445.457798 -6.740771) (xy 433.099962 -6.740771) (xy 433.099962 -6.747868)
			(xy 433.092201 -6.801848) (xy 433.076837 -6.854174) (xy 433.054183 -6.903781) (xy 433.0247 -6.949659)
			(xy 432.988988 -6.990875) (xy 432.947774 -7.026589) (xy 432.901897 -7.056074) (xy 432.852291 -7.078731)
			(xy 432.799965 -7.094097) (xy 432.745986 -7.10186) (xy 432.718718 -7.102348) (xy 431.855118 -7.102348)
			(xy 431.827845 -7.101914) (xy 431.773854 -7.094153) (xy 431.721518 -7.078788) (xy 431.6719 -7.056131)
			(xy 431.626013 -7.026642) (xy 431.584789 -6.990924) (xy 431.549068 -6.949702) (xy 431.519578 -6.903815)
			(xy 431.496918 -6.854199) (xy 431.48155 -6.801863) (xy 431.473788 -6.747873) (xy 429.488151 -6.747873)
			(xy 429.48141 -6.794758) (xy 429.466042 -6.847091) (xy 429.443383 -6.896704) (xy 429.413893 -6.942587)
			(xy 429.378173 -6.983805) (xy 429.33695 -7.01952) (xy 429.291064 -7.049005) (xy 429.241448 -7.071658)
			(xy 429.189113 -7.087019) (xy 429.135125 -7.094776) (xy 429.107854 -7.095236) (xy 428.244254 -7.095236)
			(xy 428.216985 -7.094798) (xy 428.163003 -7.087031) (xy 428.110675 -7.07166) (xy 428.061067 -7.049)
			(xy 428.015189 -7.019511) (xy 427.973974 -6.983793) (xy 427.938261 -6.942574) (xy 427.908778 -6.896692)
			(xy 427.886123 -6.847082) (xy 427.870759 -6.794752) (xy 427.862998 -6.740769) (xy 425.88915 -6.740769)
			(xy 425.881389 -6.794746) (xy 425.866025 -6.847071) (xy 425.843371 -6.896677) (xy 425.813889 -6.942554)
			(xy 425.778177 -6.983769) (xy 425.736964 -7.019481) (xy 425.691087 -7.048966) (xy 425.641482 -7.071621)
			(xy 425.589158 -7.086986) (xy 425.535179 -7.094749) (xy 425.507912 -7.095236) (xy 424.644312 -7.095236)
			(xy 424.617039 -7.094825) (xy 424.563047 -7.087064) (xy 424.510709 -7.071698) (xy 424.461091 -7.049039)
			(xy 424.415203 -7.01955) (xy 424.373978 -6.98383) (xy 424.338257 -6.942607) (xy 424.308766 -6.89672)
			(xy 424.286106 -6.847102) (xy 424.270739 -6.794765) (xy 424.262976 -6.740773) (xy 418.279049 -6.740773)
			(xy 418.271289 -6.794745) (xy 418.255926 -6.84707) (xy 418.233272 -6.896675) (xy 418.20379 -6.942552)
			(xy 418.168079 -6.983766) (xy 418.126867 -7.019479) (xy 418.080991 -7.048964) (xy 418.031386 -7.071619)
			(xy 417.979063 -7.086985) (xy 417.925085 -7.094748) (xy 417.897818 -7.095236) (xy 417.034218 -7.095236)
			(xy 417.006944 -7.094826) (xy 416.952952 -7.087065) (xy 416.900613 -7.071699) (xy 416.850995 -7.049041)
			(xy 416.805106 -7.019552) (xy 416.763881 -6.983832) (xy 416.728159 -6.942609) (xy 416.698667 -6.896721)
			(xy 416.676007 -6.847103) (xy 416.660639 -6.794766) (xy 416.652876 -6.740774) (xy 414.679172 -6.740774)
			(xy 414.67141 -6.794756) (xy 414.656044 -6.847087) (xy 414.633386 -6.896698) (xy 414.603898 -6.94258)
			(xy 414.568181 -6.983798) (xy 414.52696 -7.019513) (xy 414.481077 -7.048998) (xy 414.431464 -7.071652)
			(xy 414.379132 -7.087015) (xy 414.325146 -7.094774) (xy 414.297876 -7.095236) (xy 413.434276 -7.095236)
			(xy 413.407006 -7.0948) (xy 413.353021 -7.087035) (xy 413.300691 -7.071666) (xy 413.25108 -7.049007)
			(xy 413.205199 -7.019519) (xy 413.163982 -6.983801) (xy 413.128267 -6.942581) (xy 413.098781 -6.896698)
			(xy 413.076125 -6.847086) (xy 413.06076 -6.794755) (xy 413.052998 -6.74077) (xy 405.56915 -6.74077)
			(xy 405.561389 -6.794746) (xy 405.546025 -6.847071) (xy 405.523371 -6.896677) (xy 405.493889 -6.942554)
			(xy 405.458177 -6.983769) (xy 405.416964 -7.019481) (xy 405.371087 -7.048966) (xy 405.321482 -7.071621)
			(xy 405.269158 -7.086986) (xy 405.215179 -7.094749) (xy 405.187912 -7.095236) (xy 404.324312 -7.095236)
			(xy 404.297039 -7.094825) (xy 404.243047 -7.087064) (xy 404.190709 -7.071698) (xy 404.141091 -7.049039)
			(xy 404.095203 -7.01955) (xy 404.053978 -6.98383) (xy 404.018257 -6.942607) (xy 403.988766 -6.89672)
			(xy 403.966106 -6.847102) (xy 403.950739 -6.794765) (xy 403.942976 -6.740773) (xy 401.968949 -6.740773)
			(xy 401.961189 -6.794745) (xy 401.945825 -6.84707) (xy 401.923172 -6.896676) (xy 401.89369 -6.942553)
			(xy 401.857978 -6.983767) (xy 401.816766 -7.01948) (xy 401.77089 -7.048964) (xy 401.721285 -7.07162)
			(xy 401.668961 -7.086986) (xy 401.614983 -7.094749) (xy 401.587716 -7.095236) (xy 400.724116 -7.095236)
			(xy 400.696842 -7.094826) (xy 400.64285 -7.087065) (xy 400.590512 -7.071699) (xy 400.540893 -7.049041)
			(xy 400.495005 -7.019551) (xy 400.45378 -6.983832) (xy 400.418058 -6.942608) (xy 400.388567 -6.896721)
			(xy 400.365907 -6.847103) (xy 400.350539 -6.794766) (xy 400.342776 -6.740774) (xy 398.369071 -6.740774)
			(xy 398.36131 -6.794756) (xy 398.345944 -6.847087) (xy 398.323286 -6.896699) (xy 398.293798 -6.94258)
			(xy 398.25808 -6.983798) (xy 398.216859 -7.019513) (xy 398.170976 -7.048998) (xy 398.121363 -7.071653)
			(xy 398.06903 -7.087016) (xy 398.015044 -7.094774) (xy 397.987774 -7.095236) (xy 397.124174 -7.095236)
			(xy 397.096904 -7.0948) (xy 397.04292 -7.087035) (xy 396.99059 -7.071666) (xy 396.940979 -7.049007)
			(xy 396.895099 -7.019518) (xy 396.853881 -6.9838) (xy 396.818166 -6.942581) (xy 396.788681 -6.896698)
			(xy 396.766025 -6.847086) (xy 396.75066 -6.794755) (xy 396.742898 -6.74077) (xy 394.769049 -6.74077)
			(xy 394.761289 -6.794743) (xy 394.745927 -6.847067) (xy 394.723274 -6.896671) (xy 394.693794 -6.942548)
			(xy 394.658084 -6.983762) (xy 394.616873 -7.019474) (xy 394.570999 -7.048959) (xy 394.521397 -7.071616)
			(xy 394.469074 -7.086983) (xy 394.415098 -7.094747) (xy 394.387832 -7.095236) (xy 393.524232 -7.095236)
			(xy 393.496958 -7.094827) (xy 393.442964 -7.087068) (xy 393.390624 -7.071703) (xy 393.341003 -7.049046)
			(xy 393.295112 -7.019557) (xy 393.253885 -6.983837) (xy 393.218162 -6.942613) (xy 393.18867 -6.896725)
			(xy 393.166008 -6.847106) (xy 393.150639 -6.794768) (xy 393.142876 -6.740774) (xy 388.110984 -6.740774)
			(xy 388.110984 -9.780016) (xy 388.110499 -9.850398) (xy 388.102605 -9.99094) (xy 388.086844 -10.130819)
			(xy 388.063264 -10.269594) (xy 388.03194 -10.406828) (xy 387.992971 -10.54209) (xy 387.946478 -10.674954)
			(xy 387.892609 -10.805003) (xy 387.831533 -10.931826) (xy 387.763442 -11.055026) (xy 387.68855 -11.174213)
			(xy 387.607093 -11.289014) (xy 387.519328 -11.399067) (xy 387.425529 -11.504025) (xy 387.325993 -11.60356)
			(xy 387.221033 -11.697356) (xy 387.110979 -11.78512) (xy 386.996176 -11.866575) (xy 386.876988 -11.941465)
			(xy 386.753787 -12.009554) (xy 386.626963 -12.070627) (xy 386.496913 -12.124494) (xy 386.364048 -12.170984)
			(xy 386.228785 -12.209951) (xy 386.091551 -12.241273) (xy 385.952775 -12.26485) (xy 385.812896 -12.280609)
			(xy 385.672354 -12.2885) (xy 385.601972 -12.289028) (xy 260.800088 -12.289028) (xy 260.744319 -12.28955)
			(xy 260.633094 -12.297886) (xy 260.522803 -12.314511) (xy 260.414062 -12.339331) (xy 260.30748 -12.372208)
			(xy 260.203654 -12.412958) (xy 260.103162 -12.461353) (xy 260.006569 -12.517122) (xy 259.914413 -12.579954)
			(xy 259.82721 -12.649497) (xy 259.745448 -12.725362) (xy 259.669584 -12.807125) (xy 259.601847 -12.892065)
			(xy 431.46197 -12.892065) (xy 431.46197 -12.837535) (xy 431.46973 -12.783559) (xy 431.485093 -12.731238)
			(xy 431.507745 -12.681635) (xy 431.537225 -12.635761) (xy 431.572934 -12.594548) (xy 431.614145 -12.558837)
			(xy 431.660017 -12.529355) (xy 431.709619 -12.5067) (xy 431.76194 -12.491335) (xy 431.815915 -12.483572)
			(xy 431.84318 -12.483084) (xy 432.70678 -12.483084) (xy 432.734055 -12.483454) (xy 432.788051 -12.491215)
			(xy 432.840392 -12.506581) (xy 432.890014 -12.529241) (xy 432.935905 -12.558731) (xy 432.977133 -12.594453)
			(xy 433.012857 -12.635678) (xy 433.04235 -12.681569) (xy 433.065012 -12.731189) (xy 433.080381 -12.78353)
			(xy 433.088144 -12.837525) (xy 433.088144 -12.864846) (xy 445.45631 -12.864846) (xy 445.45631 -12.864592)
			(xy 445.456564 -12.850622) (xy 445.45717 -12.823469) (xy 445.46523 -12.769758) (xy 445.48082 -12.717731)
			(xy 445.503625 -12.668439) (xy 445.533186 -12.622876) (xy 445.568905 -12.581962) (xy 445.610062 -12.546522)
			(xy 445.655826 -12.517273) (xy 445.705273 -12.494804) (xy 445.757405 -12.47957) (xy 445.81117 -12.471876)
			(xy 445.838326 -12.4714) (xy 446.701926 -12.4714) (xy 446.72908 -12.471883) (xy 446.782838 -12.479582)
			(xy 446.834964 -12.494821) (xy 446.884404 -12.517293) (xy 446.93016 -12.546543) (xy 446.971311 -12.581982)
			(xy 447.007024 -12.622895) (xy 447.03658 -12.668455) (xy 447.059381 -12.717744) (xy 447.074968 -12.769766)
			(xy 447.083027 -12.823472) (xy 447.083688 -12.850622) (xy 447.083942 -12.864592) (xy 447.083942 -12.864846)
			(xy 447.083472 -12.892133) (xy 447.0757 -12.946152) (xy 447.06032 -12.998515) (xy 447.037645 -13.048157)
			(xy 447.008137 -13.094067) (xy 446.972397 -13.135311) (xy 446.931151 -13.171049) (xy 446.885239 -13.200555)
			(xy 446.835597 -13.223227) (xy 446.783233 -13.238604) (xy 446.729214 -13.246374) (xy 446.701926 -13.246862)
			(xy 446.679426 -13.246581) (xy 446.634732 -13.241355) (xy 446.612772 -13.236448) (xy 446.60693 -13.234924)
			(xy 445.933322 -13.234924) (xy 445.92748 -13.236448) (xy 445.905519 -13.241348) (xy 445.860825 -13.246566)
			(xy 445.838326 -13.246862) (xy 445.811041 -13.246305) (xy 445.757027 -13.238543) (xy 445.704666 -13.223173)
			(xy 445.655026 -13.200508) (xy 445.609117 -13.17101) (xy 445.567873 -13.135278) (xy 445.532133 -13.094041)
			(xy 445.502626 -13.048137) (xy 445.479952 -12.998501) (xy 445.464572 -12.946144) (xy 445.4568 -12.892131)
			(xy 445.45631 -12.864846) (xy 433.088144 -12.864846) (xy 433.088144 -12.892075) (xy 433.080381 -12.94607)
			(xy 433.065012 -12.998411) (xy 433.04235 -13.048031) (xy 433.012857 -13.093921) (xy 432.977133 -13.135147)
			(xy 432.935905 -13.170869) (xy 432.890014 -13.200359) (xy 432.840392 -13.223019) (xy 432.788051 -13.238385)
			(xy 432.734055 -13.246146) (xy 432.70678 -13.246608) (xy 431.84318 -13.246608) (xy 431.815915 -13.246028)
			(xy 431.76194 -13.238265) (xy 431.709619 -13.2229) (xy 431.660017 -13.200245) (xy 431.614145 -13.170763)
			(xy 431.572934 -13.135052) (xy 431.537225 -13.093839) (xy 431.507745 -13.047965) (xy 431.485093 -12.998362)
			(xy 431.46973 -12.946041) (xy 431.46197 -12.892065) (xy 259.601847 -12.892065) (xy 259.600042 -12.894329)
			(xy 259.537211 -12.986486) (xy 259.481443 -13.08308) (xy 259.43305 -13.183572) (xy 259.392301 -13.287399)
			(xy 259.359426 -13.393981) (xy 259.334607 -13.502722) (xy 259.317984 -13.613014) (xy 259.309649 -13.724239)
			(xy 259.309108 -13.780008) (xy 259.309108 -17.628666) (xy 389.660162 -17.628666) (xy 389.660162 -17.574134)
			(xy 389.667923 -17.520157) (xy 389.683286 -17.467834) (xy 389.705939 -17.41823) (xy 389.73542 -17.372354)
			(xy 389.77113 -17.331141) (xy 389.812342 -17.29543) (xy 389.858216 -17.265946) (xy 389.907819 -17.243291)
			(xy 389.960142 -17.227926) (xy 390.014118 -17.220163) (xy 390.041384 -17.219676) (xy 390.904984 -17.219676)
			(xy 390.932258 -17.220062) (xy 390.986252 -17.227824) (xy 391.038592 -17.24319) (xy 391.088212 -17.265849)
			(xy 391.134103 -17.295339) (xy 391.175329 -17.33106) (xy 391.211051 -17.372285) (xy 391.240543 -17.418174)
			(xy 391.263204 -17.467793) (xy 391.278573 -17.520132) (xy 391.286336 -17.574126) (xy 391.286336 -17.628666)
			(xy 395.248162 -17.628666) (xy 395.248162 -17.574134) (xy 395.255923 -17.520157) (xy 395.271286 -17.467834)
			(xy 395.293939 -17.41823) (xy 395.32342 -17.372354) (xy 395.35913 -17.331141) (xy 395.400342 -17.29543)
			(xy 395.446216 -17.265946) (xy 395.495819 -17.243291) (xy 395.548142 -17.227926) (xy 395.602118 -17.220163)
			(xy 395.629384 -17.219676) (xy 396.492984 -17.219676) (xy 396.520258 -17.220062) (xy 396.574252 -17.227824)
			(xy 396.626592 -17.24319) (xy 396.676212 -17.265849) (xy 396.722103 -17.295339) (xy 396.763329 -17.33106)
			(xy 396.799051 -17.372285) (xy 396.828543 -17.418174) (xy 396.851204 -17.467793) (xy 396.866573 -17.520132)
			(xy 396.874336 -17.574126) (xy 396.874336 -17.628666) (xy 400.836162 -17.628666) (xy 400.836162 -17.574134)
			(xy 400.843923 -17.520157) (xy 400.859286 -17.467834) (xy 400.881939 -17.41823) (xy 400.91142 -17.372354)
			(xy 400.94713 -17.331141) (xy 400.988342 -17.29543) (xy 401.034216 -17.265946) (xy 401.083819 -17.243291)
			(xy 401.136142 -17.227926) (xy 401.190118 -17.220163) (xy 401.217384 -17.219676) (xy 402.080984 -17.219676)
			(xy 402.108258 -17.220062) (xy 402.162252 -17.227824) (xy 402.214592 -17.24319) (xy 402.264212 -17.265849)
			(xy 402.310103 -17.295339) (xy 402.351329 -17.33106) (xy 402.387051 -17.372285) (xy 402.416543 -17.418174)
			(xy 402.439204 -17.467793) (xy 402.454573 -17.520132) (xy 402.462336 -17.574126) (xy 402.462336 -17.628666)
			(xy 406.424162 -17.628666) (xy 406.424162 -17.574134) (xy 406.431923 -17.520157) (xy 406.447286 -17.467834)
			(xy 406.469939 -17.41823) (xy 406.49942 -17.372354) (xy 406.53513 -17.331141) (xy 406.576342 -17.29543)
			(xy 406.622216 -17.265946) (xy 406.671819 -17.243291) (xy 406.724142 -17.227926) (xy 406.778118 -17.220163)
			(xy 406.805384 -17.219676) (xy 407.668984 -17.219676) (xy 407.696258 -17.220062) (xy 407.750252 -17.227824)
			(xy 407.802592 -17.24319) (xy 407.852212 -17.265849) (xy 407.898103 -17.295339) (xy 407.939329 -17.33106)
			(xy 407.975051 -17.372285) (xy 408.004543 -17.418174) (xy 408.027204 -17.467793) (xy 408.042573 -17.520132)
			(xy 408.050336 -17.574126) (xy 408.050336 -17.628666) (xy 412.012162 -17.628666) (xy 412.012162 -17.574134)
			(xy 412.019923 -17.520157) (xy 412.035286 -17.467834) (xy 412.057939 -17.41823) (xy 412.08742 -17.372354)
			(xy 412.12313 -17.331141) (xy 412.164342 -17.29543) (xy 412.210216 -17.265946) (xy 412.259819 -17.243291)
			(xy 412.312142 -17.227926) (xy 412.366118 -17.220163) (xy 412.393384 -17.219676) (xy 413.256984 -17.219676)
			(xy 413.284258 -17.220062) (xy 413.338252 -17.227824) (xy 413.390592 -17.24319) (xy 413.440212 -17.265849)
			(xy 413.486103 -17.295339) (xy 413.527329 -17.33106) (xy 413.563051 -17.372285) (xy 413.592543 -17.418174)
			(xy 413.615204 -17.467793) (xy 413.630573 -17.520132) (xy 413.638336 -17.574126) (xy 413.638336 -17.628667)
			(xy 417.905962 -17.628667) (xy 417.905962 -17.574133) (xy 417.913723 -17.520155) (xy 417.929087 -17.467831)
			(xy 417.951741 -17.418226) (xy 417.981224 -17.372349) (xy 418.016936 -17.331136) (xy 418.058149 -17.295424)
			(xy 418.104026 -17.265941) (xy 418.153631 -17.243287) (xy 418.205955 -17.227923) (xy 418.259933 -17.220162)
			(xy 418.2872 -17.219676) (xy 419.1508 -17.219676) (xy 419.178072 -17.220087) (xy 419.232061 -17.227849)
			(xy 419.284396 -17.243216) (xy 419.334011 -17.265874) (xy 419.379896 -17.295363) (xy 419.421118 -17.331082)
			(xy 419.456837 -17.372304) (xy 419.486326 -17.418189) (xy 419.508984 -17.467804) (xy 419.524351 -17.520139)
			(xy 419.532113 -17.574128) (xy 419.532113 -17.628667) (xy 423.493962 -17.628667) (xy 423.493962 -17.574133)
			(xy 423.501723 -17.520155) (xy 423.517087 -17.467831) (xy 423.539741 -17.418226) (xy 423.569224 -17.372349)
			(xy 423.604936 -17.331136) (xy 423.646149 -17.295424) (xy 423.692026 -17.265941) (xy 423.741631 -17.243287)
			(xy 423.793955 -17.227923) (xy 423.847933 -17.220162) (xy 423.8752 -17.219676) (xy 424.7388 -17.219676)
			(xy 424.766072 -17.220087) (xy 424.820061 -17.227849) (xy 424.872396 -17.243216) (xy 424.922011 -17.265874)
			(xy 424.967896 -17.295363) (xy 425.009118 -17.331082) (xy 425.044837 -17.372304) (xy 425.074326 -17.418189)
			(xy 425.096984 -17.467804) (xy 425.112351 -17.520139) (xy 425.120113 -17.574128) (xy 425.120113 -17.62867)
			(xy 429.11594 -17.62867) (xy 429.11594 -17.57413) (xy 429.123702 -17.520145) (xy 429.139068 -17.467815)
			(xy 429.161726 -17.418204) (xy 429.191214 -17.372324) (xy 429.226932 -17.331107) (xy 429.268152 -17.295393)
			(xy 429.314036 -17.265909) (xy 429.363649 -17.243256) (xy 429.415981 -17.227894) (xy 429.469966 -17.220137)
			(xy 429.497236 -17.219676) (xy 430.360836 -17.219676) (xy 430.388106 -17.220089) (xy 430.442091 -17.227856)
			(xy 430.494422 -17.243226) (xy 430.544032 -17.265886) (xy 430.589913 -17.295376) (xy 430.631131 -17.331095)
			(xy 430.666846 -17.372315) (xy 430.696331 -17.418199) (xy 430.718987 -17.467812) (xy 430.734352 -17.520144)
			(xy 430.742114 -17.57413) (xy 430.742114 -17.62867) (xy 430.734352 -17.682656) (xy 430.718987 -17.734988)
			(xy 430.696331 -17.784601) (xy 430.666846 -17.830485) (xy 430.631131 -17.871705) (xy 430.589913 -17.907424)
			(xy 430.544032 -17.936914) (xy 430.494422 -17.959574) (xy 430.442091 -17.974944) (xy 430.388106 -17.982711)
			(xy 430.360836 -17.9832) (xy 429.497236 -17.9832) (xy 429.469966 -17.982663) (xy 429.415981 -17.974906)
			(xy 429.363649 -17.959544) (xy 429.314036 -17.936891) (xy 429.268152 -17.907407) (xy 429.226932 -17.871693)
			(xy 429.191214 -17.830476) (xy 429.161726 -17.784596) (xy 429.139068 -17.734985) (xy 429.123702 -17.682655)
			(xy 429.11594 -17.62867) (xy 425.120113 -17.62867) (xy 425.120113 -17.628672) (xy 425.112351 -17.682661)
			(xy 425.096984 -17.734996) (xy 425.074326 -17.784611) (xy 425.044837 -17.830496) (xy 425.009118 -17.871718)
			(xy 424.967896 -17.907437) (xy 424.922011 -17.936926) (xy 424.872396 -17.959584) (xy 424.820061 -17.974951)
			(xy 424.766072 -17.982713) (xy 424.7388 -17.9832) (xy 423.8752 -17.9832) (xy 423.847933 -17.982638)
			(xy 423.793955 -17.974877) (xy 423.741631 -17.959513) (xy 423.692026 -17.936859) (xy 423.646149 -17.907376)
			(xy 423.604936 -17.871664) (xy 423.569224 -17.830451) (xy 423.539741 -17.784574) (xy 423.517087 -17.734969)
			(xy 423.501723 -17.682645) (xy 423.493962 -17.628667) (xy 419.532113 -17.628667) (xy 419.532113 -17.628672)
			(xy 419.524351 -17.682661) (xy 419.508984 -17.734996) (xy 419.486326 -17.784611) (xy 419.456837 -17.830496)
			(xy 419.421118 -17.871718) (xy 419.379896 -17.907437) (xy 419.334011 -17.936926) (xy 419.284396 -17.959584)
			(xy 419.232061 -17.974951) (xy 419.178072 -17.982713) (xy 419.1508 -17.9832) (xy 418.2872 -17.9832)
			(xy 418.259933 -17.982638) (xy 418.205955 -17.974877) (xy 418.153631 -17.959513) (xy 418.104026 -17.936859)
			(xy 418.058149 -17.907376) (xy 418.016936 -17.871664) (xy 417.981224 -17.830451) (xy 417.951741 -17.784574)
			(xy 417.929087 -17.734969) (xy 417.913723 -17.682645) (xy 417.905962 -17.628667) (xy 413.638336 -17.628667)
			(xy 413.638336 -17.628674) (xy 413.630573 -17.682668) (xy 413.615204 -17.735007) (xy 413.592543 -17.784626)
			(xy 413.563051 -17.830515) (xy 413.527329 -17.87174) (xy 413.486103 -17.907461) (xy 413.440212 -17.936951)
			(xy 413.390592 -17.95961) (xy 413.338252 -17.974976) (xy 413.284258 -17.982738) (xy 413.256984 -17.9832)
			(xy 412.393384 -17.9832) (xy 412.366118 -17.982637) (xy 412.312142 -17.974874) (xy 412.259819 -17.959509)
			(xy 412.210216 -17.936854) (xy 412.164342 -17.90737) (xy 412.12313 -17.871659) (xy 412.08742 -17.830446)
			(xy 412.057939 -17.78457) (xy 412.035286 -17.734966) (xy 412.019923 -17.682643) (xy 412.012162 -17.628666)
			(xy 408.050336 -17.628666) (xy 408.050336 -17.628674) (xy 408.042573 -17.682668) (xy 408.027204 -17.735007)
			(xy 408.004543 -17.784626) (xy 407.975051 -17.830515) (xy 407.939329 -17.87174) (xy 407.898103 -17.907461)
			(xy 407.852212 -17.936951) (xy 407.802592 -17.95961) (xy 407.750252 -17.974976) (xy 407.696258 -17.982738)
			(xy 407.668984 -17.9832) (xy 406.805384 -17.9832) (xy 406.778118 -17.982637) (xy 406.724142 -17.974874)
			(xy 406.671819 -17.959509) (xy 406.622216 -17.936854) (xy 406.576342 -17.90737) (xy 406.53513 -17.871659)
			(xy 406.49942 -17.830446) (xy 406.469939 -17.78457) (xy 406.447286 -17.734966) (xy 406.431923 -17.682643)
			(xy 406.424162 -17.628666) (xy 402.462336 -17.628666) (xy 402.462336 -17.628674) (xy 402.454573 -17.682668)
			(xy 402.439204 -17.735007) (xy 402.416543 -17.784626) (xy 402.387051 -17.830515) (xy 402.351329 -17.87174)
			(xy 402.310103 -17.907461) (xy 402.264212 -17.936951) (xy 402.214592 -17.95961) (xy 402.162252 -17.974976)
			(xy 402.108258 -17.982738) (xy 402.080984 -17.9832) (xy 401.217384 -17.9832) (xy 401.190118 -17.982637)
			(xy 401.136142 -17.974874) (xy 401.083819 -17.959509) (xy 401.034216 -17.936854) (xy 400.988342 -17.90737)
			(xy 400.94713 -17.871659) (xy 400.91142 -17.830446) (xy 400.881939 -17.78457) (xy 400.859286 -17.734966)
			(xy 400.843923 -17.682643) (xy 400.836162 -17.628666) (xy 396.874336 -17.628666) (xy 396.874336 -17.628674)
			(xy 396.866573 -17.682668) (xy 396.851204 -17.735007) (xy 396.828543 -17.784626) (xy 396.799051 -17.830515)
			(xy 396.763329 -17.87174) (xy 396.722103 -17.907461) (xy 396.676212 -17.936951) (xy 396.626592 -17.95961)
			(xy 396.574252 -17.974976) (xy 396.520258 -17.982738) (xy 396.492984 -17.9832) (xy 395.629384 -17.9832)
			(xy 395.602118 -17.982637) (xy 395.548142 -17.974874) (xy 395.495819 -17.959509) (xy 395.446216 -17.936854)
			(xy 395.400342 -17.90737) (xy 395.35913 -17.871659) (xy 395.32342 -17.830446) (xy 395.293939 -17.78457)
			(xy 395.271286 -17.734966) (xy 395.255923 -17.682643) (xy 395.248162 -17.628666) (xy 391.286336 -17.628666)
			(xy 391.286336 -17.628674) (xy 391.278573 -17.682668) (xy 391.263204 -17.735007) (xy 391.240543 -17.784626)
			(xy 391.211051 -17.830515) (xy 391.175329 -17.87174) (xy 391.134103 -17.907461) (xy 391.088212 -17.936951)
			(xy 391.038592 -17.95961) (xy 390.986252 -17.974976) (xy 390.932258 -17.982738) (xy 390.904984 -17.9832)
			(xy 390.041384 -17.9832) (xy 390.014118 -17.982637) (xy 389.960142 -17.974874) (xy 389.907819 -17.959509)
			(xy 389.858216 -17.936854) (xy 389.812342 -17.90737) (xy 389.77113 -17.871659) (xy 389.73542 -17.830446)
			(xy 389.705939 -17.78457) (xy 389.683286 -17.734966) (xy 389.667923 -17.682643) (xy 389.660162 -17.628666)
			(xy 259.309108 -17.628666) (xy 259.309108 -19.152666) (xy 392.454162 -19.152666) (xy 392.454162 -19.098134)
			(xy 392.461923 -19.044157) (xy 392.477286 -18.991834) (xy 392.499939 -18.94223) (xy 392.52942 -18.896354)
			(xy 392.56513 -18.855141) (xy 392.606342 -18.81943) (xy 392.652216 -18.789946) (xy 392.701819 -18.767291)
			(xy 392.754142 -18.751926) (xy 392.808118 -18.744163) (xy 392.835384 -18.743676) (xy 393.698984 -18.743676)
			(xy 393.726258 -18.744062) (xy 393.780252 -18.751824) (xy 393.832592 -18.76719) (xy 393.882212 -18.789849)
			(xy 393.928103 -18.819339) (xy 393.969329 -18.85506) (xy 394.005051 -18.896285) (xy 394.034543 -18.942174)
			(xy 394.057204 -18.991793) (xy 394.072573 -19.044132) (xy 394.080336 -19.098126) (xy 394.080336 -19.152666)
			(xy 398.042162 -19.152666) (xy 398.042162 -19.098134) (xy 398.049923 -19.044157) (xy 398.065286 -18.991834)
			(xy 398.087939 -18.94223) (xy 398.11742 -18.896354) (xy 398.15313 -18.855141) (xy 398.194342 -18.81943)
			(xy 398.240216 -18.789946) (xy 398.289819 -18.767291) (xy 398.342142 -18.751926) (xy 398.396118 -18.744163)
			(xy 398.423384 -18.743676) (xy 399.286984 -18.743676) (xy 399.314258 -18.744062) (xy 399.368252 -18.751824)
			(xy 399.420592 -18.76719) (xy 399.470212 -18.789849) (xy 399.516103 -18.819339) (xy 399.557329 -18.85506)
			(xy 399.593051 -18.896285) (xy 399.622543 -18.942174) (xy 399.645204 -18.991793) (xy 399.660573 -19.044132)
			(xy 399.668336 -19.098126) (xy 399.668336 -19.152666) (xy 403.630162 -19.152666) (xy 403.630162 -19.098134)
			(xy 403.637923 -19.044157) (xy 403.653286 -18.991834) (xy 403.675939 -18.94223) (xy 403.70542 -18.896354)
			(xy 403.74113 -18.855141) (xy 403.782342 -18.81943) (xy 403.828216 -18.789946) (xy 403.877819 -18.767291)
			(xy 403.930142 -18.751926) (xy 403.984118 -18.744163) (xy 404.011384 -18.743676) (xy 404.874984 -18.743676)
			(xy 404.902258 -18.744062) (xy 404.956252 -18.751824) (xy 405.008592 -18.76719) (xy 405.058212 -18.789849)
			(xy 405.104103 -18.819339) (xy 405.145329 -18.85506) (xy 405.181051 -18.896285) (xy 405.210543 -18.942174)
			(xy 405.233204 -18.991793) (xy 405.248573 -19.044132) (xy 405.256336 -19.098126) (xy 405.256336 -19.152666)
			(xy 409.218162 -19.152666) (xy 409.218162 -19.098134) (xy 409.225923 -19.044157) (xy 409.241286 -18.991834)
			(xy 409.263939 -18.94223) (xy 409.29342 -18.896354) (xy 409.32913 -18.855141) (xy 409.370342 -18.81943)
			(xy 409.416216 -18.789946) (xy 409.465819 -18.767291) (xy 409.518142 -18.751926) (xy 409.572118 -18.744163)
			(xy 409.599384 -18.743676) (xy 410.462984 -18.743676) (xy 410.490258 -18.744062) (xy 410.544252 -18.751824)
			(xy 410.596592 -18.76719) (xy 410.646212 -18.789849) (xy 410.692103 -18.819339) (xy 410.733329 -18.85506)
			(xy 410.769051 -18.896285) (xy 410.798543 -18.942174) (xy 410.821204 -18.991793) (xy 410.836573 -19.044132)
			(xy 410.844336 -19.098126) (xy 410.844336 -19.152667) (xy 415.111962 -19.152667) (xy 415.111962 -19.098133)
			(xy 415.119723 -19.044155) (xy 415.135087 -18.991831) (xy 415.157741 -18.942226) (xy 415.187224 -18.896349)
			(xy 415.222936 -18.855136) (xy 415.264149 -18.819424) (xy 415.310026 -18.789941) (xy 415.359631 -18.767287)
			(xy 415.411955 -18.751923) (xy 415.465933 -18.744162) (xy 415.4932 -18.743676) (xy 416.3568 -18.743676)
			(xy 416.384072 -18.744087) (xy 416.438061 -18.751849) (xy 416.490396 -18.767216) (xy 416.540011 -18.789874)
			(xy 416.585896 -18.819363) (xy 416.627118 -18.855082) (xy 416.662837 -18.896304) (xy 416.692326 -18.942189)
			(xy 416.714984 -18.991804) (xy 416.730351 -19.044139) (xy 416.738113 -19.098128) (xy 416.738113 -19.152667)
			(xy 420.699962 -19.152667) (xy 420.699962 -19.098133) (xy 420.707723 -19.044155) (xy 420.723087 -18.991831)
			(xy 420.745741 -18.942226) (xy 420.775224 -18.896349) (xy 420.810936 -18.855136) (xy 420.852149 -18.819424)
			(xy 420.898026 -18.789941) (xy 420.947631 -18.767287) (xy 420.999955 -18.751923) (xy 421.053933 -18.744162)
			(xy 421.0812 -18.743676) (xy 421.9448 -18.743676) (xy 421.972072 -18.744087) (xy 422.026061 -18.751849)
			(xy 422.078396 -18.767216) (xy 422.128011 -18.789874) (xy 422.173896 -18.819363) (xy 422.215118 -18.855082)
			(xy 422.250837 -18.896304) (xy 422.280326 -18.942189) (xy 422.302984 -18.991804) (xy 422.318351 -19.044139)
			(xy 422.326113 -19.098128) (xy 422.326113 -19.15267) (xy 426.32194 -19.15267) (xy 426.32194 -19.09813)
			(xy 426.329702 -19.044145) (xy 426.345068 -18.991815) (xy 426.367726 -18.942204) (xy 426.397214 -18.896324)
			(xy 426.432932 -18.855107) (xy 426.474152 -18.819393) (xy 426.520036 -18.789909) (xy 426.569649 -18.767256)
			(xy 426.621981 -18.751894) (xy 426.675966 -18.744137) (xy 426.703236 -18.743676) (xy 427.566836 -18.743676)
			(xy 427.594106 -18.744089) (xy 427.648091 -18.751856) (xy 427.700422 -18.767226) (xy 427.750032 -18.789886)
			(xy 427.795913 -18.819376) (xy 427.837131 -18.855095) (xy 427.872846 -18.896315) (xy 427.902331 -18.942199)
			(xy 427.924987 -18.991812) (xy 427.940352 -19.044144) (xy 427.948114 -19.09813) (xy 427.948114 -19.15267)
			(xy 431.90994 -19.15267) (xy 431.90994 -19.09813) (xy 431.917702 -19.044145) (xy 431.933068 -18.991815)
			(xy 431.955726 -18.942204) (xy 431.985214 -18.896324) (xy 432.020932 -18.855107) (xy 432.062152 -18.819393)
			(xy 432.108036 -18.789909) (xy 432.157649 -18.767256) (xy 432.209981 -18.751894) (xy 432.263966 -18.744137)
			(xy 432.291236 -18.743676) (xy 433.154836 -18.743676) (xy 433.182106 -18.744089) (xy 433.236091 -18.751856)
			(xy 433.288422 -18.767226) (xy 433.338032 -18.789886) (xy 433.383913 -18.819376) (xy 433.425131 -18.855095)
			(xy 433.460846 -18.896315) (xy 433.490331 -18.942199) (xy 433.512987 -18.991812) (xy 433.528352 -19.044144)
			(xy 433.536114 -19.09813) (xy 433.536114 -19.15267) (xy 433.528352 -19.206656) (xy 433.512987 -19.258988)
			(xy 433.490331 -19.308601) (xy 433.460846 -19.354485) (xy 433.425131 -19.395705) (xy 433.383913 -19.431424)
			(xy 433.338032 -19.460914) (xy 433.288422 -19.483574) (xy 433.236091 -19.498944) (xy 433.182106 -19.506711)
			(xy 433.154836 -19.5072) (xy 432.291236 -19.5072) (xy 432.263966 -19.506663) (xy 432.209981 -19.498906)
			(xy 432.157649 -19.483544) (xy 432.108036 -19.460891) (xy 432.062152 -19.431407) (xy 432.020932 -19.395693)
			(xy 431.985214 -19.354476) (xy 431.955726 -19.308596) (xy 431.933068 -19.258985) (xy 431.917702 -19.206655)
			(xy 431.90994 -19.15267) (xy 427.948114 -19.15267) (xy 427.940352 -19.206656) (xy 427.924987 -19.258988)
			(xy 427.902331 -19.308601) (xy 427.872846 -19.354485) (xy 427.837131 -19.395705) (xy 427.795913 -19.431424)
			(xy 427.750032 -19.460914) (xy 427.700422 -19.483574) (xy 427.648091 -19.498944) (xy 427.594106 -19.506711)
			(xy 427.566836 -19.5072) (xy 426.703236 -19.5072) (xy 426.675966 -19.506663) (xy 426.621981 -19.498906)
			(xy 426.569649 -19.483544) (xy 426.520036 -19.460891) (xy 426.474152 -19.431407) (xy 426.432932 -19.395693)
			(xy 426.397214 -19.354476) (xy 426.367726 -19.308596) (xy 426.345068 -19.258985) (xy 426.329702 -19.206655)
			(xy 426.32194 -19.15267) (xy 422.326113 -19.15267) (xy 422.326113 -19.152672) (xy 422.318351 -19.206661)
			(xy 422.302984 -19.258996) (xy 422.280326 -19.308611) (xy 422.250837 -19.354496) (xy 422.215118 -19.395718)
			(xy 422.173896 -19.431437) (xy 422.128011 -19.460926) (xy 422.078396 -19.483584) (xy 422.026061 -19.498951)
			(xy 421.972072 -19.506713) (xy 421.9448 -19.5072) (xy 421.0812 -19.5072) (xy 421.053933 -19.506638)
			(xy 420.999955 -19.498877) (xy 420.947631 -19.483513) (xy 420.898026 -19.460859) (xy 420.852149 -19.431376)
			(xy 420.810936 -19.395664) (xy 420.775224 -19.354451) (xy 420.745741 -19.308574) (xy 420.723087 -19.258969)
			(xy 420.707723 -19.206645) (xy 420.699962 -19.152667) (xy 416.738113 -19.152667) (xy 416.738113 -19.152672)
			(xy 416.730351 -19.206661) (xy 416.714984 -19.258996) (xy 416.692326 -19.308611) (xy 416.662837 -19.354496)
			(xy 416.627118 -19.395718) (xy 416.585896 -19.431437) (xy 416.540011 -19.460926) (xy 416.490396 -19.483584)
			(xy 416.438061 -19.498951) (xy 416.384072 -19.506713) (xy 416.3568 -19.5072) (xy 415.4932 -19.5072)
			(xy 415.465933 -19.506638) (xy 415.411955 -19.498877) (xy 415.359631 -19.483513) (xy 415.310026 -19.460859)
			(xy 415.264149 -19.431376) (xy 415.222936 -19.395664) (xy 415.187224 -19.354451) (xy 415.157741 -19.308574)
			(xy 415.135087 -19.258969) (xy 415.119723 -19.206645) (xy 415.111962 -19.152667) (xy 410.844336 -19.152667)
			(xy 410.844336 -19.152674) (xy 410.836573 -19.206668) (xy 410.821204 -19.259007) (xy 410.798543 -19.308626)
			(xy 410.769051 -19.354515) (xy 410.733329 -19.39574) (xy 410.692103 -19.431461) (xy 410.646212 -19.460951)
			(xy 410.596592 -19.48361) (xy 410.544252 -19.498976) (xy 410.490258 -19.506738) (xy 410.462984 -19.5072)
			(xy 409.599384 -19.5072) (xy 409.572118 -19.506637) (xy 409.518142 -19.498874) (xy 409.465819 -19.483509)
			(xy 409.416216 -19.460854) (xy 409.370342 -19.43137) (xy 409.32913 -19.395659) (xy 409.29342 -19.354446)
			(xy 409.263939 -19.30857) (xy 409.241286 -19.258966) (xy 409.225923 -19.206643) (xy 409.218162 -19.152666)
			(xy 405.256336 -19.152666) (xy 405.256336 -19.152674) (xy 405.248573 -19.206668) (xy 405.233204 -19.259007)
			(xy 405.210543 -19.308626) (xy 405.181051 -19.354515) (xy 405.145329 -19.39574) (xy 405.104103 -19.431461)
			(xy 405.058212 -19.460951) (xy 405.008592 -19.48361) (xy 404.956252 -19.498976) (xy 404.902258 -19.506738)
			(xy 404.874984 -19.5072) (xy 404.011384 -19.5072) (xy 403.984118 -19.506637) (xy 403.930142 -19.498874)
			(xy 403.877819 -19.483509) (xy 403.828216 -19.460854) (xy 403.782342 -19.43137) (xy 403.74113 -19.395659)
			(xy 403.70542 -19.354446) (xy 403.675939 -19.30857) (xy 403.653286 -19.258966) (xy 403.637923 -19.206643)
			(xy 403.630162 -19.152666) (xy 399.668336 -19.152666) (xy 399.668336 -19.152674) (xy 399.660573 -19.206668)
			(xy 399.645204 -19.259007) (xy 399.622543 -19.308626) (xy 399.593051 -19.354515) (xy 399.557329 -19.39574)
			(xy 399.516103 -19.431461) (xy 399.470212 -19.460951) (xy 399.420592 -19.48361) (xy 399.368252 -19.498976)
			(xy 399.314258 -19.506738) (xy 399.286984 -19.5072) (xy 398.423384 -19.5072) (xy 398.396118 -19.506637)
			(xy 398.342142 -19.498874) (xy 398.289819 -19.483509) (xy 398.240216 -19.460854) (xy 398.194342 -19.43137)
			(xy 398.15313 -19.395659) (xy 398.11742 -19.354446) (xy 398.087939 -19.30857) (xy 398.065286 -19.258966)
			(xy 398.049923 -19.206643) (xy 398.042162 -19.152666) (xy 394.080336 -19.152666) (xy 394.080336 -19.152674)
			(xy 394.072573 -19.206668) (xy 394.057204 -19.259007) (xy 394.034543 -19.308626) (xy 394.005051 -19.354515)
			(xy 393.969329 -19.39574) (xy 393.928103 -19.431461) (xy 393.882212 -19.460951) (xy 393.832592 -19.48361)
			(xy 393.780252 -19.498976) (xy 393.726258 -19.506738) (xy 393.698984 -19.5072) (xy 392.835384 -19.5072)
			(xy 392.808118 -19.506637) (xy 392.754142 -19.498874) (xy 392.701819 -19.483509) (xy 392.652216 -19.460854)
			(xy 392.606342 -19.43137) (xy 392.56513 -19.395659) (xy 392.52942 -19.354446) (xy 392.499939 -19.30857)
			(xy 392.477286 -19.258966) (xy 392.461923 -19.206643) (xy 392.454162 -19.152666) (xy 259.309108 -19.152666)
			(xy 259.309108 -25.468351) (xy 388.406603 -25.468351) (xy 388.406603 -25.413849) (xy 388.41436 -25.359901)
			(xy 388.429716 -25.307607) (xy 388.452359 -25.25803) (xy 388.481827 -25.212181) (xy 388.517521 -25.170992)
			(xy 388.558713 -25.135303) (xy 388.604565 -25.10584) (xy 388.654144 -25.083202) (xy 388.70644 -25.067852)
			(xy 388.760389 -25.0601) (xy 388.78764 -25.05964) (xy 389.65124 -25.05964) (xy 389.678493 -25.060033)
			(xy 389.732443 -25.067795) (xy 389.78474 -25.083155) (xy 389.834318 -25.105802) (xy 389.880169 -25.135273)
			(xy 389.92136 -25.170969) (xy 389.957051 -25.212163) (xy 389.986518 -25.258017) (xy 390.009159 -25.307598)
			(xy 390.024514 -25.359896) (xy 390.03227 -25.413847) (xy 390.03227 -25.468353) (xy 390.024514 -25.522304)
			(xy 390.009159 -25.574602) (xy 389.986518 -25.624183) (xy 389.957051 -25.670037) (xy 389.92136 -25.711231)
			(xy 389.880169 -25.746927) (xy 389.834318 -25.776398) (xy 389.78474 -25.799045) (xy 389.732443 -25.814405)
			(xy 389.678493 -25.822167) (xy 389.65124 -25.822656) (xy 388.78764 -25.822656) (xy 388.760389 -25.8221)
			(xy 388.70644 -25.814348) (xy 388.654144 -25.798998) (xy 388.604565 -25.77636) (xy 388.558713 -25.746897)
			(xy 388.517521 -25.711208) (xy 388.481827 -25.670019) (xy 388.452359 -25.62417) (xy 388.429716 -25.574593)
			(xy 388.41436 -25.522299) (xy 388.406603 -25.468351) (xy 259.309108 -25.468351) (xy 259.309108 -28.450032)
			(xy 354.840804 -28.450032) (xy 354.844787 -28.322014) (xy 354.856722 -28.194492) (xy 354.876561 -28.067958)
			(xy 354.904228 -27.942902) (xy 354.939617 -27.819809) (xy 354.98259 -27.699153) (xy 355.032981 -27.581403)
			(xy 355.090595 -27.467013) (xy 355.155209 -27.356426) (xy 355.226573 -27.25007) (xy 355.304411 -27.148357)
			(xy 355.388422 -27.051679) (xy 355.478281 -26.960412) (xy 355.57364 -26.874907) (xy 355.674131 -26.795497)
			(xy 355.779364 -26.722487) (xy 355.888933 -26.656161) (xy 356.002413 -26.596775) (xy 356.119365 -26.544559)
			(xy 356.239338 -26.499715) (xy 356.361866 -26.462417) (xy 356.486477 -26.432808) (xy 356.612686 -26.411003)
			(xy 356.740008 -26.397087) (xy 356.867948 -26.391113) (xy 356.996012 -26.393105) (xy 357.123705 -26.403055)
			(xy 357.250532 -26.420924) (xy 357.376003 -26.446643) (xy 357.499632 -26.480113) (xy 357.620941 -26.521204)
			(xy 357.739461 -26.569758) (xy 357.854733 -26.625586) (xy 357.966311 -26.688472) (xy 358.073764 -26.758174)
			(xy 358.176676 -26.834421) (xy 358.274648 -26.916918) (xy 358.367302 -27.005347) (xy 358.454279 -27.099365)
			(xy 358.535243 -27.198608) (xy 358.60988 -27.302693) (xy 358.677902 -27.411217) (xy 358.739046 -27.52376)
			(xy 358.793074 -27.639886) (xy 358.839779 -27.759147) (xy 358.878979 -27.88108) (xy 358.910522 -28.005215)
			(xy 358.934287 -28.131071) (xy 358.950181 -28.25816) (xy 358.958144 -28.385992) (xy 358.958642 -28.450032)
			(xy 358.958144 -28.514072) (xy 358.950181 -28.641904) (xy 358.934287 -28.768993) (xy 358.910522 -28.894849)
			(xy 358.878979 -29.018984) (xy 358.839779 -29.140917) (xy 358.793074 -29.260178) (xy 358.739046 -29.376304)
			(xy 358.677902 -29.488847) (xy 358.60988 -29.597371) (xy 358.535243 -29.701456) (xy 358.454279 -29.800699)
			(xy 358.367302 -29.894717) (xy 358.274648 -29.983146) (xy 358.176676 -30.065643) (xy 358.073764 -30.14189)
			(xy 357.966311 -30.211592) (xy 357.854733 -30.274478) (xy 357.739461 -30.330306) (xy 357.620941 -30.37886)
			(xy 357.499632 -30.419951) (xy 357.376003 -30.453421) (xy 357.250532 -30.47914) (xy 357.123705 -30.497009)
			(xy 356.996012 -30.506959) (xy 356.867948 -30.508951) (xy 356.740008 -30.502977) (xy 356.612686 -30.489061)
			(xy 356.486477 -30.467256) (xy 356.361866 -30.437647) (xy 356.239338 -30.400349) (xy 356.119365 -30.355505)
			(xy 356.002413 -30.303289) (xy 355.888933 -30.243903) (xy 355.779364 -30.177577) (xy 355.674131 -30.104567)
			(xy 355.57364 -30.025157) (xy 355.478281 -29.939652) (xy 355.388422 -29.848385) (xy 355.304411 -29.751707)
			(xy 355.226573 -29.649994) (xy 355.155209 -29.543638) (xy 355.090595 -29.433051) (xy 355.032981 -29.318661)
			(xy 354.98259 -29.200911) (xy 354.939617 -29.080255) (xy 354.904228 -28.957162) (xy 354.876561 -28.832106)
			(xy 354.856722 -28.705572) (xy 354.844787 -28.57805) (xy 354.840804 -28.450032) (xy 259.309108 -28.450032)
			(xy 259.309108 -33.275016) (xy 259.308614 -33.345398) (xy 259.30072 -33.48594) (xy 259.284959 -33.625819)
			(xy 259.261379 -33.764594) (xy 259.230448 -33.90011) (xy 462.69148 -33.90011) (xy 462.69148 -32.29991)
			(xy 462.691988 -32.23523) (xy 462.700111 -32.106124) (xy 462.716324 -31.977784) (xy 462.740564 -31.850714)
			(xy 462.772734 -31.725418) (xy 462.812709 -31.602388) (xy 462.86033 -31.482112) (xy 462.915409 -31.365063)
			(xy 462.977729 -31.251703) (xy 463.047044 -31.14248) (xy 463.12308 -31.037825) (xy 463.205538 -30.938151)
			(xy 463.294091 -30.843851) (xy 463.388391 -30.755298) (xy 463.488065 -30.67284) (xy 463.59272 -30.596804)
			(xy 463.701943 -30.527489) (xy 463.815303 -30.465169) (xy 463.932352 -30.41009) (xy 464.052628 -30.362469)
			(xy 464.175658 -30.322494) (xy 464.300954 -30.290324) (xy 464.428024 -30.266084) (xy 464.556364 -30.249871)
			(xy 464.68547 -30.241748) (xy 464.81483 -30.241748) (xy 464.943936 -30.249871) (xy 465.072276 -30.266084)
			(xy 465.199346 -30.290324) (xy 465.324642 -30.322494) (xy 465.447672 -30.362469) (xy 465.567948 -30.41009)
			(xy 465.684997 -30.465169) (xy 465.798357 -30.527489) (xy 465.90758 -30.596804) (xy 466.012235 -30.67284)
			(xy 466.111909 -30.755298) (xy 466.206209 -30.843851) (xy 466.294762 -30.938151) (xy 466.37722 -31.037825)
			(xy 466.453256 -31.14248) (xy 466.522571 -31.251703) (xy 466.584891 -31.365063) (xy 466.63997 -31.482112)
			(xy 466.687591 -31.602388) (xy 466.727566 -31.725418) (xy 466.759736 -31.850714) (xy 466.783976 -31.977784)
			(xy 466.800189 -32.106124) (xy 466.808312 -32.23523) (xy 466.80882 -32.29991) (xy 466.80882 -33.90011)
			(xy 466.808312 -33.96479) (xy 466.800189 -34.093896) (xy 466.783976 -34.222236) (xy 466.759736 -34.349306)
			(xy 466.727566 -34.474602) (xy 466.687591 -34.597632) (xy 466.63997 -34.717908) (xy 466.584891 -34.834957)
			(xy 466.522571 -34.948317) (xy 466.453256 -35.05754) (xy 466.37722 -35.162195) (xy 466.294762 -35.261869)
			(xy 466.206209 -35.356169) (xy 466.111909 -35.444722) (xy 466.012235 -35.52718) (xy 465.90758 -35.603216)
			(xy 465.798357 -35.672531) (xy 465.684997 -35.734851) (xy 465.567948 -35.78993) (xy 465.447672 -35.837551)
			(xy 465.324642 -35.877526) (xy 465.199346 -35.909696) (xy 465.072276 -35.933936) (xy 464.943936 -35.950149)
			(xy 464.81483 -35.958272) (xy 464.68547 -35.958272) (xy 464.556364 -35.950149) (xy 464.428024 -35.933936)
			(xy 464.300954 -35.909696) (xy 464.175658 -35.877526) (xy 464.052628 -35.837551) (xy 463.932352 -35.78993)
			(xy 463.815303 -35.734851) (xy 463.701943 -35.672531) (xy 463.59272 -35.603216) (xy 463.488065 -35.52718)
			(xy 463.388391 -35.444722) (xy 463.294091 -35.356169) (xy 463.205538 -35.261869) (xy 463.12308 -35.162195)
			(xy 463.047044 -35.05754) (xy 462.977729 -34.948317) (xy 462.915409 -34.834957) (xy 462.86033 -34.717908)
			(xy 462.812709 -34.597632) (xy 462.772734 -34.474602) (xy 462.740564 -34.349306) (xy 462.716324 -34.222236)
			(xy 462.700111 -34.093896) (xy 462.691988 -33.96479) (xy 462.69148 -33.90011) (xy 259.230448 -33.90011)
			(xy 259.230056 -33.901828) (xy 259.191086 -34.03709) (xy 259.144594 -34.169955) (xy 259.090726 -34.300003)
			(xy 259.02965 -34.426827) (xy 258.961559 -34.550026) (xy 258.886668 -34.669214) (xy 258.805211 -34.784015)
			(xy 258.717446 -34.894068) (xy 258.623648 -34.999027) (xy 258.524113 -35.098562) (xy 258.419153 -35.192359)
			(xy 258.324611 -35.267753) (xy 356.989346 -35.267753) (xy 356.989346 -35.213247) (xy 356.997102 -35.159297)
			(xy 357.012458 -35.106999) (xy 357.035099 -35.057419) (xy 357.064566 -35.011566) (xy 357.100259 -34.970373)
			(xy 357.14145 -34.934678) (xy 357.187302 -34.905209) (xy 357.236881 -34.882565) (xy 357.289177 -34.867207)
			(xy 357.343127 -34.859447) (xy 357.37038 -34.85896) (xy 358.23398 -34.85896) (xy 358.261232 -34.859486)
			(xy 358.31518 -34.86724) (xy 358.367476 -34.882593) (xy 358.417054 -34.905232) (xy 358.462906 -34.934697)
			(xy 358.504098 -34.970388) (xy 358.539791 -35.011578) (xy 358.569258 -35.057428) (xy 358.5919 -35.107005)
			(xy 358.607256 -35.1593) (xy 358.615013 -35.213249) (xy 358.615013 -35.267751) (xy 358.607256 -35.3217)
			(xy 358.5919 -35.373995) (xy 358.569258 -35.423572) (xy 358.539791 -35.469422) (xy 358.504098 -35.510612)
			(xy 358.462906 -35.546303) (xy 358.417054 -35.575768) (xy 358.367476 -35.598407) (xy 358.31518 -35.61376)
			(xy 358.261232 -35.621514) (xy 358.23398 -35.621976) (xy 357.37038 -35.621976) (xy 357.343127 -35.621553)
			(xy 357.289177 -35.613793) (xy 357.236881 -35.598435) (xy 357.187302 -35.575791) (xy 357.14145 -35.546322)
			(xy 357.100259 -35.510627) (xy 357.064566 -35.469434) (xy 357.035099 -35.423581) (xy 357.012458 -35.374001)
			(xy 356.997102 -35.321703) (xy 356.989346 -35.267753) (xy 258.324611 -35.267753) (xy 258.309099 -35.280123)
			(xy 258.194297 -35.361579) (xy 258.075109 -35.436469) (xy 257.951909 -35.504559) (xy 257.825085 -35.565634)
			(xy 257.695036 -35.619502) (xy 257.562171 -35.665993) (xy 257.426909 -35.704961) (xy 257.289674 -35.736283)
			(xy 257.150899 -35.759862) (xy 257.01102 -35.775622) (xy 256.870478 -35.783514) (xy 256.800096 -35.784028)
			(xy 225.300032 -35.784028) (xy 225.229649 -35.783544) (xy 225.089104 -35.775653) (xy 224.949222 -35.759894)
			(xy 224.810444 -35.736316) (xy 224.673207 -35.704995) (xy 224.537941 -35.666027) (xy 224.405074 -35.619536)
			(xy 224.275022 -35.565669) (xy 224.148195 -35.504594) (xy 224.024992 -35.436504) (xy 223.905801 -35.361613)
			(xy 223.790997 -35.280156) (xy 223.68094 -35.192391) (xy 223.575978 -35.098593) (xy 223.47644 -34.999057)
			(xy 223.38264 -34.894096) (xy 223.294872 -34.784042) (xy 223.213414 -34.669239) (xy 223.138521 -34.550049)
			(xy 223.070428 -34.426848) (xy 223.009351 -34.300022) (xy 222.955481 -34.169971) (xy 222.908988 -34.037104)
			(xy 222.870017 -33.90184) (xy 222.838693 -33.764603) (xy 222.815113 -33.625825) (xy 222.799351 -33.485944)
			(xy 222.791457 -33.345399) (xy 222.79102 -33.275016) (xy 222.79102 -13.780008) (xy 222.790499 -13.724238)
			(xy 222.782164 -13.613011) (xy 222.765541 -13.502717) (xy 222.740722 -13.393974) (xy 222.707846 -13.287389)
			(xy 222.667097 -13.183559) (xy 222.618703 -13.083065) (xy 222.562935 -12.986469) (xy 222.500103 -12.894309)
			(xy 222.430561 -12.807103) (xy 222.354696 -12.725338) (xy 222.272933 -12.64947) (xy 222.185729 -12.579925)
			(xy 222.093572 -12.517091) (xy 221.996977 -12.461319) (xy 221.896485 -12.412922) (xy 221.792656 -12.37217)
			(xy 221.686073 -12.339291) (xy 221.57733 -12.314468) (xy 221.467037 -12.297841) (xy 221.35581 -12.289503)
			(xy 221.30004 -12.289028) (xy 196.701918 -12.289028) (xy 196.631535 -12.288544) (xy 196.49099 -12.280652)
			(xy 196.35111 -12.264892) (xy 196.212332 -12.241314) (xy 196.075095 -12.209992) (xy 195.939831 -12.171024)
			(xy 195.806964 -12.124532) (xy 195.676913 -12.070665) (xy 195.550086 -12.009589) (xy 195.426884 -11.941499)
			(xy 195.307694 -11.866608) (xy 195.19289 -11.785152) (xy 195.082834 -11.697386) (xy 194.977873 -11.603588)
			(xy 194.878335 -11.504052) (xy 194.784536 -11.399092) (xy 194.696769 -11.289037) (xy 194.615311 -11.174234)
			(xy 194.540418 -11.055045) (xy 194.472326 -10.931844) (xy 194.411249 -10.805018) (xy 194.35738 -10.674968)
			(xy 194.310887 -10.542102) (xy 194.271917 -10.406837) (xy 194.240593 -10.269601) (xy 194.217013 -10.130824)
			(xy 194.201251 -9.990943) (xy 194.193357 -9.850399) (xy 194.192906 -9.780016) (xy 194.192906 -6.279896)
			(xy 194.19238 -6.247749) (xy 194.183988 -6.184006) (xy 194.167348 -6.121904) (xy 194.142744 -6.062504)
			(xy 194.110598 -6.006824) (xy 194.07146 -5.955816) (xy 194.025999 -5.910353) (xy 193.974992 -5.871213)
			(xy 193.919314 -5.839064) (xy 193.859915 -5.814458) (xy 193.797813 -5.797816) (xy 193.734071 -5.789421)
			(xy 193.701924 -5.788914) (xy 127.102108 -5.788914) (xy 127.06996 -5.789416) (xy 127.006214 -5.797808)
			(xy 126.944108 -5.814448) (xy 126.884706 -5.839052) (xy 126.829023 -5.8712) (xy 126.778013 -5.91034)
			(xy 126.732548 -5.955804) (xy 126.693406 -6.006813) (xy 126.661257 -6.062495) (xy 126.636652 -6.121897)
			(xy 126.62001 -6.184002) (xy 126.611617 -6.247748) (xy 126.611126 -6.279896) (xy 126.611126 -9.780016)
			(xy 126.610632 -9.850398) (xy 126.602738 -9.990941) (xy 126.586977 -10.13082) (xy 126.563397 -10.269595)
			(xy 126.532074 -10.40683) (xy 126.519617 -10.450068) (xy 127.350273 -10.450068) (xy 127.354278 -10.36216)
			(xy 127.366261 -10.27498) (xy 127.386121 -10.189251) (xy 127.413696 -10.105683) (xy 127.448755 -10.024969)
			(xy 127.491008 -9.947777) (xy 127.540106 -9.874748) (xy 127.595642 -9.806486) (xy 127.657154 -9.743556)
			(xy 127.724135 -9.686482) (xy 127.796028 -9.635734) (xy 127.872237 -9.591734) (xy 127.952132 -9.554847)
			(xy 128.035051 -9.525378) (xy 128.120306 -9.503571) (xy 128.20719 -9.489607) (xy 128.294984 -9.483601)
			(xy 128.382961 -9.485605) (xy 128.470391 -9.4956) (xy 128.55655 -9.513504) (xy 128.640724 -9.539168)
			(xy 128.722215 -9.572381) (xy 128.800349 -9.612867) (xy 128.874477 -9.660289) (xy 128.943985 -9.714256)
			(xy 129.008299 -9.774321) (xy 129.066883 -9.839985) (xy 129.119254 -9.910704) (xy 129.164977 -9.985892)
			(xy 129.203674 -10.064927) (xy 129.235023 -10.147153) (xy 129.258765 -10.231889) (xy 129.265884 -10.270548)
			(xy 131.63909 -10.270548) (xy 131.63909 -10.216052) (xy 131.646845 -10.16211) (xy 131.662198 -10.10982)
			(xy 131.684835 -10.060247) (xy 131.714296 -10.014401) (xy 131.749982 -9.973213) (xy 131.791165 -9.937522)
			(xy 131.837009 -9.908056) (xy 131.886579 -9.885413) (xy 131.938866 -9.870055) (xy 131.992808 -9.862293)
			(xy 132.020056 -9.861804) (xy 132.883656 -9.861804) (xy 132.910912 -9.86224) (xy 132.964869 -9.869992)
			(xy 133.017174 -9.885345) (xy 133.066761 -9.907985) (xy 133.112622 -9.937453) (xy 133.153821 -9.973148)
			(xy 133.18952 -10.014343) (xy 133.218993 -10.0602) (xy 133.24164 -10.109785) (xy 133.256999 -10.162088)
			(xy 133.264757 -10.216044) (xy 133.264757 -10.270556) (xy 133.256999 -10.324512) (xy 133.24164 -10.376815)
			(xy 133.218993 -10.4264) (xy 133.18952 -10.472257) (xy 133.153821 -10.513452) (xy 133.112622 -10.549147)
			(xy 133.066761 -10.578615) (xy 133.017174 -10.601255) (xy 132.964869 -10.616608) (xy 132.910912 -10.62436)
			(xy 132.883656 -10.62482) (xy 132.020056 -10.62482) (xy 131.992808 -10.624307) (xy 131.938866 -10.616545)
			(xy 131.886579 -10.601187) (xy 131.837009 -10.578544) (xy 131.791165 -10.549078) (xy 131.749982 -10.513387)
			(xy 131.714296 -10.472199) (xy 131.684835 -10.426353) (xy 131.662198 -10.37678) (xy 131.646845 -10.32449)
			(xy 131.63909 -10.270548) (xy 129.265884 -10.270548) (xy 129.274703 -10.318433) (xy 129.282705 -10.406068)
			(xy 129.283206 -10.450068) (xy 129.282705 -10.494068) (xy 129.274703 -10.581703) (xy 129.258765 -10.668247)
			(xy 129.235023 -10.752983) (xy 129.203674 -10.835209) (xy 129.164977 -10.914244) (xy 129.119254 -10.989432)
			(xy 129.087321 -11.032553) (xy 168.158867 -11.032553) (xy 168.158867 -10.978047) (xy 168.166625 -10.924096)
			(xy 168.181981 -10.871798) (xy 168.204625 -10.822218) (xy 168.234094 -10.776365) (xy 168.269789 -10.735173)
			(xy 168.310983 -10.699481) (xy 168.356837 -10.670014) (xy 168.406419 -10.647374) (xy 168.458717 -10.63202)
			(xy 168.512669 -10.624266) (xy 168.539922 -10.623804) (xy 169.403522 -10.623804) (xy 169.430773 -10.624267)
			(xy 169.48472 -10.632027) (xy 169.537014 -10.647384) (xy 169.58659 -10.670027) (xy 169.632439 -10.699495)
			(xy 169.673628 -10.735188) (xy 169.709318 -10.776379) (xy 169.738783 -10.822229) (xy 169.761424 -10.871807)
			(xy 169.776778 -10.924101) (xy 169.784534 -10.978049) (xy 169.784534 -11.032551) (xy 169.776778 -11.086499)
			(xy 169.761424 -11.138793) (xy 169.738783 -11.188371) (xy 169.709318 -11.234221) (xy 169.673628 -11.275412)
			(xy 169.632439 -11.311105) (xy 169.58659 -11.340573) (xy 169.537014 -11.363216) (xy 169.48472 -11.378573)
			(xy 169.430773 -11.386333) (xy 169.403522 -11.38682) (xy 168.539922 -11.38682) (xy 168.512669 -11.386334)
			(xy 168.458717 -11.37858) (xy 168.406419 -11.363226) (xy 168.356837 -11.340586) (xy 168.310983 -11.311119)
			(xy 168.269789 -11.275427) (xy 168.234094 -11.234235) (xy 168.204625 -11.188382) (xy 168.181981 -11.138802)
			(xy 168.166625 -11.086504) (xy 168.158867 -11.032553) (xy 129.087321 -11.032553) (xy 129.066883 -11.060151)
			(xy 129.008299 -11.125815) (xy 128.943985 -11.18588) (xy 128.874477 -11.239847) (xy 128.800349 -11.287269)
			(xy 128.722215 -11.327755) (xy 128.640724 -11.360968) (xy 128.55655 -11.386632) (xy 128.470391 -11.404536)
			(xy 128.382961 -11.414531) (xy 128.294984 -11.416535) (xy 128.20719 -11.410529) (xy 128.120306 -11.396565)
			(xy 128.035051 -11.374758) (xy 127.952132 -11.345289) (xy 127.872237 -11.308402) (xy 127.796028 -11.264402)
			(xy 127.724135 -11.213654) (xy 127.657154 -11.15658) (xy 127.595642 -11.09365) (xy 127.540106 -11.025388)
			(xy 127.491008 -10.952359) (xy 127.448755 -10.875167) (xy 127.413696 -10.794453) (xy 127.386121 -10.710885)
			(xy 127.366261 -10.625156) (xy 127.354278 -10.537976) (xy 127.350273 -10.450068) (xy 126.519617 -10.450068)
			(xy 126.493105 -10.542092) (xy 126.446613 -10.674957) (xy 126.392744 -10.805006) (xy 126.331668 -10.93183)
			(xy 126.263578 -11.05503) (xy 126.188687 -11.174218) (xy 126.10723 -11.28902) (xy 126.019465 -11.399074)
			(xy 125.973895 -11.450066) (xy 191.515245 -11.450066) (xy 191.51925 -11.362158) (xy 191.531233 -11.274978)
			(xy 191.551093 -11.189249) (xy 191.578668 -11.105681) (xy 191.613727 -11.024967) (xy 191.65598 -10.947775)
			(xy 191.705078 -10.874746) (xy 191.760614 -10.806484) (xy 191.822126 -10.743554) (xy 191.889107 -10.68648)
			(xy 191.961 -10.635732) (xy 192.037209 -10.591732) (xy 192.117104 -10.554845) (xy 192.200023 -10.525376)
			(xy 192.285278 -10.503569) (xy 192.372162 -10.489605) (xy 192.459956 -10.483599) (xy 192.547933 -10.485603)
			(xy 192.635363 -10.495598) (xy 192.721522 -10.513502) (xy 192.805696 -10.539166) (xy 192.887187 -10.572379)
			(xy 192.965321 -10.612865) (xy 193.039449 -10.660287) (xy 193.108957 -10.714254) (xy 193.173271 -10.774319)
			(xy 193.231855 -10.839983) (xy 193.284226 -10.910702) (xy 193.329949 -10.98589) (xy 193.368646 -11.064925)
			(xy 193.399995 -11.147151) (xy 193.423737 -11.231887) (xy 193.439675 -11.318431) (xy 193.447677 -11.406066)
			(xy 193.448178 -11.450066) (xy 193.447677 -11.494066) (xy 193.439675 -11.581701) (xy 193.423737 -11.668245)
			(xy 193.399995 -11.752981) (xy 193.368646 -11.835207) (xy 193.329949 -11.914242) (xy 193.284226 -11.98943)
			(xy 193.231855 -12.060149) (xy 193.173271 -12.125813) (xy 193.108957 -12.185878) (xy 193.039449 -12.239845)
			(xy 192.965321 -12.287267) (xy 192.887187 -12.327753) (xy 192.805696 -12.360966) (xy 192.721522 -12.38663)
			(xy 192.635363 -12.404534) (xy 192.547933 -12.414529) (xy 192.459956 -12.416533) (xy 192.372162 -12.410527)
			(xy 192.285278 -12.396563) (xy 192.200023 -12.374756) (xy 192.117104 -12.345287) (xy 192.037209 -12.3084)
			(xy 191.961 -12.2644) (xy 191.889107 -12.213652) (xy 191.822126 -12.156578) (xy 191.760614 -12.093648)
			(xy 191.705078 -12.025386) (xy 191.65598 -11.952357) (xy 191.613727 -11.875165) (xy 191.578668 -11.794451)
			(xy 191.551093 -11.710883) (xy 191.531233 -11.625154) (xy 191.51925 -11.537974) (xy 191.515245 -11.450066)
			(xy 125.973895 -11.450066) (xy 125.925667 -11.504033) (xy 125.826132 -11.603569) (xy 125.721172 -11.697366)
			(xy 125.611118 -11.785131) (xy 125.496317 -11.866588) (xy 125.377128 -11.941479) (xy 125.253928 -12.009569)
			(xy 125.206611 -12.032356) (xy 166.354411 -12.032356) (xy 166.354411 -11.977844) (xy 166.362169 -11.923886)
			(xy 166.377527 -11.871582) (xy 166.400173 -11.821995) (xy 166.429645 -11.776137) (xy 166.465343 -11.734939)
			(xy 166.506541 -11.699241) (xy 166.552401 -11.66977) (xy 166.601987 -11.647125) (xy 166.654292 -11.631768)
			(xy 166.70825 -11.624011) (xy 166.735506 -11.623548) (xy 167.599106 -11.623548) (xy 167.626354 -11.624123)
			(xy 167.680295 -11.631879) (xy 167.732583 -11.647233) (xy 167.782153 -11.669872) (xy 167.827998 -11.699335)
			(xy 167.869182 -11.735022) (xy 167.904869 -11.776207) (xy 167.934331 -11.822052) (xy 167.956969 -11.871623)
			(xy 167.972322 -11.923911) (xy 167.980078 -11.977852) (xy 167.980078 -12.032348) (xy 167.980077 -12.032358)
			(xy 169.954311 -12.032358) (xy 169.954311 -11.977842) (xy 169.96207 -11.92388) (xy 169.97743 -11.871573)
			(xy 170.000079 -11.821984) (xy 170.029555 -11.776123) (xy 170.065258 -11.734924) (xy 170.106461 -11.699226)
			(xy 170.152326 -11.669756) (xy 170.201918 -11.647114) (xy 170.254227 -11.63176) (xy 170.30819 -11.624008)
			(xy 170.335448 -11.623548) (xy 171.199048 -11.623548) (xy 171.226294 -11.624125) (xy 171.28023 -11.631887)
			(xy 171.332513 -11.647244) (xy 171.382078 -11.669885) (xy 171.427917 -11.699349) (xy 171.469097 -11.735037)
			(xy 171.504779 -11.776221) (xy 171.534238 -11.822064) (xy 171.556873 -11.871632) (xy 171.572224 -11.923917)
			(xy 171.579978 -11.977854) (xy 171.579978 -12.032346) (xy 171.572224 -12.086283) (xy 171.556873 -12.138568)
			(xy 171.534238 -12.188136) (xy 171.504779 -12.233979) (xy 171.469097 -12.275163) (xy 171.427917 -12.310851)
			(xy 171.382078 -12.340315) (xy 171.332513 -12.362956) (xy 171.28023 -12.378313) (xy 171.226294 -12.386075)
			(xy 171.199048 -12.386564) (xy 170.335448 -12.386564) (xy 170.30819 -12.386192) (xy 170.254227 -12.37844)
			(xy 170.201918 -12.363086) (xy 170.152326 -12.340444) (xy 170.106461 -12.310974) (xy 170.065258 -12.275276)
			(xy 170.029555 -12.234077) (xy 170.000079 -12.188216) (xy 169.97743 -12.138627) (xy 169.96207 -12.08632)
			(xy 169.954311 -12.032358) (xy 167.980077 -12.032358) (xy 167.972322 -12.086289) (xy 167.956969 -12.138577)
			(xy 167.934331 -12.188148) (xy 167.904869 -12.233993) (xy 167.869182 -12.275178) (xy 167.827998 -12.310865)
			(xy 167.782153 -12.340328) (xy 167.732583 -12.362967) (xy 167.680295 -12.378321) (xy 167.626354 -12.386077)
			(xy 167.599106 -12.386564) (xy 166.735506 -12.386564) (xy 166.70825 -12.386189) (xy 166.654292 -12.378432)
			(xy 166.601987 -12.363075) (xy 166.552401 -12.34043) (xy 166.506541 -12.310959) (xy 166.465343 -12.275261)
			(xy 166.429645 -12.234063) (xy 166.400173 -12.188205) (xy 166.377527 -12.138618) (xy 166.362169 -12.086314)
			(xy 166.354411 -12.032356) (xy 125.206611 -12.032356) (xy 125.127104 -12.070645) (xy 124.997055 -12.124513)
			(xy 124.86419 -12.171005) (xy 124.728928 -12.209974) (xy 124.591693 -12.241298) (xy 124.452918 -12.264877)
			(xy 124.313039 -12.280639) (xy 124.172496 -12.288532) (xy 124.102114 -12.289028) (xy 83.70189 -12.289028)
			(xy 83.631508 -12.288534) (xy 83.490965 -12.280641) (xy 83.351086 -12.26488) (xy 83.21231 -12.2413)
			(xy 83.075075 -12.209977) (xy 82.939812 -12.171008) (xy 82.806947 -12.124516) (xy 82.676898 -12.070648)
			(xy 82.550073 -12.009572) (xy 82.426873 -11.941482) (xy 82.307684 -11.866591) (xy 82.192882 -11.785134)
			(xy 82.082828 -11.697369) (xy 81.977868 -11.603571) (xy 81.878333 -11.504036) (xy 81.784535 -11.399076)
			(xy 81.696769 -11.289022) (xy 81.615313 -11.174221) (xy 81.540421 -11.055032) (xy 81.47233 -10.931832)
			(xy 81.411254 -10.805008) (xy 81.357386 -10.674959) (xy 81.310894 -10.542094) (xy 81.271924 -10.406831)
			(xy 81.240601 -10.269596) (xy 81.217021 -10.13082) (xy 81.20126 -9.990941) (xy 81.193366 -9.850398)
			(xy 81.192878 -9.780016) (xy 81.192878 -0.999998) (xy 81.192375 -0.96785) (xy 81.183982 -0.904106)
			(xy 81.167341 -0.842001) (xy 81.142736 -0.782601) (xy 81.110589 -0.72692) (xy 81.071448 -0.675911)
			(xy 81.025984 -0.630448) (xy 80.974975 -0.591308) (xy 80.919294 -0.559161) (xy 80.859893 -0.534557)
			(xy 80.797789 -0.517916) (xy 80.734044 -0.509525) (xy 80.701896 -0.509016) (xy 14.10208 -0.509016)
			(xy 14.069935 -0.509543) (xy 14.006194 -0.517937) (xy 13.944095 -0.534579) (xy 13.884698 -0.559184)
			(xy 13.829022 -0.59133) (xy 13.778017 -0.630469) (xy 13.732558 -0.675931) (xy 13.69342 -0.726937)
			(xy 13.661276 -0.782614) (xy 13.636673 -0.842012) (xy 13.620034 -0.904112) (xy 13.611642 -0.967853)
			(xy 13.611098 -0.999998) (xy 13.611098 -5.184498) (xy 14.350702 -5.184498) (xy 14.35331 -5.097781)
			(xy 14.363685 -5.011647) (xy 14.381743 -4.926791) (xy 14.40734 -4.843896) (xy 14.440268 -4.763631)
			(xy 14.480262 -4.686643) (xy 14.526999 -4.613552) (xy 14.580104 -4.544948) (xy 14.639148 -4.481383)
			(xy 14.703655 -4.42337) (xy 14.738096 -4.396994) (xy 14.773029 -4.371293) (xy 14.846784 -4.325653)
			(xy 14.924335 -4.28681) (xy 15.005056 -4.255076) (xy 15.088297 -4.230709) (xy 15.173387 -4.213903)
			(xy 15.259642 -4.204794) (xy 15.346366 -4.203455) (xy 15.432861 -4.209898) (xy 15.518429 -4.224071)
			(xy 15.602382 -4.245858) (xy 15.684044 -4.275086) (xy 15.762756 -4.311517) (xy 15.837884 -4.35486)
			(xy 15.908824 -4.404764) (xy 15.975003 -4.460828) (xy 16.035889 -4.5226) (xy 16.090991 -4.589582)
			(xy 16.139865 -4.661235) (xy 16.182118 -4.736981) (xy 16.217409 -4.816211) (xy 16.245454 -4.898286)
			(xy 16.266027 -4.982545) (xy 16.267136 -4.989901) (xy 20.44038 -4.989901) (xy 20.44038 -4.935399)
			(xy 20.448136 -4.881452) (xy 20.463491 -4.829158) (xy 20.486132 -4.779581) (xy 20.515597 -4.733731)
			(xy 20.551288 -4.692541) (xy 20.592478 -4.65685) (xy 20.638328 -4.627384) (xy 20.687904 -4.604742)
			(xy 20.740198 -4.589387) (xy 20.794145 -4.58163) (xy 20.821396 -4.581144) (xy 21.684996 -4.581144)
			(xy 21.712249 -4.581603) (xy 21.766201 -4.58936) (xy 21.818499 -4.604715) (xy 21.86808 -4.627358)
			(xy 21.913934 -4.656826) (xy 21.955128 -4.69252) (xy 21.990822 -4.733713) (xy 22.02029 -4.779566)
			(xy 22.042933 -4.829147) (xy 22.05829 -4.881445) (xy 22.066047 -4.935397) (xy 22.066047 -4.989901)
			(xy 24.04032 -4.989901) (xy 24.04032 -4.935399) (xy 24.048076 -4.881452) (xy 24.063431 -4.829157)
			(xy 24.086072 -4.779581) (xy 24.115538 -4.73373) (xy 24.151229 -4.692541) (xy 24.192419 -4.656849)
			(xy 24.238269 -4.627383) (xy 24.287846 -4.604742) (xy 24.34014 -4.589387) (xy 24.394087 -4.58163)
			(xy 24.421338 -4.581144) (xy 25.284938 -4.581144) (xy 25.312191 -4.581603) (xy 25.366143 -4.58936)
			(xy 25.418441 -4.604716) (xy 25.468021 -4.627358) (xy 25.513875 -4.656827) (xy 25.555068 -4.69252)
			(xy 25.590762 -4.733713) (xy 25.620231 -4.779567) (xy 25.642873 -4.829147) (xy 25.65823 -4.881446)
			(xy 25.665987 -4.935397) (xy 25.665987 -4.989903) (xy 25.66598 -4.989954) (xy 27.64023 -4.989954)
			(xy 27.64023 -4.935446) (xy 27.647987 -4.881493) (xy 27.663343 -4.829194) (xy 27.685985 -4.779612)
			(xy 27.715454 -4.733756) (xy 27.751147 -4.692562) (xy 27.79234 -4.656866) (xy 27.838194 -4.627395)
			(xy 27.887775 -4.60475) (xy 27.940074 -4.589391) (xy 27.994026 -4.581631) (xy 28.02128 -4.581144)
			(xy 28.88488 -4.581144) (xy 28.91213 -4.581702) (xy 28.966077 -4.589456) (xy 29.01837 -4.604808)
			(xy 29.067947 -4.627446) (xy 29.113797 -4.65691) (xy 29.154986 -4.692599) (xy 29.190678 -4.733787)
			(xy 29.220144 -4.779636) (xy 29.242785 -4.829211) (xy 29.25814 -4.881504) (xy 29.265897 -4.93545)
			(xy 29.265897 -4.98995) (xy 29.265896 -4.989954) (xy 31.24043 -4.989954) (xy 31.24043 -4.935446)
			(xy 31.248187 -4.881494) (xy 31.263543 -4.829195) (xy 31.286185 -4.779613) (xy 31.315653 -4.733758)
			(xy 31.351346 -4.692563) (xy 31.392538 -4.656867) (xy 31.438392 -4.627396) (xy 31.487972 -4.604751)
			(xy 31.540271 -4.589392) (xy 31.594222 -4.581632) (xy 31.621476 -4.581144) (xy 32.485076 -4.581144)
			(xy 32.512327 -4.581702) (xy 32.566273 -4.589455) (xy 32.618567 -4.604807) (xy 32.668144 -4.627445)
			(xy 32.713995 -4.656909) (xy 32.755185 -4.692598) (xy 32.790877 -4.733786) (xy 32.820343 -4.779635)
			(xy 32.842985 -4.82921) (xy 32.85834 -4.881503) (xy 32.866097 -4.935449) (xy 32.866097 -4.989951)
			(xy 32.866096 -4.989958) (xy 40.350307 -4.989958) (xy 40.350307 -4.935442) (xy 40.358066 -4.881481)
			(xy 40.373426 -4.829173) (xy 40.396074 -4.779584) (xy 40.42555 -4.733723) (xy 40.461252 -4.692524)
			(xy 40.502455 -4.656826) (xy 40.548319 -4.627355) (xy 40.59791 -4.604712) (xy 40.65022 -4.589358)
			(xy 40.704182 -4.581604) (xy 40.73144 -4.581144) (xy 41.59504 -4.581144) (xy 41.622286 -4.581729)
			(xy 41.676222 -4.589489) (xy 41.728506 -4.604846) (xy 41.778072 -4.627486) (xy 41.823911 -4.65695)
			(xy 41.865091 -4.692637) (xy 41.900774 -4.733821) (xy 41.930233 -4.779663) (xy 41.952868 -4.829232)
			(xy 41.968219 -4.881517) (xy 41.975974 -4.935454) (xy 41.975974 -4.989946) (xy 41.975973 -4.989954)
			(xy 43.95033 -4.989954) (xy 43.95033 -4.935446) (xy 43.958087 -4.881493) (xy 43.973443 -4.829193)
			(xy 43.996086 -4.779611) (xy 44.025554 -4.733756) (xy 44.061248 -4.692561) (xy 44.102441 -4.656865)
			(xy 44.148295 -4.627394) (xy 44.197876 -4.604749) (xy 44.250176 -4.589391) (xy 44.304128 -4.581631)
			(xy 44.331382 -4.581144) (xy 45.194982 -4.581144) (xy 45.222232 -4.581702) (xy 45.276178 -4.589456)
			(xy 45.328472 -4.604808) (xy 45.378048 -4.627447) (xy 45.423898 -4.656911) (xy 45.465087 -4.6926)
			(xy 45.500778 -4.733788) (xy 45.530244 -4.779636) (xy 45.552885 -4.829211) (xy 45.56824 -4.881504)
			(xy 45.575997 -4.93545) (xy 45.575997 -4.98995) (xy 45.575996 -4.989954) (xy 51.56043 -4.989954)
			(xy 51.56043 -4.935446) (xy 51.568187 -4.881494) (xy 51.583543 -4.829195) (xy 51.606185 -4.779613)
			(xy 51.635653 -4.733758) (xy 51.671346 -4.692563) (xy 51.712538 -4.656867) (xy 51.758392 -4.627396)
			(xy 51.807972 -4.604751) (xy 51.860271 -4.589392) (xy 51.914222 -4.581632) (xy 51.941476 -4.581144)
			(xy 52.805076 -4.581144) (xy 52.832327 -4.581702) (xy 52.886273 -4.589455) (xy 52.938567 -4.604807)
			(xy 52.988144 -4.627445) (xy 53.033995 -4.656909) (xy 53.075185 -4.692598) (xy 53.110877 -4.733786)
			(xy 53.140343 -4.779635) (xy 53.162985 -4.82921) (xy 53.17834 -4.881503) (xy 53.186097 -4.935449)
			(xy 53.186097 -4.989951) (xy 53.186096 -4.989957) (xy 55.160307 -4.989957) (xy 55.160307 -4.935443)
			(xy 55.168065 -4.881484) (xy 55.183424 -4.829178) (xy 55.206071 -4.77959) (xy 55.235544 -4.73373)
			(xy 55.271245 -4.692532) (xy 55.312445 -4.656834) (xy 55.358306 -4.627362) (xy 55.407894 -4.604718)
			(xy 55.460201 -4.589362) (xy 55.514161 -4.581606) (xy 55.541418 -4.581144) (xy 56.405018 -4.581144)
			(xy 56.432265 -4.581727) (xy 56.486204 -4.589485) (xy 56.53849 -4.60484) (xy 56.588058 -4.627479)
			(xy 56.633901 -4.656942) (xy 56.675084 -4.692629) (xy 56.710769 -4.733814) (xy 56.74023 -4.779657)
			(xy 56.762867 -4.829227) (xy 56.778219 -4.881514) (xy 56.785974 -4.935453) (xy 56.785974 -4.989947)
			(xy 56.778219 -5.043886) (xy 56.762867 -5.096173) (xy 56.74023 -5.145743) (xy 56.710769 -5.191586)
			(xy 56.675084 -5.232771) (xy 56.633901 -5.268458) (xy 56.588058 -5.297921) (xy 56.53849 -5.32056)
			(xy 56.486204 -5.335915) (xy 56.432265 -5.343673) (xy 56.405018 -5.34416) (xy 55.541418 -5.34416)
			(xy 55.514161 -5.343794) (xy 55.460201 -5.336038) (xy 55.407894 -5.320682) (xy 55.358306 -5.298038)
			(xy 55.312445 -5.268566) (xy 55.271245 -5.232868) (xy 55.235544 -5.19167) (xy 55.206071 -5.14581)
			(xy 55.183424 -5.096222) (xy 55.168065 -5.043916) (xy 55.160307 -4.989957) (xy 53.186096 -4.989957)
			(xy 53.17834 -5.043897) (xy 53.162985 -5.09619) (xy 53.140343 -5.145765) (xy 53.110877 -5.191614)
			(xy 53.075185 -5.232802) (xy 53.033995 -5.268491) (xy 52.988144 -5.297955) (xy 52.938567 -5.320593)
			(xy 52.886273 -5.335945) (xy 52.832327 -5.343698) (xy 52.805076 -5.34416) (xy 51.941476 -5.34416)
			(xy 51.914222 -5.343768) (xy 51.860271 -5.336008) (xy 51.807972 -5.320649) (xy 51.758392 -5.298004)
			(xy 51.712538 -5.268533) (xy 51.671346 -5.232837) (xy 51.635653 -5.191642) (xy 51.606185 -5.145787)
			(xy 51.583543 -5.096205) (xy 51.568187 -5.043906) (xy 51.56043 -4.989954) (xy 45.575996 -4.989954)
			(xy 45.56824 -5.043896) (xy 45.552885 -5.096189) (xy 45.530244 -5.145764) (xy 45.500778 -5.191612)
			(xy 45.465087 -5.2328) (xy 45.423898 -5.268489) (xy 45.378048 -5.297953) (xy 45.328472 -5.320592)
			(xy 45.276178 -5.335944) (xy 45.222232 -5.343698) (xy 45.194982 -5.34416) (xy 44.331382 -5.34416)
			(xy 44.304128 -5.343769) (xy 44.250176 -5.336009) (xy 44.197876 -5.320651) (xy 44.148295 -5.298006)
			(xy 44.102441 -5.268535) (xy 44.061248 -5.232839) (xy 44.025554 -5.191644) (xy 43.996086 -5.145789)
			(xy 43.973443 -5.096207) (xy 43.958087 -5.043907) (xy 43.95033 -4.989954) (xy 41.975973 -4.989954)
			(xy 41.968219 -5.043883) (xy 41.952868 -5.096168) (xy 41.930233 -5.145737) (xy 41.900774 -5.191579)
			(xy 41.865091 -5.232763) (xy 41.823911 -5.26845) (xy 41.778072 -5.297914) (xy 41.728506 -5.320554)
			(xy 41.676222 -5.335911) (xy 41.622286 -5.343671) (xy 41.59504 -5.34416) (xy 40.73144 -5.34416) (xy 40.704182 -5.343796)
			(xy 40.65022 -5.336042) (xy 40.59791 -5.320688) (xy 40.548319 -5.298045) (xy 40.502455 -5.268574)
			(xy 40.461252 -5.232876) (xy 40.42555 -5.191677) (xy 40.396074 -5.145816) (xy 40.373426 -5.096227)
			(xy 40.358066 -5.043919) (xy 40.350307 -4.989958) (xy 32.866096 -4.989958) (xy 32.85834 -5.043897)
			(xy 32.842985 -5.09619) (xy 32.820343 -5.145765) (xy 32.790877 -5.191614) (xy 32.755185 -5.232802)
			(xy 32.713995 -5.268491) (xy 32.668144 -5.297955) (xy 32.618567 -5.320593) (xy 32.566273 -5.335945)
			(xy 32.512327 -5.343698) (xy 32.485076 -5.34416) (xy 31.621476 -5.34416) (xy 31.594222 -5.343768)
			(xy 31.540271 -5.336008) (xy 31.487972 -5.320649) (xy 31.438392 -5.298004) (xy 31.392538 -5.268533)
			(xy 31.351346 -5.232837) (xy 31.315653 -5.191642) (xy 31.286185 -5.145787) (xy 31.263543 -5.096205)
			(xy 31.248187 -5.043906) (xy 31.24043 -4.989954) (xy 29.265896 -4.989954) (xy 29.25814 -5.043896)
			(xy 29.242785 -5.096189) (xy 29.220144 -5.145764) (xy 29.190678 -5.191613) (xy 29.154986 -5.232801)
			(xy 29.113797 -5.26849) (xy 29.067947 -5.297954) (xy 29.01837 -5.320592) (xy 28.966077 -5.335944)
			(xy 28.91213 -5.343698) (xy 28.88488 -5.34416) (xy 28.02128 -5.34416) (xy 27.994026 -5.343769) (xy 27.940074 -5.336009)
			(xy 27.887775 -5.32065) (xy 27.838194 -5.298005) (xy 27.79234 -5.268534) (xy 27.751147 -5.232838)
			(xy 27.715454 -5.191644) (xy 27.685985 -5.145788) (xy 27.663343 -5.096206) (xy 27.647987 -5.043907)
			(xy 27.64023 -4.989954) (xy 25.66598 -4.989954) (xy 25.65823 -5.043854) (xy 25.642873 -5.096153)
			(xy 25.620231 -5.145733) (xy 25.590762 -5.191587) (xy 25.555068 -5.23278) (xy 25.513875 -5.268473)
			(xy 25.468021 -5.297942) (xy 25.418441 -5.320584) (xy 25.366143 -5.33594) (xy 25.312191 -5.343697)
			(xy 25.284938 -5.34416) (xy 24.421338 -5.34416) (xy 24.394087 -5.34367) (xy 24.34014 -5.335913) (xy 24.287846 -5.320558)
			(xy 24.238269 -5.297917) (xy 24.192419 -5.268451) (xy 24.151229 -5.232759) (xy 24.115538 -5.19157)
			(xy 24.086072 -5.145719) (xy 24.063431 -5.096143) (xy 24.048076 -5.043848) (xy 24.04032 -4.989901)
			(xy 22.066047 -4.989901) (xy 22.066047 -4.989903) (xy 22.05829 -5.043855) (xy 22.042933 -5.096153)
			(xy 22.02029 -5.145734) (xy 21.990822 -5.191587) (xy 21.955128 -5.23278) (xy 21.913934 -5.268474)
			(xy 21.86808 -5.297942) (xy 21.818499 -5.320585) (xy 21.766201 -5.33594) (xy 21.712249 -5.343697)
			(xy 21.684996 -5.34416) (xy 20.821396 -5.34416) (xy 20.794145 -5.34367) (xy 20.740198 -5.335913)
			(xy 20.687904 -5.320558) (xy 20.638328 -5.297916) (xy 20.592478 -5.26845) (xy 20.551288 -5.232759)
			(xy 20.515597 -5.191569) (xy 20.486132 -5.145719) (xy 20.463491 -5.096142) (xy 20.448136 -5.043848)
			(xy 20.44038 -4.989901) (xy 16.267136 -4.989901) (xy 16.278962 -5.06831) (xy 16.284155 -5.154889)
			(xy 16.281564 -5.241584) (xy 16.27121 -5.327698) (xy 16.253177 -5.412537) (xy 16.22761 -5.495418)
			(xy 16.194714 -5.575672) (xy 16.154755 -5.652653) (xy 16.108054 -5.725741) (xy 16.054988 -5.794348)
			(xy 15.995985 -5.85792) (xy 15.931519 -5.915946) (xy 15.897098 -5.94233) (xy 15.862132 -5.968006)
			(xy 15.788377 -6.013689) (xy 15.710822 -6.052572) (xy 15.630093 -6.084344) (xy 15.546839 -6.108746)
			(xy 15.461732 -6.125584) (xy 15.375458 -6.13472) (xy 15.288712 -6.136082) (xy 15.202194 -6.129659)
			(xy 15.116601 -6.115502) (xy 15.032622 -6.093724) (xy 14.950935 -6.064503) (xy 14.872197 -6.028073)
			(xy 14.797045 -5.984729) (xy 14.726083 -5.934818) (xy 14.659883 -5.878744) (xy 14.598979 -5.816959)
			(xy 14.543862 -5.749961) (xy 14.494977 -5.678289) (xy 14.452716 -5.602521) (xy 14.417421 -5.523269)
			(xy 14.389376 -5.44117) (xy 14.368808 -5.356887) (xy 14.355882 -5.271099) (xy 14.350702 -5.184498)
			(xy 13.611098 -5.184498) (xy 13.611098 -6.169914) (xy 78.515217 -6.169914) (xy 78.519222 -6.082006)
			(xy 78.531205 -5.994826) (xy 78.551065 -5.909097) (xy 78.57864 -5.825529) (xy 78.613699 -5.744815)
			(xy 78.655952 -5.667623) (xy 78.70505 -5.594594) (xy 78.760586 -5.526332) (xy 78.822098 -5.463402)
			(xy 78.889079 -5.406328) (xy 78.960972 -5.35558) (xy 79.037181 -5.31158) (xy 79.117076 -5.274693)
			(xy 79.199995 -5.245224) (xy 79.28525 -5.223417) (xy 79.372134 -5.209453) (xy 79.459928 -5.203447)
			(xy 79.547905 -5.205451) (xy 79.635335 -5.215446) (xy 79.721494 -5.23335) (xy 79.805668 -5.259014)
			(xy 79.887159 -5.292227) (xy 79.965293 -5.332713) (xy 80.039421 -5.380135) (xy 80.108929 -5.434102)
			(xy 80.173243 -5.494167) (xy 80.231827 -5.559831) (xy 80.284198 -5.63055) (xy 80.329921 -5.705738)
			(xy 80.368618 -5.784773) (xy 80.399967 -5.866999) (xy 80.423709 -5.951735) (xy 80.439647 -6.038279)
			(xy 80.447649 -6.125914) (xy 80.44815 -6.169914) (xy 80.447649 -6.213914) (xy 80.439647 -6.301549)
			(xy 80.423709 -6.388093) (xy 80.399967 -6.472829) (xy 80.368618 -6.555055) (xy 80.329921 -6.63409)
			(xy 80.284198 -6.709278) (xy 80.231827 -6.779997) (xy 80.173243 -6.845661) (xy 80.108929 -6.905726)
			(xy 80.039421 -6.959693) (xy 79.965293 -7.007115) (xy 79.887159 -7.047601) (xy 79.805668 -7.080814)
			(xy 79.721494 -7.106478) (xy 79.635335 -7.124382) (xy 79.547905 -7.134377) (xy 79.459928 -7.136381)
			(xy 79.372134 -7.130375) (xy 79.28525 -7.116411) (xy 79.199995 -7.094604) (xy 79.117076 -7.065135)
			(xy 79.037181 -7.028248) (xy 78.960972 -6.984248) (xy 78.889079 -6.9335) (xy 78.822098 -6.876426)
			(xy 78.760586 -6.813496) (xy 78.70505 -6.745234) (xy 78.655952 -6.672205) (xy 78.613699 -6.595013)
			(xy 78.57864 -6.514299) (xy 78.551065 -6.430731) (xy 78.531205 -6.345002) (xy 78.519222 -6.257822)
			(xy 78.515217 -6.169914) (xy 13.611098 -6.169914) (xy 13.611098 -6.751654) (xy 18.635651 -6.751654)
			(xy 18.635651 -6.697146) (xy 18.643409 -6.643192) (xy 18.658767 -6.590891) (xy 18.681411 -6.541309)
			(xy 18.710882 -6.495454) (xy 18.746579 -6.45426) (xy 18.787775 -6.418566) (xy 18.833632 -6.389099)
			(xy 18.883216 -6.366458) (xy 18.935517 -6.351104) (xy 18.989472 -6.34335) (xy 19.016726 -6.342888)
			(xy 19.880326 -6.342888) (xy 19.907576 -6.343384) (xy 19.96152 -6.351143) (xy 20.013811 -6.3665)
			(xy 20.063385 -6.389143) (xy 20.109231 -6.418609) (xy 20.150418 -6.4543) (xy 20.186106 -6.49549)
			(xy 20.21557 -6.541338) (xy 20.238209 -6.590913) (xy 20.253563 -6.643205) (xy 20.261318 -6.69715)
			(xy 20.261318 -6.75165) (xy 22.235674 -6.75165) (xy 22.235674 -6.69715) (xy 22.243429 -6.643204)
			(xy 22.258783 -6.590912) (xy 22.281422 -6.541336) (xy 22.310886 -6.495487) (xy 22.346574 -6.454297)
			(xy 22.387761 -6.418605) (xy 22.433608 -6.389138) (xy 22.483182 -6.366494) (xy 22.535473 -6.351136)
			(xy 22.589418 -6.343376) (xy 22.616668 -6.342888) (xy 23.480268 -6.342888) (xy 23.507522 -6.343357)
			(xy 23.561476 -6.35111) (xy 23.613777 -6.366463) (xy 23.663361 -6.389104) (xy 23.709217 -6.418571)
			(xy 23.750413 -6.454264) (xy 23.78611 -6.495457) (xy 23.815581 -6.541311) (xy 23.838225 -6.590893)
			(xy 23.853583 -6.643193) (xy 23.861341 -6.697146) (xy 23.861341 -6.751654) (xy 25.835551 -6.751654)
			(xy 25.835551 -6.697146) (xy 25.843309 -6.643194) (xy 25.858665 -6.590895) (xy 25.881309 -6.541314)
			(xy 25.910778 -6.495459) (xy 25.946473 -6.454266) (xy 25.987667 -6.418572) (xy 26.033522 -6.389104)
			(xy 26.083104 -6.366462) (xy 26.135404 -6.351107) (xy 26.189356 -6.343351) (xy 26.21661 -6.342888)
			(xy 27.08021 -6.342888) (xy 27.10746 -6.343382) (xy 27.161407 -6.35114) (xy 27.2137 -6.366496) (xy 27.263275 -6.389137)
			(xy 27.309124 -6.418604) (xy 27.350312 -6.454295) (xy 27.386002 -6.495484) (xy 27.415467 -6.541334)
			(xy 27.438108 -6.59091) (xy 27.453462 -6.643203) (xy 27.461218 -6.697149) (xy 27.461218 -6.751651)
			(xy 27.461218 -6.751653) (xy 29.435751 -6.751653) (xy 29.435751 -6.697147) (xy 29.443509 -6.643195)
			(xy 29.458865 -6.590896) (xy 29.481508 -6.541315) (xy 29.510977 -6.495461) (xy 29.546672 -6.454268)
			(xy 29.587866 -6.418574) (xy 29.63372 -6.389105) (xy 29.683301 -6.366463) (xy 29.7356 -6.351107)
			(xy 29.789553 -6.343351) (xy 29.816806 -6.342888) (xy 30.680406 -6.342888) (xy 30.707657 -6.343382)
			(xy 30.761603 -6.351139) (xy 30.813897 -6.366495) (xy 30.863473 -6.389136) (xy 30.909322 -6.418602)
			(xy 30.950511 -6.454293) (xy 30.986201 -6.495483) (xy 31.015667 -6.541333) (xy 31.038307 -6.590909)
			(xy 31.053662 -6.643203) (xy 31.061418 -6.697149) (xy 31.061418 -6.75165) (xy 38.545774 -6.75165)
			(xy 38.545774 -6.69715) (xy 38.55353 -6.643204) (xy 38.568883 -6.590911) (xy 38.591522 -6.541336)
			(xy 38.620986 -6.495486) (xy 38.656675 -6.454296) (xy 38.697862 -6.418604) (xy 38.743709 -6.389137)
			(xy 38.793283 -6.366494) (xy 38.845575 -6.351136) (xy 38.89952 -6.343376) (xy 38.92677 -6.342888)
			(xy 39.79037 -6.342888) (xy 39.817624 -6.343357) (xy 39.871578 -6.351111) (xy 39.923878 -6.366464)
			(xy 39.973462 -6.389105) (xy 40.019318 -6.418571) (xy 40.060514 -6.454265) (xy 40.096211 -6.495458)
			(xy 40.125681 -6.541312) (xy 40.148326 -6.590893) (xy 40.163683 -6.643193) (xy 40.171441 -6.697146)
			(xy 40.171441 -6.751654) (xy 42.145651 -6.751654) (xy 42.145651 -6.697146) (xy 42.153409 -6.643194)
			(xy 42.168766 -6.590894) (xy 42.191409 -6.541313) (xy 42.220879 -6.495459) (xy 42.256574 -6.454265)
			(xy 42.297768 -6.418571) (xy 42.343624 -6.389103) (xy 42.393206 -6.366461) (xy 42.445506 -6.351106)
			(xy 42.499458 -6.343351) (xy 42.526712 -6.342888) (xy 43.390312 -6.342888) (xy 43.417562 -6.343383)
			(xy 43.471508 -6.35114) (xy 43.523801 -6.366496) (xy 43.573376 -6.389138) (xy 43.619225 -6.418604)
			(xy 43.660413 -6.454295) (xy 43.696103 -6.495485) (xy 43.725568 -6.541334) (xy 43.748208 -6.59091)
			(xy 43.763562 -6.643203) (xy 43.771318 -6.69715) (xy 43.771318 -6.75165) (xy 43.771318 -6.751653)
			(xy 49.755751 -6.751653) (xy 49.755751 -6.697147) (xy 49.763509 -6.643195) (xy 49.778865 -6.590896)
			(xy 49.801508 -6.541315) (xy 49.830977 -6.495461) (xy 49.866672 -6.454268) (xy 49.907866 -6.418574)
			(xy 49.95372 -6.389105) (xy 50.003301 -6.366463) (xy 50.0556 -6.351107) (xy 50.109553 -6.343351)
			(xy 50.136806 -6.342888) (xy 51.000406 -6.342888) (xy 51.027657 -6.343382) (xy 51.081603 -6.351139)
			(xy 51.133897 -6.366495) (xy 51.183473 -6.389136) (xy 51.229322 -6.418602) (xy 51.270511 -6.454293)
			(xy 51.306201 -6.495483) (xy 51.335667 -6.541333) (xy 51.358307 -6.590909) (xy 51.373662 -6.643203)
			(xy 51.381418 -6.697149) (xy 51.381418 -6.751651) (xy 51.381417 -6.751655) (xy 53.355652 -6.751655)
			(xy 53.355652 -6.697145) (xy 53.36341 -6.643189) (xy 53.378768 -6.590887) (xy 53.401415 -6.541303)
			(xy 53.430887 -6.495447) (xy 53.466587 -6.454253) (xy 53.507785 -6.418559) (xy 53.553645 -6.389092)
			(xy 53.603232 -6.366452) (xy 53.655536 -6.3511) (xy 53.709493 -6.343348) (xy 53.736748 -6.342888)
			(xy 54.600348 -6.342888) (xy 54.627597 -6.343385) (xy 54.681539 -6.351147) (xy 54.733827 -6.366506)
			(xy 54.783398 -6.38915) (xy 54.829242 -6.418617) (xy 54.870426 -6.454308) (xy 54.906112 -6.495497)
			(xy 54.935573 -6.541344) (xy 54.958211 -6.590918) (xy 54.973563 -6.643208) (xy 54.981318 -6.697151)
			(xy 54.981318 -6.751649) (xy 54.981318 -6.751651) (xy 56.955674 -6.751651) (xy 56.955674 -6.697149)
			(xy 56.96343 -6.643201) (xy 56.978785 -6.590907) (xy 57.001426 -6.54133) (xy 57.030891 -6.49548)
			(xy 57.066582 -6.454289) (xy 57.107771 -6.418597) (xy 57.153621 -6.38913) (xy 57.203198 -6.366488)
			(xy 57.255492 -6.351132) (xy 57.309439 -6.343374) (xy 57.33669 -6.342888) (xy 58.20029 -6.342888)
			(xy 58.227543 -6.343359) (xy 58.281494 -6.351114) (xy 58.333793 -6.366469) (xy 58.383374 -6.389111)
			(xy 58.429228 -6.418578) (xy 58.470421 -6.454272) (xy 58.506116 -6.495464) (xy 58.535584 -6.541317)
			(xy 58.558227 -6.590898) (xy 58.573583 -6.643196) (xy 58.581341 -6.697147) (xy 58.581341 -6.751651)
			(xy 70.950574 -6.751651) (xy 70.950574 -6.697149) (xy 70.95833 -6.643203) (xy 70.973684 -6.590909)
			(xy 70.996324 -6.541332) (xy 71.025789 -6.495482) (xy 71.061479 -6.454292) (xy 71.102668 -6.4186)
			(xy 71.148516 -6.389133) (xy 71.198092 -6.366491) (xy 71.250385 -6.351134) (xy 71.304331 -6.343375)
			(xy 71.331582 -6.342888) (xy 72.195182 -6.342888) (xy 72.222435 -6.343358) (xy 72.276388 -6.351113)
			(xy 72.328687 -6.366467) (xy 72.378269 -6.389108) (xy 72.424124 -6.418576) (xy 72.465318 -6.454269)
			(xy 72.501014 -6.495462) (xy 72.530483 -6.541315) (xy 72.553126 -6.590896) (xy 72.568483 -6.643195)
			(xy 72.576241 -6.697147) (xy 72.576241 -6.751653) (xy 72.568483 -6.805605) (xy 72.553126 -6.857904)
			(xy 72.530483 -6.907485) (xy 72.501014 -6.953338) (xy 72.465318 -6.994531) (xy 72.424124 -7.030224)
			(xy 72.378269 -7.059692) (xy 72.328687 -7.082333) (xy 72.276388 -7.097687) (xy 72.222435 -7.105442)
			(xy 72.195182 -7.105904) (xy 71.331582 -7.105904) (xy 71.304331 -7.105425) (xy 71.250385 -7.097666)
			(xy 71.198092 -7.082309) (xy 71.148516 -7.059667) (xy 71.102668 -7.0302) (xy 71.061479 -6.994508)
			(xy 71.025789 -6.953318) (xy 70.996324 -6.907468) (xy 70.973684 -6.857891) (xy 70.95833 -6.805597)
			(xy 70.950574 -6.751651) (xy 58.581341 -6.751651) (xy 58.581341 -6.751653) (xy 58.573583 -6.805604)
			(xy 58.558227 -6.857902) (xy 58.535584 -6.907483) (xy 58.506116 -6.953336) (xy 58.470421 -6.994528)
			(xy 58.429228 -7.030222) (xy 58.383374 -7.059689) (xy 58.333793 -7.082331) (xy 58.281494 -7.097686)
			(xy 58.227543 -7.105441) (xy 58.20029 -7.105904) (xy 57.33669 -7.105904) (xy 57.309439 -7.105426)
			(xy 57.255492 -7.097668) (xy 57.203198 -7.082312) (xy 57.153621 -7.05967) (xy 57.107771 -7.030203)
			(xy 57.066582 -6.994511) (xy 57.030891 -6.95332) (xy 57.001426 -6.90747) (xy 56.978785 -6.857893)
			(xy 56.96343 -6.805599) (xy 56.955674 -6.751651) (xy 54.981318 -6.751651) (xy 54.973563 -6.805592)
			(xy 54.958211 -6.857882) (xy 54.935573 -6.907456) (xy 54.906112 -6.953303) (xy 54.870426 -6.994492)
			(xy 54.829242 -7.030183) (xy 54.783398 -7.05965) (xy 54.733827 -7.082294) (xy 54.681539 -7.097653)
			(xy 54.627597 -7.105415) (xy 54.600348 -7.105904) (xy 53.736748 -7.105904) (xy 53.709493 -7.105452)
			(xy 53.655536 -7.0977) (xy 53.603232 -7.082348) (xy 53.553645 -7.059708) (xy 53.507785 -7.030241)
			(xy 53.466587 -6.994547) (xy 53.430887 -6.953353) (xy 53.401415 -6.907497) (xy 53.378768 -6.857913)
			(xy 53.36341 -6.805611) (xy 53.355652 -6.751655) (xy 51.381417 -6.751655) (xy 51.373662 -6.805597)
			(xy 51.358307 -6.857891) (xy 51.335667 -6.907467) (xy 51.306201 -6.953317) (xy 51.270511 -6.994507)
			(xy 51.229322 -7.030198) (xy 51.183473 -7.059664) (xy 51.133897 -7.082305) (xy 51.081603 -7.097661)
			(xy 51.027657 -7.105418) (xy 51.000406 -7.105904) (xy 50.136806 -7.105904) (xy 50.109553 -7.105449)
			(xy 50.0556 -7.097693) (xy 50.003301 -7.082337) (xy 49.95372 -7.059695) (xy 49.907866 -7.030226)
			(xy 49.866672 -6.994532) (xy 49.830977 -6.953339) (xy 49.801508 -6.907485) (xy 49.778865 -6.857904)
			(xy 49.763509 -6.805605) (xy 49.755751 -6.751653) (xy 43.771318 -6.751653) (xy 43.763562 -6.805597)
			(xy 43.748208 -6.85789) (xy 43.725568 -6.907466) (xy 43.696103 -6.953315) (xy 43.660413 -6.994505)
			(xy 43.619225 -7.030196) (xy 43.573376 -7.059662) (xy 43.523801 -7.082304) (xy 43.471508 -7.09766)
			(xy 43.417562 -7.105417) (xy 43.390312 -7.105904) (xy 42.526712 -7.105904) (xy 42.499458 -7.105449)
			(xy 42.445506 -7.097694) (xy 42.393206 -7.082339) (xy 42.343624 -7.059697) (xy 42.297768 -7.030229)
			(xy 42.256574 -6.994535) (xy 42.220879 -6.953341) (xy 42.191409 -6.907487) (xy 42.168766 -6.857906)
			(xy 42.153409 -6.805606) (xy 42.145651 -6.751654) (xy 40.171441 -6.751654) (xy 40.163683 -6.805607)
			(xy 40.148326 -6.857907) (xy 40.125681 -6.907488) (xy 40.096211 -6.953342) (xy 40.060514 -6.994535)
			(xy 40.019318 -7.030229) (xy 39.973462 -7.059695) (xy 39.923878 -7.082336) (xy 39.871578 -7.097689)
			(xy 39.817624 -7.105443) (xy 39.79037 -7.105904) (xy 38.92677 -7.105904) (xy 38.89952 -7.105424)
			(xy 38.845575 -7.097664) (xy 38.793283 -7.082306) (xy 38.743709 -7.059663) (xy 38.697862 -7.030196)
			(xy 38.656675 -6.994504) (xy 38.620986 -6.953314) (xy 38.591522 -6.907464) (xy 38.568883 -6.857889)
			(xy 38.55353 -6.805596) (xy 38.545774 -6.75165) (xy 31.061418 -6.75165) (xy 31.061418 -6.751651)
			(xy 31.053662 -6.805597) (xy 31.038307 -6.857891) (xy 31.015667 -6.907467) (xy 30.986201 -6.953317)
			(xy 30.950511 -6.994507) (xy 30.909322 -7.030198) (xy 30.863473 -7.059664) (xy 30.813897 -7.082305)
			(xy 30.761603 -7.097661) (xy 30.707657 -7.105418) (xy 30.680406 -7.105904) (xy 29.816806 -7.105904)
			(xy 29.789553 -7.105449) (xy 29.7356 -7.097693) (xy 29.683301 -7.082337) (xy 29.63372 -7.059695)
			(xy 29.587866 -7.030226) (xy 29.546672 -6.994532) (xy 29.510977 -6.953339) (xy 29.481508 -6.907485)
			(xy 29.458865 -6.857904) (xy 29.443509 -6.805605) (xy 29.435751 -6.751653) (xy 27.461218 -6.751653)
			(xy 27.453462 -6.805597) (xy 27.438108 -6.85789) (xy 27.415467 -6.907466) (xy 27.386002 -6.953316)
			(xy 27.350312 -6.994505) (xy 27.309124 -7.030196) (xy 27.263275 -7.059663) (xy 27.2137 -7.082304)
			(xy 27.161407 -7.09766) (xy 27.10746 -7.105418) (xy 27.08021 -7.105904) (xy 26.21661 -7.105904) (xy 26.189356 -7.105449)
			(xy 26.135404 -7.097693) (xy 26.083104 -7.082338) (xy 26.033522 -7.059696) (xy 25.987667 -7.030228)
			(xy 25.946473 -6.994534) (xy 25.910778 -6.953341) (xy 25.881309 -6.907486) (xy 25.858665 -6.857905)
			(xy 25.843309 -6.805606) (xy 25.835551 -6.751654) (xy 23.861341 -6.751654) (xy 23.853583 -6.805607)
			(xy 23.838225 -6.857907) (xy 23.815581 -6.907489) (xy 23.78611 -6.953343) (xy 23.750413 -6.994536)
			(xy 23.709217 -7.030229) (xy 23.663361 -7.059696) (xy 23.613777 -7.082337) (xy 23.561476 -7.09769)
			(xy 23.507522 -7.105443) (xy 23.480268 -7.105904) (xy 22.616668 -7.105904) (xy 22.589418 -7.105424)
			(xy 22.535473 -7.097664) (xy 22.483182 -7.082306) (xy 22.433608 -7.059662) (xy 22.387761 -7.030195)
			(xy 22.346574 -6.994503) (xy 22.310886 -6.953313) (xy 22.281422 -6.907464) (xy 22.258783 -6.857888)
			(xy 22.243429 -6.805596) (xy 22.235674 -6.75165) (xy 20.261318 -6.75165) (xy 20.253563 -6.805595)
			(xy 20.238209 -6.857887) (xy 20.21557 -6.907462) (xy 20.186106 -6.95331) (xy 20.150418 -6.9945) (xy 20.109231 -7.030191)
			(xy 20.063385 -7.059657) (xy 20.013811 -7.0823) (xy 19.96152 -7.097657) (xy 19.907576 -7.105416)
			(xy 19.880326 -7.105904) (xy 19.016726 -7.105904) (xy 18.989472 -7.10545) (xy 18.935517 -7.097696)
			(xy 18.883216 -7.082342) (xy 18.833632 -7.059701) (xy 18.787775 -7.030234) (xy 18.746579 -6.99454)
			(xy 18.710882 -6.953346) (xy 18.681411 -6.907491) (xy 18.658767 -6.857909) (xy 18.643409 -6.805608)
			(xy 18.635651 -6.751654) (xy 13.611098 -6.751654) (xy 13.611098 -9.780016) (xy 13.610604 -9.850398)
			(xy 13.602711 -9.990941) (xy 13.58695 -10.13082) (xy 13.563371 -10.269596) (xy 13.532048 -10.406831)
			(xy 13.493079 -10.542094) (xy 13.446587 -10.674959) (xy 13.392719 -10.805008) (xy 13.331643 -10.931832)
			(xy 13.263553 -11.055033) (xy 13.188662 -11.174221) (xy 13.107205 -11.289023) (xy 13.01944 -11.399077)
			(xy 12.925642 -11.504037) (xy 12.826107 -11.603572) (xy 12.721147 -11.69737) (xy 12.611093 -11.785135)
			(xy 12.496291 -11.866592) (xy 12.377103 -11.941483) (xy 12.253902 -12.009573) (xy 12.127078 -12.070649)
			(xy 11.997029 -12.124517) (xy 11.864164 -12.171009) (xy 11.728901 -12.209978) (xy 11.591666 -12.241301)
			(xy 11.45289 -12.26488) (xy 11.313011 -12.280641) (xy 11.172468 -12.288534) (xy 11.102086 -12.289028)
			(xy 1.999996 -12.289028) (xy 1.944227 -12.289537) (xy 1.833 -12.297872) (xy 1.722707 -12.314497)
			(xy 1.613965 -12.339317) (xy 1.507382 -12.372193) (xy 1.403554 -12.412943) (xy 1.303061 -12.461339)
			(xy 1.206466 -12.517108) (xy 1.114309 -12.579941) (xy 1.027105 -12.649484) (xy 0.945341 -12.72535)
			(xy 0.869476 -12.807114) (xy 0.802299 -12.891351) (xy 56.954662 -12.891351) (xy 56.954662 -12.836849)
			(xy 56.962418 -12.782901) (xy 56.977772 -12.730606) (xy 57.000413 -12.681029) (xy 57.029878 -12.635178)
			(xy 57.065568 -12.593986) (xy 57.106757 -12.558293) (xy 57.152606 -12.528825) (xy 57.202182 -12.506181)
			(xy 57.254476 -12.490823) (xy 57.308423 -12.483064) (xy 57.335674 -12.482576) (xy 58.199274 -12.482576)
			(xy 58.226527 -12.48307) (xy 58.280478 -12.490823) (xy 58.332777 -12.506176) (xy 58.382358 -12.528816)
			(xy 58.428213 -12.558282) (xy 58.469407 -12.593975) (xy 58.505102 -12.635166) (xy 58.534571 -12.681019)
			(xy 58.557215 -12.730598) (xy 58.572571 -12.782896) (xy 58.580329 -12.836847) (xy 58.580329 -12.891353)
			(xy 58.580329 -12.891355) (xy 70.949739 -12.891355) (xy 70.949739 -12.836845) (xy 70.957497 -12.78289)
			(xy 70.972854 -12.730588) (xy 70.995499 -12.681005) (xy 71.024971 -12.635149) (xy 71.060668 -12.593954)
			(xy 71.101865 -12.558259) (xy 71.147722 -12.52879) (xy 71.197307 -12.506147) (xy 71.24961 -12.490793)
			(xy 71.303565 -12.483038) (xy 71.33082 -12.482576) (xy 72.19442 -12.482576) (xy 72.221669 -12.483096)
			(xy 72.275612 -12.490854) (xy 72.327902 -12.50621) (xy 72.377475 -12.528852) (xy 72.423321 -12.558317)
			(xy 72.464507 -12.594007) (xy 72.500195 -12.635195) (xy 72.529658 -12.681043) (xy 72.552297 -12.730616)
			(xy 72.56765 -12.782907) (xy 72.575406 -12.836851) (xy 72.575406 -12.891349) (xy 72.56765 -12.945293)
			(xy 72.552297 -12.997584) (xy 72.529658 -13.047157) (xy 72.500195 -13.093005) (xy 72.464507 -13.134193)
			(xy 72.423321 -13.169883) (xy 72.377475 -13.199348) (xy 72.327902 -13.22199) (xy 72.275612 -13.237346)
			(xy 72.221669 -13.245104) (xy 72.19442 -13.245592) (xy 71.33082 -13.245592) (xy 71.303565 -13.245162)
			(xy 71.24961 -13.237407) (xy 71.197307 -13.222053) (xy 71.147722 -13.19941) (xy 71.101865 -13.169941)
			(xy 71.060668 -13.134246) (xy 71.024971 -13.093051) (xy 70.995499 -13.047195) (xy 70.972854 -12.997612)
			(xy 70.957497 -12.94531) (xy 70.949739 -12.891355) (xy 58.580329 -12.891355) (xy 58.572571 -12.945304)
			(xy 58.557215 -12.997602) (xy 58.534571 -13.047181) (xy 58.505102 -13.093034) (xy 58.469407 -13.134225)
			(xy 58.428213 -13.169918) (xy 58.382358 -13.199384) (xy 58.332777 -13.222024) (xy 58.280478 -13.237377)
			(xy 58.226527 -13.24513) (xy 58.199274 -13.245592) (xy 57.335674 -13.245592) (xy 57.308423 -13.245136)
			(xy 57.254476 -13.237377) (xy 57.202182 -13.222019) (xy 57.152606 -13.199375) (xy 57.106757 -13.169907)
			(xy 57.065568 -13.134214) (xy 57.029878 -13.093022) (xy 57.000413 -13.047171) (xy 56.977772 -12.997594)
			(xy 56.962418 -12.945299) (xy 56.954662 -12.891351) (xy 0.802299 -12.891351) (xy 0.799933 -12.894318)
			(xy 0.737102 -12.986476) (xy 0.681333 -13.083072) (xy 0.632939 -13.183565) (xy 0.59219 -13.287393)
			(xy 0.559313 -13.393977) (xy 0.534494 -13.502719) (xy 0.517871 -13.613012) (xy 0.509536 -13.724239)
			(xy 0.509016 -13.780008) (xy 0.509016 -15.222054) (xy 135.233343 -15.222054) (xy 135.233343 -15.167546)
			(xy 135.2411 -15.113592) (xy 135.256457 -15.061292) (xy 135.279101 -15.011709) (xy 135.308571 -14.965854)
			(xy 135.344267 -14.92466) (xy 135.385462 -14.888965) (xy 135.431318 -14.859497) (xy 135.480901 -14.836854)
			(xy 135.533202 -14.821498) (xy 135.587156 -14.813742) (xy 135.61441 -14.81328) (xy 136.47801 -14.81328)
			(xy 136.50526 -14.813791) (xy 136.559205 -14.821548) (xy 136.611497 -14.836904) (xy 136.661071 -14.859545)
			(xy 136.706919 -14.88901) (xy 136.748106 -14.924701) (xy 136.783796 -14.965889) (xy 136.81326 -15.011738)
			(xy 136.8359 -15.061313) (xy 136.851254 -15.113605) (xy 136.85901 -15.16755) (xy 136.85901 -15.22205)
			(xy 136.851254 -15.275995) (xy 136.8359 -15.328287) (xy 136.81326 -15.377862) (xy 136.783796 -15.423711)
			(xy 136.748106 -15.464899) (xy 136.706919 -15.50059) (xy 136.661071 -15.530055) (xy 136.611497 -15.552696)
			(xy 136.559205 -15.568052) (xy 136.50526 -15.575809) (xy 136.47801 -15.576296) (xy 135.61441 -15.576296)
			(xy 135.587156 -15.575858) (xy 135.533202 -15.568102) (xy 135.480901 -15.552746) (xy 135.431318 -15.530103)
			(xy 135.385462 -15.500635) (xy 135.344267 -15.46494) (xy 135.308571 -15.423746) (xy 135.279101 -15.377891)
			(xy 135.256457 -15.328308) (xy 135.2411 -15.276008) (xy 135.233343 -15.222054) (xy 0.509016 -15.222054)
			(xy 0.509016 -17.639611) (xy 15.152858 -17.639611) (xy 15.152858 -17.585109) (xy 15.160614 -17.531161)
			(xy 15.175969 -17.478867) (xy 15.19861 -17.42929) (xy 15.228076 -17.383439) (xy 15.263768 -17.342249)
			(xy 15.304958 -17.306558) (xy 15.350808 -17.277091) (xy 15.400385 -17.25445) (xy 15.452679 -17.239095)
			(xy 15.506627 -17.231338) (xy 15.533878 -17.230852) (xy 16.397478 -17.230852) (xy 16.424731 -17.231315)
			(xy 16.478682 -17.239072) (xy 16.53098 -17.254428) (xy 16.580561 -17.27707) (xy 16.626414 -17.306538)
			(xy 16.667607 -17.342232) (xy 16.703301 -17.383424) (xy 16.732769 -17.429278) (xy 16.755412 -17.478858)
			(xy 16.770768 -17.531156) (xy 16.778525 -17.585107) (xy 16.778525 -17.639611) (xy 20.740858 -17.639611)
			(xy 20.740858 -17.585109) (xy 20.748614 -17.531161) (xy 20.763969 -17.478867) (xy 20.78661 -17.42929)
			(xy 20.816076 -17.383439) (xy 20.851768 -17.342249) (xy 20.892958 -17.306558) (xy 20.938808 -17.277091)
			(xy 20.988385 -17.25445) (xy 21.040679 -17.239095) (xy 21.094627 -17.231338) (xy 21.121878 -17.230852)
			(xy 21.985478 -17.230852) (xy 22.012729 -17.231394) (xy 22.066677 -17.239147) (xy 22.118972 -17.2545)
			(xy 22.168549 -17.277139) (xy 22.2144 -17.306603) (xy 22.255591 -17.342293) (xy 22.291284 -17.383482)
			(xy 22.320751 -17.429331) (xy 22.343392 -17.478908) (xy 22.358748 -17.531202) (xy 22.366505 -17.585149)
			(xy 22.366505 -17.639651) (xy 22.366505 -17.639653) (xy 26.328838 -17.639653) (xy 26.328838 -17.585147)
			(xy 26.336595 -17.531195) (xy 26.35195 -17.478897) (xy 26.374592 -17.429316) (xy 26.404059 -17.383462)
			(xy 26.439752 -17.342268) (xy 26.480944 -17.306573) (xy 26.526797 -17.277103) (xy 26.576376 -17.254458)
			(xy 26.628674 -17.239099) (xy 26.682625 -17.231339) (xy 26.709878 -17.230852) (xy 27.573478 -17.230852)
			(xy 27.600729 -17.231394) (xy 27.654677 -17.239147) (xy 27.706972 -17.2545) (xy 27.756549 -17.277139)
			(xy 27.8024 -17.306603) (xy 27.843591 -17.342293) (xy 27.879284 -17.383482) (xy 27.908751 -17.429331)
			(xy 27.931392 -17.478908) (xy 27.946748 -17.531202) (xy 27.954505 -17.585149) (xy 27.954505 -17.639651)
			(xy 27.954505 -17.639653) (xy 31.916838 -17.639653) (xy 31.916838 -17.585147) (xy 31.924595 -17.531195)
			(xy 31.93995 -17.478897) (xy 31.962592 -17.429316) (xy 31.992059 -17.383462) (xy 32.027752 -17.342268)
			(xy 32.068944 -17.306573) (xy 32.114797 -17.277103) (xy 32.164376 -17.254458) (xy 32.216674 -17.239099)
			(xy 32.270625 -17.231339) (xy 32.297878 -17.230852) (xy 33.161478 -17.230852) (xy 33.188729 -17.231394)
			(xy 33.242677 -17.239147) (xy 33.294972 -17.2545) (xy 33.344549 -17.277139) (xy 33.3904 -17.306603)
			(xy 33.431591 -17.342293) (xy 33.467284 -17.383482) (xy 33.496751 -17.429331) (xy 33.519392 -17.478908)
			(xy 33.534748 -17.531202) (xy 33.542505 -17.585149) (xy 33.542505 -17.639651) (xy 33.542505 -17.639653)
			(xy 37.504838 -17.639653) (xy 37.504838 -17.585147) (xy 37.512595 -17.531195) (xy 37.52795 -17.478897)
			(xy 37.550592 -17.429316) (xy 37.580059 -17.383462) (xy 37.615752 -17.342268) (xy 37.656944 -17.306573)
			(xy 37.702797 -17.277103) (xy 37.752376 -17.254458) (xy 37.804674 -17.239099) (xy 37.858625 -17.231339)
			(xy 37.885878 -17.230852) (xy 38.749478 -17.230852) (xy 38.776729 -17.231394) (xy 38.830677 -17.239147)
			(xy 38.882972 -17.2545) (xy 38.932549 -17.277139) (xy 38.9784 -17.306603) (xy 39.019591 -17.342293)
			(xy 39.055284 -17.383482) (xy 39.084751 -17.429331) (xy 39.107392 -17.478908) (xy 39.122748 -17.531202)
			(xy 39.130505 -17.585149) (xy 39.130505 -17.639651) (xy 39.130505 -17.639654) (xy 43.398638 -17.639654)
			(xy 43.398638 -17.585146) (xy 43.406395 -17.531193) (xy 43.421751 -17.478894) (xy 43.444395 -17.429312)
			(xy 43.473863 -17.383457) (xy 43.509558 -17.342262) (xy 43.550752 -17.306567) (xy 43.596606 -17.277097)
			(xy 43.646188 -17.254454) (xy 43.698487 -17.239096) (xy 43.75244 -17.231338) (xy 43.779694 -17.230852)
			(xy 44.643294 -17.230852) (xy 44.670544 -17.231395) (xy 44.72449 -17.23915) (xy 44.776783 -17.254504)
			(xy 44.826359 -17.277144) (xy 44.872208 -17.306609) (xy 44.913397 -17.342299) (xy 44.949088 -17.383487)
			(xy 44.978553 -17.429336) (xy 45.001194 -17.478911) (xy 45.016548 -17.531204) (xy 45.024305 -17.58515)
			(xy 45.024305 -17.63965) (xy 45.024304 -17.639654) (xy 48.986638 -17.639654) (xy 48.986638 -17.585146)
			(xy 48.994395 -17.531193) (xy 49.009751 -17.478894) (xy 49.032395 -17.429312) (xy 49.061863 -17.383457)
			(xy 49.097558 -17.342262) (xy 49.138752 -17.306567) (xy 49.184606 -17.277097) (xy 49.234188 -17.254454)
			(xy 49.286487 -17.239096) (xy 49.34044 -17.231338) (xy 49.367694 -17.230852) (xy 50.231294 -17.230852)
			(xy 50.258544 -17.231395) (xy 50.31249 -17.23915) (xy 50.364783 -17.254504) (xy 50.414359 -17.277144)
			(xy 50.460208 -17.306609) (xy 50.501397 -17.342299) (xy 50.537088 -17.383487) (xy 50.566553 -17.429336)
			(xy 50.589194 -17.478911) (xy 50.604548 -17.531204) (xy 50.612305 -17.58515) (xy 50.612305 -17.63965)
			(xy 50.612304 -17.639657) (xy 54.608615 -17.639657) (xy 54.608615 -17.585143) (xy 54.616374 -17.531184)
			(xy 54.631733 -17.478878) (xy 54.65438 -17.42929) (xy 54.683854 -17.383431) (xy 54.719554 -17.342233)
			(xy 54.760755 -17.306536) (xy 54.806617 -17.277065) (xy 54.856206 -17.254422) (xy 54.908513 -17.239067)
			(xy 54.962473 -17.231313) (xy 54.98973 -17.230852) (xy 55.85333 -17.230852) (xy 55.880577 -17.23142)
			(xy 55.934516 -17.239179) (xy 55.986801 -17.254535) (xy 56.03637 -17.277176) (xy 56.082211 -17.30664)
			(xy 56.123394 -17.342328) (xy 56.159078 -17.383513) (xy 56.188538 -17.429357) (xy 56.211175 -17.478927)
			(xy 56.226527 -17.531214) (xy 56.234282 -17.585153) (xy 56.234282 -17.639647) (xy 56.226527 -17.693586)
			(xy 56.211175 -17.745873) (xy 56.188538 -17.795443) (xy 56.159078 -17.841287) (xy 56.123394 -17.882472)
			(xy 56.082211 -17.91816) (xy 56.03637 -17.947624) (xy 55.986801 -17.970265) (xy 55.934516 -17.985621)
			(xy 55.880577 -17.99338) (xy 55.85333 -17.993868) (xy 54.98973 -17.993868) (xy 54.962473 -17.993487)
			(xy 54.908513 -17.985733) (xy 54.856206 -17.970378) (xy 54.806617 -17.947735) (xy 54.760755 -17.918264)
			(xy 54.719554 -17.882567) (xy 54.683854 -17.841369) (xy 54.65438 -17.79551) (xy 54.631733 -17.745922)
			(xy 54.616374 -17.693616) (xy 54.608615 -17.639657) (xy 50.612304 -17.639657) (xy 50.604548 -17.693596)
			(xy 50.589194 -17.745889) (xy 50.566553 -17.795464) (xy 50.537088 -17.841313) (xy 50.501397 -17.882501)
			(xy 50.460208 -17.918191) (xy 50.414359 -17.947656) (xy 50.364783 -17.970296) (xy 50.31249 -17.98565)
			(xy 50.258544 -17.993405) (xy 50.231294 -17.993868) (xy 49.367694 -17.993868) (xy 49.34044 -17.993462)
			(xy 49.286487 -17.985704) (xy 49.234188 -17.970346) (xy 49.184606 -17.947703) (xy 49.138752 -17.918233)
			(xy 49.097558 -17.882538) (xy 49.061863 -17.841343) (xy 49.032395 -17.795488) (xy 49.009751 -17.745906)
			(xy 48.994395 -17.693607) (xy 48.986638 -17.639654) (xy 45.024304 -17.639654) (xy 45.016548 -17.693596)
			(xy 45.001194 -17.745889) (xy 44.978553 -17.795464) (xy 44.949088 -17.841313) (xy 44.913397 -17.882501)
			(xy 44.872208 -17.918191) (xy 44.826359 -17.947656) (xy 44.776783 -17.970296) (xy 44.72449 -17.98565)
			(xy 44.670544 -17.993405) (xy 44.643294 -17.993868) (xy 43.779694 -17.993868) (xy 43.75244 -17.993462)
			(xy 43.698487 -17.985704) (xy 43.646188 -17.970346) (xy 43.596606 -17.947703) (xy 43.550752 -17.918233)
			(xy 43.509558 -17.882538) (xy 43.473863 -17.841343) (xy 43.444395 -17.795488) (xy 43.421751 -17.745906)
			(xy 43.406395 -17.693607) (xy 43.398638 -17.639654) (xy 39.130505 -17.639654) (xy 39.122748 -17.693598)
			(xy 39.107392 -17.745892) (xy 39.084751 -17.795469) (xy 39.055284 -17.841318) (xy 39.019591 -17.882507)
			(xy 38.9784 -17.918197) (xy 38.932549 -17.947661) (xy 38.882972 -17.9703) (xy 38.830677 -17.985653)
			(xy 38.776729 -17.993406) (xy 38.749478 -17.993868) (xy 37.885878 -17.993868) (xy 37.858625 -17.993461)
			(xy 37.804674 -17.985701) (xy 37.752376 -17.970342) (xy 37.702797 -17.947697) (xy 37.656944 -17.918227)
			(xy 37.615752 -17.882532) (xy 37.580059 -17.841338) (xy 37.550592 -17.795484) (xy 37.52795 -17.745903)
			(xy 37.512595 -17.693605) (xy 37.504838 -17.639653) (xy 33.542505 -17.639653) (xy 33.534748 -17.693598)
			(xy 33.519392 -17.745892) (xy 33.496751 -17.795469) (xy 33.467284 -17.841318) (xy 33.431591 -17.882507)
			(xy 33.3904 -17.918197) (xy 33.344549 -17.947661) (xy 33.294972 -17.9703) (xy 33.242677 -17.985653)
			(xy 33.188729 -17.993406) (xy 33.161478 -17.993868) (xy 32.297878 -17.993868) (xy 32.270625 -17.993461)
			(xy 32.216674 -17.985701) (xy 32.164376 -17.970342) (xy 32.114797 -17.947697) (xy 32.068944 -17.918227)
			(xy 32.027752 -17.882532) (xy 31.992059 -17.841338) (xy 31.962592 -17.795484) (xy 31.93995 -17.745903)
			(xy 31.924595 -17.693605) (xy 31.916838 -17.639653) (xy 27.954505 -17.639653) (xy 27.946748 -17.693598)
			(xy 27.931392 -17.745892) (xy 27.908751 -17.795469) (xy 27.879284 -17.841318) (xy 27.843591 -17.882507)
			(xy 27.8024 -17.918197) (xy 27.756549 -17.947661) (xy 27.706972 -17.9703) (xy 27.654677 -17.985653)
			(xy 27.600729 -17.993406) (xy 27.573478 -17.993868) (xy 26.709878 -17.993868) (xy 26.682625 -17.993461)
			(xy 26.628674 -17.985701) (xy 26.576376 -17.970342) (xy 26.526797 -17.947697) (xy 26.480944 -17.918227)
			(xy 26.439752 -17.882532) (xy 26.404059 -17.841338) (xy 26.374592 -17.795484) (xy 26.35195 -17.745903)
			(xy 26.336595 -17.693605) (xy 26.328838 -17.639653) (xy 22.366505 -17.639653) (xy 22.358748 -17.693598)
			(xy 22.343392 -17.745892) (xy 22.320751 -17.795469) (xy 22.291284 -17.841318) (xy 22.255591 -17.882507)
			(xy 22.2144 -17.918197) (xy 22.168549 -17.947661) (xy 22.118972 -17.9703) (xy 22.066677 -17.985653)
			(xy 22.012729 -17.993406) (xy 21.985478 -17.993868) (xy 21.121878 -17.993868) (xy 21.094627 -17.993382)
			(xy 21.040679 -17.985625) (xy 20.988385 -17.97027) (xy 20.938808 -17.947629) (xy 20.892958 -17.918162)
			(xy 20.851768 -17.882471) (xy 20.816076 -17.841281) (xy 20.78661 -17.79543) (xy 20.763969 -17.745853)
			(xy 20.748614 -17.693559) (xy 20.740858 -17.639611) (xy 16.778525 -17.639611) (xy 16.778525 -17.639613)
			(xy 16.770768 -17.693564) (xy 16.755412 -17.745862) (xy 16.732769 -17.795442) (xy 16.703301 -17.841296)
			(xy 16.667607 -17.882488) (xy 16.626414 -17.918182) (xy 16.580561 -17.94765) (xy 16.53098 -17.970292)
			(xy 16.478682 -17.985648) (xy 16.424731 -17.993405) (xy 16.397478 -17.993868) (xy 15.533878 -17.993868)
			(xy 15.506627 -17.993382) (xy 15.452679 -17.985625) (xy 15.400385 -17.97027) (xy 15.350808 -17.947629)
			(xy 15.304958 -17.918162) (xy 15.263768 -17.882471) (xy 15.228076 -17.841281) (xy 15.19861 -17.79543)
			(xy 15.175969 -17.745853) (xy 15.160614 -17.693559) (xy 15.152858 -17.639611) (xy 0.509016 -17.639611)
			(xy 0.509016 -18.171947) (xy 131.633522 -18.171947) (xy 131.633522 -18.117453) (xy 131.641277 -18.063515)
			(xy 131.656629 -18.011229) (xy 131.679265 -17.961659) (xy 131.708725 -17.915816) (xy 131.744409 -17.874631)
			(xy 131.78559 -17.838944) (xy 131.831431 -17.80948) (xy 131.880999 -17.78684) (xy 131.933283 -17.771484)
			(xy 131.987221 -17.763724) (xy 132.014468 -17.763236) (xy 132.878068 -17.763236) (xy 132.905326 -17.763609)
			(xy 132.959286 -17.771363) (xy 133.011594 -17.786718) (xy 133.061184 -17.809361) (xy 133.107046 -17.838832)
			(xy 133.148248 -17.87453) (xy 133.183949 -17.915728) (xy 133.213423 -17.961588) (xy 133.236071 -18.011176)
			(xy 133.25143 -18.063483) (xy 133.259189 -18.117443) (xy 133.259189 -18.17195) (xy 137.033499 -18.17195)
			(xy 137.033499 -18.11745) (xy 137.041256 -18.063505) (xy 137.05661 -18.011212) (xy 137.079251 -17.961637)
			(xy 137.108716 -17.915789) (xy 137.144406 -17.874601) (xy 137.185595 -17.838911) (xy 137.231444 -17.809447)
			(xy 137.28102 -17.786807) (xy 137.333312 -17.771454) (xy 137.387258 -17.763699) (xy 137.414508 -17.763236)
			(xy 138.278108 -17.763236) (xy 138.305362 -17.763634) (xy 138.359315 -17.771393) (xy 138.411615 -17.78675)
			(xy 138.461197 -17.809395) (xy 138.507052 -17.838864) (xy 138.548246 -17.87456) (xy 138.58394 -17.915755)
			(xy 138.613409 -17.96161) (xy 138.636052 -18.011193) (xy 138.651409 -18.063493) (xy 138.659166 -18.117446)
			(xy 138.659166 -18.171946) (xy 140.633522 -18.171946) (xy 140.633522 -18.117454) (xy 140.641276 -18.063517)
			(xy 140.656627 -18.011232) (xy 140.679262 -17.961664) (xy 140.70872 -17.915822) (xy 140.744402 -17.874638)
			(xy 140.785582 -17.83895) (xy 140.83142 -17.809486) (xy 140.880986 -17.786845) (xy 140.933268 -17.771487)
			(xy 140.987204 -17.763726) (xy 141.01445 -17.763236) (xy 141.87805 -17.763236) (xy 141.905308 -17.763608)
			(xy 141.959271 -17.77136) (xy 142.011581 -17.786713) (xy 142.061173 -17.809355) (xy 142.107038 -17.838825)
			(xy 142.148241 -17.874523) (xy 142.183945 -17.915722) (xy 142.213421 -17.961583) (xy 142.236069 -18.011172)
			(xy 142.25143 -18.06348) (xy 142.259189 -18.117442) (xy 142.259189 -18.171951) (xy 185.748399 -18.171951)
			(xy 185.748399 -18.117449) (xy 185.756156 -18.063503) (xy 185.771511 -18.011209) (xy 185.794153 -17.961633)
			(xy 185.823619 -17.915784) (xy 185.859311 -17.874596) (xy 185.900502 -17.838906) (xy 185.946353 -17.809442)
			(xy 185.99593 -17.786804) (xy 186.048224 -17.771451) (xy 186.102171 -17.763698) (xy 186.129422 -17.763236)
			(xy 186.993022 -17.763236) (xy 187.020275 -17.763635) (xy 187.074227 -17.771395) (xy 187.126525 -17.786754)
			(xy 187.176105 -17.809399) (xy 187.201242 -17.825555) (xy 218.803143 -17.825555) (xy 218.803143 -17.771045)
			(xy 218.810901 -17.717091) (xy 218.826258 -17.66479) (xy 218.848903 -17.615207) (xy 218.878374 -17.569351)
			(xy 218.914071 -17.528157) (xy 218.955267 -17.492462) (xy 219.001124 -17.462993) (xy 219.050709 -17.440351)
			(xy 219.10301 -17.424996) (xy 219.156965 -17.417242) (xy 219.18422 -17.41678) (xy 220.04782 -17.41678)
			(xy 220.075069 -17.417292) (xy 220.129013 -17.42505) (xy 220.181304 -17.440407) (xy 220.230877 -17.463048)
			(xy 220.276723 -17.492514) (xy 220.31791 -17.528204) (xy 220.353598 -17.569393) (xy 220.383062 -17.615241)
			(xy 220.4057 -17.664815) (xy 220.421054 -17.717106) (xy 220.42881 -17.771051) (xy 220.42881 -17.825549)
			(xy 220.421054 -17.879494) (xy 220.4057 -17.931785) (xy 220.383062 -17.981359) (xy 220.353598 -18.027207)
			(xy 220.31791 -18.068396) (xy 220.276723 -18.104086) (xy 220.230877 -18.133552) (xy 220.181304 -18.156193)
			(xy 220.129013 -18.17155) (xy 220.075069 -18.179308) (xy 220.04782 -18.179796) (xy 219.18422 -18.179796)
			(xy 219.156965 -18.179358) (xy 219.10301 -18.171604) (xy 219.050709 -18.156249) (xy 219.001124 -18.133607)
			(xy 218.955267 -18.104138) (xy 218.914071 -18.068443) (xy 218.878374 -18.027249) (xy 218.848903 -17.981393)
			(xy 218.826258 -17.93181) (xy 218.810901 -17.879509) (xy 218.803143 -17.825555) (xy 187.201242 -17.825555)
			(xy 187.221958 -17.838869) (xy 187.263151 -17.874565) (xy 187.298844 -17.915759) (xy 187.328311 -17.961614)
			(xy 187.350954 -18.011196) (xy 187.366309 -18.063495) (xy 187.374066 -18.117447) (xy 187.374066 -18.171953)
			(xy 187.366309 -18.225905) (xy 187.350954 -18.278204) (xy 187.328311 -18.327786) (xy 187.298844 -18.373641)
			(xy 187.263151 -18.414835) (xy 187.221958 -18.450531) (xy 187.176105 -18.480001) (xy 187.126525 -18.502646)
			(xy 187.074227 -18.518005) (xy 187.020275 -18.525765) (xy 186.993022 -18.526252) (xy 186.129422 -18.526252)
			(xy 186.102171 -18.525702) (xy 186.048224 -18.517949) (xy 185.99593 -18.502596) (xy 185.946353 -18.479958)
			(xy 185.900502 -18.450494) (xy 185.859311 -18.414804) (xy 185.823619 -18.373616) (xy 185.794153 -18.327767)
			(xy 185.771511 -18.278191) (xy 185.756156 -18.225897) (xy 185.748399 -18.171951) (xy 142.259189 -18.171951)
			(xy 142.259189 -18.171958) (xy 142.25143 -18.22592) (xy 142.236069 -18.278228) (xy 142.213421 -18.327817)
			(xy 142.183945 -18.373678) (xy 142.148241 -18.414877) (xy 142.107038 -18.450575) (xy 142.061173 -18.480045)
			(xy 142.011581 -18.502687) (xy 141.959271 -18.51804) (xy 141.905308 -18.525792) (xy 141.87805 -18.526252)
			(xy 141.01445 -18.526252) (xy 140.987204 -18.525674) (xy 140.933268 -18.517913) (xy 140.880986 -18.502555)
			(xy 140.83142 -18.479914) (xy 140.785582 -18.45045) (xy 140.744402 -18.414762) (xy 140.70872 -18.373578)
			(xy 140.679262 -18.327736) (xy 140.656627 -18.278168) (xy 140.641276 -18.225883) (xy 140.633522 -18.171946)
			(xy 138.659166 -18.171946) (xy 138.659166 -18.171954) (xy 138.651409 -18.225907) (xy 138.636052 -18.278207)
			(xy 138.613409 -18.32779) (xy 138.58394 -18.373645) (xy 138.548246 -18.41484) (xy 138.507052 -18.450536)
			(xy 138.461197 -18.480005) (xy 138.411615 -18.50265) (xy 138.359315 -18.518007) (xy 138.305362 -18.525766)
			(xy 138.278108 -18.526252) (xy 137.414508 -18.526252) (xy 137.387258 -18.525701) (xy 137.333312 -18.517946)
			(xy 137.28102 -18.502593) (xy 137.231444 -18.479953) (xy 137.185595 -18.450489) (xy 137.144406 -18.414799)
			(xy 137.108716 -18.373611) (xy 137.079251 -18.327763) (xy 137.05661 -18.278188) (xy 137.041256 -18.225895)
			(xy 137.033499 -18.17195) (xy 133.259189 -18.17195) (xy 133.259189 -18.171957) (xy 133.25143 -18.225917)
			(xy 133.236071 -18.278224) (xy 133.213423 -18.327812) (xy 133.183949 -18.373672) (xy 133.148248 -18.41487)
			(xy 133.107046 -18.450568) (xy 133.061184 -18.480039) (xy 133.011594 -18.502682) (xy 132.959286 -18.518037)
			(xy 132.905326 -18.525791) (xy 132.878068 -18.526252) (xy 132.014468 -18.526252) (xy 131.987221 -18.525676)
			(xy 131.933283 -18.517916) (xy 131.880999 -18.50256) (xy 131.831431 -18.47992) (xy 131.78559 -18.450456)
			(xy 131.744409 -18.414769) (xy 131.708725 -18.373584) (xy 131.679265 -18.327741) (xy 131.656629 -18.278171)
			(xy 131.641277 -18.225885) (xy 131.633522 -18.171947) (xy 0.509016 -18.171947) (xy 0.509016 -19.163611)
			(xy 17.946858 -19.163611) (xy 17.946858 -19.109109) (xy 17.954614 -19.055161) (xy 17.969969 -19.002867)
			(xy 17.99261 -18.95329) (xy 18.022076 -18.907439) (xy 18.057768 -18.866249) (xy 18.098958 -18.830558)
			(xy 18.144808 -18.801091) (xy 18.194385 -18.77845) (xy 18.246679 -18.763095) (xy 18.300627 -18.755338)
			(xy 18.327878 -18.754852) (xy 19.191478 -18.754852) (xy 19.218731 -18.755315) (xy 19.272682 -18.763072)
			(xy 19.32498 -18.778428) (xy 19.374561 -18.80107) (xy 19.420414 -18.830538) (xy 19.461607 -18.866232)
			(xy 19.497301 -18.907424) (xy 19.526769 -18.953278) (xy 19.549412 -19.002858) (xy 19.564768 -19.055156)
			(xy 19.572525 -19.109107) (xy 19.572525 -19.163613) (xy 19.572519 -19.163653) (xy 23.534838 -19.163653)
			(xy 23.534838 -19.109147) (xy 23.542595 -19.055195) (xy 23.55795 -19.002897) (xy 23.580592 -18.953316)
			(xy 23.610059 -18.907462) (xy 23.645752 -18.866268) (xy 23.686944 -18.830573) (xy 23.732797 -18.801103)
			(xy 23.782376 -18.778458) (xy 23.834674 -18.763099) (xy 23.888625 -18.755339) (xy 23.915878 -18.754852)
			(xy 24.779478 -18.754852) (xy 24.806729 -18.755394) (xy 24.860677 -18.763147) (xy 24.912972 -18.7785)
			(xy 24.962549 -18.801139) (xy 25.0084 -18.830603) (xy 25.049591 -18.866293) (xy 25.085284 -18.907482)
			(xy 25.114751 -18.953331) (xy 25.137392 -19.002908) (xy 25.152748 -19.055202) (xy 25.160505 -19.109149)
			(xy 25.160505 -19.163651) (xy 25.160505 -19.163653) (xy 29.122838 -19.163653) (xy 29.122838 -19.109147)
			(xy 29.130595 -19.055195) (xy 29.14595 -19.002897) (xy 29.168592 -18.953316) (xy 29.198059 -18.907462)
			(xy 29.233752 -18.866268) (xy 29.274944 -18.830573) (xy 29.320797 -18.801103) (xy 29.370376 -18.778458)
			(xy 29.422674 -18.763099) (xy 29.476625 -18.755339) (xy 29.503878 -18.754852) (xy 30.367478 -18.754852)
			(xy 30.394729 -18.755394) (xy 30.448677 -18.763147) (xy 30.500972 -18.7785) (xy 30.550549 -18.801139)
			(xy 30.5964 -18.830603) (xy 30.637591 -18.866293) (xy 30.673284 -18.907482) (xy 30.702751 -18.953331)
			(xy 30.725392 -19.002908) (xy 30.740748 -19.055202) (xy 30.748505 -19.109149) (xy 30.748505 -19.163651)
			(xy 30.748505 -19.163653) (xy 34.710838 -19.163653) (xy 34.710838 -19.109147) (xy 34.718595 -19.055195)
			(xy 34.73395 -19.002897) (xy 34.756592 -18.953316) (xy 34.786059 -18.907462) (xy 34.821752 -18.866268)
			(xy 34.862944 -18.830573) (xy 34.908797 -18.801103) (xy 34.958376 -18.778458) (xy 35.010674 -18.763099)
			(xy 35.064625 -18.755339) (xy 35.091878 -18.754852) (xy 35.955478 -18.754852) (xy 35.982729 -18.755394)
			(xy 36.036677 -18.763147) (xy 36.088972 -18.7785) (xy 36.138549 -18.801139) (xy 36.1844 -18.830603)
			(xy 36.225591 -18.866293) (xy 36.261284 -18.907482) (xy 36.290751 -18.953331) (xy 36.313392 -19.002908)
			(xy 36.328748 -19.055202) (xy 36.336505 -19.109149) (xy 36.336505 -19.163651) (xy 36.336505 -19.163654)
			(xy 40.604638 -19.163654) (xy 40.604638 -19.109146) (xy 40.612395 -19.055193) (xy 40.627751 -19.002894)
			(xy 40.650395 -18.953312) (xy 40.679863 -18.907457) (xy 40.715558 -18.866262) (xy 40.756752 -18.830567)
			(xy 40.802606 -18.801097) (xy 40.852188 -18.778454) (xy 40.904487 -18.763096) (xy 40.95844 -18.755338)
			(xy 40.985694 -18.754852) (xy 41.849294 -18.754852) (xy 41.876544 -18.755395) (xy 41.93049 -18.76315)
			(xy 41.982783 -18.778504) (xy 42.032359 -18.801144) (xy 42.078208 -18.830609) (xy 42.119397 -18.866299)
			(xy 42.155088 -18.907487) (xy 42.184553 -18.953336) (xy 42.207194 -19.002911) (xy 42.222548 -19.055204)
			(xy 42.230305 -19.10915) (xy 42.230305 -19.16365) (xy 42.230304 -19.163654) (xy 46.192638 -19.163654)
			(xy 46.192638 -19.109146) (xy 46.200395 -19.055193) (xy 46.215751 -19.002894) (xy 46.238395 -18.953312)
			(xy 46.267863 -18.907457) (xy 46.303558 -18.866262) (xy 46.344752 -18.830567) (xy 46.390606 -18.801097)
			(xy 46.440188 -18.778454) (xy 46.492487 -18.763096) (xy 46.54644 -18.755338) (xy 46.573694 -18.754852)
			(xy 47.437294 -18.754852) (xy 47.464544 -18.755395) (xy 47.51849 -18.76315) (xy 47.570783 -18.778504)
			(xy 47.620359 -18.801144) (xy 47.666208 -18.830609) (xy 47.707397 -18.866299) (xy 47.743088 -18.907487)
			(xy 47.772553 -18.953336) (xy 47.795194 -19.002911) (xy 47.810548 -19.055204) (xy 47.818305 -19.10915)
			(xy 47.818305 -19.16365) (xy 47.818304 -19.163657) (xy 51.814615 -19.163657) (xy 51.814615 -19.109143)
			(xy 51.822374 -19.055184) (xy 51.837733 -19.002878) (xy 51.86038 -18.95329) (xy 51.889854 -18.907431)
			(xy 51.925554 -18.866233) (xy 51.966755 -18.830536) (xy 52.012617 -18.801065) (xy 52.062206 -18.778422)
			(xy 52.114513 -18.763067) (xy 52.168473 -18.755313) (xy 52.19573 -18.754852) (xy 53.05933 -18.754852)
			(xy 53.086577 -18.75542) (xy 53.140516 -18.763179) (xy 53.192801 -18.778535) (xy 53.24237 -18.801176)
			(xy 53.288211 -18.83064) (xy 53.329394 -18.866328) (xy 53.365078 -18.907513) (xy 53.394538 -18.953357)
			(xy 53.417175 -19.002927) (xy 53.432527 -19.055214) (xy 53.440282 -19.109153) (xy 53.440282 -19.163647)
			(xy 53.440281 -19.163657) (xy 57.402615 -19.163657) (xy 57.402615 -19.109143) (xy 57.410374 -19.055184)
			(xy 57.425733 -19.002878) (xy 57.44838 -18.95329) (xy 57.477854 -18.907431) (xy 57.513554 -18.866233)
			(xy 57.554755 -18.830536) (xy 57.600617 -18.801065) (xy 57.650206 -18.778422) (xy 57.702513 -18.763067)
			(xy 57.756473 -18.755313) (xy 57.78373 -18.754852) (xy 58.64733 -18.754852) (xy 58.674577 -18.75542)
			(xy 58.728516 -18.763179) (xy 58.780801 -18.778535) (xy 58.83037 -18.801176) (xy 58.876211 -18.83064)
			(xy 58.917394 -18.866328) (xy 58.953078 -18.907513) (xy 58.982538 -18.953357) (xy 59.005175 -19.002927)
			(xy 59.020527 -19.055214) (xy 59.028282 -19.109153) (xy 59.028282 -19.163647) (xy 59.020527 -19.217586)
			(xy 59.005175 -19.269873) (xy 58.982538 -19.319443) (xy 58.953078 -19.365287) (xy 58.917394 -19.406472)
			(xy 58.876211 -19.44216) (xy 58.83037 -19.471624) (xy 58.780801 -19.494265) (xy 58.728516 -19.509621)
			(xy 58.674577 -19.51738) (xy 58.64733 -19.517868) (xy 57.78373 -19.517868) (xy 57.756473 -19.517487)
			(xy 57.702513 -19.509733) (xy 57.650206 -19.494378) (xy 57.600617 -19.471735) (xy 57.554755 -19.442264)
			(xy 57.513554 -19.406567) (xy 57.477854 -19.365369) (xy 57.44838 -19.31951) (xy 57.425733 -19.269922)
			(xy 57.410374 -19.217616) (xy 57.402615 -19.163657) (xy 53.440281 -19.163657) (xy 53.432527 -19.217586)
			(xy 53.417175 -19.269873) (xy 53.394538 -19.319443) (xy 53.365078 -19.365287) (xy 53.329394 -19.406472)
			(xy 53.288211 -19.44216) (xy 53.24237 -19.471624) (xy 53.192801 -19.494265) (xy 53.140516 -19.509621)
			(xy 53.086577 -19.51738) (xy 53.05933 -19.517868) (xy 52.19573 -19.517868) (xy 52.168473 -19.517487)
			(xy 52.114513 -19.509733) (xy 52.062206 -19.494378) (xy 52.012617 -19.471735) (xy 51.966755 -19.442264)
			(xy 51.925554 -19.406567) (xy 51.889854 -19.365369) (xy 51.86038 -19.31951) (xy 51.837733 -19.269922)
			(xy 51.822374 -19.217616) (xy 51.814615 -19.163657) (xy 47.818304 -19.163657) (xy 47.810548 -19.217596)
			(xy 47.795194 -19.269889) (xy 47.772553 -19.319464) (xy 47.743088 -19.365313) (xy 47.707397 -19.406501)
			(xy 47.666208 -19.442191) (xy 47.620359 -19.471656) (xy 47.570783 -19.494296) (xy 47.51849 -19.50965)
			(xy 47.464544 -19.517405) (xy 47.437294 -19.517868) (xy 46.573694 -19.517868) (xy 46.54644 -19.517462)
			(xy 46.492487 -19.509704) (xy 46.440188 -19.494346) (xy 46.390606 -19.471703) (xy 46.344752 -19.442233)
			(xy 46.303558 -19.406538) (xy 46.267863 -19.365343) (xy 46.238395 -19.319488) (xy 46.215751 -19.269906)
			(xy 46.200395 -19.217607) (xy 46.192638 -19.163654) (xy 42.230304 -19.163654) (xy 42.222548 -19.217596)
			(xy 42.207194 -19.269889) (xy 42.184553 -19.319464) (xy 42.155088 -19.365313) (xy 42.119397 -19.406501)
			(xy 42.078208 -19.442191) (xy 42.032359 -19.471656) (xy 41.982783 -19.494296) (xy 41.93049 -19.50965)
			(xy 41.876544 -19.517405) (xy 41.849294 -19.517868) (xy 40.985694 -19.517868) (xy 40.95844 -19.517462)
			(xy 40.904487 -19.509704) (xy 40.852188 -19.494346) (xy 40.802606 -19.471703) (xy 40.756752 -19.442233)
			(xy 40.715558 -19.406538) (xy 40.679863 -19.365343) (xy 40.650395 -19.319488) (xy 40.627751 -19.269906)
			(xy 40.612395 -19.217607) (xy 40.604638 -19.163654) (xy 36.336505 -19.163654) (xy 36.328748 -19.217598)
			(xy 36.313392 -19.269892) (xy 36.290751 -19.319469) (xy 36.261284 -19.365318) (xy 36.225591 -19.406507)
			(xy 36.1844 -19.442197) (xy 36.138549 -19.471661) (xy 36.088972 -19.4943) (xy 36.036677 -19.509653)
			(xy 35.982729 -19.517406) (xy 35.955478 -19.517868) (xy 35.091878 -19.517868) (xy 35.064625 -19.517461)
			(xy 35.010674 -19.509701) (xy 34.958376 -19.494342) (xy 34.908797 -19.471697) (xy 34.862944 -19.442227)
			(xy 34.821752 -19.406532) (xy 34.786059 -19.365338) (xy 34.756592 -19.319484) (xy 34.73395 -19.269903)
			(xy 34.718595 -19.217605) (xy 34.710838 -19.163653) (xy 30.748505 -19.163653) (xy 30.740748 -19.217598)
			(xy 30.725392 -19.269892) (xy 30.702751 -19.319469) (xy 30.673284 -19.365318) (xy 30.637591 -19.406507)
			(xy 30.5964 -19.442197) (xy 30.550549 -19.471661) (xy 30.500972 -19.4943) (xy 30.448677 -19.509653)
			(xy 30.394729 -19.517406) (xy 30.367478 -19.517868) (xy 29.503878 -19.517868) (xy 29.476625 -19.517461)
			(xy 29.422674 -19.509701) (xy 29.370376 -19.494342) (xy 29.320797 -19.471697) (xy 29.274944 -19.442227)
			(xy 29.233752 -19.406532) (xy 29.198059 -19.365338) (xy 29.168592 -19.319484) (xy 29.14595 -19.269903)
			(xy 29.130595 -19.217605) (xy 29.122838 -19.163653) (xy 25.160505 -19.163653) (xy 25.152748 -19.217598)
			(xy 25.137392 -19.269892) (xy 25.114751 -19.319469) (xy 25.085284 -19.365318) (xy 25.049591 -19.406507)
			(xy 25.0084 -19.442197) (xy 24.962549 -19.471661) (xy 24.912972 -19.4943) (xy 24.860677 -19.509653)
			(xy 24.806729 -19.517406) (xy 24.779478 -19.517868) (xy 23.915878 -19.517868) (xy 23.888625 -19.517461)
			(xy 23.834674 -19.509701) (xy 23.782376 -19.494342) (xy 23.732797 -19.471697) (xy 23.686944 -19.442227)
			(xy 23.645752 -19.406532) (xy 23.610059 -19.365338) (xy 23.580592 -19.319484) (xy 23.55795 -19.269903)
			(xy 23.542595 -19.217605) (xy 23.534838 -19.163653) (xy 19.572519 -19.163653) (xy 19.564768 -19.217564)
			(xy 19.549412 -19.269862) (xy 19.526769 -19.319442) (xy 19.497301 -19.365296) (xy 19.461607 -19.406488)
			(xy 19.420414 -19.442182) (xy 19.374561 -19.47165) (xy 19.32498 -19.494292) (xy 19.272682 -19.509648)
			(xy 19.218731 -19.517405) (xy 19.191478 -19.517868) (xy 18.327878 -19.517868) (xy 18.300627 -19.517382)
			(xy 18.246679 -19.509625) (xy 18.194385 -19.49427) (xy 18.144808 -19.471629) (xy 18.098958 -19.442162)
			(xy 18.057768 -19.406471) (xy 18.022076 -19.365281) (xy 17.99261 -19.31943) (xy 17.969969 -19.269853)
			(xy 17.954614 -19.217559) (xy 17.946858 -19.163611) (xy 0.509016 -19.163611) (xy 0.509016 -20.187751)
			(xy 138.828766 -20.187751) (xy 138.828766 -20.133249) (xy 138.836522 -20.079301) (xy 138.851877 -20.027006)
			(xy 138.874517 -19.977429) (xy 138.903982 -19.931578) (xy 138.939673 -19.890387) (xy 138.980862 -19.854694)
			(xy 139.026711 -19.825227) (xy 139.076288 -19.802584) (xy 139.128582 -19.787226) (xy 139.182529 -19.779467)
			(xy 139.20978 -19.77898) (xy 140.07338 -19.77898) (xy 140.100633 -19.779466) (xy 140.154584 -19.78722)
			(xy 140.206883 -19.802574) (xy 140.256464 -19.825215) (xy 140.302318 -19.854681) (xy 140.343512 -19.890374)
			(xy 140.379207 -19.931566) (xy 140.408676 -19.977418) (xy 140.431319 -20.026998) (xy 140.446675 -20.079296)
			(xy 140.454433 -20.133247) (xy 140.454433 -20.187753) (xy 140.446675 -20.241704) (xy 140.431319 -20.294002)
			(xy 140.408676 -20.343582) (xy 140.379207 -20.389434) (xy 140.343512 -20.430626) (xy 140.302318 -20.466319)
			(xy 140.256464 -20.495785) (xy 140.206883 -20.518426) (xy 140.154584 -20.53378) (xy 140.100633 -20.541534)
			(xy 140.07338 -20.541996) (xy 139.20978 -20.541996) (xy 139.182529 -20.541533) (xy 139.128582 -20.533774)
			(xy 139.076288 -20.518416) (xy 139.026711 -20.495773) (xy 138.980862 -20.466306) (xy 138.939673 -20.430613)
			(xy 138.903982 -20.389422) (xy 138.874517 -20.343571) (xy 138.851877 -20.293994) (xy 138.836522 -20.241699)
			(xy 138.828766 -20.187751) (xy 0.509016 -20.187751) (xy 0.509016 -21.521251) (xy 15.232366 -21.521251)
			(xy 15.232366 -21.466749) (xy 15.240122 -21.412801) (xy 15.255477 -21.360506) (xy 15.278117 -21.310929)
			(xy 15.307582 -21.265078) (xy 15.343273 -21.223887) (xy 15.384462 -21.188194) (xy 15.430311 -21.158727)
			(xy 15.479888 -21.136084) (xy 15.532182 -21.120726) (xy 15.586129 -21.112967) (xy 15.61338 -21.11248)
			(xy 16.47698 -21.11248) (xy 16.504233 -21.112966) (xy 16.558184 -21.12072) (xy 16.610483 -21.136074)
			(xy 16.660064 -21.158715) (xy 16.705918 -21.188181) (xy 16.747112 -21.223874) (xy 16.782807 -21.265066)
			(xy 16.812276 -21.310918) (xy 16.834919 -21.360498) (xy 16.850275 -21.412796) (xy 16.858033 -21.466747)
			(xy 16.858033 -21.521253) (xy 16.850275 -21.575204) (xy 16.834919 -21.627502) (xy 16.812276 -21.677082)
			(xy 16.782807 -21.722934) (xy 16.747112 -21.764126) (xy 16.705918 -21.799819) (xy 16.660064 -21.829285)
			(xy 16.610483 -21.851926) (xy 16.558184 -21.86728) (xy 16.504233 -21.875034) (xy 16.47698 -21.875496)
			(xy 15.61338 -21.875496) (xy 15.586129 -21.875033) (xy 15.532182 -21.867274) (xy 15.479888 -21.851916)
			(xy 15.430311 -21.829273) (xy 15.384462 -21.799806) (xy 15.343273 -21.764113) (xy 15.307582 -21.722922)
			(xy 15.278117 -21.677071) (xy 15.255477 -21.627494) (xy 15.240122 -21.575199) (xy 15.232366 -21.521251)
			(xy 0.509016 -21.521251) (xy 0.509016 -24.929338) (xy 133.555232 -24.929338) (xy 133.555232 -24.065738)
			(xy 133.555718 -24.038487) (xy 133.563474 -23.984539) (xy 133.578829 -23.932244) (xy 133.601471 -23.882667)
			(xy 133.630937 -23.836817) (xy 133.666628 -23.795626) (xy 133.707819 -23.759935) (xy 133.753669 -23.730469)
			(xy 133.803246 -23.707827) (xy 133.855541 -23.692472) (xy 133.909489 -23.684716) (xy 133.963991 -23.684716)
			(xy 134.017939 -23.692472) (xy 134.070234 -23.707827) (xy 134.119811 -23.730469) (xy 134.165661 -23.759935)
			(xy 134.206852 -23.795626) (xy 134.242543 -23.836817) (xy 134.272009 -23.882667) (xy 134.294651 -23.932244)
			(xy 134.310006 -23.984539) (xy 134.317762 -24.038487) (xy 134.318248 -24.065738) (xy 134.318248 -24.929338)
			(xy 134.317762 -24.956589) (xy 134.310006 -25.010537) (xy 134.294651 -25.062832) (xy 134.272009 -25.112409)
			(xy 134.242543 -25.158259) (xy 134.206852 -25.19945) (xy 134.165661 -25.235141) (xy 134.119811 -25.264607)
			(xy 134.070234 -25.287249) (xy 134.017939 -25.302604) (xy 133.963991 -25.31036) (xy 133.909489 -25.31036)
			(xy 133.855541 -25.302604) (xy 133.803246 -25.287249) (xy 133.753669 -25.264607) (xy 133.707819 -25.235141)
			(xy 133.666628 -25.19945) (xy 133.630937 -25.158259) (xy 133.601471 -25.112409) (xy 133.578829 -25.062832)
			(xy 133.563474 -25.010537) (xy 133.555718 -24.956589) (xy 133.555232 -24.929338) (xy 0.509016 -24.929338)
			(xy 0.509016 -29.070615) (xy 12.244307 -29.070615) (xy 12.252198 -28.941486) (xy 12.268182 -28.813107)
			(xy 12.292195 -28.685984) (xy 12.324144 -28.560621) (xy 12.363901 -28.437511) (xy 12.41131 -28.31714)
			(xy 12.466183 -28.199984) (xy 12.528305 -28.086504) (xy 12.59743 -27.97715) (xy 12.673285 -27.872351)
			(xy 12.75557 -27.772522) (xy 12.843962 -27.678057) (xy 12.938111 -27.589329) (xy 13.037646 -27.506688)
			(xy 13.142173 -27.43046) (xy 13.25128 -27.360945) (xy 13.364537 -27.298419) (xy 13.481497 -27.243128)
			(xy 13.601698 -27.19529) (xy 13.724665 -27.155093) (xy 13.849914 -27.122698) (xy 13.97695 -27.098231)
			(xy 14.105271 -27.081789) (xy 14.234372 -27.073437) (xy 14.363742 -27.073208) (xy 14.492871 -27.081103)
			(xy 14.62125 -27.097091) (xy 14.748372 -27.121108) (xy 14.873734 -27.15306) (xy 14.996843 -27.19282)
			(xy 15.117212 -27.240232) (xy 15.234367 -27.295109) (xy 15.347845 -27.357234) (xy 15.457198 -27.426362)
			(xy 15.561994 -27.50222) (xy 15.661821 -27.584508) (xy 15.709392 -27.628342) (xy 16.877792 -28.721304)
			(xy 16.92464 -28.765906) (xy 17.013363 -28.860052) (xy 17.096 -28.959584) (xy 17.172224 -29.064107)
			(xy 17.241734 -29.17321) (xy 17.304257 -29.286463) (xy 17.359545 -29.403418) (xy 17.407381 -29.523614)
			(xy 17.447575 -29.646576) (xy 17.479969 -29.771819) (xy 17.504435 -29.898849) (xy 17.520877 -30.027165)
			(xy 17.529229 -30.15626) (xy 17.529459 -30.285624) (xy 17.521566 -30.414748) (xy 17.50558 -30.543122)
			(xy 17.481566 -30.670238) (xy 17.449617 -30.795596) (xy 17.40986 -30.9187) (xy 17.362452 -31.039065)
			(xy 17.30758 -31.156215) (xy 17.24546 -31.26969) (xy 17.176338 -31.379039) (xy 17.100486 -31.483833)
			(xy 17.018204 -31.583657) (xy 16.929816 -31.678118) (xy 16.835671 -31.766843) (xy 16.736141 -31.849481)
			(xy 16.631619 -31.925706) (xy 16.522517 -31.995218) (xy 16.409265 -32.057743) (xy 16.292311 -32.113033)
			(xy 16.172116 -32.16087) (xy 16.049154 -32.201066) (xy 15.923911 -32.233462) (xy 15.796882 -32.25793)
			(xy 15.668566 -32.274374) (xy 15.539471 -32.282728) (xy 15.410107 -32.28296) (xy 15.280983 -32.275069)
			(xy 15.152609 -32.259085) (xy 15.025493 -32.235073) (xy 14.900134 -32.203126) (xy 14.77703 -32.163371)
			(xy 14.656664 -32.115965) (xy 14.539512 -32.061094) (xy 14.426037 -31.998976) (xy 14.316687 -31.929855)
			(xy 14.211892 -31.854005) (xy 14.112066 -31.771724) (xy 14.064488 -31.727902) (xy 12.896088 -30.63494)
			(xy 12.849198 -30.590378) (xy 12.760467 -30.496232) (xy 12.677823 -30.3967) (xy 12.601592 -30.292174)
			(xy 12.532074 -30.183069) (xy 12.469545 -30.069814) (xy 12.41425 -29.952855) (xy 12.366409 -29.832656)
			(xy 12.32621 -29.70969) (xy 12.293811 -29.584442) (xy 12.26934 -29.457407) (xy 12.252895 -29.329086)
			(xy 12.244539 -29.199985) (xy 12.244307 -29.070615) (xy 0.509016 -29.070615) (xy 0.509016 -37.099629)
			(xy 170.600616 -37.099629) (xy 170.600616 -37.000299) (xy 170.608608 -36.901292) (xy 170.624542 -36.803249)
			(xy 170.648313 -36.706806) (xy 170.679768 -36.612588) (xy 170.718701 -36.521208) (xy 170.764862 -36.433256)
			(xy 170.81795 -36.349304) (xy 170.877621 -36.269895) (xy 170.943489 -36.195546) (xy 171.015126 -36.126738)
			(xy 171.092067 -36.063918) (xy 171.173813 -36.007493) (xy 171.259835 -35.957828) (xy 171.349574 -35.915246)
			(xy 171.442448 -35.880024) (xy 171.537856 -35.852388) (xy 171.635178 -35.83252) (xy 171.733783 -35.820547)
			(xy 171.833032 -35.816548) (xy 171.932281 -35.820547) (xy 172.030886 -35.83252) (xy 172.128208 -35.852388)
			(xy 172.223616 -35.880024) (xy 172.31649 -35.915246) (xy 172.406229 -35.957828) (xy 172.492251 -36.007493)
			(xy 172.573997 -36.063918) (xy 172.650938 -36.126738) (xy 172.722575 -36.195546) (xy 172.788443 -36.269895)
			(xy 172.848114 -36.349304) (xy 172.901202 -36.433256) (xy 172.947363 -36.521208) (xy 172.986296 -36.612588)
			(xy 173.017751 -36.706806) (xy 173.041522 -36.803249) (xy 173.057456 -36.901292) (xy 173.065448 -37.000299)
			(xy 173.065948 -37.049964) (xy 173.065448 -37.099629) (xy 173.057456 -37.198636) (xy 173.041522 -37.296679)
			(xy 173.017751 -37.393122) (xy 172.986296 -37.48734) (xy 172.947363 -37.57872) (xy 172.901202 -37.666672)
			(xy 172.848114 -37.750624) (xy 172.788443 -37.830033) (xy 172.722575 -37.904382) (xy 172.650938 -37.97319)
			(xy 172.573997 -38.03601) (xy 172.492251 -38.092435) (xy 172.406229 -38.1421) (xy 172.31649 -38.184682)
			(xy 172.223616 -38.219904) (xy 172.128208 -38.24754) (xy 172.030886 -38.267408) (xy 171.932281 -38.279381)
			(xy 171.833032 -38.283381) (xy 171.733783 -38.279381) (xy 171.635178 -38.267408) (xy 171.537856 -38.24754)
			(xy 171.442448 -38.219904) (xy 171.349574 -38.184682) (xy 171.259835 -38.1421) (xy 171.173813 -38.092435)
			(xy 171.092067 -38.03601) (xy 171.015126 -37.97319) (xy 170.943489 -37.904382) (xy 170.877621 -37.830033)
			(xy 170.81795 -37.750624) (xy 170.764862 -37.666672) (xy 170.718701 -37.57872) (xy 170.679768 -37.48734)
			(xy 170.648313 -37.393122) (xy 170.624542 -37.296679) (xy 170.608608 -37.198636) (xy 170.600616 -37.099629)
			(xy 0.509016 -37.099629) (xy 0.509016 -39.657528) (xy 357.003604 -39.657528) (xy 357.003604 -38.793928)
			(xy 357.00409 -38.766659) (xy 357.011852 -38.712675) (xy 357.027217 -38.660345) (xy 357.049874 -38.610735)
			(xy 357.07936 -38.564854) (xy 357.115075 -38.523637) (xy 357.156292 -38.487922) (xy 357.202173 -38.458436)
			(xy 357.251783 -38.435779) (xy 357.304113 -38.420414) (xy 357.358097 -38.412652) (xy 357.412635 -38.412652)
			(xy 357.466619 -38.420414) (xy 357.518949 -38.435779) (xy 357.568559 -38.458436) (xy 357.61444 -38.487922)
			(xy 357.655657 -38.523637) (xy 357.691372 -38.564854) (xy 357.720858 -38.610735) (xy 357.743515 -38.660345)
			(xy 357.75888 -38.712675) (xy 357.766642 -38.766659) (xy 357.767128 -38.793928) (xy 357.767128 -39.657528)
			(xy 357.766642 -39.684797) (xy 357.75888 -39.738781) (xy 357.743515 -39.791111) (xy 357.720858 -39.840721)
			(xy 357.691372 -39.886602) (xy 357.655657 -39.927819) (xy 357.61444 -39.963534) (xy 357.568559 -39.99302)
			(xy 357.518949 -40.015677) (xy 357.466619 -40.031042) (xy 357.412635 -40.038804) (xy 357.358097 -40.038804)
			(xy 357.304113 -40.031042) (xy 357.251783 -40.015677) (xy 357.202173 -39.99302) (xy 357.156292 -39.963534)
			(xy 357.115075 -39.927819) (xy 357.07936 -39.886602) (xy 357.049874 -39.840721) (xy 357.027217 -39.791111)
			(xy 357.011852 -39.738781) (xy 357.00409 -39.684797) (xy 357.003604 -39.657528) (xy 0.509016 -39.657528)
			(xy 0.509016 -40.744902) (xy 235.083357 -40.744902) (xy 235.087362 -40.656994) (xy 235.099345 -40.569814)
			(xy 235.119205 -40.484085) (xy 235.14678 -40.400517) (xy 235.181839 -40.319803) (xy 235.224092 -40.242611)
			(xy 235.27319 -40.169582) (xy 235.328726 -40.10132) (xy 235.390238 -40.03839) (xy 235.457219 -39.981316)
			(xy 235.529112 -39.930568) (xy 235.605321 -39.886568) (xy 235.685216 -39.849681) (xy 235.768135 -39.820212)
			(xy 235.85339 -39.798405) (xy 235.940274 -39.784441) (xy 236.028068 -39.778435) (xy 236.116045 -39.780439)
			(xy 236.203475 -39.790434) (xy 236.289634 -39.808338) (xy 236.373808 -39.834002) (xy 236.455299 -39.867215)
			(xy 236.533433 -39.907701) (xy 236.607561 -39.955123) (xy 236.677069 -40.00909) (xy 236.741383 -40.069155)
			(xy 236.799967 -40.134819) (xy 236.852338 -40.205538) (xy 236.898061 -40.280726) (xy 236.936758 -40.359761)
			(xy 236.968107 -40.441987) (xy 236.991849 -40.526723) (xy 237.007787 -40.613267) (xy 237.015789 -40.700902)
			(xy 237.01629 -40.744902) (xy 237.015789 -40.788902) (xy 237.007787 -40.876537) (xy 236.991849 -40.963081)
			(xy 236.968107 -41.047817) (xy 236.936758 -41.130043) (xy 236.898061 -41.209078) (xy 236.852338 -41.284266)
			(xy 236.799967 -41.354985) (xy 236.741383 -41.420649) (xy 236.677069 -41.480714) (xy 236.607561 -41.534681)
			(xy 236.533433 -41.582103) (xy 236.455299 -41.622589) (xy 236.373808 -41.655802) (xy 236.289634 -41.681466)
			(xy 236.203475 -41.69937) (xy 236.116045 -41.709365) (xy 236.028068 -41.711369) (xy 235.940274 -41.705363)
			(xy 235.85339 -41.691399) (xy 235.768135 -41.669592) (xy 235.685216 -41.640123) (xy 235.605321 -41.603236)
			(xy 235.529112 -41.559236) (xy 235.457219 -41.508488) (xy 235.390238 -41.451414) (xy 235.328726 -41.388484)
			(xy 235.27319 -41.320222) (xy 235.224092 -41.247193) (xy 235.181839 -41.170001) (xy 235.14678 -41.089287)
			(xy 235.119205 -41.005719) (xy 235.099345 -40.91999) (xy 235.087362 -40.83281) (xy 235.083357 -40.744902)
			(xy 0.509016 -40.744902) (xy 0.509016 -43.999912) (xy 16.983969 -43.999912) (xy 16.987993 -43.914144)
			(xy 17.000031 -43.82913) (xy 17.019978 -43.745616) (xy 17.047657 -43.664337) (xy 17.082825 -43.586008)
			(xy 17.125174 -43.511315) (xy 17.174331 -43.440917) (xy 17.229864 -43.375431) (xy 17.291286 -43.315433)
			(xy 17.358055 -43.26145) (xy 17.429587 -43.213957) (xy 17.505251 -43.173371) (xy 17.584384 -43.140048)
			(xy 17.666289 -43.114282) (xy 17.750247 -43.096299) (xy 17.835521 -43.086257) (xy 17.92136 -43.084244)
			(xy 18.00701 -43.090278) (xy 18.091718 -43.104306) (xy 18.174741 -43.126205) (xy 18.255349 -43.155782)
			(xy 18.332833 -43.192777) (xy 18.406512 -43.236865) (xy 18.475738 -43.287659) (xy 18.539905 -43.344712)
			(xy 18.598446 -43.407523) (xy 18.650849 -43.47554) (xy 18.696652 -43.548165) (xy 18.735453 -43.62476)
			(xy 18.766912 -43.704652) (xy 18.790751 -43.787139) (xy 18.806761 -43.871496) (xy 18.814801 -43.956981)
			(xy 18.815304 -43.999912) (xy 18.814801 -44.042843) (xy 18.806761 -44.128328) (xy 18.790751 -44.212685)
			(xy 18.766912 -44.295172) (xy 18.735453 -44.375064) (xy 18.696652 -44.451659) (xy 18.650849 -44.524284)
			(xy 18.598446 -44.592301) (xy 18.539905 -44.655112) (xy 18.475738 -44.712165) (xy 18.406512 -44.762959)
			(xy 18.332833 -44.807047) (xy 18.255349 -44.844042) (xy 18.174741 -44.873619) (xy 18.091718 -44.895518)
			(xy 18.00701 -44.909546) (xy 17.92136 -44.91558) (xy 17.835521 -44.913567) (xy 17.750247 -44.903525)
			(xy 17.666289 -44.885542) (xy 17.584384 -44.859776) (xy 17.505251 -44.826453) (xy 17.429587 -44.785867)
			(xy 17.358055 -44.738374) (xy 17.291286 -44.684391) (xy 17.229864 -44.624393) (xy 17.174331 -44.558907)
			(xy 17.125174 -44.488509) (xy 17.082825 -44.413816) (xy 17.047657 -44.335487) (xy 17.019978 -44.254208)
			(xy 17.000031 -44.170694) (xy 16.987993 -44.08568) (xy 16.983969 -43.999912) (xy 0.509016 -43.999912)
			(xy 0.509016 -47.049813) (xy 59.781451 -47.049813) (xy 59.785436 -46.895317) (xy 59.79737 -46.74123)
			(xy 59.817219 -46.587962) (xy 59.844933 -46.43592) (xy 59.880436 -46.285505) (xy 59.923635 -46.137118)
			(xy 59.974415 -45.991151) (xy 60.032642 -45.847991) (xy 60.098162 -45.708019) (xy 60.1708 -45.571605)
			(xy 60.250363 -45.439111) (xy 60.336642 -45.310889) (xy 60.429407 -45.187278) (xy 60.528412 -45.068606)
			(xy 60.633395 -44.955188) (xy 60.744077 -44.847324) (xy 60.860165 -44.745302) (xy 60.981351 -44.64939)
			(xy 61.107313 -44.559844) (xy 61.237718 -44.476901) (xy 61.37222 -44.400781) (xy 61.510462 -44.331685)
			(xy 61.652077 -44.269798) (xy 61.796691 -44.215282) (xy 61.943919 -44.168283) (xy 62.093371 -44.128926)
			(xy 62.244652 -44.097314) (xy 62.397358 -44.073531) (xy 62.551087 -44.057641) (xy 62.70543 -44.049685)
			(xy 62.782704 -44.049188) (xy 64.383158 -44.049188) (xy 64.460432 -44.049684) (xy 64.614774 -44.057653)
			(xy 64.768502 -44.073557) (xy 64.921207 -44.097353) (xy 65.072484 -44.128978) (xy 65.221933 -44.168349)
			(xy 65.369158 -44.21536) (xy 65.513767 -44.269888) (xy 65.655377 -44.331788) (xy 65.793613 -44.400896)
			(xy 65.928108 -44.477028) (xy 66.058506 -44.559982) (xy 66.184461 -44.649539) (xy 66.305639 -44.745461)
			(xy 66.421718 -44.847494) (xy 66.532391 -44.955367) (xy 66.637364 -45.068794) (xy 66.736359 -45.187475)
			(xy 66.829113 -45.311094) (xy 66.915381 -45.439324) (xy 66.994934 -45.571824) (xy 67.06756 -45.708245)
			(xy 67.133068 -45.848223) (xy 67.191283 -45.991387) (xy 67.242051 -46.137359) (xy 67.285237 -46.28575)
			(xy 67.320727 -46.436168) (xy 67.348428 -46.588213) (xy 67.368264 -46.741483) (xy 67.380185 -46.89557)
			(xy 67.384154 -47.04994) (xy 89.78165 -47.04994) (xy 89.78563 -46.895439) (xy 89.797557 -46.741349)
			(xy 89.817402 -46.588076) (xy 89.84511 -46.436028) (xy 89.880608 -46.285609) (xy 89.923803 -46.137216)
			(xy 89.97458 -45.991243) (xy 90.032804 -45.848078) (xy 90.098321 -45.708101) (xy 90.170957 -45.571681)
			(xy 90.250519 -45.439181) (xy 90.336796 -45.310953) (xy 90.42956 -45.187337) (xy 90.528565 -45.068659)
			(xy 90.633548 -44.955236) (xy 90.74423 -44.847368) (xy 90.860319 -44.74534) (xy 90.981506 -44.649424)
			(xy 91.10747 -44.559873) (xy 91.237877 -44.476926) (xy 91.372381 -44.400801) (xy 91.510626 -44.331702)
			(xy 91.652244 -44.269811) (xy 91.796861 -44.215293) (xy 91.944092 -44.168291) (xy 92.093548 -44.128931)
			(xy 92.244832 -44.097317) (xy 92.397543 -44.073533) (xy 92.551275 -44.057642) (xy 92.705622 -44.049686)
			(xy 92.782898 -44.049188) (xy 94.383098 -44.049188) (xy 94.460374 -44.049669) (xy 94.614722 -44.057625)
			(xy 94.768456 -44.073516) (xy 94.921168 -44.0973) (xy 95.072452 -44.128914) (xy 95.221909 -44.168274)
			(xy 95.369142 -44.215276) (xy 95.513759 -44.269795) (xy 95.655379 -44.331686) (xy 95.793624 -44.400785)
			(xy 95.928129 -44.47691) (xy 96.058537 -44.559858) (xy 96.184502 -44.649409) (xy 96.30569 -44.745326)
			(xy 96.421779 -44.847354) (xy 96.532463 -44.955223) (xy 96.637446 -45.068647) (xy 96.736452 -45.187325)
			(xy 96.829216 -45.310943) (xy 96.915495 -45.439171) (xy 96.995057 -45.571672) (xy 97.038059 -45.652436)
			(xy 155.97378 -45.652436) (xy 155.97378 -44.788836) (xy 155.974266 -44.761567) (xy 155.982028 -44.707583)
			(xy 155.997393 -44.655253) (xy 156.02005 -44.605643) (xy 156.049536 -44.559762) (xy 156.085251 -44.518545)
			(xy 156.126468 -44.48283) (xy 156.172349 -44.453344) (xy 156.221959 -44.430687) (xy 156.274289 -44.415322)
			(xy 156.328273 -44.40756) (xy 156.382811 -44.40756) (xy 156.436795 -44.415322) (xy 156.489125 -44.430687)
			(xy 156.538735 -44.453344) (xy 156.584616 -44.48283) (xy 156.625833 -44.518545) (xy 156.661548 -44.559762)
			(xy 156.691034 -44.605643) (xy 156.713691 -44.655253) (xy 156.72159 -44.682156) (xy 159.179768 -44.682156)
			(xy 159.179768 -43.818556) (xy 159.180254 -43.791287) (xy 159.188016 -43.737303) (xy 159.203381 -43.684973)
			(xy 159.226038 -43.635363) (xy 159.255524 -43.589482) (xy 159.291239 -43.548265) (xy 159.332456 -43.51255)
			(xy 159.378337 -43.483064) (xy 159.427947 -43.460407) (xy 159.480277 -43.445042) (xy 159.534261 -43.43728)
			(xy 159.588799 -43.43728) (xy 159.642783 -43.445042) (xy 159.695113 -43.460407) (xy 159.74185 -43.481752)
			(xy 178.891692 -43.481752) (xy 178.891692 -42.618152) (xy 178.892178 -42.590901) (xy 178.899934 -42.536953)
			(xy 178.915289 -42.484658) (xy 178.937931 -42.435081) (xy 178.967397 -42.389231) (xy 179.003088 -42.34804)
			(xy 179.044279 -42.312349) (xy 179.090129 -42.282883) (xy 179.139706 -42.260241) (xy 179.192001 -42.244886)
			(xy 179.245949 -42.23713) (xy 179.300451 -42.23713) (xy 179.354399 -42.244886) (xy 179.406694 -42.260241)
			(xy 179.456271 -42.282883) (xy 179.502121 -42.312349) (xy 179.543312 -42.34804) (xy 179.579003 -42.389231)
			(xy 179.608469 -42.435081) (xy 179.631111 -42.484658) (xy 179.646466 -42.536953) (xy 179.654222 -42.590901)
			(xy 179.654708 -42.618152) (xy 179.654708 -43.481752) (xy 179.654222 -43.509003) (xy 179.647839 -43.5534)
			(xy 353.767583 -43.5534) (xy 353.771544 -43.500544) (xy 353.783339 -43.44887) (xy 353.802705 -43.39953)
			(xy 353.829208 -43.353628) (xy 353.862256 -43.312189) (xy 353.901112 -43.276139) (xy 353.944908 -43.246283)
			(xy 353.992664 -43.223289) (xy 354.043314 -43.207669) (xy 354.095726 -43.199773) (xy 354.122228 -43.199304)
			(xy 354.122736 -43.199304) (xy 354.153713 -43.199978) (xy 354.214715 -43.210807) (xy 354.272905 -43.232077)
			(xy 354.300028 -43.247056) (xy 354.328004 -43.238767) (xy 354.385663 -43.229845) (xy 354.414836 -43.229276)
			(xy 354.99548 -43.229276) (xy 355.004624 -43.225466) (xy 355.025917 -43.217194) (xy 355.070087 -43.205543)
			(xy 355.115388 -43.199665) (xy 355.138228 -43.199304) (xy 355.162681 -43.199729) (xy 355.211118 -43.206478)
			(xy 355.25817 -43.219815) (xy 355.280722 -43.229276) (xy 355.307866 -43.229907) (xy 355.361565 -43.237931)
			(xy 355.413585 -43.253486) (xy 355.462874 -43.276259) (xy 355.508436 -43.305789) (xy 355.549352 -43.341481)
			(xy 355.584795 -43.382612) (xy 355.61405 -43.428352) (xy 355.636524 -43.477777) (xy 355.651765 -43.52989)
			(xy 355.659465 -43.583636) (xy 355.659944 -43.610784) (xy 355.659468 -43.634951) (xy 356.178591 -43.634951)
			(xy 356.178591 -43.580449) (xy 356.186348 -43.526502) (xy 356.201703 -43.474208) (xy 356.224344 -43.424632)
			(xy 356.253811 -43.378783) (xy 356.289502 -43.337594) (xy 356.330692 -43.301903) (xy 356.376543 -43.272438)
			(xy 356.42612 -43.249799) (xy 356.478414 -43.234445) (xy 356.532361 -43.22669) (xy 356.559612 -43.226228)
			(xy 357.423212 -43.226228) (xy 357.450465 -43.226643) (xy 357.504417 -43.234401) (xy 357.556715 -43.249759)
			(xy 357.606295 -43.272403) (xy 357.652149 -43.301872) (xy 357.693341 -43.337567) (xy 357.729035 -43.378761)
			(xy 357.758503 -43.424615) (xy 357.781145 -43.474196) (xy 357.796501 -43.526495) (xy 357.804258 -43.580447)
			(xy 357.804258 -43.634953) (xy 357.803812 -43.638056) (xy 358.339039 -43.638056) (xy 358.339039 -43.583544)
			(xy 358.346797 -43.529588) (xy 358.362156 -43.477285) (xy 358.384802 -43.4277) (xy 358.414274 -43.381843)
			(xy 358.449974 -43.340648) (xy 358.491172 -43.304953) (xy 358.537032 -43.275485) (xy 358.586619 -43.252843)
			(xy 358.638923 -43.23749) (xy 358.69288 -43.229736) (xy 358.720136 -43.229276) (xy 359.583736 -43.229276)
			(xy 359.610984 -43.229797) (xy 359.664926 -43.237557) (xy 359.717214 -43.252915) (xy 359.766785 -43.275557)
			(xy 359.812629 -43.305023) (xy 359.853813 -43.340713) (xy 359.889499 -43.3819) (xy 359.91896 -43.427747)
			(xy 359.941598 -43.47732) (xy 359.956951 -43.529609) (xy 359.964706 -43.583552) (xy 359.964706 -43.638048)
			(xy 359.956951 -43.691991) (xy 359.941598 -43.74428) (xy 359.91896 -43.793853) (xy 359.889499 -43.8397)
			(xy 359.853813 -43.880887) (xy 359.812629 -43.916577) (xy 359.766785 -43.946043) (xy 359.717214 -43.968685)
			(xy 359.664926 -43.984043) (xy 359.610984 -43.991803) (xy 359.583736 -43.992292) (xy 358.720136 -43.992292)
			(xy 358.69288 -43.991864) (xy 358.638923 -43.98411) (xy 358.586619 -43.968757) (xy 358.537032 -43.946115)
			(xy 358.491172 -43.916647) (xy 358.449974 -43.880952) (xy 358.414274 -43.839757) (xy 358.384802 -43.7939)
			(xy 358.362156 -43.744315) (xy 358.346797 -43.692012) (xy 358.339039 -43.638056) (xy 357.803812 -43.638056)
			(xy 357.796501 -43.688905) (xy 357.781145 -43.741204) (xy 357.758503 -43.790785) (xy 357.729035 -43.836639)
			(xy 357.693341 -43.877833) (xy 357.652149 -43.913528) (xy 357.606295 -43.942997) (xy 357.556715 -43.965641)
			(xy 357.504417 -43.980999) (xy 357.450465 -43.988757) (xy 357.423212 -43.989244) (xy 356.559612 -43.989244)
			(xy 356.532361 -43.98871) (xy 356.478414 -43.980955) (xy 356.42612 -43.965601) (xy 356.376543 -43.942962)
			(xy 356.330692 -43.913497) (xy 356.289502 -43.877806) (xy 356.253811 -43.836617) (xy 356.224344 -43.790768)
			(xy 356.201703 -43.741192) (xy 356.186348 -43.688898) (xy 356.178591 -43.634951) (xy 355.659468 -43.634951)
			(xy 355.659407 -43.638033) (xy 355.651654 -43.691977) (xy 355.636302 -43.744269) (xy 355.613666 -43.793843)
			(xy 355.584204 -43.839692) (xy 355.548518 -43.880882) (xy 355.507334 -43.916573) (xy 355.461489 -43.946041)
			(xy 355.411917 -43.968684) (xy 355.359628 -43.984043) (xy 355.305685 -43.991803) (xy 355.278436 -43.992292)
			(xy 354.414836 -43.992292) (xy 354.388369 -43.991825) (xy 354.335944 -43.984518) (xy 354.285033 -43.970025)
			(xy 354.236619 -43.948625) (xy 354.191633 -43.920731) (xy 354.170996 -43.904154) (xy 354.158864 -43.905712)
			(xy 354.134459 -43.907367) (xy 354.122228 -43.907456) (xy 354.095726 -43.907027) (xy 354.043314 -43.899131)
			(xy 353.992664 -43.883511) (xy 353.944908 -43.860517) (xy 353.901112 -43.830661) (xy 353.862256 -43.794611)
			(xy 353.829208 -43.753172) (xy 353.802705 -43.70727) (xy 353.783339 -43.65793) (xy 353.771544 -43.606256)
			(xy 353.767583 -43.5534) (xy 179.647839 -43.5534) (xy 179.646466 -43.562951) (xy 179.631111 -43.615246)
			(xy 179.608469 -43.664823) (xy 179.579003 -43.710673) (xy 179.543312 -43.751864) (xy 179.502121 -43.787555)
			(xy 179.456271 -43.817021) (xy 179.406694 -43.839663) (xy 179.354399 -43.855018) (xy 179.300451 -43.862774)
			(xy 179.245949 -43.862774) (xy 179.192001 -43.855018) (xy 179.139706 -43.839663) (xy 179.090129 -43.817021)
			(xy 179.044279 -43.787555) (xy 179.003088 -43.751864) (xy 178.967397 -43.710673) (xy 178.937931 -43.664823)
			(xy 178.915289 -43.615246) (xy 178.899934 -43.562951) (xy 178.892178 -43.509003) (xy 178.891692 -43.481752)
			(xy 159.74185 -43.481752) (xy 159.744723 -43.483064) (xy 159.790604 -43.51255) (xy 159.831821 -43.548265)
			(xy 159.867536 -43.589482) (xy 159.897022 -43.635363) (xy 159.919679 -43.684973) (xy 159.935044 -43.737303)
			(xy 159.942806 -43.791287) (xy 159.943292 -43.818556) (xy 159.943292 -44.682156) (xy 159.942806 -44.709425)
			(xy 159.935044 -44.763409) (xy 159.919679 -44.815739) (xy 159.897022 -44.865349) (xy 159.867536 -44.91123)
			(xy 159.831821 -44.952447) (xy 159.79991 -44.980098) (xy 181.659784 -44.980098) (xy 181.659784 -44.116498)
			(xy 181.66027 -44.089247) (xy 181.668026 -44.035299) (xy 181.683381 -43.983004) (xy 181.706023 -43.933427)
			(xy 181.735489 -43.887577) (xy 181.77118 -43.846386) (xy 181.812371 -43.810695) (xy 181.858221 -43.781229)
			(xy 181.907798 -43.758587) (xy 181.960093 -43.743232) (xy 182.014041 -43.735476) (xy 182.068543 -43.735476)
			(xy 182.122491 -43.743232) (xy 182.174786 -43.758587) (xy 182.224363 -43.781229) (xy 182.270213 -43.810695)
			(xy 182.311404 -43.846386) (xy 182.347095 -43.887577) (xy 182.376561 -43.933427) (xy 182.399203 -43.983004)
			(xy 182.414558 -44.035299) (xy 182.422314 -44.089247) (xy 182.4228 -44.116498) (xy 182.4228 -44.840452)
			(xy 348.511075 -44.840452) (xy 348.511075 -44.785948) (xy 348.518832 -44.731999) (xy 348.534188 -44.679702)
			(xy 348.556831 -44.630124) (xy 348.586298 -44.584273) (xy 348.621992 -44.543082) (xy 348.663184 -44.50739)
			(xy 348.709036 -44.477924) (xy 348.758616 -44.455283) (xy 348.810912 -44.439929) (xy 348.864862 -44.432174)
			(xy 348.892114 -44.431712) (xy 349.755714 -44.431712) (xy 349.782966 -44.432159) (xy 349.836915 -44.439917)
			(xy 349.889211 -44.455274) (xy 349.938789 -44.477918) (xy 349.98464 -44.507386) (xy 350.025831 -44.543079)
			(xy 350.061523 -44.584271) (xy 350.090989 -44.630123) (xy 350.11363 -44.679702) (xy 350.128986 -44.731999)
			(xy 350.136742 -44.785948) (xy 350.136742 -44.840452) (xy 350.128986 -44.894401) (xy 350.11363 -44.946698)
			(xy 350.090989 -44.996277) (xy 350.072098 -45.025673) (xy 355.559288 -45.025673) (xy 355.559288 -44.971127)
			(xy 355.56705 -44.917137) (xy 355.582418 -44.864802) (xy 355.605077 -44.815186) (xy 355.634567 -44.7693)
			(xy 355.670288 -44.728078) (xy 355.711511 -44.692359) (xy 355.757398 -44.662871) (xy 355.807015 -44.640213)
			(xy 355.859351 -44.624847) (xy 355.913341 -44.617087) (xy 355.940614 -44.616624) (xy 356.804214 -44.616624)
			(xy 356.831482 -44.617139) (xy 356.885462 -44.624902) (xy 356.937788 -44.640268) (xy 356.987394 -44.662925)
			(xy 357.033272 -44.69241) (xy 357.074486 -44.728124) (xy 357.110199 -44.769339) (xy 357.139682 -44.815218)
			(xy 357.162337 -44.864825) (xy 357.177701 -44.917152) (xy 357.185462 -44.971132) (xy 357.185462 -45.025668)
			(xy 357.177701 -45.079648) (xy 357.162337 -45.131975) (xy 357.139682 -45.181582) (xy 357.110199 -45.227461)
			(xy 357.074486 -45.268676) (xy 357.033272 -45.30439) (xy 356.987394 -45.333875) (xy 356.937788 -45.356532)
			(xy 356.885462 -45.371898) (xy 356.831482 -45.379661) (xy 356.804214 -45.380148) (xy 355.940614 -45.380148)
			(xy 355.913341 -45.379713) (xy 355.859351 -45.371953) (xy 355.807015 -45.356587) (xy 355.757398 -45.333929)
			(xy 355.711511 -45.304441) (xy 355.670288 -45.268722) (xy 355.634567 -45.2275) (xy 355.605077 -45.181614)
			(xy 355.582418 -45.131998) (xy 355.56705 -45.079663) (xy 355.559288 -45.025673) (xy 350.072098 -45.025673)
			(xy 350.061523 -45.042129) (xy 350.025831 -45.083321) (xy 349.98464 -45.119014) (xy 349.938789 -45.148482)
			(xy 349.889211 -45.171126) (xy 349.836915 -45.186483) (xy 349.782966 -45.194241) (xy 349.755714 -45.194728)
			(xy 348.892114 -45.194728) (xy 348.864862 -45.194226) (xy 348.810912 -45.186471) (xy 348.758616 -45.171117)
			(xy 348.709036 -45.148476) (xy 348.663184 -45.11901) (xy 348.621992 -45.083318) (xy 348.586298 -45.042127)
			(xy 348.556831 -44.996276) (xy 348.534188 -44.946698) (xy 348.518832 -44.894401) (xy 348.511075 -44.840452)
			(xy 182.4228 -44.840452) (xy 182.4228 -44.980098) (xy 182.422314 -45.007349) (xy 182.414558 -45.061297)
			(xy 182.399203 -45.113592) (xy 182.376561 -45.163169) (xy 182.347095 -45.209019) (xy 182.311404 -45.25021)
			(xy 182.270213 -45.285901) (xy 182.224363 -45.315367) (xy 182.174786 -45.338009) (xy 182.122491 -45.353364)
			(xy 182.068543 -45.36112) (xy 182.014041 -45.36112) (xy 181.960093 -45.353364) (xy 181.907798 -45.338009)
			(xy 181.858221 -45.315367) (xy 181.812371 -45.285901) (xy 181.77118 -45.25021) (xy 181.735489 -45.209019)
			(xy 181.706023 -45.163169) (xy 181.683381 -45.113592) (xy 181.668026 -45.061297) (xy 181.66027 -45.007349)
			(xy 181.659784 -44.980098) (xy 159.79991 -44.980098) (xy 159.790604 -44.988162) (xy 159.744723 -45.017648)
			(xy 159.695113 -45.040305) (xy 159.642783 -45.05567) (xy 159.588799 -45.063432) (xy 159.534261 -45.063432)
			(xy 159.480277 -45.05567) (xy 159.427947 -45.040305) (xy 159.378337 -45.017648) (xy 159.332456 -44.988162)
			(xy 159.291239 -44.952447) (xy 159.255524 -44.91123) (xy 159.226038 -44.865349) (xy 159.203381 -44.815739)
			(xy 159.188016 -44.763409) (xy 159.180254 -44.709425) (xy 159.179768 -44.682156) (xy 156.72159 -44.682156)
			(xy 156.729056 -44.707583) (xy 156.736818 -44.761567) (xy 156.737304 -44.788836) (xy 156.737304 -45.652436)
			(xy 156.736818 -45.679705) (xy 156.729056 -45.733689) (xy 156.713691 -45.786019) (xy 156.691034 -45.835629)
			(xy 156.661548 -45.88151) (xy 156.625833 -45.922727) (xy 156.584616 -45.958442) (xy 156.538735 -45.987928)
			(xy 156.489125 -46.010585) (xy 156.436795 -46.02595) (xy 156.382811 -46.033712) (xy 156.328273 -46.033712)
			(xy 156.274289 -46.02595) (xy 156.221959 -46.010585) (xy 156.172349 -45.987928) (xy 156.126468 -45.958442)
			(xy 156.085251 -45.922727) (xy 156.049536 -45.88151) (xy 156.02005 -45.835629) (xy 155.997393 -45.786019)
			(xy 155.982028 -45.733689) (xy 155.974266 -45.679705) (xy 155.97378 -45.652436) (xy 97.038059 -45.652436)
			(xy 97.067693 -45.708092) (xy 97.133211 -45.848071) (xy 97.191435 -45.991237) (xy 97.242212 -46.13721)
			(xy 97.285407 -46.285604) (xy 97.320906 -46.436025) (xy 97.329238 -46.481746) (xy 178.630072 -46.481746)
			(xy 178.630072 -45.618146) (xy 178.630558 -45.590895) (xy 178.638314 -45.536947) (xy 178.653669 -45.484652)
			(xy 178.676311 -45.435075) (xy 178.705777 -45.389225) (xy 178.741468 -45.348034) (xy 178.782659 -45.312343)
			(xy 178.828509 -45.282877) (xy 178.878086 -45.260235) (xy 178.930381 -45.24488) (xy 178.984329 -45.237124)
			(xy 179.038831 -45.237124) (xy 179.092779 -45.24488) (xy 179.145074 -45.260235) (xy 179.194651 -45.282877)
			(xy 179.240501 -45.312343) (xy 179.281692 -45.348034) (xy 179.317383 -45.389225) (xy 179.346849 -45.435075)
			(xy 179.369491 -45.484652) (xy 179.384846 -45.536947) (xy 179.392602 -45.590895) (xy 179.393088 -45.618146)
			(xy 179.393088 -46.481746) (xy 179.392602 -46.508997) (xy 179.384846 -46.562945) (xy 179.369491 -46.61524)
			(xy 179.346849 -46.664817) (xy 179.317383 -46.710667) (xy 179.281692 -46.751858) (xy 179.240501 -46.787549)
			(xy 179.194651 -46.817015) (xy 179.145074 -46.839657) (xy 179.092779 -46.855012) (xy 179.038831 -46.862768)
			(xy 178.984329 -46.862768) (xy 178.930381 -46.855012) (xy 178.878086 -46.839657) (xy 178.828509 -46.817015)
			(xy 178.782659 -46.787549) (xy 178.741468 -46.751858) (xy 178.705777 -46.710667) (xy 178.676311 -46.664817)
			(xy 178.653669 -46.61524) (xy 178.638314 -46.562945) (xy 178.630558 -46.508997) (xy 178.630072 -46.481746)
			(xy 97.329238 -46.481746) (xy 97.348615 -46.588073) (xy 97.368459 -46.741347) (xy 97.380387 -46.895438)
			(xy 97.384366 -47.04994) (xy 97.380387 -47.204442) (xy 97.368459 -47.358533) (xy 97.348615 -47.511807)
			(xy 97.320906 -47.663855) (xy 97.285407 -47.814276) (xy 97.242212 -47.96267) (xy 97.239575 -47.97025)
			(xy 155.567386 -47.97025) (xy 155.567386 -47.91575) (xy 155.575142 -47.861805) (xy 155.590495 -47.809513)
			(xy 155.613135 -47.759938) (xy 155.642598 -47.71409) (xy 155.678287 -47.672901) (xy 155.719474 -47.63721)
			(xy 155.765321 -47.607744) (xy 155.814895 -47.585102) (xy 155.867186 -47.569746) (xy 155.92113 -47.561987)
			(xy 155.94838 -47.5615) (xy 156.81198 -47.5615) (xy 156.839234 -47.561946) (xy 156.893189 -47.569701)
			(xy 156.94549 -47.585055) (xy 156.995074 -47.607697) (xy 157.04093 -47.637165) (xy 157.082126 -47.67286)
			(xy 157.117823 -47.714054) (xy 157.147293 -47.759909) (xy 157.169938 -47.809491) (xy 157.185295 -47.861792)
			(xy 157.193053 -47.915746) (xy 157.193053 -47.970249) (xy 158.785586 -47.970249) (xy 158.785586 -47.915751)
			(xy 158.793341 -47.861808) (xy 158.808694 -47.809518) (xy 158.831331 -47.759944) (xy 158.860793 -47.714097)
			(xy 158.89648 -47.672908) (xy 158.937664 -47.637217) (xy 158.983509 -47.607751) (xy 159.03308 -47.585108)
			(xy 159.085369 -47.569749) (xy 159.139311 -47.561988) (xy 159.16656 -47.5615) (xy 160.03016 -47.5615)
			(xy 160.057415 -47.561945) (xy 160.111372 -47.569697) (xy 160.163675 -47.58505) (xy 160.213262 -47.607691)
			(xy 160.259121 -47.637158) (xy 160.300319 -47.672853) (xy 160.336018 -47.714047) (xy 160.36549 -47.759903)
			(xy 160.388136 -47.809487) (xy 160.403494 -47.861789) (xy 160.411253 -47.915745) (xy 160.411253 -47.970255)
			(xy 160.403494 -48.024211) (xy 160.402353 -48.028098) (xy 181.659784 -48.028098) (xy 181.659784 -47.164498)
			(xy 181.66027 -47.137247) (xy 181.668026 -47.083299) (xy 181.683381 -47.031004) (xy 181.706023 -46.981427)
			(xy 181.735489 -46.935577) (xy 181.77118 -46.894386) (xy 181.812371 -46.858695) (xy 181.858221 -46.829229)
			(xy 181.907798 -46.806587) (xy 181.960093 -46.791232) (xy 182.014041 -46.783476) (xy 182.068543 -46.783476)
			(xy 182.122491 -46.791232) (xy 182.174786 -46.806587) (xy 182.224363 -46.829229) (xy 182.225669 -46.830068)
			(xy 356.445326 -46.830068) (xy 356.445326 -46.775532) (xy 356.453087 -46.721552) (xy 356.468451 -46.669225)
			(xy 356.491104 -46.619618) (xy 356.520587 -46.573739) (xy 356.556298 -46.532522) (xy 356.597512 -46.496807)
			(xy 356.643388 -46.467321) (xy 356.692994 -46.444663) (xy 356.745319 -46.429294) (xy 356.799298 -46.421529)
			(xy 356.826566 -46.42104) (xy 357.690166 -46.42104) (xy 357.717439 -46.421497) (xy 357.77143 -46.429255)
			(xy 357.823767 -46.444619) (xy 357.873384 -46.467275) (xy 357.919272 -46.496761) (xy 357.960497 -46.532479)
			(xy 357.996218 -46.5737) (xy 358.025709 -46.619586) (xy 358.048369 -46.669202) (xy 358.063737 -46.721537)
			(xy 358.0715 -46.775527) (xy 358.0715 -46.830069) (xy 358.762026 -46.830069) (xy 358.762026 -46.775531)
			(xy 358.769788 -46.721547) (xy 358.785153 -46.669218) (xy 358.807809 -46.619608) (xy 358.837295 -46.573728)
			(xy 358.87301 -46.53251) (xy 358.914228 -46.496795) (xy 358.960108 -46.467309) (xy 359.009718 -46.444653)
			(xy 359.062047 -46.429288) (xy 359.116031 -46.421526) (xy 359.1433 -46.42104) (xy 360.0069 -46.42104)
			(xy 360.03417 -46.421522) (xy 360.088153 -46.429284) (xy 360.140483 -46.44465) (xy 360.190094 -46.467306)
			(xy 360.235975 -46.496792) (xy 360.277193 -46.532507) (xy 360.312908 -46.573725) (xy 360.342394 -46.619606)
			(xy 360.36505 -46.669217) (xy 360.380416 -46.721547) (xy 360.388178 -46.77553) (xy 360.388178 -46.83007)
			(xy 360.388178 -46.830073) (xy 361.088604 -46.830073) (xy 361.088604 -46.775527) (xy 361.096367 -46.721537)
			(xy 361.111735 -46.669202) (xy 361.134395 -46.619586) (xy 361.163887 -46.573701) (xy 361.199608 -46.53248)
			(xy 361.240833 -46.496763) (xy 361.286721 -46.467276) (xy 361.336339 -46.444621) (xy 361.388676 -46.429258)
			(xy 361.442667 -46.421501) (xy 361.46994 -46.42104) (xy 362.33354 -46.42104) (xy 362.360808 -46.421525)
			(xy 362.414787 -46.429291) (xy 362.467112 -46.44466) (xy 362.516718 -46.467319) (xy 362.562594 -46.496806)
			(xy 362.603807 -46.532522) (xy 362.639518 -46.573738) (xy 362.669 -46.619618) (xy 362.691654 -46.669225)
			(xy 362.707017 -46.721552) (xy 362.714778 -46.775532) (xy 362.714778 -46.830068) (xy 362.707017 -46.884048)
			(xy 362.691654 -46.936375) (xy 362.672751 -46.977768) (xy 396.642323 -46.977768) (xy 396.642323 -46.891996)
			(xy 396.650237 -46.806588) (xy 396.665998 -46.722276) (xy 396.689471 -46.639777) (xy 396.720456 -46.559796)
			(xy 396.758688 -46.483015) (xy 396.803842 -46.41009) (xy 396.855532 -46.341642) (xy 396.913317 -46.278255)
			(xy 396.976704 -46.22047) (xy 397.045152 -46.16878) (xy 397.118077 -46.123626) (xy 397.194858 -46.085394)
			(xy 397.274839 -46.054409) (xy 397.357338 -46.030936) (xy 397.44165 -46.015175) (xy 397.527058 -46.007261)
			(xy 397.61283 -46.007261) (xy 397.698238 -46.015175) (xy 397.78255 -46.030936) (xy 397.865049 -46.054409)
			(xy 397.94503 -46.085394) (xy 398.021811 -46.123626) (xy 398.094736 -46.16878) (xy 398.163184 -46.22047)
			(xy 398.226571 -46.278255) (xy 398.284356 -46.341642) (xy 398.336046 -46.41009) (xy 398.3812 -46.483015)
			(xy 398.419432 -46.559796) (xy 398.450417 -46.639777) (xy 398.47389 -46.722276) (xy 398.489651 -46.806588)
			(xy 398.497565 -46.891996) (xy 398.49806 -46.934882) (xy 398.497565 -46.977768) (xy 398.489651 -47.063176)
			(xy 398.47389 -47.147488) (xy 398.450417 -47.229987) (xy 398.419432 -47.309968) (xy 398.3812 -47.386749)
			(xy 398.336046 -47.459674) (xy 398.284356 -47.528122) (xy 398.226571 -47.591509) (xy 398.163184 -47.649294)
			(xy 398.094736 -47.700984) (xy 398.021811 -47.746138) (xy 397.94503 -47.78437) (xy 397.865049 -47.815355)
			(xy 397.78255 -47.838828) (xy 397.698238 -47.854589) (xy 397.61283 -47.862503) (xy 397.527058 -47.862503)
			(xy 397.44165 -47.854589) (xy 397.357338 -47.838828) (xy 397.274839 -47.815355) (xy 397.194858 -47.78437)
			(xy 397.118077 -47.746138) (xy 397.045152 -47.700984) (xy 396.976704 -47.649294) (xy 396.913317 -47.591509)
			(xy 396.855532 -47.528122) (xy 396.803842 -47.459674) (xy 396.758688 -47.386749) (xy 396.720456 -47.309968)
			(xy 396.689471 -47.229987) (xy 396.665998 -47.147488) (xy 396.650237 -47.063176) (xy 396.642323 -46.977768)
			(xy 362.672751 -46.977768) (xy 362.669 -46.985982) (xy 362.639518 -47.031862) (xy 362.603807 -47.073078)
			(xy 362.562594 -47.108794) (xy 362.516718 -47.138281) (xy 362.467112 -47.16094) (xy 362.414787 -47.176309)
			(xy 362.360808 -47.184075) (xy 362.33354 -47.184564) (xy 361.46994 -47.184564) (xy 361.442667 -47.184099)
			(xy 361.388676 -47.176342) (xy 361.336339 -47.160979) (xy 361.286721 -47.138324) (xy 361.240833 -47.108837)
			(xy 361.199608 -47.07312) (xy 361.163887 -47.031899) (xy 361.134395 -46.986014) (xy 361.111735 -46.936398)
			(xy 361.096367 -46.884063) (xy 361.088604 -46.830073) (xy 360.388178 -46.830073) (xy 360.380416 -46.884053)
			(xy 360.36505 -46.936383) (xy 360.342394 -46.985994) (xy 360.312908 -47.031875) (xy 360.277193 -47.073093)
			(xy 360.235975 -47.108808) (xy 360.190094 -47.138294) (xy 360.140483 -47.16095) (xy 360.088153 -47.176316)
			(xy 360.03417 -47.184078) (xy 360.0069 -47.184564) (xy 359.1433 -47.184564) (xy 359.116031 -47.184074)
			(xy 359.062047 -47.176312) (xy 359.009718 -47.160947) (xy 358.960108 -47.138291) (xy 358.914228 -47.108805)
			(xy 358.87301 -47.07309) (xy 358.837295 -47.031872) (xy 358.807809 -46.985992) (xy 358.785153 -46.936382)
			(xy 358.769788 -46.884053) (xy 358.762026 -46.830069) (xy 358.0715 -46.830069) (xy 358.0715 -46.830073)
			(xy 358.063737 -46.884063) (xy 358.048369 -46.936398) (xy 358.025709 -46.986014) (xy 357.996218 -47.0319)
			(xy 357.960497 -47.073121) (xy 357.919272 -47.108839) (xy 357.873384 -47.138325) (xy 357.823767 -47.160981)
			(xy 357.77143 -47.176345) (xy 357.717439 -47.184103) (xy 357.690166 -47.184564) (xy 356.826566 -47.184564)
			(xy 356.799298 -47.184071) (xy 356.745319 -47.176306) (xy 356.692994 -47.160937) (xy 356.643388 -47.138279)
			(xy 356.597512 -47.108793) (xy 356.556298 -47.073078) (xy 356.520587 -47.031861) (xy 356.491104 -46.985982)
			(xy 356.468451 -46.936375) (xy 356.453087 -46.884048) (xy 356.445326 -46.830068) (xy 182.225669 -46.830068)
			(xy 182.270213 -46.858695) (xy 182.311404 -46.894386) (xy 182.347095 -46.935577) (xy 182.376561 -46.981427)
			(xy 182.399203 -47.031004) (xy 182.414558 -47.083299) (xy 182.422314 -47.137247) (xy 182.4228 -47.164498)
			(xy 182.4228 -48.028098) (xy 182.422314 -48.055349) (xy 182.414558 -48.109297) (xy 182.399203 -48.161592)
			(xy 182.376561 -48.211169) (xy 182.347095 -48.257019) (xy 182.311404 -48.29821) (xy 182.270213 -48.333901)
			(xy 182.224363 -48.363367) (xy 182.174786 -48.386009) (xy 182.122491 -48.401364) (xy 182.068543 -48.40912)
			(xy 182.014041 -48.40912) (xy 181.960093 -48.401364) (xy 181.907798 -48.386009) (xy 181.858221 -48.363367)
			(xy 181.812371 -48.333901) (xy 181.77118 -48.29821) (xy 181.735489 -48.257019) (xy 181.706023 -48.211169)
			(xy 181.683381 -48.161592) (xy 181.668026 -48.109297) (xy 181.66027 -48.055349) (xy 181.659784 -48.028098)
			(xy 160.402353 -48.028098) (xy 160.388136 -48.076513) (xy 160.36549 -48.126097) (xy 160.336018 -48.171953)
			(xy 160.300319 -48.213147) (xy 160.259121 -48.248842) (xy 160.213262 -48.278309) (xy 160.163675 -48.30095)
			(xy 160.111372 -48.316303) (xy 160.057415 -48.324055) (xy 160.03016 -48.324516) (xy 159.16656 -48.324516)
			(xy 159.139311 -48.324012) (xy 159.085369 -48.316251) (xy 159.03308 -48.300892) (xy 158.983509 -48.278249)
			(xy 158.937664 -48.248783) (xy 158.89648 -48.213092) (xy 158.860793 -48.171903) (xy 158.831331 -48.126056)
			(xy 158.808694 -48.076482) (xy 158.793341 -48.024192) (xy 158.785586 -47.970249) (xy 157.193053 -47.970249)
			(xy 157.193053 -47.970254) (xy 157.185295 -48.024208) (xy 157.169938 -48.076509) (xy 157.147293 -48.126091)
			(xy 157.117823 -48.171946) (xy 157.082126 -48.21314) (xy 157.04093 -48.248835) (xy 156.995074 -48.278303)
			(xy 156.94549 -48.300945) (xy 156.893189 -48.316299) (xy 156.839234 -48.324054) (xy 156.81198 -48.324516)
			(xy 155.94838 -48.324516) (xy 155.92113 -48.324013) (xy 155.867186 -48.316254) (xy 155.814895 -48.300898)
			(xy 155.765321 -48.278256) (xy 155.719474 -48.24879) (xy 155.678287 -48.213099) (xy 155.642598 -48.17191)
			(xy 155.613135 -48.126062) (xy 155.590495 -48.076487) (xy 155.575142 -48.024195) (xy 155.567386 -47.97025)
			(xy 97.239575 -47.97025) (xy 97.191435 -48.108643) (xy 97.133211 -48.251809) (xy 97.067693 -48.391788)
			(xy 96.995057 -48.528208) (xy 96.915495 -48.660709) (xy 96.829216 -48.788937) (xy 96.736452 -48.912555)
			(xy 96.637446 -49.031233) (xy 96.532463 -49.144657) (xy 96.421779 -49.252526) (xy 96.30569 -49.354554)
			(xy 96.184502 -49.450471) (xy 96.140518 -49.48174) (xy 178.630072 -49.48174) (xy 178.630072 -48.61814)
			(xy 178.630558 -48.590889) (xy 178.638314 -48.536941) (xy 178.653669 -48.484646) (xy 178.676311 -48.435069)
			(xy 178.705777 -48.389219) (xy 178.741468 -48.348028) (xy 178.782659 -48.312337) (xy 178.828509 -48.282871)
			(xy 178.878086 -48.260229) (xy 178.930381 -48.244874) (xy 178.984329 -48.237118) (xy 179.038831 -48.237118)
			(xy 179.092779 -48.244874) (xy 179.145074 -48.260229) (xy 179.194651 -48.282871) (xy 179.240501 -48.312337)
			(xy 179.281692 -48.348028) (xy 179.317383 -48.389219) (xy 179.346849 -48.435069) (xy 179.369491 -48.484646)
			(xy 179.384846 -48.536941) (xy 179.392602 -48.590889) (xy 179.393088 -48.61814) (xy 179.393088 -49.48174)
			(xy 179.392602 -49.508991) (xy 179.384846 -49.562939) (xy 179.369491 -49.615234) (xy 179.346849 -49.664811)
			(xy 179.317383 -49.710661) (xy 179.281692 -49.751852) (xy 179.240501 -49.787543) (xy 179.194651 -49.817009)
			(xy 179.145074 -49.839651) (xy 179.092779 -49.855006) (xy 179.038831 -49.862762) (xy 178.984329 -49.862762)
			(xy 178.930381 -49.855006) (xy 178.878086 -49.839651) (xy 178.828509 -49.817009) (xy 178.782659 -49.787543)
			(xy 178.741468 -49.751852) (xy 178.705777 -49.710661) (xy 178.676311 -49.664811) (xy 178.653669 -49.615234)
			(xy 178.638314 -49.562939) (xy 178.630558 -49.508991) (xy 178.630072 -49.48174) (xy 96.140518 -49.48174)
			(xy 96.058537 -49.540022) (xy 95.928129 -49.62297) (xy 95.793624 -49.699095) (xy 95.655379 -49.768194)
			(xy 95.513759 -49.830085) (xy 95.369142 -49.884604) (xy 95.221909 -49.931606) (xy 95.072452 -49.970966)
			(xy 94.921168 -50.00258) (xy 94.768456 -50.026364) (xy 94.614722 -50.042255) (xy 94.460374 -50.050211)
			(xy 94.383098 -50.0507) (xy 92.782898 -50.0507) (xy 92.705622 -50.050194) (xy 92.551275 -50.042238)
			(xy 92.397543 -50.026347) (xy 92.244832 -50.002563) (xy 92.093548 -49.970949) (xy 91.944092 -49.931589)
			(xy 91.796861 -49.884587) (xy 91.652244 -49.830069) (xy 91.510626 -49.768178) (xy 91.372381 -49.699079)
			(xy 91.237877 -49.622954) (xy 91.10747 -49.540007) (xy 90.981506 -49.450456) (xy 90.860319 -49.35454)
			(xy 90.74423 -49.252512) (xy 90.633548 -49.144644) (xy 90.528565 -49.031221) (xy 90.42956 -48.912543)
			(xy 90.336796 -48.788927) (xy 90.250519 -48.660699) (xy 90.170957 -48.528199) (xy 90.098321 -48.391779)
			(xy 90.032804 -48.251802) (xy 89.97458 -48.108637) (xy 89.923803 -47.962664) (xy 89.880608 -47.814271)
			(xy 89.84511 -47.663852) (xy 89.817402 -47.511804) (xy 89.797557 -47.358531) (xy 89.78563 -47.204441)
			(xy 89.78165 -47.04994) (xy 67.384154 -47.04994) (xy 67.384157 -47.050067) (xy 67.380172 -47.204564)
			(xy 67.368238 -47.35865) (xy 67.348389 -47.511918) (xy 67.320675 -47.663961) (xy 67.285172 -47.814376)
			(xy 67.241973 -47.962763) (xy 67.191193 -48.108731) (xy 67.132966 -48.25189) (xy 67.067447 -48.391863)
			(xy 66.994809 -48.528277) (xy 66.915245 -48.660771) (xy 66.828966 -48.788993) (xy 66.736201 -48.912605)
			(xy 66.637196 -49.031277) (xy 66.532213 -49.144695) (xy 66.421531 -49.252559) (xy 66.305444 -49.354582)
			(xy 66.184258 -49.450493) (xy 66.058295 -49.54004) (xy 65.927891 -49.622983) (xy 65.793389 -49.699104)
			(xy 65.655147 -49.768199) (xy 65.513531 -49.830087) (xy 65.368918 -49.884603) (xy 65.22169 -49.931602)
			(xy 65.072237 -49.970961) (xy 64.920957 -50.002573) (xy 64.76825 -50.026356) (xy 64.614521 -50.042247)
			(xy 64.460178 -50.050202) (xy 64.382904 -50.0507) (xy 62.78245 -50.0507) (xy 62.705176 -50.050188)
			(xy 62.550834 -50.04222) (xy 62.397107 -50.026316) (xy 62.244402 -50.002521) (xy 62.093124 -49.970896)
			(xy 61.943675 -49.931526) (xy 61.796451 -49.884514) (xy 61.651842 -49.829987) (xy 61.510232 -49.768087)
			(xy 61.371996 -49.69898) (xy 61.2375 -49.622848) (xy 61.107102 -49.539894) (xy 60.981148 -49.450337)
			(xy 60.85997 -49.354416) (xy 60.743891 -49.252383) (xy 60.633218 -49.14451) (xy 60.528245 -49.031083)
			(xy 60.429249 -48.912403) (xy 60.336495 -48.788784) (xy 60.250227 -48.660555) (xy 60.170674 -48.528054)
			(xy 60.098048 -48.391634) (xy 60.032541 -48.251656) (xy 59.974326 -48.108492) (xy 59.923558 -47.96252)
			(xy 59.880371 -47.814129) (xy 59.844881 -47.663712) (xy 59.81718 -47.511667) (xy 59.797344 -47.358397)
			(xy 59.785423 -47.20431) (xy 59.781451 -47.049813) (xy 0.509016 -47.049813) (xy 0.509016 -50.949098)
			(xy 181.659784 -50.949098) (xy 181.659784 -50.085498) (xy 181.66027 -50.058247) (xy 181.668026 -50.004299)
			(xy 181.683381 -49.952004) (xy 181.706023 -49.902427) (xy 181.735489 -49.856577) (xy 181.77118 -49.815386)
			(xy 181.812371 -49.779695) (xy 181.858221 -49.750229) (xy 181.907798 -49.727587) (xy 181.960093 -49.712232)
			(xy 182.014041 -49.704476) (xy 182.068543 -49.704476) (xy 182.122491 -49.712232) (xy 182.174786 -49.727587)
			(xy 182.224363 -49.750229) (xy 182.270213 -49.779695) (xy 182.311404 -49.815386) (xy 182.347095 -49.856577)
			(xy 182.376561 -49.902427) (xy 182.399203 -49.952004) (xy 182.414558 -50.004299) (xy 182.422314 -50.058247)
			(xy 182.4228 -50.085498) (xy 182.4228 -50.949098) (xy 182.422314 -50.976349) (xy 182.414558 -51.030297)
			(xy 182.399203 -51.082592) (xy 182.376561 -51.132169) (xy 182.347095 -51.178019) (xy 182.311404 -51.21921)
			(xy 182.270213 -51.254901) (xy 182.224363 -51.284367) (xy 182.174786 -51.307009) (xy 182.122491 -51.322364)
			(xy 182.068543 -51.33012) (xy 182.014041 -51.33012) (xy 181.960093 -51.322364) (xy 181.907798 -51.307009)
			(xy 181.858221 -51.284367) (xy 181.812371 -51.254901) (xy 181.77118 -51.21921) (xy 181.735489 -51.178019)
			(xy 181.706023 -51.132169) (xy 181.683381 -51.082592) (xy 181.668026 -51.030297) (xy 181.66027 -50.976349)
			(xy 181.659784 -50.949098) (xy 0.509016 -50.949098) (xy 0.509016 -52.481734) (xy 178.630072 -52.481734)
			(xy 178.630072 -51.618134) (xy 178.630558 -51.590883) (xy 178.638314 -51.536935) (xy 178.653669 -51.48464)
			(xy 178.676311 -51.435063) (xy 178.705777 -51.389213) (xy 178.741468 -51.348022) (xy 178.782659 -51.312331)
			(xy 178.828509 -51.282865) (xy 178.878086 -51.260223) (xy 178.930381 -51.244868) (xy 178.984329 -51.237112)
			(xy 179.038831 -51.237112) (xy 179.092779 -51.244868) (xy 179.145074 -51.260223) (xy 179.194651 -51.282865)
			(xy 179.240501 -51.312331) (xy 179.281692 -51.348022) (xy 179.317383 -51.389213) (xy 179.346849 -51.435063)
			(xy 179.369491 -51.48464) (xy 179.384846 -51.536935) (xy 179.392602 -51.590883) (xy 179.393088 -51.618134)
			(xy 179.393088 -51.999896) (xy 201.367397 -51.999896) (xy 201.371407 -51.837793) (xy 201.38343 -51.676088)
			(xy 201.403434 -51.515174) (xy 201.431372 -51.355447) (xy 201.467175 -51.197297) (xy 201.510755 -51.041111)
			(xy 201.562006 -50.887271) (xy 201.620802 -50.736154) (xy 201.687 -50.58813) (xy 201.760436 -50.44356)
			(xy 201.840933 -50.302799) (xy 201.928292 -50.166191) (xy 202.0223 -50.034071) (xy 202.122727 -49.906761)
			(xy 202.229327 -49.784573) (xy 202.341839 -49.667807) (xy 202.459987 -49.556748) (xy 202.583484 -49.451667)
			(xy 202.712026 -49.352823) (xy 202.845299 -49.260456) (xy 202.982977 -49.174793) (xy 203.124723 -49.096044)
			(xy 203.27019 -49.024401) (xy 203.419022 -48.960039) (xy 203.570854 -48.903117) (xy 203.725316 -48.853773)
			(xy 203.882029 -48.812128) (xy 204.04061 -48.778283) (xy 204.200671 -48.752323) (xy 204.361819 -48.73431)
			(xy 204.523661 -48.724289) (xy 204.685801 -48.722283) (xy 204.847842 -48.728299) (xy 205.009386 -48.74232)
			(xy 205.17004 -48.764313) (xy 205.32941 -48.794225) (xy 205.487105 -48.831981) (xy 205.64274 -48.877489)
			(xy 205.795934 -48.930639) (xy 205.946312 -48.9913) (xy 206.093507 -49.059323) (xy 206.237157 -49.134542)
			(xy 206.376912 -49.216773) (xy 206.512428 -49.305815) (xy 206.643376 -49.40145) (xy 206.769434 -49.503444)
			(xy 206.890294 -49.611547) (xy 207.00566 -49.725494) (xy 207.115249 -49.845008) (xy 207.218794 -49.969795)
			(xy 207.316041 -50.09955) (xy 207.406753 -50.233955) (xy 207.424818 -50.263806) (xy 239.457992 -50.263806)
			(xy 239.457992 -49.400206) (xy 239.458478 -49.372955) (xy 239.466234 -49.319007) (xy 239.481589 -49.266712)
			(xy 239.504231 -49.217135) (xy 239.533697 -49.171285) (xy 239.569388 -49.130094) (xy 239.610579 -49.094403)
			(xy 239.656429 -49.064937) (xy 239.706006 -49.042295) (xy 239.758301 -49.02694) (xy 239.812249 -49.019184)
			(xy 239.866751 -49.019184) (xy 239.920699 -49.02694) (xy 239.972994 -49.042295) (xy 240.022571 -49.064937)
			(xy 240.068421 -49.094403) (xy 240.109612 -49.130094) (xy 240.145303 -49.171285) (xy 240.174769 -49.217135)
			(xy 240.197411 -49.266712) (xy 240.212766 -49.319007) (xy 240.220522 -49.372955) (xy 240.221008 -49.400206)
			(xy 240.221008 -50.263806) (xy 240.220522 -50.291057) (xy 240.212766 -50.345005) (xy 240.197411 -50.3973)
			(xy 240.174769 -50.446877) (xy 240.145303 -50.492727) (xy 240.109612 -50.533918) (xy 240.068421 -50.569609)
			(xy 240.022571 -50.599075) (xy 239.972994 -50.621717) (xy 239.920699 -50.637072) (xy 239.866751 -50.644828)
			(xy 239.812249 -50.644828) (xy 239.758301 -50.637072) (xy 239.706006 -50.621717) (xy 239.656429 -50.599075)
			(xy 239.610579 -50.569609) (xy 239.569388 -50.533918) (xy 239.533697 -50.492727) (xy 239.504231 -50.446877)
			(xy 239.481589 -50.3973) (xy 239.466234 -50.345005) (xy 239.458478 -50.291057) (xy 239.457992 -50.263806)
			(xy 207.424818 -50.263806) (xy 207.490706 -50.372682) (xy 207.567696 -50.515391) (xy 207.637535 -50.661732)
			(xy 207.70005 -50.811349) (xy 207.755091 -50.963874) (xy 207.802521 -51.118934) (xy 207.842224 -51.27615)
			(xy 207.874105 -51.435138) (xy 207.898083 -51.595507) (xy 207.914102 -51.756866) (xy 207.922121 -51.91882)
			(xy 207.922622 -51.999896) (xy 207.922121 -52.080972) (xy 207.914102 -52.242926) (xy 207.898083 -52.404285)
			(xy 207.874105 -52.564654) (xy 207.842224 -52.723642) (xy 207.802521 -52.880858) (xy 207.794624 -52.906676)
			(xy 228.815392 -52.906676) (xy 228.815392 -52.043076) (xy 228.815878 -52.015825) (xy 228.823634 -51.961877)
			(xy 228.838989 -51.909582) (xy 228.861631 -51.860005) (xy 228.891097 -51.814155) (xy 228.926788 -51.772964)
			(xy 228.967979 -51.737273) (xy 229.013829 -51.707807) (xy 229.063406 -51.685165) (xy 229.115701 -51.66981)
			(xy 229.169649 -51.662054) (xy 229.224151 -51.662054) (xy 229.278099 -51.66981) (xy 229.330394 -51.685165)
			(xy 229.379971 -51.707807) (xy 229.425821 -51.737273) (xy 229.467012 -51.772964) (xy 229.502703 -51.814155)
			(xy 229.532169 -51.860005) (xy 229.554811 -51.909582) (xy 229.570166 -51.961877) (xy 229.577922 -52.015825)
			(xy 229.578408 -52.043076) (xy 229.578408 -52.90185) (xy 241.926872 -52.90185) (xy 241.926872 -52.03825)
			(xy 241.927358 -52.010999) (xy 241.935114 -51.957051) (xy 241.950469 -51.904756) (xy 241.973111 -51.855179)
			(xy 242.002577 -51.809329) (xy 242.038268 -51.768138) (xy 242.079459 -51.732447) (xy 242.125309 -51.702981)
			(xy 242.174886 -51.680339) (xy 242.227181 -51.664984) (xy 242.281129 -51.657228) (xy 242.335631 -51.657228)
			(xy 242.389579 -51.664984) (xy 242.441874 -51.680339) (xy 242.491451 -51.702981) (xy 242.537301 -51.732447)
			(xy 242.578492 -51.768138) (xy 242.614183 -51.809329) (xy 242.643649 -51.855179) (xy 242.666291 -51.904756)
			(xy 242.681646 -51.957051) (xy 242.687806 -51.999896) (xy 265.367269 -51.999896) (xy 265.371279 -51.837793)
			(xy 265.383302 -51.676088) (xy 265.403306 -51.515174) (xy 265.431244 -51.355447) (xy 265.467047 -51.197297)
			(xy 265.510627 -51.041111) (xy 265.561878 -50.887271) (xy 265.620674 -50.736154) (xy 265.686872 -50.58813)
			(xy 265.760308 -50.44356) (xy 265.840805 -50.302799) (xy 265.928164 -50.166191) (xy 266.022172 -50.034071)
			(xy 266.122599 -49.906761) (xy 266.229199 -49.784573) (xy 266.341711 -49.667807) (xy 266.459859 -49.556748)
			(xy 266.583356 -49.451667) (xy 266.711898 -49.352823) (xy 266.845171 -49.260456) (xy 266.982849 -49.174793)
			(xy 267.124595 -49.096044) (xy 267.270062 -49.024401) (xy 267.418894 -48.960039) (xy 267.570726 -48.903117)
			(xy 267.725188 -48.853773) (xy 267.881901 -48.812128) (xy 268.040482 -48.778283) (xy 268.200543 -48.752323)
			(xy 268.361691 -48.73431) (xy 268.523533 -48.724289) (xy 268.685673 -48.722283) (xy 268.847714 -48.728299)
			(xy 269.009258 -48.74232) (xy 269.169912 -48.764313) (xy 269.329282 -48.794225) (xy 269.486977 -48.831981)
			(xy 269.642612 -48.877489) (xy 269.795806 -48.930639) (xy 269.946184 -48.9913) (xy 270.093379 -49.059323)
			(xy 270.237029 -49.134542) (xy 270.376784 -49.216773) (xy 270.5123 -49.305815) (xy 270.643248 -49.40145)
			(xy 270.769306 -49.503444) (xy 270.890166 -49.611547) (xy 271.005532 -49.725494) (xy 271.115121 -49.845008)
			(xy 271.218666 -49.969795) (xy 271.315913 -50.09955) (xy 271.406625 -50.233955) (xy 271.40723 -50.234955)
			(xy 350.291827 -50.234955) (xy 350.291827 -50.180445) (xy 350.299585 -50.126489) (xy 350.314942 -50.074187)
			(xy 350.337587 -50.024602) (xy 350.367058 -49.978745) (xy 350.402755 -49.937549) (xy 350.443952 -49.901853)
			(xy 350.489809 -49.872383) (xy 350.539394 -49.849739) (xy 350.591697 -49.834383) (xy 350.645653 -49.826626)
			(xy 350.672908 -49.826164) (xy 351.536508 -49.826164) (xy 351.563757 -49.826707) (xy 351.6177 -49.834464)
			(xy 351.66999 -49.849818) (xy 351.719562 -49.872458) (xy 351.765408 -49.901922) (xy 351.806594 -49.937611)
			(xy 351.842282 -49.978798) (xy 351.871746 -50.024645) (xy 351.894385 -50.074218) (xy 351.909738 -50.126508)
			(xy 351.917494 -50.180451) (xy 351.917494 -50.234949) (xy 351.917493 -50.234956) (xy 352.489927 -50.234956)
			(xy 352.489927 -50.180444) (xy 352.497685 -50.126487) (xy 352.513044 -50.074183) (xy 352.535689 -50.024598)
			(xy 352.565162 -49.97874) (xy 352.600861 -49.937544) (xy 352.642059 -49.901848) (xy 352.687919 -49.872378)
			(xy 352.737506 -49.849735) (xy 352.78981 -49.83438) (xy 352.843768 -49.826625) (xy 352.871024 -49.826164)
			(xy 353.734624 -49.826164) (xy 353.761872 -49.826708) (xy 353.815813 -49.834467) (xy 353.868101 -49.849823)
			(xy 353.917672 -49.872463) (xy 353.963516 -49.901928) (xy 354.0047 -49.937617) (xy 354.040386 -49.978804)
			(xy 354.069848 -50.024649) (xy 354.092486 -50.074221) (xy 354.107839 -50.12651) (xy 354.115594 -50.180452)
			(xy 354.115594 -50.234948) (xy 354.115593 -50.234956) (xy 354.712427 -50.234956) (xy 354.712427 -50.180444)
			(xy 354.720185 -50.126487) (xy 354.735544 -50.074183) (xy 354.758189 -50.024598) (xy 354.787662 -49.97874)
			(xy 354.823361 -49.937544) (xy 354.864559 -49.901848) (xy 354.910419 -49.872378) (xy 354.960006 -49.849735)
			(xy 355.01231 -49.83438) (xy 355.066268 -49.826625) (xy 355.093524 -49.826164) (xy 355.957124 -49.826164)
			(xy 355.984372 -49.826708) (xy 356.038313 -49.834467) (xy 356.090601 -49.849823) (xy 356.140172 -49.872463)
			(xy 356.186016 -49.901928) (xy 356.2272 -49.937617) (xy 356.262886 -49.978804) (xy 356.292348 -50.024649)
			(xy 356.314986 -50.074221) (xy 356.330339 -50.12651) (xy 356.338094 -50.180452) (xy 356.338094 -50.234948)
			(xy 356.338093 -50.234957) (xy 356.942527 -50.234957) (xy 356.942527 -50.180443) (xy 356.950286 -50.126484)
			(xy 356.965645 -50.074179) (xy 356.988293 -50.024592) (xy 357.017767 -49.978734) (xy 357.053468 -49.937537)
			(xy 357.094669 -49.90184) (xy 357.140531 -49.872371) (xy 357.19012 -49.84973) (xy 357.242427 -49.834376)
			(xy 357.296387 -49.826624) (xy 357.323644 -49.826164) (xy 358.187244 -49.826164) (xy 358.214491 -49.826709)
			(xy 358.26843 -49.83447) (xy 358.320716 -49.849828) (xy 358.370284 -49.87247) (xy 358.416125 -49.901935)
			(xy 358.457307 -49.937624) (xy 358.492991 -49.97881) (xy 358.522451 -50.024655) (xy 358.545087 -50.074226)
			(xy 358.560439 -50.126513) (xy 358.568194 -50.180453) (xy 358.568194 -50.234947) (xy 358.560439 -50.288887)
			(xy 358.545087 -50.341174) (xy 358.522451 -50.390745) (xy 358.492991 -50.43659) (xy 358.457307 -50.477776)
			(xy 358.416125 -50.513465) (xy 358.370284 -50.54293) (xy 358.320716 -50.565572) (xy 358.26843 -50.58093)
			(xy 358.214491 -50.588691) (xy 358.187244 -50.58918) (xy 357.323644 -50.58918) (xy 357.296387 -50.588776)
			(xy 357.242427 -50.581024) (xy 357.19012 -50.56567) (xy 357.140531 -50.543029) (xy 357.094669 -50.51356)
			(xy 357.053468 -50.477863) (xy 357.017767 -50.436666) (xy 356.988293 -50.390808) (xy 356.965645 -50.341221)
			(xy 356.950286 -50.288916) (xy 356.942527 -50.234957) (xy 356.338093 -50.234957) (xy 356.330339 -50.28889)
			(xy 356.314986 -50.341179) (xy 356.292348 -50.390751) (xy 356.262886 -50.436596) (xy 356.2272 -50.477783)
			(xy 356.186016 -50.513472) (xy 356.140172 -50.542937) (xy 356.090601 -50.565577) (xy 356.038313 -50.580933)
			(xy 355.984372 -50.588692) (xy 355.957124 -50.58918) (xy 355.093524 -50.58918) (xy 355.066268 -50.588775)
			(xy 355.01231 -50.58102) (xy 354.960006 -50.565665) (xy 354.910419 -50.543022) (xy 354.864559 -50.513552)
			(xy 354.823361 -50.477856) (xy 354.787662 -50.43666) (xy 354.758189 -50.390802) (xy 354.735544 -50.341217)
			(xy 354.720185 -50.288913) (xy 354.712427 -50.234956) (xy 354.115593 -50.234956) (xy 354.107839 -50.28889)
			(xy 354.092486 -50.341179) (xy 354.069848 -50.390751) (xy 354.040386 -50.436596) (xy 354.0047 -50.477783)
			(xy 353.963516 -50.513472) (xy 353.917672 -50.542937) (xy 353.868101 -50.565577) (xy 353.815813 -50.580933)
			(xy 353.761872 -50.588692) (xy 353.734624 -50.58918) (xy 352.871024 -50.58918) (xy 352.843768 -50.588775)
			(xy 352.78981 -50.58102) (xy 352.737506 -50.565665) (xy 352.687919 -50.543022) (xy 352.642059 -50.513552)
			(xy 352.600861 -50.477856) (xy 352.565162 -50.43666) (xy 352.535689 -50.390802) (xy 352.513044 -50.341217)
			(xy 352.497685 -50.288913) (xy 352.489927 -50.234956) (xy 351.917493 -50.234956) (xy 351.909738 -50.288892)
			(xy 351.894385 -50.341182) (xy 351.871746 -50.390755) (xy 351.842282 -50.436602) (xy 351.806594 -50.477789)
			(xy 351.765408 -50.513477) (xy 351.719562 -50.542942) (xy 351.66999 -50.565582) (xy 351.6177 -50.580936)
			(xy 351.563757 -50.588693) (xy 351.536508 -50.58918) (xy 350.672908 -50.58918) (xy 350.645653 -50.588774)
			(xy 350.591697 -50.581017) (xy 350.539394 -50.565661) (xy 350.489809 -50.543017) (xy 350.443952 -50.513547)
			(xy 350.402755 -50.477851) (xy 350.367058 -50.436655) (xy 350.337587 -50.390798) (xy 350.314942 -50.341213)
			(xy 350.299585 -50.288911) (xy 350.291827 -50.234955) (xy 271.40723 -50.234955) (xy 271.490578 -50.372682)
			(xy 271.567568 -50.515391) (xy 271.637407 -50.661732) (xy 271.699922 -50.811349) (xy 271.754963 -50.963874)
			(xy 271.802393 -51.118934) (xy 271.842096 -51.27615) (xy 271.873977 -51.435138) (xy 271.897955 -51.595507)
			(xy 271.913974 -51.756866) (xy 271.921993 -51.91882) (xy 271.922494 -51.999896) (xy 271.921993 -52.080972)
			(xy 271.913974 -52.242926) (xy 271.897955 -52.404285) (xy 271.873977 -52.564654) (xy 271.842096 -52.723642)
			(xy 271.802393 -52.880858) (xy 271.754963 -53.035918) (xy 271.699922 -53.188443) (xy 271.637407 -53.33806)
			(xy 271.567568 -53.484401) (xy 271.490578 -53.62711) (xy 271.406625 -53.765837) (xy 271.315913 -53.900242)
			(xy 271.218666 -54.029997) (xy 271.115121 -54.154784) (xy 271.005532 -54.274298) (xy 270.890166 -54.388245)
			(xy 270.769306 -54.496348) (xy 270.643248 -54.598342) (xy 270.5123 -54.693977) (xy 270.376784 -54.783019)
			(xy 270.237029 -54.86525) (xy 270.093379 -54.940469) (xy 269.946184 -55.008492) (xy 269.795806 -55.069153)
			(xy 269.642612 -55.122303) (xy 269.486977 -55.167811) (xy 269.329282 -55.205567) (xy 269.169912 -55.235479)
			(xy 269.009258 -55.257472) (xy 268.847714 -55.271493) (xy 268.685673 -55.277509) (xy 268.523533 -55.275503)
			(xy 268.361691 -55.265482) (xy 268.200543 -55.247469) (xy 268.040482 -55.221509) (xy 267.881901 -55.187664)
			(xy 267.725188 -55.146019) (xy 267.570726 -55.096675) (xy 267.418894 -55.039753) (xy 267.270062 -54.975391)
			(xy 267.124595 -54.903748) (xy 266.982849 -54.824999) (xy 266.845171 -54.739336) (xy 266.711898 -54.646969)
			(xy 266.583356 -54.548125) (xy 266.459859 -54.443044) (xy 266.341711 -54.331985) (xy 266.229199 -54.215219)
			(xy 266.122599 -54.093031) (xy 266.022172 -53.965721) (xy 265.928164 -53.833601) (xy 265.840805 -53.696993)
			(xy 265.760308 -53.556232) (xy 265.686872 -53.411662) (xy 265.620674 -53.263638) (xy 265.561878 -53.112521)
			(xy 265.510627 -52.958681) (xy 265.467047 -52.802495) (xy 265.431244 -52.644345) (xy 265.403306 -52.484618)
			(xy 265.383302 -52.323704) (xy 265.371279 -52.161999) (xy 265.367269 -51.999896) (xy 242.687806 -51.999896)
			(xy 242.689402 -52.010999) (xy 242.689888 -52.03825) (xy 242.689888 -52.90185) (xy 242.689402 -52.929101)
			(xy 242.681646 -52.983049) (xy 242.666291 -53.035344) (xy 242.643649 -53.084921) (xy 242.614183 -53.130771)
			(xy 242.578492 -53.171962) (xy 242.537301 -53.207653) (xy 242.491451 -53.237119) (xy 242.441874 -53.259761)
			(xy 242.389579 -53.275116) (xy 242.335631 -53.282872) (xy 242.281129 -53.282872) (xy 242.227181 -53.275116)
			(xy 242.174886 -53.259761) (xy 242.125309 -53.237119) (xy 242.079459 -53.207653) (xy 242.038268 -53.171962)
			(xy 242.002577 -53.130771) (xy 241.973111 -53.084921) (xy 241.950469 -53.035344) (xy 241.935114 -52.983049)
			(xy 241.927358 -52.929101) (xy 241.926872 -52.90185) (xy 229.578408 -52.90185) (xy 229.578408 -52.906676)
			(xy 229.577922 -52.933927) (xy 229.570166 -52.987875) (xy 229.554811 -53.04017) (xy 229.532169 -53.089747)
			(xy 229.502703 -53.135597) (xy 229.467012 -53.176788) (xy 229.425821 -53.212479) (xy 229.379971 -53.241945)
			(xy 229.330394 -53.264587) (xy 229.278099 -53.279942) (xy 229.224151 -53.287698) (xy 229.169649 -53.287698)
			(xy 229.115701 -53.279942) (xy 229.063406 -53.264587) (xy 229.013829 -53.241945) (xy 228.967979 -53.212479)
			(xy 228.926788 -53.176788) (xy 228.891097 -53.135597) (xy 228.861631 -53.089747) (xy 228.838989 -53.04017)
			(xy 228.823634 -52.987875) (xy 228.815878 -52.933927) (xy 228.815392 -52.906676) (xy 207.794624 -52.906676)
			(xy 207.755091 -53.035918) (xy 207.70005 -53.188443) (xy 207.637535 -53.33806) (xy 207.567696 -53.484401)
			(xy 207.490706 -53.62711) (xy 207.406753 -53.765837) (xy 207.316041 -53.900242) (xy 207.218794 -54.029997)
			(xy 207.115249 -54.154784) (xy 207.00566 -54.274298) (xy 206.890294 -54.388245) (xy 206.769434 -54.496348)
			(xy 206.643376 -54.598342) (xy 206.512428 -54.693977) (xy 206.493338 -54.70652) (xy 230.115872 -54.70652)
			(xy 230.115872 -53.84292) (xy 230.116358 -53.815669) (xy 230.124114 -53.761721) (xy 230.139469 -53.709426)
			(xy 230.162111 -53.659849) (xy 230.191577 -53.613999) (xy 230.227268 -53.572808) (xy 230.268459 -53.537117)
			(xy 230.314309 -53.507651) (xy 230.363886 -53.485009) (xy 230.416181 -53.469654) (xy 230.470129 -53.461898)
			(xy 230.524631 -53.461898) (xy 230.578579 -53.469654) (xy 230.630874 -53.485009) (xy 230.680451 -53.507651)
			(xy 230.726301 -53.537117) (xy 230.767492 -53.572808) (xy 230.803183 -53.613999) (xy 230.832649 -53.659849)
			(xy 230.855291 -53.709426) (xy 230.870646 -53.761721) (xy 230.878402 -53.815669) (xy 230.878888 -53.84292)
			(xy 230.878888 -54.70652) (xy 230.878811 -54.710838) (xy 240.282476 -54.710838) (xy 240.282476 -53.847238)
			(xy 240.282962 -53.819987) (xy 240.290718 -53.766039) (xy 240.306073 -53.713744) (xy 240.328715 -53.664167)
			(xy 240.358181 -53.618317) (xy 240.393872 -53.577126) (xy 240.435063 -53.541435) (xy 240.480913 -53.511969)
			(xy 240.53049 -53.489327) (xy 240.582785 -53.473972) (xy 240.636733 -53.466216) (xy 240.691235 -53.466216)
			(xy 240.745183 -53.473972) (xy 240.797478 -53.489327) (xy 240.847055 -53.511969) (xy 240.892905 -53.541435)
			(xy 240.934096 -53.577126) (xy 240.969787 -53.618317) (xy 240.999253 -53.664167) (xy 241.021895 -53.713744)
			(xy 241.03725 -53.766039) (xy 241.045006 -53.819987) (xy 241.045492 -53.847238) (xy 241.045492 -54.710838)
			(xy 241.045006 -54.738089) (xy 241.03725 -54.792037) (xy 241.021895 -54.844332) (xy 240.999253 -54.893909)
			(xy 240.969787 -54.939759) (xy 240.934096 -54.98095) (xy 240.892905 -55.016641) (xy 240.847055 -55.046107)
			(xy 240.797478 -55.068749) (xy 240.745183 -55.084104) (xy 240.691235 -55.09186) (xy 240.636733 -55.09186)
			(xy 240.582785 -55.084104) (xy 240.53049 -55.068749) (xy 240.480913 -55.046107) (xy 240.435063 -55.016641)
			(xy 240.393872 -54.98095) (xy 240.358181 -54.939759) (xy 240.328715 -54.893909) (xy 240.306073 -54.844332)
			(xy 240.290718 -54.792037) (xy 240.282962 -54.738089) (xy 240.282476 -54.710838) (xy 230.878811 -54.710838)
			(xy 230.878402 -54.733771) (xy 230.870646 -54.787719) (xy 230.855291 -54.840014) (xy 230.832649 -54.889591)
			(xy 230.803183 -54.935441) (xy 230.767492 -54.976632) (xy 230.726301 -55.012323) (xy 230.680451 -55.041789)
			(xy 230.630874 -55.064431) (xy 230.578579 -55.079786) (xy 230.524631 -55.087542) (xy 230.470129 -55.087542)
			(xy 230.416181 -55.079786) (xy 230.363886 -55.064431) (xy 230.314309 -55.041789) (xy 230.268459 -55.012323)
			(xy 230.227268 -54.976632) (xy 230.191577 -54.935441) (xy 230.162111 -54.889591) (xy 230.139469 -54.840014)
			(xy 230.124114 -54.787719) (xy 230.116358 -54.733771) (xy 230.115872 -54.70652) (xy 206.493338 -54.70652)
			(xy 206.376912 -54.783019) (xy 206.237157 -54.86525) (xy 206.093507 -54.940469) (xy 205.946312 -55.008492)
			(xy 205.795934 -55.069153) (xy 205.64274 -55.122303) (xy 205.487105 -55.167811) (xy 205.32941 -55.205567)
			(xy 205.17004 -55.235479) (xy 205.009386 -55.257472) (xy 204.847842 -55.271493) (xy 204.685801 -55.277509)
			(xy 204.523661 -55.275503) (xy 204.361819 -55.265482) (xy 204.200671 -55.247469) (xy 204.04061 -55.221509)
			(xy 203.882029 -55.187664) (xy 203.725316 -55.146019) (xy 203.570854 -55.096675) (xy 203.419022 -55.039753)
			(xy 203.27019 -54.975391) (xy 203.124723 -54.903748) (xy 202.982977 -54.824999) (xy 202.845299 -54.739336)
			(xy 202.712026 -54.646969) (xy 202.583484 -54.548125) (xy 202.459987 -54.443044) (xy 202.341839 -54.331985)
			(xy 202.229327 -54.215219) (xy 202.122727 -54.093031) (xy 202.0223 -53.965721) (xy 201.928292 -53.833601)
			(xy 201.840933 -53.696993) (xy 201.760436 -53.556232) (xy 201.687 -53.411662) (xy 201.620802 -53.263638)
			(xy 201.562006 -53.112521) (xy 201.510755 -52.958681) (xy 201.467175 -52.802495) (xy 201.431372 -52.644345)
			(xy 201.403434 -52.484618) (xy 201.38343 -52.323704) (xy 201.371407 -52.161999) (xy 201.367397 -51.999896)
			(xy 179.393088 -51.999896) (xy 179.393088 -52.481734) (xy 179.392602 -52.508985) (xy 179.384846 -52.562933)
			(xy 179.369491 -52.615228) (xy 179.346849 -52.664805) (xy 179.317383 -52.710655) (xy 179.281692 -52.751846)
			(xy 179.240501 -52.787537) (xy 179.194651 -52.817003) (xy 179.145074 -52.839645) (xy 179.092779 -52.855)
			(xy 179.038831 -52.862756) (xy 178.984329 -52.862756) (xy 178.930381 -52.855) (xy 178.878086 -52.839645)
			(xy 178.828509 -52.817003) (xy 178.782659 -52.787537) (xy 178.741468 -52.751846) (xy 178.705777 -52.710655)
			(xy 178.676311 -52.664805) (xy 178.653669 -52.615228) (xy 178.638314 -52.562933) (xy 178.630558 -52.508985)
			(xy 178.630072 -52.481734) (xy 0.509016 -52.481734) (xy 0.509016 -53.954934) (xy 181.659784 -53.954934)
			(xy 181.659784 -53.091334) (xy 181.66027 -53.064083) (xy 181.668026 -53.010135) (xy 181.683381 -52.95784)
			(xy 181.706023 -52.908263) (xy 181.735489 -52.862413) (xy 181.77118 -52.821222) (xy 181.812371 -52.785531)
			(xy 181.858221 -52.756065) (xy 181.907798 -52.733423) (xy 181.960093 -52.718068) (xy 182.014041 -52.710312)
			(xy 182.068543 -52.710312) (xy 182.122491 -52.718068) (xy 182.174786 -52.733423) (xy 182.224363 -52.756065)
			(xy 182.270213 -52.785531) (xy 182.311404 -52.821222) (xy 182.347095 -52.862413) (xy 182.376561 -52.908263)
			(xy 182.399203 -52.95784) (xy 182.414558 -53.010135) (xy 182.422314 -53.064083) (xy 182.4228 -53.091334)
			(xy 182.4228 -53.954934) (xy 182.422314 -53.982185) (xy 182.414558 -54.036133) (xy 182.399203 -54.088428)
			(xy 182.376561 -54.138005) (xy 182.347095 -54.183855) (xy 182.311404 -54.225046) (xy 182.270213 -54.260737)
			(xy 182.224363 -54.290203) (xy 182.174786 -54.312845) (xy 182.122491 -54.3282) (xy 182.068543 -54.335956)
			(xy 182.014041 -54.335956) (xy 181.960093 -54.3282) (xy 181.907798 -54.312845) (xy 181.858221 -54.290203)
			(xy 181.812371 -54.260737) (xy 181.77118 -54.225046) (xy 181.735489 -54.183855) (xy 181.706023 -54.138005)
			(xy 181.683381 -54.088428) (xy 181.668026 -54.036133) (xy 181.66027 -53.982185) (xy 181.659784 -53.954934)
			(xy 0.509016 -53.954934) (xy 0.509016 -55.481728) (xy 178.630072 -55.481728) (xy 178.630072 -54.618128)
			(xy 178.630558 -54.590877) (xy 178.638314 -54.536929) (xy 178.653669 -54.484634) (xy 178.676311 -54.435057)
			(xy 178.705777 -54.389207) (xy 178.741468 -54.348016) (xy 178.782659 -54.312325) (xy 178.828509 -54.282859)
			(xy 178.878086 -54.260217) (xy 178.930381 -54.244862) (xy 178.984329 -54.237106) (xy 179.038831 -54.237106)
			(xy 179.092779 -54.244862) (xy 179.145074 -54.260217) (xy 179.194651 -54.282859) (xy 179.240501 -54.312325)
			(xy 179.281692 -54.348016) (xy 179.317383 -54.389207) (xy 179.346849 -54.435057) (xy 179.369491 -54.484634)
			(xy 179.384846 -54.536929) (xy 179.392602 -54.590877) (xy 179.393088 -54.618128) (xy 179.393088 -55.481728)
			(xy 179.392602 -55.508979) (xy 179.384846 -55.562927) (xy 179.369491 -55.615222) (xy 179.346849 -55.664799)
			(xy 179.317383 -55.710649) (xy 179.281692 -55.75184) (xy 179.240501 -55.787531) (xy 179.194651 -55.816997)
			(xy 179.145074 -55.839639) (xy 179.092779 -55.854994) (xy 179.038831 -55.86275) (xy 178.984329 -55.86275)
			(xy 178.930381 -55.854994) (xy 178.878086 -55.839639) (xy 178.828509 -55.816997) (xy 178.782659 -55.787531)
			(xy 178.741468 -55.75184) (xy 178.705777 -55.710649) (xy 178.676311 -55.664799) (xy 178.653669 -55.615222)
			(xy 178.638314 -55.562927) (xy 178.630558 -55.508979) (xy 178.630072 -55.481728) (xy 0.509016 -55.481728)
			(xy 0.509016 -57.094435) (xy 170.841915 -57.094435) (xy 170.841915 -57.005413) (xy 170.849895 -56.916749)
			(xy 170.865791 -56.829158) (xy 170.889474 -56.743343) (xy 170.920754 -56.659998) (xy 170.95938 -56.579792)
			(xy 171.005039 -56.503371) (xy 171.057365 -56.43135) (xy 171.115936 -56.36431) (xy 171.180281 -56.30279)
			(xy 171.249881 -56.247286) (xy 171.324177 -56.198244) (xy 171.402569 -56.156059) (xy 171.484428 -56.121071)
			(xy 171.569093 -56.093562) (xy 171.655883 -56.073752) (xy 171.744099 -56.061802) (xy 171.833032 -56.057809)
			(xy 171.921965 -56.061802) (xy 172.010181 -56.073752) (xy 172.096971 -56.093562) (xy 172.181636 -56.121071)
			(xy 172.263495 -56.156059) (xy 172.341887 -56.198244) (xy 172.416183 -56.247286) (xy 172.485783 -56.30279)
			(xy 172.550128 -56.36431) (xy 172.608699 -56.43135) (xy 172.661025 -56.503371) (xy 172.663117 -56.506872)
			(xy 228.815392 -56.506872) (xy 228.815392 -55.643272) (xy 228.815878 -55.616021) (xy 228.823634 -55.562073)
			(xy 228.838989 -55.509778) (xy 228.861631 -55.460201) (xy 228.891097 -55.414351) (xy 228.926788 -55.37316)
			(xy 228.967979 -55.337469) (xy 229.013829 -55.308003) (xy 229.063406 -55.285361) (xy 229.115701 -55.270006)
			(xy 229.169649 -55.26225) (xy 229.224151 -55.26225) (xy 229.278099 -55.270006) (xy 229.330394 -55.285361)
			(xy 229.379971 -55.308003) (xy 229.425821 -55.337469) (xy 229.467012 -55.37316) (xy 229.502703 -55.414351)
			(xy 229.532169 -55.460201) (xy 229.554811 -55.509778) (xy 229.570166 -55.562073) (xy 229.577922 -55.616021)
			(xy 229.578408 -55.643272) (xy 229.578408 -55.911852) (xy 357.10365 -55.911852) (xy 357.10365 -55.857348)
			(xy 357.111406 -55.803398) (xy 357.126762 -55.751101) (xy 357.149403 -55.701521) (xy 357.17887 -55.655668)
			(xy 357.214562 -55.614476) (xy 357.255752 -55.578782) (xy 357.301604 -55.549313) (xy 357.351182 -55.526669)
			(xy 357.403478 -55.511311) (xy 357.457428 -55.503551) (xy 357.48468 -55.503064) (xy 358.34828 -55.503064)
			(xy 358.375532 -55.503582) (xy 358.429481 -55.511336) (xy 358.481777 -55.526689) (xy 358.531356 -55.549329)
			(xy 358.577209 -55.578794) (xy 358.618401 -55.614485) (xy 358.654094 -55.655675) (xy 358.683562 -55.701526)
			(xy 358.706204 -55.751104) (xy 358.72156 -55.8034) (xy 358.729317 -55.857348) (xy 358.729317 -55.911852)
			(xy 358.729316 -55.911856) (xy 359.950927 -55.911856) (xy 359.950927 -55.857344) (xy 359.958685 -55.803388)
			(xy 359.974043 -55.751084) (xy 359.996689 -55.701499) (xy 360.026161 -55.655642) (xy 360.061859 -55.614445)
			(xy 360.103058 -55.578749) (xy 360.148917 -55.549279) (xy 360.198503 -55.526636) (xy 360.250807 -55.511281)
			(xy 360.304764 -55.503526) (xy 360.33202 -55.503064) (xy 361.19562 -55.503064) (xy 361.222868 -55.503608)
			(xy 361.27681 -55.511366) (xy 361.329098 -55.526722) (xy 361.378669 -55.549362) (xy 361.424514 -55.578827)
			(xy 361.465699 -55.614516) (xy 361.501385 -55.655702) (xy 361.530847 -55.701548) (xy 361.553485 -55.75112)
			(xy 361.568838 -55.80341) (xy 361.576594 -55.857352) (xy 361.576594 -55.911848) (xy 361.576593 -55.911857)
			(xy 363.514527 -55.911857) (xy 363.514527 -55.857343) (xy 363.522286 -55.803385) (xy 363.537645 -55.75108)
			(xy 363.560292 -55.701493) (xy 363.589766 -55.655635) (xy 363.625466 -55.614438) (xy 363.666667 -55.578742)
			(xy 363.712529 -55.549273) (xy 363.762117 -55.526631) (xy 363.814424 -55.511277) (xy 363.868383 -55.503524)
			(xy 363.89564 -55.503064) (xy 364.75924 -55.503064) (xy 364.786487 -55.503609) (xy 364.840427 -55.511369)
			(xy 364.892713 -55.526727) (xy 364.942281 -55.549369) (xy 364.988123 -55.578834) (xy 365.029306 -55.614523)
			(xy 365.06499 -55.655709) (xy 365.094451 -55.701554) (xy 365.117087 -55.751125) (xy 365.132439 -55.803412)
			(xy 365.140194 -55.857353) (xy 365.140194 -55.911847) (xy 365.132439 -55.965788) (xy 365.117087 -56.018075)
			(xy 365.094451 -56.067646) (xy 365.06499 -56.113491) (xy 365.029306 -56.154677) (xy 364.988123 -56.190366)
			(xy 364.942281 -56.219831) (xy 364.892713 -56.242473) (xy 364.840427 -56.257831) (xy 364.786487 -56.265591)
			(xy 364.75924 -56.26608) (xy 363.89564 -56.26608) (xy 363.868383 -56.265676) (xy 363.814424 -56.257923)
			(xy 363.762117 -56.242569) (xy 363.712529 -56.219927) (xy 363.666667 -56.190458) (xy 363.625466 -56.154762)
			(xy 363.589766 -56.113565) (xy 363.560292 -56.067707) (xy 363.537645 -56.01812) (xy 363.522286 -55.965815)
			(xy 363.514527 -55.911857) (xy 361.576593 -55.911857) (xy 361.568838 -55.96579) (xy 361.553485 -56.01808)
			(xy 361.530847 -56.067652) (xy 361.501385 -56.113498) (xy 361.465699 -56.154684) (xy 361.424514 -56.190373)
			(xy 361.378669 -56.219838) (xy 361.329098 -56.242478) (xy 361.27681 -56.257834) (xy 361.222868 -56.265592)
			(xy 361.19562 -56.26608) (xy 360.33202 -56.26608) (xy 360.304764 -56.265674) (xy 360.250807 -56.257919)
			(xy 360.198503 -56.242564) (xy 360.148917 -56.219921) (xy 360.103058 -56.190451) (xy 360.061859 -56.154755)
			(xy 360.026161 -56.113558) (xy 359.996689 -56.067701) (xy 359.974043 -56.018116) (xy 359.958685 -55.965812)
			(xy 359.950927 -55.911856) (xy 358.729316 -55.911856) (xy 358.72156 -55.9658) (xy 358.706204 -56.018096)
			(xy 358.683562 -56.067674) (xy 358.654094 -56.113525) (xy 358.618401 -56.154715) (xy 358.577209 -56.190406)
			(xy 358.531356 -56.219871) (xy 358.481777 -56.242511) (xy 358.429481 -56.257864) (xy 358.375532 -56.265618)
			(xy 358.34828 -56.26608) (xy 357.48468 -56.26608) (xy 357.457428 -56.265649) (xy 357.403478 -56.257889)
			(xy 357.351182 -56.242531) (xy 357.301604 -56.219887) (xy 357.255752 -56.190418) (xy 357.214562 -56.154724)
			(xy 357.17887 -56.113532) (xy 357.149403 -56.067679) (xy 357.126762 -56.018099) (xy 357.111406 -55.965802)
			(xy 357.10365 -55.911852) (xy 229.578408 -55.911852) (xy 229.578408 -56.506872) (xy 229.577922 -56.534123)
			(xy 229.570166 -56.588071) (xy 229.554811 -56.640366) (xy 229.532169 -56.689943) (xy 229.502703 -56.735793)
			(xy 229.467012 -56.776984) (xy 229.425821 -56.812675) (xy 229.379971 -56.842141) (xy 229.330394 -56.864783)
			(xy 229.278099 -56.880138) (xy 229.224151 -56.887894) (xy 229.169649 -56.887894) (xy 229.115701 -56.880138)
			(xy 229.063406 -56.864783) (xy 229.013829 -56.842141) (xy 228.967979 -56.812675) (xy 228.926788 -56.776984)
			(xy 228.891097 -56.735793) (xy 228.861631 -56.689943) (xy 228.838989 -56.640366) (xy 228.823634 -56.588071)
			(xy 228.815878 -56.534123) (xy 228.815392 -56.506872) (xy 172.663117 -56.506872) (xy 172.706684 -56.579792)
			(xy 172.74531 -56.659998) (xy 172.77659 -56.743343) (xy 172.800273 -56.829158) (xy 172.816169 -56.916749)
			(xy 172.824149 -57.005413) (xy 172.824648 -57.049924) (xy 172.824149 -57.094435) (xy 172.816169 -57.183099)
			(xy 172.800273 -57.27069) (xy 172.77659 -57.356505) (xy 172.74531 -57.43985) (xy 172.706684 -57.520056)
			(xy 172.661025 -57.596477) (xy 172.608699 -57.668498) (xy 172.550128 -57.735538) (xy 172.485783 -57.797058)
			(xy 172.416183 -57.852562) (xy 172.341887 -57.901604) (xy 172.263495 -57.943789) (xy 172.181636 -57.978777)
			(xy 172.096971 -58.006286) (xy 172.010181 -58.026096) (xy 171.921965 -58.038046) (xy 171.833032 -58.04204)
			(xy 171.744099 -58.038046) (xy 171.655883 -58.026096) (xy 171.569093 -58.006286) (xy 171.484428 -57.978777)
			(xy 171.402569 -57.943789) (xy 171.324177 -57.901604) (xy 171.249881 -57.852562) (xy 171.180281 -57.797058)
			(xy 171.115936 -57.735538) (xy 171.057365 -57.668498) (xy 171.005039 -57.596477) (xy 170.95938 -57.520056)
			(xy 170.920754 -57.43985) (xy 170.889474 -57.356505) (xy 170.865791 -57.27069) (xy 170.849895 -57.183099)
			(xy 170.841915 -57.094435) (xy 0.509016 -57.094435) (xy 0.509016 -58.306716) (xy 230.115872 -58.306716)
			(xy 230.115872 -57.443116) (xy 230.116358 -57.415865) (xy 230.124114 -57.361917) (xy 230.139469 -57.309622)
			(xy 230.162111 -57.260045) (xy 230.191577 -57.214195) (xy 230.227268 -57.173004) (xy 230.268459 -57.137313)
			(xy 230.314309 -57.107847) (xy 230.363886 -57.085205) (xy 230.416181 -57.06985) (xy 230.470129 -57.062094)
			(xy 230.524631 -57.062094) (xy 230.578579 -57.06985) (xy 230.630874 -57.085205) (xy 230.680451 -57.107847)
			(xy 230.726301 -57.137313) (xy 230.767492 -57.173004) (xy 230.803183 -57.214195) (xy 230.832649 -57.260045)
			(xy 230.855291 -57.309622) (xy 230.870646 -57.361917) (xy 230.878402 -57.415865) (xy 230.878888 -57.443116)
			(xy 230.878888 -58.30189) (xy 240.282476 -58.30189) (xy 240.282476 -57.43829) (xy 240.282962 -57.411039)
			(xy 240.290718 -57.357091) (xy 240.306073 -57.304796) (xy 240.328715 -57.255219) (xy 240.358181 -57.209369)
			(xy 240.393872 -57.168178) (xy 240.435063 -57.132487) (xy 240.480913 -57.103021) (xy 240.53049 -57.080379)
			(xy 240.582785 -57.065024) (xy 240.636733 -57.057268) (xy 240.691235 -57.057268) (xy 240.745183 -57.065024)
			(xy 240.797478 -57.080379) (xy 240.847055 -57.103021) (xy 240.892905 -57.132487) (xy 240.934096 -57.168178)
			(xy 240.969787 -57.209369) (xy 240.999253 -57.255219) (xy 241.021895 -57.304796) (xy 241.03725 -57.357091)
			(xy 241.045006 -57.411039) (xy 241.045492 -57.43829) (xy 241.045492 -58.30189) (xy 241.045006 -58.329141)
			(xy 241.03725 -58.383089) (xy 241.021895 -58.435384) (xy 240.999253 -58.484961) (xy 240.969787 -58.530811)
			(xy 240.941894 -58.563002) (xy 242.736116 -58.563002) (xy 242.736116 -57.699402) (xy 242.736602 -57.672151)
			(xy 242.744358 -57.618203) (xy 242.759713 -57.565908) (xy 242.782355 -57.516331) (xy 242.811821 -57.470481)
			(xy 242.847512 -57.42929) (xy 242.888703 -57.393599) (xy 242.934553 -57.364133) (xy 242.98413 -57.341491)
			(xy 243.036425 -57.326136) (xy 243.090373 -57.31838) (xy 243.144875 -57.31838) (xy 243.198823 -57.326136)
			(xy 243.251118 -57.341491) (xy 243.300695 -57.364133) (xy 243.346545 -57.393599) (xy 243.387736 -57.42929)
			(xy 243.423427 -57.470481) (xy 243.452893 -57.516331) (xy 243.475535 -57.565908) (xy 243.49089 -57.618203)
			(xy 243.498646 -57.672151) (xy 243.499132 -57.699402) (xy 243.499132 -58.563002) (xy 243.498646 -58.590253)
			(xy 243.49089 -58.644201) (xy 243.475535 -58.696496) (xy 243.452893 -58.746073) (xy 243.423427 -58.791923)
			(xy 243.387736 -58.833114) (xy 243.346545 -58.868805) (xy 243.300695 -58.898271) (xy 243.251118 -58.920913)
			(xy 243.198823 -58.936268) (xy 243.144875 -58.944024) (xy 243.090373 -58.944024) (xy 243.036425 -58.936268)
			(xy 242.98413 -58.920913) (xy 242.934553 -58.898271) (xy 242.888703 -58.868805) (xy 242.847512 -58.833114)
			(xy 242.811821 -58.791923) (xy 242.782355 -58.746073) (xy 242.759713 -58.696496) (xy 242.744358 -58.644201)
			(xy 242.736602 -58.590253) (xy 242.736116 -58.563002) (xy 240.941894 -58.563002) (xy 240.934096 -58.572002)
			(xy 240.892905 -58.607693) (xy 240.847055 -58.637159) (xy 240.797478 -58.659801) (xy 240.745183 -58.675156)
			(xy 240.691235 -58.682912) (xy 240.636733 -58.682912) (xy 240.582785 -58.675156) (xy 240.53049 -58.659801)
			(xy 240.480913 -58.637159) (xy 240.435063 -58.607693) (xy 240.393872 -58.572002) (xy 240.358181 -58.530811)
			(xy 240.328715 -58.484961) (xy 240.306073 -58.435384) (xy 240.290718 -58.383089) (xy 240.282962 -58.329141)
			(xy 240.282476 -58.30189) (xy 230.878888 -58.30189) (xy 230.878888 -58.306716) (xy 230.878402 -58.333967)
			(xy 230.870646 -58.387915) (xy 230.855291 -58.44021) (xy 230.832649 -58.489787) (xy 230.803183 -58.535637)
			(xy 230.767492 -58.576828) (xy 230.726301 -58.612519) (xy 230.680451 -58.641985) (xy 230.630874 -58.664627)
			(xy 230.578579 -58.679982) (xy 230.524631 -58.687738) (xy 230.470129 -58.687738) (xy 230.416181 -58.679982)
			(xy 230.363886 -58.664627) (xy 230.314309 -58.641985) (xy 230.268459 -58.612519) (xy 230.227268 -58.576828)
			(xy 230.191577 -58.535637) (xy 230.162111 -58.489787) (xy 230.139469 -58.44021) (xy 230.124114 -58.387915)
			(xy 230.116358 -58.333967) (xy 230.115872 -58.306716) (xy 0.509016 -58.306716) (xy 0.509016 -59.99988)
			(xy 16.983969 -59.99988) (xy 16.987993 -59.914112) (xy 17.000031 -59.829098) (xy 17.019978 -59.745584)
			(xy 17.047657 -59.664305) (xy 17.082825 -59.585976) (xy 17.125174 -59.511283) (xy 17.174331 -59.440885)
			(xy 17.229864 -59.375399) (xy 17.291286 -59.315401) (xy 17.358055 -59.261418) (xy 17.429587 -59.213925)
			(xy 17.505251 -59.173339) (xy 17.584384 -59.140016) (xy 17.666289 -59.11425) (xy 17.750247 -59.096267)
			(xy 17.835521 -59.086225) (xy 17.92136 -59.084212) (xy 18.00701 -59.090246) (xy 18.091718 -59.104274)
			(xy 18.174741 -59.126173) (xy 18.255349 -59.15575) (xy 18.332833 -59.192745) (xy 18.406512 -59.236833)
			(xy 18.475738 -59.287627) (xy 18.539905 -59.34468) (xy 18.598446 -59.407491) (xy 18.650849 -59.475508)
			(xy 18.696652 -59.548133) (xy 18.735453 -59.624728) (xy 18.766912 -59.70462) (xy 18.790751 -59.787107)
			(xy 18.806761 -59.871464) (xy 18.814801 -59.956949) (xy 18.815304 -59.99988) (xy 18.814801 -60.042811)
			(xy 18.806761 -60.128296) (xy 18.790751 -60.212653) (xy 18.766912 -60.29514) (xy 18.735453 -60.375032)
			(xy 18.73545 -60.375038) (xy 233.333297 -60.375038) (xy 233.337302 -60.28713) (xy 233.349285 -60.19995)
			(xy 233.369145 -60.114221) (xy 233.39672 -60.030653) (xy 233.431779 -59.949939) (xy 233.474032 -59.872747)
			(xy 233.52313 -59.799718) (xy 233.578666 -59.731456) (xy 233.640178 -59.668526) (xy 233.707159 -59.611452)
			(xy 233.779052 -59.560704) (xy 233.855261 -59.516704) (xy 233.935156 -59.479817) (xy 234.018075 -59.450348)
			(xy 234.10333 -59.428541) (xy 234.190214 -59.414577) (xy 234.278008 -59.408571) (xy 234.365985 -59.410575)
			(xy 234.453415 -59.42057) (xy 234.539574 -59.438474) (xy 234.623748 -59.464138) (xy 234.705239 -59.497351)
			(xy 234.783373 -59.537837) (xy 234.857501 -59.585259) (xy 234.927009 -59.639226) (xy 234.991323 -59.699291)
			(xy 235.049907 -59.764955) (xy 235.102278 -59.835674) (xy 235.148001 -59.910862) (xy 235.186698 -59.989897)
			(xy 235.218047 -60.072123) (xy 235.241789 -60.156859) (xy 235.257727 -60.243403) (xy 235.265729 -60.331038)
			(xy 235.26623 -60.375038) (xy 235.265729 -60.419038) (xy 235.257727 -60.506673) (xy 235.241789 -60.593217)
			(xy 235.218047 -60.677953) (xy 235.186698 -60.760179) (xy 235.148001 -60.839214) (xy 235.102278 -60.914402)
			(xy 235.049907 -60.985121) (xy 234.991323 -61.050785) (xy 234.927009 -61.11085) (xy 234.857501 -61.164817)
			(xy 234.783373 -61.212239) (xy 234.705239 -61.252725) (xy 234.623748 -61.285938) (xy 234.539574 -61.311602)
			(xy 234.453415 -61.329506) (xy 234.365985 -61.339501) (xy 234.278008 -61.341505) (xy 234.190214 -61.335499)
			(xy 234.10333 -61.321535) (xy 234.018075 -61.299728) (xy 233.935156 -61.270259) (xy 233.855261 -61.233372)
			(xy 233.779052 -61.189372) (xy 233.707159 -61.138624) (xy 233.640178 -61.08155) (xy 233.578666 -61.01862)
			(xy 233.52313 -60.950358) (xy 233.474032 -60.877329) (xy 233.431779 -60.800137) (xy 233.39672 -60.719423)
			(xy 233.369145 -60.635855) (xy 233.349285 -60.550126) (xy 233.337302 -60.462946) (xy 233.333297 -60.375038)
			(xy 18.73545 -60.375038) (xy 18.696652 -60.451627) (xy 18.650849 -60.524252) (xy 18.598446 -60.592269)
			(xy 18.539905 -60.65508) (xy 18.475738 -60.712133) (xy 18.406512 -60.762927) (xy 18.332833 -60.807015)
			(xy 18.255349 -60.84401) (xy 18.174741 -60.873587) (xy 18.091718 -60.895486) (xy 18.00701 -60.909514)
			(xy 17.92136 -60.915548) (xy 17.835521 -60.913535) (xy 17.750247 -60.903493) (xy 17.666289 -60.88551)
			(xy 17.584384 -60.859744) (xy 17.505251 -60.826421) (xy 17.429587 -60.785835) (xy 17.358055 -60.738342)
			(xy 17.291286 -60.684359) (xy 17.229864 -60.624361) (xy 17.174331 -60.558875) (xy 17.125174 -60.488477)
			(xy 17.082825 -60.413784) (xy 17.047657 -60.335455) (xy 17.019978 -60.254176) (xy 17.000031 -60.170662)
			(xy 16.987993 -60.085648) (xy 16.983969 -59.99988) (xy 0.509016 -59.99988) (xy 0.509016 -74.760836)
			(xy 39.554404 -74.760836) (xy 39.554404 -66.060828) (xy 39.554909 -65.955304) (xy 39.562993 -65.74441)
			(xy 39.579149 -65.533981) (xy 39.603352 -65.324324) (xy 39.635569 -65.115749) (xy 39.675751 -64.908561)
			(xy 39.723839 -64.703064) (xy 39.779763 -64.49956) (xy 39.84344 -64.298347) (xy 39.914778 -64.09972)
			(xy 39.993672 -63.903972) (xy 40.080005 -63.71139) (xy 40.173652 -63.522255) (xy 40.274474 -63.336846)
			(xy 40.382324 -63.155435) (xy 40.497043 -62.978288) (xy 40.618463 -62.805666) (xy 40.746406 -62.63782)
			(xy 40.880684 -62.474998) (xy 41.0211 -62.317439) (xy 41.167448 -62.165374) (xy 41.319513 -62.019026)
			(xy 41.477072 -61.87861) (xy 41.639894 -61.744332) (xy 41.80774 -61.616389) (xy 41.980362 -61.494969)
			(xy 42.157509 -61.38025) (xy 42.33892 -61.2724) (xy 42.524329 -61.171578) (xy 42.713464 -61.077931)
			(xy 42.906046 -60.991598) (xy 43.101794 -60.912704) (xy 43.300421 -60.841366) (xy 43.501634 -60.777689)
			(xy 43.705138 -60.721765) (xy 43.910635 -60.673677) (xy 44.117823 -60.633495) (xy 44.326398 -60.601278)
			(xy 44.536055 -60.577075) (xy 44.746484 -60.560919) (xy 44.957378 -60.552835) (xy 45.168426 -60.552835)
			(xy 45.37932 -60.560919) (xy 45.589749 -60.577075) (xy 45.799406 -60.601278) (xy 46.007981 -60.633495)
			(xy 46.215169 -60.673677) (xy 46.420666 -60.721765) (xy 46.62417 -60.777689) (xy 46.825383 -60.841366)
			(xy 47.02401 -60.912704) (xy 47.219758 -60.991598) (xy 47.41234 -61.077931) (xy 47.601475 -61.171578)
			(xy 47.786884 -61.2724) (xy 47.968295 -61.38025) (xy 48.145442 -61.494969) (xy 48.318064 -61.616389)
			(xy 48.48591 -61.744332) (xy 48.648732 -61.87861) (xy 48.806291 -62.019026) (xy 48.958356 -62.165374)
			(xy 49.104704 -62.317439) (xy 49.24512 -62.474998) (xy 49.379398 -62.63782) (xy 49.507341 -62.805666)
			(xy 49.628761 -62.978288) (xy 49.74348 -63.155435) (xy 49.85133 -63.336846) (xy 49.952152 -63.522255)
			(xy 50.045799 -63.71139) (xy 50.132132 -63.903972) (xy 50.211026 -64.09972) (xy 50.282364 -64.298347)
			(xy 50.346041 -64.49956) (xy 50.401965 -64.703064) (xy 50.450053 -64.908561) (xy 50.490235 -65.115749)
			(xy 50.522452 -65.324324) (xy 50.546655 -65.533981) (xy 50.562811 -65.74441) (xy 50.570895 -65.955304)
			(xy 50.5714 -66.060828) (xy 50.5714 -74.760836) (xy 50.571366 -74.767948) (xy 173.354492 -74.767948)
			(xy 173.354492 -66.06794) (xy 173.354997 -65.962416) (xy 173.363081 -65.751522) (xy 173.379237 -65.541093)
			(xy 173.40344 -65.331436) (xy 173.435657 -65.122861) (xy 173.475839 -64.915673) (xy 173.523927 -64.710176)
			(xy 173.579851 -64.506672) (xy 173.643528 -64.305459) (xy 173.714866 -64.106832) (xy 173.79376 -63.911084)
			(xy 173.880093 -63.718502) (xy 173.97374 -63.529367) (xy 174.074562 -63.343958) (xy 174.182412 -63.162547)
			(xy 174.297131 -62.9854) (xy 174.418551 -62.812778) (xy 174.546494 -62.644932) (xy 174.680772 -62.48211)
			(xy 174.821188 -62.324551) (xy 174.967536 -62.172486) (xy 175.119601 -62.026138) (xy 175.27716 -61.885722)
			(xy 175.439982 -61.751444) (xy 175.607828 -61.623501) (xy 175.78045 -61.502081) (xy 175.957597 -61.387362)
			(xy 176.139008 -61.279512) (xy 176.324417 -61.17869) (xy 176.513552 -61.085043) (xy 176.706134 -60.99871)
			(xy 176.901882 -60.919816) (xy 177.100509 -60.848478) (xy 177.301722 -60.784801) (xy 177.505226 -60.728877)
			(xy 177.710723 -60.680789) (xy 177.917911 -60.640607) (xy 178.126486 -60.60839) (xy 178.336143 -60.584187)
			(xy 178.546572 -60.568031) (xy 178.757466 -60.559947) (xy 178.968514 -60.559947) (xy 179.179408 -60.568031)
			(xy 179.389837 -60.584187) (xy 179.599494 -60.60839) (xy 179.808069 -60.640607) (xy 180.015257 -60.680789)
			(xy 180.220754 -60.728877) (xy 180.424258 -60.784801) (xy 180.625471 -60.848478) (xy 180.824098 -60.919816)
			(xy 181.019846 -60.99871) (xy 181.212428 -61.085043) (xy 181.401563 -61.17869) (xy 181.586972 -61.279512)
			(xy 181.768383 -61.387362) (xy 181.94553 -61.502081) (xy 182.118152 -61.623501) (xy 182.285998 -61.751444)
			(xy 182.44882 -61.885722) (xy 182.606379 -62.026138) (xy 182.758444 -62.172486) (xy 182.904792 -62.324551)
			(xy 183.045208 -62.48211) (xy 183.179486 -62.644932) (xy 183.307429 -62.812778) (xy 183.428849 -62.9854)
			(xy 183.543568 -63.162547) (xy 183.651418 -63.343958) (xy 183.75224 -63.529367) (xy 183.845887 -63.718502)
			(xy 183.93222 -63.911084) (xy 184.011114 -64.106832) (xy 184.082452 -64.305459) (xy 184.146129 -64.506672)
			(xy 184.202053 -64.710176) (xy 184.250141 -64.915673) (xy 184.290323 -65.122861) (xy 184.32254 -65.331436)
			(xy 184.346743 -65.541093) (xy 184.362899 -65.751522) (xy 184.370983 -65.962416) (xy 184.371488 -66.06794)
			(xy 184.371488 -74.760836) (xy 287.494472 -74.760836) (xy 287.494472 -66.060828) (xy 287.494977 -65.955304)
			(xy 287.503061 -65.74441) (xy 287.519217 -65.533981) (xy 287.54342 -65.324324) (xy 287.575637 -65.115749)
			(xy 287.615819 -64.908561) (xy 287.663907 -64.703064) (xy 287.719831 -64.49956) (xy 287.783508 -64.298347)
			(xy 287.854846 -64.09972) (xy 287.93374 -63.903972) (xy 288.020073 -63.71139) (xy 288.11372 -63.522255)
			(xy 288.214542 -63.336846) (xy 288.322392 -63.155435) (xy 288.437111 -62.978288) (xy 288.558531 -62.805666)
			(xy 288.686474 -62.63782) (xy 288.820752 -62.474998) (xy 288.961168 -62.317439) (xy 289.107516 -62.165374)
			(xy 289.259581 -62.019026) (xy 289.41714 -61.87861) (xy 289.579962 -61.744332) (xy 289.747808 -61.616389)
			(xy 289.92043 -61.494969) (xy 290.097577 -61.38025) (xy 290.278988 -61.2724) (xy 290.464397 -61.171578)
			(xy 290.653532 -61.077931) (xy 290.846114 -60.991598) (xy 291.041862 -60.912704) (xy 291.240489 -60.841366)
			(xy 291.441702 -60.777689) (xy 291.645206 -60.721765) (xy 291.850703 -60.673677) (xy 292.057891 -60.633495)
			(xy 292.266466 -60.601278) (xy 292.476123 -60.577075) (xy 292.686552 -60.560919) (xy 292.897446 -60.552835)
			(xy 293.108494 -60.552835) (xy 293.319388 -60.560919) (xy 293.529817 -60.577075) (xy 293.739474 -60.601278)
			(xy 293.948049 -60.633495) (xy 294.155237 -60.673677) (xy 294.360734 -60.721765) (xy 294.564238 -60.777689)
			(xy 294.765451 -60.841366) (xy 294.964078 -60.912704) (xy 295.159826 -60.991598) (xy 295.352408 -61.077931)
			(xy 295.541543 -61.171578) (xy 295.726952 -61.2724) (xy 295.908363 -61.38025) (xy 296.063868 -61.480954)
			(xy 351.822512 -61.480954) (xy 351.822512 -60.617354) (xy 351.822998 -60.590103) (xy 351.830754 -60.536155)
			(xy 351.846109 -60.48386) (xy 351.868751 -60.434283) (xy 351.898217 -60.388433) (xy 351.933908 -60.347242)
			(xy 351.975099 -60.311551) (xy 352.020949 -60.282085) (xy 352.070526 -60.259443) (xy 352.122821 -60.244088)
			(xy 352.176769 -60.236332) (xy 352.231271 -60.236332) (xy 352.285219 -60.244088) (xy 352.337514 -60.259443)
			(xy 352.387091 -60.282085) (xy 352.432941 -60.311551) (xy 352.474132 -60.347242) (xy 352.509823 -60.388433)
			(xy 352.539289 -60.434283) (xy 352.561931 -60.48386) (xy 352.577286 -60.536155) (xy 352.585042 -60.590103)
			(xy 352.585528 -60.617354) (xy 352.585528 -61.223271) (xy 355.46889 -61.223271) (xy 355.46889 -61.168729)
			(xy 355.476653 -61.114741) (xy 355.492019 -61.062408) (xy 355.514676 -61.012794) (xy 355.544164 -60.966909)
			(xy 355.579881 -60.925688) (xy 355.621101 -60.88997) (xy 355.666985 -60.860481) (xy 355.716598 -60.837822)
			(xy 355.768931 -60.822455) (xy 355.822919 -60.814691) (xy 355.85019 -60.814204) (xy 356.71379 -60.814204)
			(xy 356.741059 -60.814735) (xy 356.795042 -60.822495) (xy 356.847371 -60.837859) (xy 356.896981 -60.860514)
			(xy 356.942862 -60.889999) (xy 356.98408 -60.925713) (xy 357.019795 -60.96693) (xy 357.049281 -61.01281)
			(xy 357.071937 -61.062419) (xy 357.087303 -61.114748) (xy 357.095065 -61.168731) (xy 357.095065 -61.223269)
			(xy 357.087303 -61.277252) (xy 357.071937 -61.329581) (xy 357.049281 -61.37919) (xy 357.019795 -61.42507)
			(xy 356.98408 -61.466287) (xy 356.942862 -61.502001) (xy 356.896981 -61.531486) (xy 356.847371 -61.554141)
			(xy 356.795042 -61.569505) (xy 356.741059 -61.577265) (xy 356.71379 -61.577728) (xy 355.85019 -61.577728)
			(xy 355.822919 -61.577309) (xy 355.768931 -61.569545) (xy 355.716598 -61.554178) (xy 355.666985 -61.531519)
			(xy 355.621101 -61.50203) (xy 355.579881 -61.466312) (xy 355.544164 -61.425091) (xy 355.514676 -61.379206)
			(xy 355.492019 -61.329592) (xy 355.476653 -61.277259) (xy 355.46889 -61.223271) (xy 352.585528 -61.223271)
			(xy 352.585528 -61.480954) (xy 352.585042 -61.508205) (xy 352.577286 -61.562153) (xy 352.561931 -61.614448)
			(xy 352.539289 -61.664025) (xy 352.509823 -61.709875) (xy 352.474132 -61.751066) (xy 352.432941 -61.786757)
			(xy 352.387091 -61.816223) (xy 352.337514 -61.838865) (xy 352.285219 -61.85422) (xy 352.231271 -61.861976)
			(xy 352.176769 -61.861976) (xy 352.122821 -61.85422) (xy 352.070526 -61.838865) (xy 352.020949 -61.816223)
			(xy 351.975099 -61.786757) (xy 351.933908 -61.751066) (xy 351.898217 -61.709875) (xy 351.868751 -61.664025)
			(xy 351.846109 -61.614448) (xy 351.830754 -61.562153) (xy 351.822998 -61.508205) (xy 351.822512 -61.480954)
			(xy 296.063868 -61.480954) (xy 296.08551 -61.494969) (xy 296.258132 -61.616389) (xy 296.425978 -61.744332)
			(xy 296.5888 -61.87861) (xy 296.746359 -62.019026) (xy 296.898424 -62.165374) (xy 297.044772 -62.317439)
			(xy 297.185188 -62.474998) (xy 297.319466 -62.63782) (xy 297.447409 -62.805666) (xy 297.568829 -62.978288)
			(xy 297.683548 -63.155435) (xy 297.751584 -63.269876) (xy 350.300544 -63.269876) (xy 350.300544 -62.406276)
			(xy 350.30103 -62.379025) (xy 350.308786 -62.325077) (xy 350.324141 -62.272782) (xy 350.346783 -62.223205)
			(xy 350.376249 -62.177355) (xy 350.41194 -62.136164) (xy 350.453131 -62.100473) (xy 350.498981 -62.071007)
			(xy 350.548558 -62.048365) (xy 350.600853 -62.03301) (xy 350.654801 -62.025254) (xy 350.709303 -62.025254)
			(xy 350.763251 -62.03301) (xy 350.815546 -62.048365) (xy 350.865123 -62.071007) (xy 350.910973 -62.100473)
			(xy 350.952164 -62.136164) (xy 350.987855 -62.177355) (xy 351.017321 -62.223205) (xy 351.039963 -62.272782)
			(xy 351.055318 -62.325077) (xy 351.063074 -62.379025) (xy 351.06356 -62.406276) (xy 351.06356 -63.269876)
			(xy 351.063074 -63.297127) (xy 351.055318 -63.351075) (xy 351.039963 -63.40337) (xy 351.017321 -63.452947)
			(xy 350.987855 -63.498797) (xy 350.952164 -63.539988) (xy 350.910973 -63.575679) (xy 350.865123 -63.605145)
			(xy 350.815546 -63.627787) (xy 350.763251 -63.643142) (xy 350.709303 -63.650898) (xy 350.654801 -63.650898)
			(xy 350.600853 -63.643142) (xy 350.548558 -63.627787) (xy 350.498981 -63.605145) (xy 350.453131 -63.575679)
			(xy 350.41194 -63.539988) (xy 350.376249 -63.498797) (xy 350.346783 -63.452947) (xy 350.324141 -63.40337)
			(xy 350.308786 -63.351075) (xy 350.30103 -63.297127) (xy 350.300544 -63.269876) (xy 297.751584 -63.269876)
			(xy 297.791398 -63.336846) (xy 297.89222 -63.522255) (xy 297.985867 -63.71139) (xy 298.0722 -63.903972)
			(xy 298.151094 -64.09972) (xy 298.222432 -64.298347) (xy 298.286109 -64.49956) (xy 298.342033 -64.703064)
			(xy 298.390121 -64.908561) (xy 298.396302 -64.940434) (xy 325.410068 -64.940434) (xy 325.410068 -64.076834)
			(xy 325.410554 -64.049565) (xy 325.418316 -63.995581) (xy 325.433681 -63.943251) (xy 325.456338 -63.893641)
			(xy 325.485824 -63.84776) (xy 325.521539 -63.806543) (xy 325.562756 -63.770828) (xy 325.608637 -63.741342)
			(xy 325.658247 -63.718685) (xy 325.710577 -63.70332) (xy 325.764561 -63.695558) (xy 325.819099 -63.695558)
			(xy 325.873083 -63.70332) (xy 325.925413 -63.718685) (xy 325.975023 -63.741342) (xy 326.020904 -63.770828)
			(xy 326.062121 -63.806543) (xy 326.097836 -63.84776) (xy 326.127322 -63.893641) (xy 326.149979 -63.943251)
			(xy 326.165344 -63.995581) (xy 326.173106 -64.049565) (xy 326.173592 -64.076834) (xy 326.173592 -64.940434)
			(xy 326.173106 -64.967703) (xy 326.165344 -65.021687) (xy 326.149979 -65.074017) (xy 326.127322 -65.123627)
			(xy 326.097836 -65.169508) (xy 326.062121 -65.210725) (xy 326.020904 -65.24644) (xy 325.975023 -65.275926)
			(xy 325.925413 -65.298583) (xy 325.873083 -65.313948) (xy 325.819099 -65.32171) (xy 325.764561 -65.32171)
			(xy 325.710577 -65.313948) (xy 325.658247 -65.298583) (xy 325.608637 -65.275926) (xy 325.562756 -65.24644)
			(xy 325.521539 -65.210725) (xy 325.485824 -65.169508) (xy 325.456338 -65.123627) (xy 325.433681 -65.074017)
			(xy 325.418316 -65.021687) (xy 325.410554 -64.967703) (xy 325.410068 -64.940434) (xy 298.396302 -64.940434)
			(xy 298.430303 -65.115749) (xy 298.46252 -65.324324) (xy 298.463125 -65.329562) (xy 352.362008 -65.329562)
			(xy 352.362008 -64.465962) (xy 352.362494 -64.438711) (xy 352.37025 -64.384763) (xy 352.385605 -64.332468)
			(xy 352.408247 -64.282891) (xy 352.437713 -64.237041) (xy 352.473404 -64.19585) (xy 352.514595 -64.160159)
			(xy 352.560445 -64.130693) (xy 352.610022 -64.108051) (xy 352.662317 -64.092696) (xy 352.716265 -64.08494)
			(xy 352.770767 -64.08494) (xy 352.824715 -64.092696) (xy 352.87701 -64.108051) (xy 352.926587 -64.130693)
			(xy 352.972437 -64.160159) (xy 353.013628 -64.19585) (xy 353.049319 -64.237041) (xy 353.078785 -64.282891)
			(xy 353.101427 -64.332468) (xy 353.116782 -64.384763) (xy 353.124538 -64.438711) (xy 353.125024 -64.465962)
			(xy 353.125024 -65.329562) (xy 353.124538 -65.356813) (xy 353.116782 -65.410761) (xy 353.101427 -65.463056)
			(xy 353.078785 -65.512633) (xy 353.049319 -65.558483) (xy 353.013628 -65.599674) (xy 352.972437 -65.635365)
			(xy 352.926587 -65.664831) (xy 352.87701 -65.687473) (xy 352.824715 -65.702828) (xy 352.770767 -65.710584)
			(xy 352.716265 -65.710584) (xy 352.662317 -65.702828) (xy 352.610022 -65.687473) (xy 352.560445 -65.664831)
			(xy 352.514595 -65.635365) (xy 352.473404 -65.599674) (xy 352.437713 -65.558483) (xy 352.408247 -65.512633)
			(xy 352.385605 -65.463056) (xy 352.37025 -65.410761) (xy 352.362494 -65.356813) (xy 352.362008 -65.329562)
			(xy 298.463125 -65.329562) (xy 298.486723 -65.533981) (xy 298.502879 -65.74441) (xy 298.510963 -65.955304)
			(xy 298.511468 -66.060828) (xy 298.511468 -68.449952) (xy 314.840884 -68.449952) (xy 314.844867 -68.321934)
			(xy 314.856802 -68.194412) (xy 314.876641 -68.067878) (xy 314.904308 -67.942822) (xy 314.939697 -67.819729)
			(xy 314.98267 -67.699073) (xy 315.033061 -67.581323) (xy 315.090675 -67.466933) (xy 315.155289 -67.356346)
			(xy 315.226653 -67.24999) (xy 315.304491 -67.148277) (xy 315.388502 -67.051599) (xy 315.478361 -66.960332)
			(xy 315.57372 -66.874827) (xy 315.674211 -66.795417) (xy 315.779444 -66.722407) (xy 315.889013 -66.656081)
			(xy 316.002493 -66.596695) (xy 316.119445 -66.544479) (xy 316.239418 -66.499635) (xy 316.361946 -66.462337)
			(xy 316.486557 -66.432728) (xy 316.612766 -66.410923) (xy 316.740088 -66.397007) (xy 316.868028 -66.391033)
			(xy 316.996092 -66.393025) (xy 317.123785 -66.402975) (xy 317.250612 -66.420844) (xy 317.376083 -66.446563)
			(xy 317.499712 -66.480033) (xy 317.621021 -66.521124) (xy 317.739541 -66.569678) (xy 317.854813 -66.625506)
			(xy 317.966391 -66.688392) (xy 318.073844 -66.758094) (xy 318.176756 -66.834341) (xy 318.274728 -66.916838)
			(xy 318.323666 -66.963544) (xy 350.27108 -66.963544) (xy 350.27108 -66.099944) (xy 350.271566 -66.072693)
			(xy 350.279322 -66.018745) (xy 350.294677 -65.96645) (xy 350.317319 -65.916873) (xy 350.346785 -65.871023)
			(xy 350.382476 -65.829832) (xy 350.423667 -65.794141) (xy 350.469517 -65.764675) (xy 350.519094 -65.742033)
			(xy 350.571389 -65.726678) (xy 350.625337 -65.718922) (xy 350.679839 -65.718922) (xy 350.733787 -65.726678)
			(xy 350.786082 -65.742033) (xy 350.835659 -65.764675) (xy 350.881509 -65.794141) (xy 350.9227 -65.829832)
			(xy 350.958391 -65.871023) (xy 350.987857 -65.916873) (xy 351.010499 -65.96645) (xy 351.025854 -66.018745)
			(xy 351.03361 -66.072693) (xy 351.034096 -66.099944) (xy 351.034096 -66.963544) (xy 351.03361 -66.990795)
			(xy 351.025854 -67.044743) (xy 351.010499 -67.097038) (xy 351.005595 -67.107776) (xy 396.642323 -67.107776)
			(xy 396.642323 -67.022004) (xy 396.650237 -66.936596) (xy 396.665998 -66.852284) (xy 396.689471 -66.769785)
			(xy 396.720456 -66.689804) (xy 396.758688 -66.613023) (xy 396.803842 -66.540098) (xy 396.855532 -66.47165)
			(xy 396.913317 -66.408263) (xy 396.976704 -66.350478) (xy 397.045152 -66.298788) (xy 397.118077 -66.253634)
			(xy 397.194858 -66.215402) (xy 397.274839 -66.184417) (xy 397.357338 -66.160944) (xy 397.44165 -66.145183)
			(xy 397.527058 -66.137269) (xy 397.61283 -66.137269) (xy 397.698238 -66.145183) (xy 397.78255 -66.160944)
			(xy 397.865049 -66.184417) (xy 397.94503 -66.215402) (xy 398.021811 -66.253634) (xy 398.094736 -66.298788)
			(xy 398.163184 -66.350478) (xy 398.226571 -66.408263) (xy 398.284356 -66.47165) (xy 398.336046 -66.540098)
			(xy 398.3812 -66.613023) (xy 398.419432 -66.689804) (xy 398.450417 -66.769785) (xy 398.47389 -66.852284)
			(xy 398.489651 -66.936596) (xy 398.497565 -67.022004) (xy 398.49806 -67.06489) (xy 398.497565 -67.107776)
			(xy 398.489651 -67.193184) (xy 398.47389 -67.277496) (xy 398.450417 -67.359995) (xy 398.419432 -67.439976)
			(xy 398.3812 -67.516757) (xy 398.336046 -67.589682) (xy 398.284356 -67.65813) (xy 398.226571 -67.721517)
			(xy 398.163184 -67.779302) (xy 398.094736 -67.830992) (xy 398.021811 -67.876146) (xy 397.94503 -67.914378)
			(xy 397.865049 -67.945363) (xy 397.78255 -67.968836) (xy 397.698238 -67.984597) (xy 397.61283 -67.992511)
			(xy 397.527058 -67.992511) (xy 397.44165 -67.984597) (xy 397.357338 -67.968836) (xy 397.274839 -67.945363)
			(xy 397.194858 -67.914378) (xy 397.118077 -67.876146) (xy 397.045152 -67.830992) (xy 396.976704 -67.779302)
			(xy 396.913317 -67.721517) (xy 396.855532 -67.65813) (xy 396.803842 -67.589682) (xy 396.758688 -67.516757)
			(xy 396.720456 -67.439976) (xy 396.689471 -67.359995) (xy 396.665998 -67.277496) (xy 396.650237 -67.193184)
			(xy 396.642323 -67.107776) (xy 351.005595 -67.107776) (xy 350.987857 -67.146615) (xy 350.958391 -67.192465)
			(xy 350.9227 -67.233656) (xy 350.881509 -67.269347) (xy 350.835659 -67.298813) (xy 350.786082 -67.321455)
			(xy 350.733787 -67.33681) (xy 350.679839 -67.344566) (xy 350.625337 -67.344566) (xy 350.571389 -67.33681)
			(xy 350.519094 -67.321455) (xy 350.469517 -67.298813) (xy 350.423667 -67.269347) (xy 350.382476 -67.233656)
			(xy 350.346785 -67.192465) (xy 350.317319 -67.146615) (xy 350.294677 -67.097038) (xy 350.279322 -67.044743)
			(xy 350.271566 -66.990795) (xy 350.27108 -66.963544) (xy 318.323666 -66.963544) (xy 318.367382 -67.005267)
			(xy 318.454359 -67.099285) (xy 318.535323 -67.198528) (xy 318.60996 -67.302613) (xy 318.677982 -67.411137)
			(xy 318.739126 -67.52368) (xy 318.793154 -67.639806) (xy 318.839859 -67.759067) (xy 318.879059 -67.881)
			(xy 318.910602 -68.005135) (xy 318.934367 -68.130991) (xy 318.950261 -68.25808) (xy 318.958224 -68.385912)
			(xy 318.958722 -68.449952) (xy 318.958224 -68.513992) (xy 318.950261 -68.641824) (xy 318.934367 -68.768913)
			(xy 318.910602 -68.894769) (xy 318.879059 -69.018904) (xy 318.851129 -69.10578) (xy 351.73158 -69.10578)
			(xy 351.73158 -68.24218) (xy 351.732066 -68.214911) (xy 351.739828 -68.160927) (xy 351.755193 -68.108597)
			(xy 351.77785 -68.058987) (xy 351.807336 -68.013106) (xy 351.843051 -67.971889) (xy 351.884268 -67.936174)
			(xy 351.930149 -67.906688) (xy 351.979759 -67.884031) (xy 352.032089 -67.868666) (xy 352.086073 -67.860904)
			(xy 352.140611 -67.860904) (xy 352.194595 -67.868666) (xy 352.246925 -67.884031) (xy 352.296535 -67.906688)
			(xy 352.342416 -67.936174) (xy 352.383633 -67.971889) (xy 352.419348 -68.013106) (xy 352.448834 -68.058987)
			(xy 352.471491 -68.108597) (xy 352.486856 -68.160927) (xy 352.494618 -68.214911) (xy 352.495104 -68.24218)
			(xy 352.495104 -69.10578) (xy 352.494618 -69.133049) (xy 352.486856 -69.187033) (xy 352.471491 -69.239363)
			(xy 352.448834 -69.288973) (xy 352.419348 -69.334854) (xy 352.383633 -69.376071) (xy 352.342416 -69.411786)
			(xy 352.296535 -69.441272) (xy 352.246925 -69.463929) (xy 352.194595 -69.479294) (xy 352.140611 -69.487056)
			(xy 352.086073 -69.487056) (xy 352.032089 -69.479294) (xy 351.979759 -69.463929) (xy 351.930149 -69.441272)
			(xy 351.884268 -69.411786) (xy 351.843051 -69.376071) (xy 351.807336 -69.334854) (xy 351.77785 -69.288973)
			(xy 351.755193 -69.239363) (xy 351.739828 -69.187033) (xy 351.732066 -69.133049) (xy 351.73158 -69.10578)
			(xy 318.851129 -69.10578) (xy 318.839859 -69.140837) (xy 318.793154 -69.260098) (xy 318.739126 -69.376224)
			(xy 318.677982 -69.488767) (xy 318.60996 -69.597291) (xy 318.535323 -69.701376) (xy 318.454359 -69.800619)
			(xy 318.367382 -69.894637) (xy 318.274728 -69.983066) (xy 318.176756 -70.065563) (xy 318.073844 -70.14181)
			(xy 317.966391 -70.211512) (xy 317.854813 -70.274398) (xy 317.739541 -70.330226) (xy 317.621021 -70.37878)
			(xy 317.499712 -70.419871) (xy 317.376083 -70.453341) (xy 317.250612 -70.47906) (xy 317.123785 -70.496929)
			(xy 316.996092 -70.506879) (xy 316.868028 -70.508871) (xy 316.740088 -70.502897) (xy 316.612766 -70.488981)
			(xy 316.486557 -70.467176) (xy 316.361946 -70.437567) (xy 316.239418 -70.400269) (xy 316.119445 -70.355425)
			(xy 316.002493 -70.303209) (xy 315.889013 -70.243823) (xy 315.779444 -70.177497) (xy 315.674211 -70.104487)
			(xy 315.57372 -70.025077) (xy 315.478361 -69.939572) (xy 315.388502 -69.848305) (xy 315.304491 -69.751627)
			(xy 315.226653 -69.649914) (xy 315.155289 -69.543558) (xy 315.090675 -69.432971) (xy 315.033061 -69.318581)
			(xy 314.98267 -69.200831) (xy 314.939697 -69.080175) (xy 314.904308 -68.957082) (xy 314.876641 -68.832026)
			(xy 314.856802 -68.705492) (xy 314.844867 -68.57797) (xy 314.840884 -68.449952) (xy 298.511468 -68.449952)
			(xy 298.511468 -71.213074) (xy 341.168388 -71.213074) (xy 341.168388 -71.158526) (xy 341.176151 -71.104534)
			(xy 341.19152 -71.052197) (xy 341.214181 -71.00258) (xy 341.243673 -70.956692) (xy 341.279395 -70.91547)
			(xy 341.320621 -70.879751) (xy 341.366511 -70.850263) (xy 341.416131 -70.827607) (xy 341.46847 -70.812243)
			(xy 341.522462 -70.804485) (xy 341.549736 -70.804024) (xy 342.413336 -70.804024) (xy 342.440603 -70.804541)
			(xy 342.49458 -70.812306) (xy 342.546904 -70.827674) (xy 342.596508 -70.850332) (xy 342.642382 -70.879817)
			(xy 342.683594 -70.915531) (xy 342.719304 -70.956747) (xy 342.748786 -71.002624) (xy 342.771438 -71.05223)
			(xy 342.786801 -71.104555) (xy 342.794562 -71.158533) (xy 342.794562 -71.213067) (xy 342.786801 -71.267045)
			(xy 342.771438 -71.31937) (xy 342.748786 -71.368976) (xy 342.719304 -71.414853) (xy 342.683594 -71.456069)
			(xy 342.642382 -71.491783) (xy 342.596508 -71.521268) (xy 342.546904 -71.543926) (xy 342.49458 -71.559294)
			(xy 342.440603 -71.567059) (xy 342.413336 -71.567548) (xy 341.549736 -71.567548) (xy 341.522462 -71.567115)
			(xy 341.46847 -71.559357) (xy 341.416131 -71.543993) (xy 341.366511 -71.521337) (xy 341.320621 -71.491849)
			(xy 341.279395 -71.45613) (xy 341.243673 -71.414908) (xy 341.214181 -71.36902) (xy 341.19152 -71.319403)
			(xy 341.176151 -71.267066) (xy 341.168388 -71.213074) (xy 298.511468 -71.213074) (xy 298.511468 -71.844253)
			(xy 346.360454 -71.844253) (xy 346.360454 -71.789747) (xy 346.368211 -71.735796) (xy 346.383567 -71.683499)
			(xy 346.406209 -71.633919) (xy 346.435677 -71.588066) (xy 346.47137 -71.546873) (xy 346.512562 -71.511179)
			(xy 346.558415 -71.481711) (xy 346.607995 -71.459068) (xy 346.660293 -71.443712) (xy 346.714243 -71.435954)
			(xy 346.741496 -71.435468) (xy 347.605096 -71.435468) (xy 347.632347 -71.435979) (xy 347.686295 -71.443735)
			(xy 347.73859 -71.45909) (xy 347.788168 -71.481731) (xy 347.834019 -71.511197) (xy 347.875209 -71.546888)
			(xy 347.910901 -71.588078) (xy 347.940367 -71.633929) (xy 347.963009 -71.683506) (xy 347.978364 -71.735801)
			(xy 347.986121 -71.789749) (xy 347.986121 -71.844251) (xy 347.978364 -71.898199) (xy 347.963009 -71.950494)
			(xy 347.940367 -72.000071) (xy 347.910901 -72.045922) (xy 347.875209 -72.087112) (xy 347.834019 -72.122803)
			(xy 347.788168 -72.152269) (xy 347.73859 -72.17491) (xy 347.686295 -72.190265) (xy 347.632347 -72.198021)
			(xy 347.605096 -72.198484) (xy 346.741496 -72.198484) (xy 346.714243 -72.198046) (xy 346.660293 -72.190288)
			(xy 346.607995 -72.174932) (xy 346.558415 -72.152289) (xy 346.512562 -72.122821) (xy 346.47137 -72.087127)
			(xy 346.435677 -72.045934) (xy 346.406209 -72.000081) (xy 346.383567 -71.950501) (xy 346.368211 -71.898204)
			(xy 346.360454 -71.844253) (xy 298.511468 -71.844253) (xy 298.511468 -72.404055) (xy 332.037847 -72.404055)
			(xy 332.037847 -72.349545) (xy 332.045606 -72.295589) (xy 332.060964 -72.243286) (xy 332.083611 -72.193702)
			(xy 332.113083 -72.147846) (xy 332.148782 -72.106651) (xy 332.189981 -72.070957) (xy 332.235841 -72.041489)
			(xy 332.285427 -72.018849) (xy 332.337732 -72.003496) (xy 332.391689 -71.995744) (xy 332.418944 -71.995284)
			(xy 333.282544 -71.995284) (xy 333.309793 -71.995789) (xy 333.363734 -72.00355) (xy 333.416023 -72.018909)
			(xy 333.465593 -72.041552) (xy 333.511437 -72.071019) (xy 333.552622 -72.10671) (xy 333.588308 -72.147898)
			(xy 333.617769 -72.193745) (xy 333.640407 -72.243318) (xy 333.655759 -72.295609) (xy 333.660251 -72.326853)
			(xy 343.845854 -72.326853) (xy 343.845854 -72.272347) (xy 343.853611 -72.218396) (xy 343.868967 -72.166099)
			(xy 343.891609 -72.116519) (xy 343.921077 -72.070666) (xy 343.95677 -72.029473) (xy 343.997962 -71.993779)
			(xy 344.043815 -71.964311) (xy 344.093395 -71.941668) (xy 344.145693 -71.926312) (xy 344.199643 -71.918554)
			(xy 344.226896 -71.918068) (xy 345.090496 -71.918068) (xy 345.117747 -71.918579) (xy 345.171695 -71.926335)
			(xy 345.22399 -71.94169) (xy 345.273568 -71.964331) (xy 345.319419 -71.993797) (xy 345.360609 -72.029488)
			(xy 345.396301 -72.070678) (xy 345.425767 -72.116529) (xy 345.448409 -72.166106) (xy 345.463764 -72.218401)
			(xy 345.471521 -72.272349) (xy 345.471521 -72.326851) (xy 345.463764 -72.380799) (xy 345.448409 -72.433094)
			(xy 345.425767 -72.482671) (xy 345.396301 -72.528522) (xy 345.360609 -72.569712) (xy 345.319419 -72.605403)
			(xy 345.273568 -72.634869) (xy 345.22399 -72.65751) (xy 345.171695 -72.672865) (xy 345.117747 -72.680621)
			(xy 345.090496 -72.681084) (xy 344.226896 -72.681084) (xy 344.199643 -72.680646) (xy 344.145693 -72.672888)
			(xy 344.093395 -72.657532) (xy 344.043815 -72.634889) (xy 343.997962 -72.605421) (xy 343.95677 -72.569727)
			(xy 343.921077 -72.528534) (xy 343.891609 -72.482681) (xy 343.868967 -72.433101) (xy 343.853611 -72.380804)
			(xy 343.845854 -72.326853) (xy 333.660251 -72.326853) (xy 333.663514 -72.349551) (xy 333.663514 -72.404049)
			(xy 333.655759 -72.457991) (xy 333.640407 -72.510282) (xy 333.617769 -72.559855) (xy 333.588308 -72.605702)
			(xy 333.552622 -72.64689) (xy 333.511437 -72.682581) (xy 333.465593 -72.712048) (xy 333.416023 -72.734691)
			(xy 333.363734 -72.75005) (xy 333.309793 -72.757811) (xy 333.282544 -72.7583) (xy 332.418944 -72.7583)
			(xy 332.391689 -72.757856) (xy 332.337732 -72.750104) (xy 332.285427 -72.734751) (xy 332.235841 -72.712111)
			(xy 332.189981 -72.682643) (xy 332.148782 -72.646949) (xy 332.113083 -72.605754) (xy 332.083611 -72.559898)
			(xy 332.060964 -72.510314) (xy 332.045606 -72.458011) (xy 332.037847 -72.404055) (xy 298.511468 -72.404055)
			(xy 298.511468 -74.617072) (xy 327.277726 -74.617072) (xy 327.281813 -74.561227) (xy 327.293988 -74.506573)
			(xy 327.31399 -74.454274) (xy 327.341395 -74.405445) (xy 327.375617 -74.361126) (xy 327.415927 -74.322262)
			(xy 327.461466 -74.289681) (xy 327.511264 -74.264078) (xy 327.564259 -74.245999) (xy 327.619321 -74.235828)
			(xy 327.675278 -74.233783) (xy 327.730936 -74.239908) (xy 327.785109 -74.25407) (xy 327.836643 -74.27597)
			(xy 327.884439 -74.305139) (xy 327.927478 -74.340957) (xy 327.941626 -74.356747) (xy 330.744122 -74.356747)
			(xy 330.744122 -74.302253) (xy 330.751877 -74.248315) (xy 330.767229 -74.196029) (xy 330.789865 -74.146459)
			(xy 330.819325 -74.100616) (xy 330.855009 -74.059431) (xy 330.89619 -74.023744) (xy 330.942031 -73.99428)
			(xy 330.991599 -73.97164) (xy 331.043883 -73.956284) (xy 331.097821 -73.948524) (xy 331.125068 -73.948036)
			(xy 331.988668 -73.948036) (xy 332.015926 -73.948409) (xy 332.069886 -73.956163) (xy 332.122194 -73.971518)
			(xy 332.171784 -73.994161) (xy 332.217646 -74.023632) (xy 332.258848 -74.05933) (xy 332.294549 -74.100528)
			(xy 332.324023 -74.146388) (xy 332.346671 -74.195976) (xy 332.36203 -74.248283) (xy 332.369789 -74.302243)
			(xy 332.369789 -74.356757) (xy 332.36203 -74.410717) (xy 332.346671 -74.463024) (xy 332.324023 -74.512612)
			(xy 332.294549 -74.558472) (xy 332.26684 -74.590448) (xy 336.274202 -74.590448) (xy 336.274202 -74.535953)
			(xy 336.281957 -74.482012) (xy 336.297309 -74.429724) (xy 336.319945 -74.380153) (xy 336.349406 -74.334308)
			(xy 336.38509 -74.293121) (xy 336.426272 -74.257432) (xy 336.472114 -74.227966) (xy 336.521683 -74.205324)
			(xy 336.573969 -74.189966) (xy 336.627909 -74.182205) (xy 336.655156 -74.181716) (xy 337.518756 -74.181716)
			(xy 337.546013 -74.182128) (xy 337.599972 -74.18988) (xy 337.652278 -74.205233) (xy 337.701867 -74.227875)
			(xy 337.747729 -74.257344) (xy 337.788929 -74.29304) (xy 337.82463 -74.334236) (xy 337.854104 -74.380094)
			(xy 337.876751 -74.42968) (xy 337.89211 -74.481985) (xy 337.899869 -74.535943) (xy 337.899869 -74.55185)
			(xy 339.156294 -74.55185) (xy 339.156294 -74.49735) (xy 339.16405 -74.443405) (xy 339.179404 -74.391113)
			(xy 339.202044 -74.341539) (xy 339.231509 -74.29569) (xy 339.267198 -74.254502) (xy 339.308386 -74.218812)
			(xy 339.354233 -74.189347) (xy 339.403808 -74.166707) (xy 339.456099 -74.151352) (xy 339.510044 -74.143595)
			(xy 339.537294 -74.143108) (xy 340.400894 -74.143108) (xy 340.428148 -74.143538) (xy 340.482102 -74.151295)
			(xy 340.534403 -74.166651) (xy 340.583986 -74.189294) (xy 340.629842 -74.218763) (xy 340.671037 -74.254459)
			(xy 340.706733 -74.295653) (xy 340.736203 -74.341509) (xy 340.758847 -74.391091) (xy 340.774204 -74.443392)
			(xy 340.781961 -74.497346) (xy 340.781961 -74.551854) (xy 340.774204 -74.605808) (xy 340.758847 -74.658109)
			(xy 340.736203 -74.707691) (xy 340.706733 -74.753547) (xy 340.694254 -74.767948) (xy 421.29456 -74.767948)
			(xy 421.29456 -66.06794) (xy 421.295065 -65.962416) (xy 421.303149 -65.751522) (xy 421.319305 -65.541093)
			(xy 421.343508 -65.331436) (xy 421.375725 -65.122861) (xy 421.415907 -64.915673) (xy 421.463995 -64.710176)
			(xy 421.519919 -64.506672) (xy 421.583596 -64.305459) (xy 421.654934 -64.106832) (xy 421.733828 -63.911084)
			(xy 421.820161 -63.718502) (xy 421.913808 -63.529367) (xy 422.01463 -63.343958) (xy 422.12248 -63.162547)
			(xy 422.237199 -62.9854) (xy 422.358619 -62.812778) (xy 422.486562 -62.644932) (xy 422.62084 -62.48211)
			(xy 422.761256 -62.324551) (xy 422.907604 -62.172486) (xy 423.059669 -62.026138) (xy 423.217228 -61.885722)
			(xy 423.38005 -61.751444) (xy 423.547896 -61.623501) (xy 423.720518 -61.502081) (xy 423.897665 -61.387362)
			(xy 424.079076 -61.279512) (xy 424.264485 -61.17869) (xy 424.45362 -61.085043) (xy 424.646202 -60.99871)
			(xy 424.84195 -60.919816) (xy 425.040577 -60.848478) (xy 425.24179 -60.784801) (xy 425.445294 -60.728877)
			(xy 425.650791 -60.680789) (xy 425.857979 -60.640607) (xy 426.066554 -60.60839) (xy 426.276211 -60.584187)
			(xy 426.48664 -60.568031) (xy 426.697534 -60.559947) (xy 426.908582 -60.559947) (xy 427.119476 -60.568031)
			(xy 427.329905 -60.584187) (xy 427.539562 -60.60839) (xy 427.748137 -60.640607) (xy 427.955325 -60.680789)
			(xy 428.160822 -60.728877) (xy 428.364326 -60.784801) (xy 428.565539 -60.848478) (xy 428.764166 -60.919816)
			(xy 428.959914 -60.99871) (xy 429.152496 -61.085043) (xy 429.341631 -61.17869) (xy 429.52704 -61.279512)
			(xy 429.708451 -61.387362) (xy 429.885598 -61.502081) (xy 430.05822 -61.623501) (xy 430.226066 -61.751444)
			(xy 430.388888 -61.885722) (xy 430.546447 -62.026138) (xy 430.698512 -62.172486) (xy 430.84486 -62.324551)
			(xy 430.985276 -62.48211) (xy 431.119554 -62.644932) (xy 431.247497 -62.812778) (xy 431.368917 -62.9854)
			(xy 431.483636 -63.162547) (xy 431.591486 -63.343958) (xy 431.692308 -63.529367) (xy 431.785955 -63.718502)
			(xy 431.872288 -63.911084) (xy 431.951182 -64.106832) (xy 432.02252 -64.305459) (xy 432.086197 -64.506672)
			(xy 432.142121 -64.710176) (xy 432.190209 -64.915673) (xy 432.230391 -65.122861) (xy 432.262608 -65.331436)
			(xy 432.286811 -65.541093) (xy 432.302967 -65.751522) (xy 432.311051 -65.962416) (xy 432.311556 -66.06794)
			(xy 432.311556 -74.767948) (xy 432.311051 -74.873472) (xy 432.302967 -75.084366) (xy 432.286811 -75.294795)
			(xy 432.262608 -75.504452) (xy 432.230391 -75.713027) (xy 432.190209 -75.920215) (xy 432.142121 -76.125712)
			(xy 432.086197 -76.329216) (xy 432.02252 -76.530429) (xy 431.951182 -76.729056) (xy 431.872288 -76.924804)
			(xy 431.785955 -77.117386) (xy 431.692308 -77.306521) (xy 431.591486 -77.49193) (xy 431.483636 -77.673341)
			(xy 431.368917 -77.850488) (xy 431.247497 -78.02311) (xy 431.119554 -78.190956) (xy 430.985276 -78.353778)
			(xy 430.84486 -78.511337) (xy 430.698512 -78.663402) (xy 430.546447 -78.80975) (xy 430.388888 -78.950166)
			(xy 430.226066 -79.084444) (xy 430.05822 -79.212387) (xy 429.885598 -79.333807) (xy 429.708451 -79.448526)
			(xy 429.52704 -79.556376) (xy 429.341631 -79.657198) (xy 429.152496 -79.750845) (xy 428.959914 -79.837178)
			(xy 428.764166 -79.916072) (xy 428.565539 -79.98741) (xy 428.364326 -80.051087) (xy 428.160822 -80.107011)
			(xy 427.955325 -80.155099) (xy 427.748137 -80.195281) (xy 427.539562 -80.227498) (xy 427.329905 -80.251701)
			(xy 427.119476 -80.267857) (xy 426.908582 -80.275941) (xy 426.697534 -80.275941) (xy 426.48664 -80.267857)
			(xy 426.276211 -80.251701) (xy 426.066554 -80.227498) (xy 425.857979 -80.195281) (xy 425.650791 -80.155099)
			(xy 425.445294 -80.107011) (xy 425.24179 -80.051087) (xy 425.040577 -79.98741) (xy 424.84195 -79.916072)
			(xy 424.646202 -79.837178) (xy 424.45362 -79.750845) (xy 424.264485 -79.657198) (xy 424.079076 -79.556376)
			(xy 423.897665 -79.448526) (xy 423.720518 -79.333807) (xy 423.547896 -79.212387) (xy 423.38005 -79.084444)
			(xy 423.217228 -78.950166) (xy 423.059669 -78.80975) (xy 422.907604 -78.663402) (xy 422.761256 -78.511337)
			(xy 422.62084 -78.353778) (xy 422.486562 -78.190956) (xy 422.358619 -78.02311) (xy 422.237199 -77.850488)
			(xy 422.12248 -77.673341) (xy 422.01463 -77.49193) (xy 421.913808 -77.306521) (xy 421.820161 -77.117386)
			(xy 421.733828 -76.924804) (xy 421.654934 -76.729056) (xy 421.583596 -76.530429) (xy 421.519919 -76.329216)
			(xy 421.463995 -76.125712) (xy 421.415907 -75.920215) (xy 421.375725 -75.713027) (xy 421.343508 -75.504452)
			(xy 421.319305 -75.294795) (xy 421.303149 -75.084366) (xy 421.295065 -74.873472) (xy 421.29456 -74.767948)
			(xy 340.694254 -74.767948) (xy 340.671037 -74.794741) (xy 340.629842 -74.830437) (xy 340.583986 -74.859906)
			(xy 340.534403 -74.882549) (xy 340.482102 -74.897905) (xy 340.428148 -74.905662) (xy 340.400894 -74.906124)
			(xy 339.537294 -74.906124) (xy 339.510044 -74.905605) (xy 339.456099 -74.897848) (xy 339.403808 -74.882493)
			(xy 339.354233 -74.859853) (xy 339.308386 -74.830388) (xy 339.267198 -74.794698) (xy 339.231509 -74.75351)
			(xy 339.202044 -74.707661) (xy 339.179404 -74.658087) (xy 339.16405 -74.605795) (xy 339.156294 -74.55185)
			(xy 337.899869 -74.55185) (xy 337.899869 -74.590457) (xy 337.89211 -74.644415) (xy 337.876751 -74.69672)
			(xy 337.854104 -74.746306) (xy 337.82463 -74.792164) (xy 337.788929 -74.83336) (xy 337.747729 -74.869056)
			(xy 337.701867 -74.898525) (xy 337.652278 -74.921167) (xy 337.599972 -74.93652) (xy 337.546013 -74.944272)
			(xy 337.518756 -74.944732) (xy 336.655156 -74.944732) (xy 336.627909 -74.944195) (xy 336.573969 -74.936434)
			(xy 336.521683 -74.921076) (xy 336.472114 -74.898434) (xy 336.426272 -74.868968) (xy 336.38509 -74.833279)
			(xy 336.349406 -74.792092) (xy 336.319945 -74.746247) (xy 336.297309 -74.696676) (xy 336.281957 -74.644388)
			(xy 336.274202 -74.590448) (xy 332.26684 -74.590448) (xy 332.258848 -74.59967) (xy 332.217646 -74.635368)
			(xy 332.171784 -74.664839) (xy 332.122194 -74.687482) (xy 332.069886 -74.702837) (xy 332.015926 -74.710591)
			(xy 331.988668 -74.711052) (xy 331.125068 -74.711052) (xy 331.097821 -74.710476) (xy 331.043883 -74.702716)
			(xy 330.991599 -74.68736) (xy 330.942031 -74.66472) (xy 330.89619 -74.635256) (xy 330.855009 -74.599569)
			(xy 330.819325 -74.558384) (xy 330.789865 -74.512541) (xy 330.767229 -74.462971) (xy 330.751877 -74.410685)
			(xy 330.744122 -74.356747) (xy 327.941626 -74.356747) (xy 327.964844 -74.38266) (xy 327.99574 -74.429358)
			(xy 328.019507 -74.480058) (xy 328.035639 -74.533678) (xy 328.043791 -74.589075) (xy 328.044302 -74.617072)
			(xy 328.043791 -74.645069) (xy 328.035639 -74.700466) (xy 328.019507 -74.754086) (xy 327.99574 -74.804786)
			(xy 327.964844 -74.851484) (xy 327.927478 -74.893187) (xy 327.884439 -74.929005) (xy 327.836643 -74.958174)
			(xy 327.785109 -74.980074) (xy 327.730936 -74.994236) (xy 327.675278 -75.000361) (xy 327.619321 -74.998316)
			(xy 327.564259 -74.988145) (xy 327.511264 -74.970066) (xy 327.461466 -74.944463) (xy 327.415927 -74.911882)
			(xy 327.375617 -74.873018) (xy 327.341395 -74.828699) (xy 327.31399 -74.77987) (xy 327.293988 -74.727571)
			(xy 327.281813 -74.672917) (xy 327.277726 -74.617072) (xy 298.511468 -74.617072) (xy 298.511468 -74.760836)
			(xy 298.510963 -74.86636) (xy 298.502879 -75.077254) (xy 298.486723 -75.287683) (xy 298.46252 -75.49734)
			(xy 298.430303 -75.705915) (xy 298.390121 -75.913103) (xy 298.342033 -76.1186) (xy 298.333664 -76.149054)
			(xy 327.558346 -76.149054) (xy 327.558346 -76.094546) (xy 327.566103 -76.040594) (xy 327.581459 -75.988295)
			(xy 327.604102 -75.938714) (xy 327.633571 -75.892859) (xy 327.669266 -75.851666) (xy 327.710459 -75.815971)
			(xy 327.756314 -75.786502) (xy 327.805895 -75.763859) (xy 327.858194 -75.748503) (xy 327.912146 -75.740746)
			(xy 327.9394 -75.74026) (xy 328.803 -75.74026) (xy 328.830249 -75.74081) (xy 328.884192 -75.748566)
			(xy 328.936482 -75.76392) (xy 328.986055 -75.786559) (xy 329.031902 -75.816023) (xy 329.073089 -75.851711)
			(xy 329.108777 -75.892898) (xy 329.138241 -75.938745) (xy 329.16088 -75.988318) (xy 329.169581 -76.017949)
			(xy 334.874382 -76.017949) (xy 334.874382 -75.963451) (xy 334.882137 -75.909507) (xy 334.89749 -75.857216)
			(xy 334.920128 -75.807642) (xy 334.949591 -75.761793) (xy 334.985278 -75.720605) (xy 335.026463 -75.684914)
			(xy 335.072308 -75.655447) (xy 335.12188 -75.632803) (xy 335.17417 -75.617445) (xy 335.228113 -75.609684)
			(xy 335.255362 -75.609196) (xy 336.118962 -75.609196) (xy 336.146217 -75.609649) (xy 336.200173 -75.617401)
			(xy 336.252475 -75.632754) (xy 336.302061 -75.655395) (xy 336.347919 -75.684862) (xy 336.389117 -75.720556)
			(xy 336.424815 -75.76175) (xy 336.454287 -75.807606) (xy 336.476932 -75.857189) (xy 336.49229 -75.90949)
			(xy 336.500049 -75.963445) (xy 336.500049 -76.017955) (xy 336.49229 -76.07191) (xy 336.476932 -76.124211)
			(xy 336.454287 -76.173794) (xy 336.424815 -76.21965) (xy 336.389117 -76.260844) (xy 336.347919 -76.296538)
			(xy 336.302061 -76.326005) (xy 336.252475 -76.348646) (xy 336.200173 -76.363999) (xy 336.146217 -76.371751)
			(xy 336.118962 -76.372212) (xy 335.255362 -76.372212) (xy 335.228113 -76.371716) (xy 335.17417 -76.363955)
			(xy 335.12188 -76.348597) (xy 335.072308 -76.325953) (xy 335.026463 -76.296486) (xy 334.985278 -76.260795)
			(xy 334.949591 -76.219607) (xy 334.920128 -76.173758) (xy 334.89749 -76.124184) (xy 334.882137 -76.071893)
			(xy 334.874382 -76.017949) (xy 329.169581 -76.017949) (xy 329.176234 -76.040608) (xy 329.18399 -76.094551)
			(xy 329.18399 -76.149049) (xy 329.176234 -76.202992) (xy 329.16088 -76.255282) (xy 329.138241 -76.304855)
			(xy 329.108777 -76.350702) (xy 329.073089 -76.391889) (xy 329.031902 -76.427577) (xy 328.986055 -76.457041)
			(xy 328.936482 -76.47968) (xy 328.884192 -76.495034) (xy 328.830249 -76.50279) (xy 328.803 -76.503276)
			(xy 327.9394 -76.503276) (xy 327.912146 -76.502854) (xy 327.858194 -76.495097) (xy 327.805895 -76.479741)
			(xy 327.756314 -76.457098) (xy 327.710459 -76.427629) (xy 327.669266 -76.391934) (xy 327.633571 -76.350741)
			(xy 327.604102 -76.304886) (xy 327.581459 -76.255305) (xy 327.566103 -76.203006) (xy 327.558346 -76.149054)
			(xy 298.333664 -76.149054) (xy 298.286109 -76.322104) (xy 298.222432 -76.523317) (xy 298.151094 -76.721944)
			(xy 298.0722 -76.917692) (xy 297.985867 -77.110274) (xy 297.89222 -77.299409) (xy 297.791398 -77.484818)
			(xy 297.683548 -77.666229) (xy 297.568829 -77.843376) (xy 297.455321 -78.00475) (xy 330.84567 -78.00475)
			(xy 330.84567 -77.95025) (xy 330.853426 -77.896304) (xy 330.868779 -77.84401) (xy 330.891419 -77.794434)
			(xy 330.920883 -77.748584) (xy 330.956571 -77.707394) (xy 330.997759 -77.671702) (xy 331.043606 -77.642234)
			(xy 331.09318 -77.619591) (xy 331.145472 -77.604232) (xy 331.199418 -77.596472) (xy 331.226668 -77.595984)
			(xy 332.090268 -77.595984) (xy 332.117522 -77.596461) (xy 332.171475 -77.604214) (xy 332.223776 -77.619567)
			(xy 332.273359 -77.642207) (xy 332.319215 -77.671674) (xy 332.360411 -77.707367) (xy 332.396107 -77.748559)
			(xy 332.425577 -77.794413) (xy 332.448222 -77.843994) (xy 332.463579 -77.896294) (xy 332.471337 -77.950246)
			(xy 332.471337 -78.004754) (xy 332.463579 -78.058706) (xy 332.448222 -78.111006) (xy 332.425577 -78.160587)
			(xy 332.396107 -78.206441) (xy 332.360411 -78.247633) (xy 332.319215 -78.283326) (xy 332.273359 -78.312793)
			(xy 332.223776 -78.335433) (xy 332.171475 -78.350786) (xy 332.117522 -78.358539) (xy 332.090268 -78.359)
			(xy 331.226668 -78.359) (xy 331.199418 -78.358528) (xy 331.145472 -78.350768) (xy 331.09318 -78.335409)
			(xy 331.043606 -78.312766) (xy 330.997759 -78.283298) (xy 330.956571 -78.247606) (xy 330.920883 -78.206416)
			(xy 330.891419 -78.160566) (xy 330.868779 -78.11099) (xy 330.853426 -78.058696) (xy 330.84567 -78.00475)
			(xy 297.455321 -78.00475) (xy 297.447409 -78.015998) (xy 297.319466 -78.183844) (xy 297.185188 -78.346666)
			(xy 297.044772 -78.504225) (xy 296.898424 -78.65629) (xy 296.746359 -78.802638) (xy 296.5888 -78.943054)
			(xy 296.425978 -79.077332) (xy 296.258132 -79.205275) (xy 296.08551 -79.326695) (xy 295.908363 -79.441414)
			(xy 295.726952 -79.549264) (xy 295.541543 -79.650086) (xy 295.352408 -79.743733) (xy 295.159826 -79.830066)
			(xy 294.964078 -79.90896) (xy 294.765451 -79.980298) (xy 294.564238 -80.043975) (xy 294.360734 -80.099899)
			(xy 294.155237 -80.147987) (xy 293.948049 -80.188169) (xy 293.739474 -80.220386) (xy 293.529817 -80.244589)
			(xy 293.319388 -80.260745) (xy 293.108494 -80.268829) (xy 292.897446 -80.268829) (xy 292.686552 -80.260745)
			(xy 292.476123 -80.244589) (xy 292.266466 -80.220386) (xy 292.057891 -80.188169) (xy 291.850703 -80.147987)
			(xy 291.645206 -80.099899) (xy 291.441702 -80.043975) (xy 291.240489 -79.980298) (xy 291.041862 -79.90896)
			(xy 290.846114 -79.830066) (xy 290.653532 -79.743733) (xy 290.464397 -79.650086) (xy 290.278988 -79.549264)
			(xy 290.097577 -79.441414) (xy 289.92043 -79.326695) (xy 289.747808 -79.205275) (xy 289.579962 -79.077332)
			(xy 289.41714 -78.943054) (xy 289.259581 -78.802638) (xy 289.107516 -78.65629) (xy 288.961168 -78.504225)
			(xy 288.820752 -78.346666) (xy 288.686474 -78.183844) (xy 288.558531 -78.015998) (xy 288.437111 -77.843376)
			(xy 288.322392 -77.666229) (xy 288.214542 -77.484818) (xy 288.11372 -77.299409) (xy 288.020073 -77.110274)
			(xy 287.93374 -76.917692) (xy 287.854846 -76.721944) (xy 287.783508 -76.523317) (xy 287.719831 -76.322104)
			(xy 287.663907 -76.1186) (xy 287.615819 -75.913103) (xy 287.575637 -75.705915) (xy 287.54342 -75.49734)
			(xy 287.519217 -75.287683) (xy 287.503061 -75.077254) (xy 287.494977 -74.86636) (xy 287.494472 -74.760836)
			(xy 184.371488 -74.760836) (xy 184.371488 -74.767948) (xy 184.370983 -74.873472) (xy 184.362899 -75.084366)
			(xy 184.346743 -75.294795) (xy 184.32254 -75.504452) (xy 184.290323 -75.713027) (xy 184.250141 -75.920215)
			(xy 184.202053 -76.125712) (xy 184.146129 -76.329216) (xy 184.082452 -76.530429) (xy 184.011114 -76.729056)
			(xy 183.93222 -76.924804) (xy 183.845887 -77.117386) (xy 183.75224 -77.306521) (xy 183.651418 -77.49193)
			(xy 183.543568 -77.673341) (xy 183.428849 -77.850488) (xy 183.307429 -78.02311) (xy 183.179486 -78.190956)
			(xy 183.045208 -78.353778) (xy 182.904792 -78.511337) (xy 182.758444 -78.663402) (xy 182.606379 -78.80975)
			(xy 182.44882 -78.950166) (xy 182.285998 -79.084444) (xy 182.118152 -79.212387) (xy 181.94553 -79.333807)
			(xy 181.768383 -79.448526) (xy 181.586972 -79.556376) (xy 181.401563 -79.657198) (xy 181.212428 -79.750845)
			(xy 181.019846 -79.837178) (xy 180.824098 -79.916072) (xy 180.625471 -79.98741) (xy 180.424258 -80.051087)
			(xy 180.220754 -80.107011) (xy 180.015257 -80.155099) (xy 179.808069 -80.195281) (xy 179.599494 -80.227498)
			(xy 179.389837 -80.251701) (xy 179.179408 -80.267857) (xy 178.968514 -80.275941) (xy 178.757466 -80.275941)
			(xy 178.546572 -80.267857) (xy 178.336143 -80.251701) (xy 178.126486 -80.227498) (xy 177.917911 -80.195281)
			(xy 177.710723 -80.155099) (xy 177.505226 -80.107011) (xy 177.301722 -80.051087) (xy 177.100509 -79.98741)
			(xy 176.901882 -79.916072) (xy 176.706134 -79.837178) (xy 176.513552 -79.750845) (xy 176.324417 -79.657198)
			(xy 176.139008 -79.556376) (xy 175.957597 -79.448526) (xy 175.78045 -79.333807) (xy 175.607828 -79.212387)
			(xy 175.439982 -79.084444) (xy 175.27716 -78.950166) (xy 175.119601 -78.80975) (xy 174.967536 -78.663402)
			(xy 174.821188 -78.511337) (xy 174.680772 -78.353778) (xy 174.546494 -78.190956) (xy 174.418551 -78.02311)
			(xy 174.297131 -77.850488) (xy 174.182412 -77.673341) (xy 174.074562 -77.49193) (xy 173.97374 -77.306521)
			(xy 173.880093 -77.117386) (xy 173.79376 -76.924804) (xy 173.714866 -76.729056) (xy 173.643528 -76.530429)
			(xy 173.579851 -76.329216) (xy 173.523927 -76.125712) (xy 173.475839 -75.920215) (xy 173.435657 -75.713027)
			(xy 173.40344 -75.504452) (xy 173.379237 -75.294795) (xy 173.363081 -75.084366) (xy 173.354997 -74.873472)
			(xy 173.354492 -74.767948) (xy 50.571366 -74.767948) (xy 50.570895 -74.86636) (xy 50.562811 -75.077254)
			(xy 50.546655 -75.287683) (xy 50.522452 -75.49734) (xy 50.490235 -75.705915) (xy 50.450053 -75.913103)
			(xy 50.401965 -76.1186) (xy 50.346041 -76.322104) (xy 50.282364 -76.523317) (xy 50.211026 -76.721944)
			(xy 50.132132 -76.917692) (xy 50.045799 -77.110274) (xy 49.952152 -77.299409) (xy 49.85133 -77.484818)
			(xy 49.74348 -77.666229) (xy 49.628761 -77.843376) (xy 49.507341 -78.015998) (xy 49.379398 -78.183844)
			(xy 49.24512 -78.346666) (xy 49.104704 -78.504225) (xy 48.958356 -78.65629) (xy 48.806291 -78.802638)
			(xy 48.648732 -78.943054) (xy 48.48591 -79.077332) (xy 48.318064 -79.205275) (xy 48.145442 -79.326695)
			(xy 47.968295 -79.441414) (xy 47.786884 -79.549264) (xy 47.601475 -79.650086) (xy 47.41234 -79.743733)
			(xy 47.219758 -79.830066) (xy 47.02401 -79.90896) (xy 46.825383 -79.980298) (xy 46.62417 -80.043975)
			(xy 46.420666 -80.099899) (xy 46.215169 -80.147987) (xy 46.007981 -80.188169) (xy 45.799406 -80.220386)
			(xy 45.589749 -80.244589) (xy 45.37932 -80.260745) (xy 45.168426 -80.268829) (xy 44.957378 -80.268829)
			(xy 44.746484 -80.260745) (xy 44.536055 -80.244589) (xy 44.326398 -80.220386) (xy 44.117823 -80.188169)
			(xy 43.910635 -80.147987) (xy 43.705138 -80.099899) (xy 43.501634 -80.043975) (xy 43.300421 -79.980298)
			(xy 43.101794 -79.90896) (xy 42.906046 -79.830066) (xy 42.713464 -79.743733) (xy 42.524329 -79.650086)
			(xy 42.33892 -79.549264) (xy 42.157509 -79.441414) (xy 41.980362 -79.326695) (xy 41.80774 -79.205275)
			(xy 41.639894 -79.077332) (xy 41.477072 -78.943054) (xy 41.319513 -78.802638) (xy 41.167448 -78.65629)
			(xy 41.0211 -78.504225) (xy 40.880684 -78.346666) (xy 40.746406 -78.183844) (xy 40.618463 -78.015998)
			(xy 40.497043 -77.843376) (xy 40.382324 -77.666229) (xy 40.274474 -77.484818) (xy 40.173652 -77.299409)
			(xy 40.080005 -77.110274) (xy 39.993672 -76.917692) (xy 39.914778 -76.721944) (xy 39.84344 -76.523317)
			(xy 39.779763 -76.322104) (xy 39.723839 -76.1186) (xy 39.675751 -75.913103) (xy 39.635569 -75.705915)
			(xy 39.603352 -75.49734) (xy 39.579149 -75.287683) (xy 39.562993 -75.077254) (xy 39.554909 -74.86636)
			(xy 39.554404 -74.760836) (xy 0.509016 -74.760836) (xy 0.509016 -77.671676) (xy 0.509504 -77.724899)
			(xy 0.51712 -77.831071) (xy 0.532286 -77.93643) (xy 0.554925 -78.04044) (xy 0.584921 -78.142572)
			(xy 0.622123 -78.242305) (xy 0.666339 -78.339132) (xy 0.717347 -78.43256) (xy 0.774885 -78.522114)
			(xy 0.838661 -78.607338) (xy 0.908351 -78.687799) (xy 0.945642 -78.725776) (xy 1.77419 -79.554324)
			(xy 1.823602 -79.604436) (xy 1.917388 -79.709385) (xy 2.005143 -79.819428) (xy 2.08659 -79.934217)
			(xy 2.161473 -80.053392) (xy 2.229556 -80.176578) (xy 2.290626 -80.303388) (xy 2.344491 -80.433422)
			(xy 2.39098 -80.566271) (xy 2.429948 -80.701518) (xy 2.461272 -80.838737) (xy 2.484853 -80.977496)
			(xy 2.500618 -81.117359) (xy 2.508516 -81.257886) (xy 2.509012 -81.32826) (xy 2.509012 -81.69181)
			(xy 232.140667 -81.69181) (xy 232.145062 -81.517977) (xy 232.15749 -81.344533) (xy 232.177927 -81.171849)
			(xy 232.206328 -81.000295) (xy 232.242632 -80.830238) (xy 232.286762 -80.662042) (xy 232.338623 -80.496067)
			(xy 232.398104 -80.332668) (xy 232.465078 -80.172194) (xy 232.539402 -80.01499) (xy 232.620917 -79.86139)
			(xy 232.709448 -79.711725) (xy 232.804805 -79.566315) (xy 232.906785 -79.425469) (xy 233.01517 -79.289491)
			(xy 233.129727 -79.158671) (xy 233.250212 -79.033288) (xy 233.376366 -78.913612) (xy 233.50792 -78.799897)
			(xy 233.644592 -78.692389) (xy 233.715052 -78.641448) (xy 238.08436 -78.641448) (xy 238.15482 -78.692389)
			(xy 238.291492 -78.799897) (xy 238.423046 -78.913612) (xy 238.5492 -79.033288) (xy 238.669685 -79.158671)
			(xy 238.784242 -79.289491) (xy 238.892627 -79.425469) (xy 238.994607 -79.566315) (xy 239.089964 -79.711725)
			(xy 239.178495 -79.86139) (xy 239.26001 -80.01499) (xy 239.334334 -80.172194) (xy 239.401308 -80.332668)
			(xy 239.460789 -80.496067) (xy 239.51265 -80.662042) (xy 239.553507 -80.817765) (xy 333.938166 -80.817765)
			(xy 333.938166 -80.763235) (xy 333.945926 -80.70926) (xy 333.961289 -80.656938) (xy 333.98394 -80.607335)
			(xy 334.01342 -80.561461) (xy 334.049129 -80.520248) (xy 334.090338 -80.484537) (xy 334.136211 -80.455054)
			(xy 334.185812 -80.432398) (xy 334.238132 -80.417032) (xy 334.292107 -80.409268) (xy 334.319372 -80.40878)
			(xy 335.182972 -80.40878) (xy 335.210247 -80.409158) (xy 335.264243 -80.416917) (xy 335.316585 -80.432283)
			(xy 335.366207 -80.454941) (xy 335.412099 -80.484432) (xy 335.453327 -80.520153) (xy 335.489052 -80.561378)
			(xy 335.518545 -80.607268) (xy 335.541207 -80.656889) (xy 335.556577 -80.709229) (xy 335.56434 -80.763225)
			(xy 335.56434 -80.817775) (xy 335.556577 -80.871771) (xy 335.541207 -80.924111) (xy 335.518545 -80.973732)
			(xy 335.489052 -81.019622) (xy 335.453327 -81.060847) (xy 335.412099 -81.096568) (xy 335.366207 -81.126059)
			(xy 335.316585 -81.148717) (xy 335.264243 -81.164083) (xy 335.210247 -81.171842) (xy 335.182972 -81.172304)
			(xy 334.319372 -81.172304) (xy 334.292107 -81.171732) (xy 334.238132 -81.163968) (xy 334.185812 -81.148602)
			(xy 334.136211 -81.125946) (xy 334.090338 -81.096463) (xy 334.049129 -81.060752) (xy 334.01342 -81.019539)
			(xy 333.98394 -80.973665) (xy 333.961289 -80.924062) (xy 333.945926 -80.87174) (xy 333.938166 -80.817765)
			(xy 239.553507 -80.817765) (xy 239.55678 -80.830238) (xy 239.593084 -81.000295) (xy 239.621485 -81.171849)
			(xy 239.641922 -81.344533) (xy 239.65435 -81.517977) (xy 239.658745 -81.69181) (xy 239.655095 -81.865661)
			(xy 239.643409 -82.039157) (xy 239.640092 -82.06825) (xy 331.768962 -82.06825) (xy 331.768962 -82.01375)
			(xy 331.776717 -81.959803) (xy 331.792071 -81.90751) (xy 331.81471 -81.857933) (xy 331.844174 -81.812083)
			(xy 331.879862 -81.770892) (xy 331.921049 -81.735199) (xy 331.966896 -81.70573) (xy 332.01647 -81.683086)
			(xy 332.068762 -81.667726) (xy 332.122708 -81.659965) (xy 332.149958 -81.659476) (xy 333.013558 -81.659476)
			(xy 333.040812 -81.659968) (xy 333.094765 -81.66772) (xy 333.147066 -81.683072) (xy 333.196649 -81.705711)
			(xy 333.242505 -81.735177) (xy 333.283701 -81.770869) (xy 333.319398 -81.812061) (xy 333.348869 -81.857914)
			(xy 333.371513 -81.907495) (xy 333.386871 -81.959794) (xy 333.394629 -82.013746) (xy 333.394629 -82.068254)
			(xy 333.386871 -82.122206) (xy 333.371513 -82.174505) (xy 333.348869 -82.224086) (xy 333.319398 -82.269939)
			(xy 333.294774 -82.298353) (xy 336.189263 -82.298353) (xy 336.189263 -82.243847) (xy 336.197021 -82.189895)
			(xy 336.212377 -82.137597) (xy 336.235021 -82.088017) (xy 336.26449 -82.042163) (xy 336.300185 -82.000971)
			(xy 336.341379 -81.965278) (xy 336.387234 -81.935811) (xy 336.436816 -81.91317) (xy 336.489115 -81.897816)
			(xy 336.543067 -81.890062) (xy 336.57032 -81.8896) (xy 337.43392 -81.8896) (xy 337.461171 -81.890071)
			(xy 337.515118 -81.89783) (xy 337.567411 -81.913187) (xy 337.616987 -81.93583) (xy 337.662836 -81.965298)
			(xy 337.692804 -81.991267) (xy 339.478646 -81.991267) (xy 339.478646 -81.936733) (xy 339.486407 -81.882755)
			(xy 339.50177 -81.830431) (xy 339.524423 -81.780825) (xy 339.553905 -81.734948) (xy 339.589615 -81.693734)
			(xy 339.630827 -81.65802) (xy 339.676702 -81.628535) (xy 339.726306 -81.605879) (xy 339.77863 -81.590512)
			(xy 339.832607 -81.582748) (xy 339.859874 -81.58226) (xy 340.723474 -81.58226) (xy 340.750748 -81.582678)
			(xy 340.804741 -81.590437) (xy 340.857079 -81.605802) (xy 340.906699 -81.62846) (xy 340.952588 -81.657948)
			(xy 340.993814 -81.693668) (xy 341.029536 -81.734891) (xy 341.059028 -81.780778) (xy 341.081689 -81.830396)
			(xy 341.097057 -81.882734) (xy 341.10482 -81.936726) (xy 341.10482 -81.991274) (xy 341.097057 -82.045266)
			(xy 341.081689 -82.097604) (xy 341.059028 -82.147222) (xy 341.029536 -82.193109) (xy 340.993814 -82.234332)
			(xy 340.952588 -82.270052) (xy 340.906699 -82.29954) (xy 340.857079 -82.322198) (xy 340.804741 -82.337563)
			(xy 340.750748 -82.345322) (xy 340.723474 -82.345784) (xy 339.859874 -82.345784) (xy 339.832607 -82.345252)
			(xy 339.77863 -82.337488) (xy 339.726306 -82.322121) (xy 339.676702 -82.299465) (xy 339.630827 -82.26998)
			(xy 339.589615 -82.234266) (xy 339.553905 -82.193052) (xy 339.524423 -82.147175) (xy 339.50177 -82.097569)
			(xy 339.486407 -82.045245) (xy 339.478646 -81.991267) (xy 337.692804 -81.991267) (xy 337.704024 -82.00099)
			(xy 337.739714 -82.04218) (xy 337.76918 -82.088031) (xy 337.79182 -82.137608) (xy 337.807174 -82.189902)
			(xy 337.81493 -82.243849) (xy 337.81493 -82.298351) (xy 337.807174 -82.352298) (xy 337.79182 -82.404592)
			(xy 337.769179 -82.454169) (xy 337.739714 -82.50002) (xy 337.704024 -82.54121) (xy 337.662836 -82.576902)
			(xy 337.616987 -82.60637) (xy 337.567411 -82.629013) (xy 337.515118 -82.64437) (xy 337.461171 -82.652129)
			(xy 337.43392 -82.652616) (xy 336.57032 -82.652616) (xy 336.543067 -82.652138) (xy 336.489115 -82.644384)
			(xy 336.436816 -82.62903) (xy 336.387234 -82.606389) (xy 336.341379 -82.576922) (xy 336.300185 -82.541229)
			(xy 336.26449 -82.500037) (xy 336.235021 -82.454183) (xy 336.212377 -82.404603) (xy 336.197021 -82.352305)
			(xy 336.189263 -82.298353) (xy 333.294774 -82.298353) (xy 333.283701 -82.311131) (xy 333.242505 -82.346823)
			(xy 333.196649 -82.376289) (xy 333.147066 -82.398928) (xy 333.094765 -82.41428) (xy 333.040812 -82.422032)
			(xy 333.013558 -82.422492) (xy 332.149958 -82.422492) (xy 332.122708 -82.422035) (xy 332.068762 -82.414274)
			(xy 332.01647 -82.398914) (xy 331.966896 -82.37627) (xy 331.921049 -82.346801) (xy 331.879862 -82.311108)
			(xy 331.844174 -82.269917) (xy 331.81471 -82.224067) (xy 331.792071 -82.17449) (xy 331.776717 -82.122197)
			(xy 331.768962 -82.06825) (xy 239.640092 -82.06825) (xy 239.623713 -82.211927) (xy 239.596047 -82.383601)
			(xy 239.560472 -82.553811) (xy 239.517063 -82.722195) (xy 239.465913 -82.888391) (xy 239.407133 -83.052043)
			(xy 239.340846 -83.212802) (xy 239.267197 -83.370324) (xy 239.186341 -83.524271) (xy 239.148735 -83.588471)
			(xy 341.356398 -83.588471) (xy 341.356398 -83.533929) (xy 341.364161 -83.479942) (xy 341.379527 -83.427609)
			(xy 341.402184 -83.377996) (xy 341.431672 -83.332112) (xy 341.467389 -83.290892) (xy 341.508609 -83.255174)
			(xy 341.554492 -83.225686) (xy 341.604106 -83.203028) (xy 341.656438 -83.187661) (xy 341.710425 -83.179899)
			(xy 341.737696 -83.179412) (xy 342.601296 -83.179412) (xy 342.628565 -83.179927) (xy 342.682549 -83.187688)
			(xy 342.734879 -83.203053) (xy 342.784489 -83.225709) (xy 342.83037 -83.255194) (xy 342.871588 -83.290909)
			(xy 342.907303 -83.332127) (xy 342.936789 -83.378008) (xy 342.959445 -83.427618) (xy 342.974811 -83.479947)
			(xy 342.982573 -83.533931) (xy 342.982573 -83.588469) (xy 342.974811 -83.642453) (xy 342.959445 -83.694782)
			(xy 342.936789 -83.744392) (xy 342.907303 -83.790273) (xy 342.871588 -83.831491) (xy 342.83037 -83.867206)
			(xy 342.784489 -83.896691) (xy 342.734879 -83.919347) (xy 342.682549 -83.934712) (xy 342.628565 -83.942473)
			(xy 342.601296 -83.942936) (xy 341.737696 -83.942936) (xy 341.710425 -83.942501) (xy 341.656438 -83.934739)
			(xy 341.604106 -83.919372) (xy 341.554492 -83.896714) (xy 341.508609 -83.867226) (xy 341.467389 -83.831508)
			(xy 341.431672 -83.790288) (xy 341.402184 -83.744404) (xy 341.379527 -83.694791) (xy 341.364161 -83.642458)
			(xy 341.356398 -83.588471) (xy 239.148735 -83.588471) (xy 239.098452 -83.674314) (xy 239.003718 -83.820132)
			(xy 238.902342 -83.961413) (xy 238.794541 -84.097854) (xy 238.680545 -84.229164) (xy 238.560599 -84.355062)
			(xy 238.434958 -84.475277) (xy 238.393119 -84.511757) (xy 337.882119 -84.511757) (xy 337.882119 -84.457243)
			(xy 337.889878 -84.403284) (xy 337.905237 -84.350979) (xy 337.927883 -84.301392) (xy 337.957357 -84.255533)
			(xy 337.993057 -84.214336) (xy 338.034257 -84.178639) (xy 338.080119 -84.149169) (xy 338.129707 -84.126526)
			(xy 338.182014 -84.111171) (xy 338.235973 -84.103417) (xy 338.26323 -84.102956) (xy 339.12683 -84.102956)
			(xy 339.154077 -84.103516) (xy 339.208017 -84.111275) (xy 339.260303 -84.126632) (xy 339.309871 -84.149272)
			(xy 339.355714 -84.178737) (xy 339.396896 -84.214425) (xy 339.432581 -84.25561) (xy 339.462042 -84.301455)
			(xy 339.484679 -84.351025) (xy 339.500031 -84.403313) (xy 339.503159 -84.425069) (xy 344.644951 -84.425069)
			(xy 344.644951 -84.370531) (xy 344.652713 -84.316548) (xy 344.668079 -84.26422) (xy 344.690737 -84.214611)
			(xy 344.720223 -84.168731) (xy 344.75594 -84.127516) (xy 344.797159 -84.091803) (xy 344.843041 -84.06232)
			(xy 344.892652 -84.039668) (xy 344.944981 -84.024306) (xy 344.998965 -84.016549) (xy 345.026234 -84.016088)
			(xy 345.889834 -84.016088) (xy 345.917105 -84.016477) (xy 345.971092 -84.024243) (xy 346.023425 -84.039614)
			(xy 346.073037 -84.062275) (xy 346.11892 -84.091766) (xy 346.160139 -84.127485) (xy 346.195855 -84.168708)
			(xy 346.225341 -84.214593) (xy 346.247998 -84.264207) (xy 346.263364 -84.316541) (xy 346.271126 -84.370529)
			(xy 346.271126 -84.425071) (xy 346.263364 -84.479059) (xy 346.247998 -84.531393) (xy 346.225341 -84.581007)
			(xy 346.195855 -84.626892) (xy 346.160139 -84.668115) (xy 346.11892 -84.703834) (xy 346.073037 -84.733325)
			(xy 346.023425 -84.755986) (xy 345.971092 -84.771357) (xy 345.917105 -84.779123) (xy 345.889834 -84.779612)
			(xy 345.026234 -84.779612) (xy 344.998965 -84.779051) (xy 344.944981 -84.771294) (xy 344.892652 -84.755932)
			(xy 344.843041 -84.73328) (xy 344.797159 -84.703797) (xy 344.75594 -84.668084) (xy 344.720223 -84.626869)
			(xy 344.690737 -84.580989) (xy 344.668079 -84.53138) (xy 344.652713 -84.479052) (xy 344.644951 -84.425069)
			(xy 339.503159 -84.425069) (xy 339.507786 -84.457253) (xy 339.507786 -84.511747) (xy 339.500031 -84.565687)
			(xy 339.484679 -84.617975) (xy 339.462042 -84.667545) (xy 339.432581 -84.71339) (xy 339.396896 -84.754575)
			(xy 339.355714 -84.790263) (xy 339.309871 -84.819728) (xy 339.260303 -84.842368) (xy 339.208017 -84.857725)
			(xy 339.154077 -84.865484) (xy 339.12683 -84.865972) (xy 338.26323 -84.865972) (xy 338.235973 -84.865583)
			(xy 338.182014 -84.857829) (xy 338.129707 -84.842474) (xy 338.080119 -84.819831) (xy 338.034257 -84.790361)
			(xy 337.993057 -84.754664) (xy 337.957357 -84.713467) (xy 337.927883 -84.667608) (xy 337.905237 -84.618021)
			(xy 337.889878 -84.565716) (xy 337.882119 -84.511757) (xy 238.393119 -84.511757) (xy 238.303893 -84.589554)
			(xy 238.167683 -84.697647) (xy 238.02662 -84.799326) (xy 237.881005 -84.894371) (xy 237.73115 -84.982581)
			(xy 237.577377 -85.063767) (xy 237.420014 -85.137754) (xy 237.259397 -85.204384) (xy 237.095871 -85.263515)
			(xy 236.929785 -85.315021) (xy 236.761494 -85.35879) (xy 236.59136 -85.39473) (xy 236.419746 -85.422763)
			(xy 236.247019 -85.44283) (xy 236.073548 -85.454887) (xy 235.899706 -85.458909) (xy 235.725864 -85.454887)
			(xy 235.552393 -85.44283) (xy 235.379666 -85.422763) (xy 235.208052 -85.39473) (xy 235.037918 -85.35879)
			(xy 234.869627 -85.315021) (xy 234.703541 -85.263515) (xy 234.540015 -85.204384) (xy 234.379398 -85.137754)
			(xy 234.222035 -85.063767) (xy 234.068262 -84.982581) (xy 233.918407 -84.894371) (xy 233.772792 -84.799326)
			(xy 233.631729 -84.697647) (xy 233.495519 -84.589554) (xy 233.364454 -84.475277) (xy 233.238813 -84.355062)
			(xy 233.118867 -84.229164) (xy 233.004871 -84.097854) (xy 232.89707 -83.961413) (xy 232.795694 -83.820132)
			(xy 232.70096 -83.674314) (xy 232.613071 -83.524271) (xy 232.532215 -83.370324) (xy 232.458566 -83.212802)
			(xy 232.392279 -83.052043) (xy 232.333499 -82.888391) (xy 232.282349 -82.722195) (xy 232.23894 -82.553811)
			(xy 232.203365 -82.383601) (xy 232.175699 -82.211927) (xy 232.156003 -82.039157) (xy 232.144317 -81.865661)
			(xy 232.140667 -81.69181) (xy 2.509012 -81.69181) (xy 2.509012 -85.764678) (xy 10.421355 -85.764678)
			(xy 10.421355 -85.635538) (xy 10.429305 -85.506643) (xy 10.445175 -85.378483) (xy 10.468904 -85.251542)
			(xy 10.500403 -85.126303) (xy 10.539552 -85.00324) (xy 10.586203 -84.882821) (xy 10.640178 -84.765502)
			(xy 10.701273 -84.651728) (xy 10.769256 -84.541931) (xy 10.84387 -84.436528) (xy 10.924831 -84.335918)
			(xy 11.011831 -84.240483) (xy 11.104542 -84.150584) (xy 11.202612 -84.066563) (xy 11.305667 -83.988739)
			(xy 11.413318 -83.917407) (xy 11.525157 -83.852837) (xy 11.640758 -83.795275) (xy 11.759683 -83.744938)
			(xy 11.881482 -83.702018) (xy 12.005692 -83.666677) (xy 12.131841 -83.63905) (xy 12.259453 -83.619241)
			(xy 12.388042 -83.607325) (xy 12.51712 -83.603349) (xy 12.646198 -83.607325) (xy 12.774787 -83.619241)
			(xy 12.902399 -83.63905) (xy 13.028548 -83.666677) (xy 13.152758 -83.702018) (xy 13.274557 -83.744938)
			(xy 13.393482 -83.795275) (xy 13.509083 -83.852837) (xy 13.620922 -83.917407) (xy 13.728573 -83.988739)
			(xy 13.831628 -84.066563) (xy 13.929698 -84.150584) (xy 14.022409 -84.240483) (xy 14.109409 -84.335918)
			(xy 14.19037 -84.436528) (xy 14.264984 -84.541931) (xy 14.332967 -84.651728) (xy 14.394062 -84.765502)
			(xy 14.448037 -84.882821) (xy 14.494688 -85.00324) (xy 14.533837 -85.126303) (xy 14.565336 -85.251542)
			(xy 14.589065 -85.378483) (xy 14.604935 -85.506643) (xy 14.612885 -85.635538) (xy 14.613382 -85.700108)
			(xy 14.612885 -85.764678) (xy 14.608278 -85.839368) (xy 342.975946 -85.839368) (xy 342.975946 -85.784832)
			(xy 342.983708 -85.730852) (xy 342.999072 -85.678525) (xy 343.021727 -85.628918) (xy 343.051211 -85.58304)
			(xy 343.086924 -85.541824) (xy 343.12814 -85.506111) (xy 343.174018 -85.476627) (xy 343.223625 -85.453972)
			(xy 343.275952 -85.438608) (xy 343.329932 -85.430846) (xy 343.3572 -85.43036) (xy 344.2208 -85.43036)
			(xy 344.248071 -85.430802) (xy 344.302058 -85.438565) (xy 344.35439 -85.453931) (xy 344.404003 -85.476588)
			(xy 344.449887 -85.506076) (xy 344.491107 -85.541793) (xy 344.526824 -85.583013) (xy 344.556312 -85.628897)
			(xy 344.578969 -85.67851) (xy 344.594335 -85.730842) (xy 344.602098 -85.784829) (xy 344.602098 -85.839371)
			(xy 344.594335 -85.893358) (xy 344.578969 -85.94569) (xy 344.556312 -85.995303) (xy 344.526824 -86.041187)
			(xy 344.491107 -86.082407) (xy 344.449887 -86.118124) (xy 344.404003 -86.147612) (xy 344.35439 -86.170269)
			(xy 344.302058 -86.185635) (xy 344.248071 -86.193398) (xy 344.2208 -86.193884) (xy 343.3572 -86.193884)
			(xy 343.329932 -86.193354) (xy 343.275952 -86.185592) (xy 343.223625 -86.170228) (xy 343.174018 -86.147573)
			(xy 343.12814 -86.118089) (xy 343.086924 -86.082376) (xy 343.051211 -86.04116) (xy 343.021727 -85.995282)
			(xy 342.999072 -85.945675) (xy 342.983708 -85.893348) (xy 342.975946 -85.839368) (xy 14.608278 -85.839368)
			(xy 14.604935 -85.893573) (xy 14.589065 -86.021733) (xy 14.565336 -86.148674) (xy 14.533837 -86.273913)
			(xy 14.494688 -86.396976) (xy 14.448037 -86.517395) (xy 14.394062 -86.634714) (xy 14.332967 -86.748488)
			(xy 14.264984 -86.858285) (xy 14.19037 -86.963688) (xy 14.109409 -87.064298) (xy 14.022409 -87.159733)
			(xy 13.929698 -87.249632) (xy 13.831628 -87.333653) (xy 13.728573 -87.411477) (xy 13.620922 -87.482809)
			(xy 13.509083 -87.547379) (xy 13.393482 -87.604941) (xy 13.274557 -87.655278) (xy 13.152758 -87.698198)
			(xy 13.028548 -87.733539) (xy 12.902399 -87.761166) (xy 12.774787 -87.780975) (xy 12.646198 -87.792891)
			(xy 12.51712 -87.796868) (xy 12.388042 -87.792891) (xy 12.259453 -87.780975) (xy 12.131841 -87.761166)
			(xy 12.005692 -87.733539) (xy 11.881482 -87.698198) (xy 11.759683 -87.655278) (xy 11.640758 -87.604941)
			(xy 11.525157 -87.547379) (xy 11.413318 -87.482809) (xy 11.305667 -87.411477) (xy 11.202612 -87.333653)
			(xy 11.104542 -87.249632) (xy 11.011831 -87.159733) (xy 10.924831 -87.064298) (xy 10.84387 -86.963688)
			(xy 10.769256 -86.858285) (xy 10.701273 -86.748488) (xy 10.640178 -86.634714) (xy 10.586203 -86.517395)
			(xy 10.539552 -86.396976) (xy 10.500403 -86.273913) (xy 10.468904 -86.148674) (xy 10.445175 -86.021733)
			(xy 10.429305 -85.893573) (xy 10.421355 -85.764678) (xy 2.509012 -85.764678) (xy 2.509012 -98.341434)
			(xy 261.733792 -98.341434) (xy 261.733792 -97.477834) (xy 261.734278 -97.450583) (xy 261.742034 -97.396635)
			(xy 261.757389 -97.34434) (xy 261.780031 -97.294763) (xy 261.809497 -97.248913) (xy 261.845188 -97.207722)
			(xy 261.886379 -97.172031) (xy 261.932229 -97.142565) (xy 261.981806 -97.119923) (xy 262.034101 -97.104568)
			(xy 262.088049 -97.096812) (xy 262.142551 -97.096812) (xy 262.196499 -97.104568) (xy 262.248794 -97.119923)
			(xy 262.298371 -97.142565) (xy 262.344221 -97.172031) (xy 262.385412 -97.207722) (xy 262.421103 -97.248913)
			(xy 262.450569 -97.294763) (xy 262.473211 -97.34434) (xy 262.488566 -97.396635) (xy 262.496322 -97.450583)
			(xy 262.496808 -97.477834) (xy 262.496808 -98.341434) (xy 262.496322 -98.368685) (xy 262.488566 -98.422633)
			(xy 262.473211 -98.474928) (xy 262.450569 -98.524505) (xy 262.421103 -98.570355) (xy 262.385412 -98.611546)
			(xy 262.344221 -98.647237) (xy 262.298371 -98.676703) (xy 262.248794 -98.699345) (xy 262.196499 -98.7147)
			(xy 262.142551 -98.722456) (xy 262.088049 -98.722456) (xy 262.034101 -98.7147) (xy 261.981806 -98.699345)
			(xy 261.932229 -98.676703) (xy 261.886379 -98.647237) (xy 261.845188 -98.611546) (xy 261.809497 -98.570355)
			(xy 261.780031 -98.524505) (xy 261.757389 -98.474928) (xy 261.742034 -98.422633) (xy 261.734278 -98.368685)
			(xy 261.733792 -98.341434) (xy 2.509012 -98.341434) (xy 2.509012 -106.40187) (xy 11.713464 -106.40187)
			(xy 11.713464 -105.53827) (xy 11.71395 -105.511001) (xy 11.721712 -105.457017) (xy 11.737077 -105.404687)
			(xy 11.759734 -105.355077) (xy 11.78922 -105.309196) (xy 11.824935 -105.267979) (xy 11.866152 -105.232264)
			(xy 11.912033 -105.202778) (xy 11.961643 -105.180121) (xy 12.013973 -105.164756) (xy 12.067957 -105.156994)
			(xy 12.122495 -105.156994) (xy 12.176479 -105.164756) (xy 12.228809 -105.180121) (xy 12.278419 -105.202778)
			(xy 12.3243 -105.232264) (xy 12.365517 -105.267979) (xy 12.401232 -105.309196) (xy 12.430718 -105.355077)
			(xy 12.453375 -105.404687) (xy 12.46874 -105.457017) (xy 12.476502 -105.511001) (xy 12.476988 -105.53827)
			(xy 12.476988 -105.664) (xy 15.57274 -105.664) (xy 15.57274 -104.8004) (xy 15.573226 -104.773131)
			(xy 15.580988 -104.719147) (xy 15.596353 -104.666817) (xy 15.61901 -104.617207) (xy 15.648496 -104.571326)
			(xy 15.684211 -104.530109) (xy 15.725428 -104.494394) (xy 15.771309 -104.464908) (xy 15.820919 -104.442251)
			(xy 15.873249 -104.426886) (xy 15.927233 -104.419124) (xy 15.981771 -104.419124) (xy 16.035755 -104.426886)
			(xy 16.088085 -104.442251) (xy 16.137695 -104.464908) (xy 16.183576 -104.494394) (xy 16.224793 -104.530109)
			(xy 16.260508 -104.571326) (xy 16.289994 -104.617207) (xy 16.312651 -104.666817) (xy 16.328016 -104.719147)
			(xy 16.335778 -104.773131) (xy 16.336264 -104.8004) (xy 16.336264 -105.664) (xy 16.335778 -105.691269)
			(xy 16.328016 -105.745253) (xy 16.312651 -105.797583) (xy 16.289994 -105.847193) (xy 16.260508 -105.893074)
			(xy 16.224793 -105.934291) (xy 16.183576 -105.970006) (xy 16.137695 -105.999492) (xy 16.088085 -106.022149)
			(xy 16.035755 -106.037514) (xy 15.981771 -106.045276) (xy 15.927233 -106.045276) (xy 15.873249 -106.037514)
			(xy 15.820919 -106.022149) (xy 15.771309 -105.999492) (xy 15.725428 -105.970006) (xy 15.684211 -105.934291)
			(xy 15.648496 -105.893074) (xy 15.61901 -105.847193) (xy 15.596353 -105.797583) (xy 15.580988 -105.745253)
			(xy 15.573226 -105.691269) (xy 15.57274 -105.664) (xy 12.476988 -105.664) (xy 12.476988 -106.40187)
			(xy 12.476502 -106.429139) (xy 12.46874 -106.483123) (xy 12.453375 -106.535453) (xy 12.430718 -106.585063)
			(xy 12.401232 -106.630944) (xy 12.365517 -106.672161) (xy 12.3243 -106.707876) (xy 12.278419 -106.737362)
			(xy 12.228809 -106.760019) (xy 12.176479 -106.775384) (xy 12.122495 -106.783146) (xy 12.067957 -106.783146)
			(xy 12.013973 -106.775384) (xy 11.961643 -106.760019) (xy 11.912033 -106.737362) (xy 11.866152 -106.707876)
			(xy 11.824935 -106.672161) (xy 11.78922 -106.630944) (xy 11.759734 -106.585063) (xy 11.737077 -106.535453)
			(xy 11.721712 -106.483123) (xy 11.71395 -106.429139) (xy 11.713464 -106.40187) (xy 2.509012 -106.40187)
			(xy 2.509012 -108.943971) (xy 11.292822 -108.943971) (xy 11.292822 -108.889469) (xy 11.300578 -108.835522)
			(xy 11.315933 -108.783228) (xy 11.338574 -108.733651) (xy 11.36804 -108.687801) (xy 11.403731 -108.646611)
			(xy 11.444921 -108.61092) (xy 11.490771 -108.581454) (xy 11.540348 -108.558813) (xy 11.592642 -108.543458)
			(xy 11.646589 -108.535702) (xy 11.67384 -108.535216) (xy 12.53744 -108.535216) (xy 12.564692 -108.535694)
			(xy 12.61864 -108.54345) (xy 12.670935 -108.558806) (xy 12.720513 -108.581447) (xy 12.766364 -108.610914)
			(xy 12.807554 -108.646606) (xy 12.843246 -108.687796) (xy 12.872713 -108.733647) (xy 12.895354 -108.783225)
			(xy 12.91071 -108.83552) (xy 12.918466 -108.889468) (xy 12.918466 -108.943972) (xy 12.918466 -108.943973)
			(xy 15.156389 -108.943973) (xy 15.156389 -108.889467) (xy 15.164146 -108.835517) (xy 15.179502 -108.783219)
			(xy 15.202145 -108.733639) (xy 15.231613 -108.687786) (xy 15.267307 -108.646594) (xy 15.308499 -108.610901)
			(xy 15.354353 -108.581433) (xy 15.403933 -108.558791) (xy 15.45623 -108.543435) (xy 15.510181 -108.535679)
			(xy 15.537434 -108.535216) (xy 16.401034 -108.535216) (xy 16.428285 -108.535694) (xy 16.482233 -108.543451)
			(xy 16.534528 -108.558807) (xy 16.584105 -108.581448) (xy 16.629956 -108.610915) (xy 16.671146 -108.646607)
			(xy 16.706837 -108.687798) (xy 16.707863 -108.689394) (xy 238.647224 -108.689394) (xy 238.647224 -107.825794)
			(xy 238.64771 -107.798525) (xy 238.655472 -107.744541) (xy 238.670837 -107.692211) (xy 238.693494 -107.642601)
			(xy 238.72298 -107.59672) (xy 238.758695 -107.555503) (xy 238.799912 -107.519788) (xy 238.845793 -107.490302)
			(xy 238.895403 -107.467645) (xy 238.947733 -107.45228) (xy 239.001717 -107.444518) (xy 239.056255 -107.444518)
			(xy 239.110239 -107.45228) (xy 239.162569 -107.467645) (xy 239.212179 -107.490302) (xy 239.25806 -107.519788)
			(xy 239.299277 -107.555503) (xy 239.334992 -107.59672) (xy 239.364478 -107.642601) (xy 239.387135 -107.692211)
			(xy 239.4025 -107.744541) (xy 239.410262 -107.798525) (xy 239.410748 -107.825794) (xy 239.410748 -108.689394)
			(xy 239.410262 -108.716663) (xy 239.4025 -108.770647) (xy 239.387135 -108.822977) (xy 239.364478 -108.872587)
			(xy 239.334992 -108.918468) (xy 239.299277 -108.959685) (xy 239.25806 -108.9954) (xy 239.212179 -109.024886)
			(xy 239.162569 -109.047543) (xy 239.110239 -109.062908) (xy 239.056255 -109.07067) (xy 239.001717 -109.07067)
			(xy 238.947733 -109.062908) (xy 238.895403 -109.047543) (xy 238.845793 -109.024886) (xy 238.799912 -108.9954)
			(xy 238.758695 -108.959685) (xy 238.72298 -108.918468) (xy 238.693494 -108.872587) (xy 238.670837 -108.822977)
			(xy 238.655472 -108.770647) (xy 238.64771 -108.716663) (xy 238.647224 -108.689394) (xy 16.707863 -108.689394)
			(xy 16.736304 -108.733648) (xy 16.758945 -108.783226) (xy 16.7743 -108.835521) (xy 16.782056 -108.889469)
			(xy 16.782056 -108.943971) (xy 16.7743 -108.997919) (xy 16.758945 -109.050214) (xy 16.736304 -109.099792)
			(xy 16.706837 -109.145642) (xy 16.671146 -109.186833) (xy 16.629956 -109.222525) (xy 16.584105 -109.251992)
			(xy 16.534528 -109.274633) (xy 16.482233 -109.289989) (xy 16.428285 -109.297746) (xy 16.401034 -109.298232)
			(xy 15.537434 -109.298232) (xy 15.510181 -109.297761) (xy 15.45623 -109.290005) (xy 15.403933 -109.274649)
			(xy 15.354353 -109.252007) (xy 15.308499 -109.222539) (xy 15.267307 -109.186846) (xy 15.231613 -109.145654)
			(xy 15.202145 -109.099801) (xy 15.179502 -109.050221) (xy 15.164146 -108.997923) (xy 15.156389 -108.943973)
			(xy 12.918466 -108.943973) (xy 12.91071 -108.99792) (xy 12.895354 -109.050215) (xy 12.872713 -109.099793)
			(xy 12.843246 -109.145644) (xy 12.807554 -109.186834) (xy 12.766364 -109.222526) (xy 12.720513 -109.251993)
			(xy 12.670935 -109.274634) (xy 12.61864 -109.28999) (xy 12.564692 -109.297746) (xy 12.53744 -109.298232)
			(xy 11.67384 -109.298232) (xy 11.646589 -109.297738) (xy 11.592642 -109.289982) (xy 11.540348 -109.274627)
			(xy 11.490771 -109.251986) (xy 11.444921 -109.22252) (xy 11.403731 -109.186829) (xy 11.36804 -109.145639)
			(xy 11.338574 -109.099789) (xy 11.315933 -109.050212) (xy 11.300578 -108.997918) (xy 11.292822 -108.943971)
			(xy 2.509012 -108.943971) (xy 2.509012 -109.550266) (xy 250.428546 -109.550266) (xy 250.428546 -109.495734)
			(xy 250.436306 -109.441757) (xy 250.451669 -109.389434) (xy 250.474321 -109.339829) (xy 250.503801 -109.293953)
			(xy 250.53951 -109.252739) (xy 250.580721 -109.217025) (xy 250.626594 -109.18754) (xy 250.676196 -109.164883)
			(xy 250.728518 -109.149515) (xy 250.782494 -109.141749) (xy 250.80976 -109.14126) (xy 251.67336 -109.14126)
			(xy 251.700634 -109.141677) (xy 251.754629 -109.149435) (xy 251.806969 -109.164798) (xy 251.85659 -109.187455)
			(xy 251.902482 -109.216943) (xy 251.943709 -109.252663) (xy 251.979433 -109.293886) (xy 252.008926 -109.339775)
			(xy 252.031588 -109.389393) (xy 252.046957 -109.441732) (xy 252.05472 -109.495726) (xy 252.05472 -109.550274)
			(xy 252.046957 -109.604268) (xy 252.031588 -109.656607) (xy 252.008926 -109.706225) (xy 251.979433 -109.752114)
			(xy 251.943709 -109.793337) (xy 251.902482 -109.829057) (xy 251.85659 -109.858545) (xy 251.806969 -109.881202)
			(xy 251.754629 -109.896565) (xy 251.700634 -109.904323) (xy 251.67336 -109.904784) (xy 250.80976 -109.904784)
			(xy 250.782494 -109.904251) (xy 250.728518 -109.896485) (xy 250.676196 -109.881117) (xy 250.626594 -109.85846)
			(xy 250.580721 -109.828975) (xy 250.53951 -109.793262) (xy 250.503801 -109.752047) (xy 250.474321 -109.706171)
			(xy 250.451669 -109.656566) (xy 250.436306 -109.604243) (xy 250.428546 -109.550266) (xy 2.509012 -109.550266)
			(xy 2.509012 -111.158274) (xy 239.40262 -111.158274) (xy 239.40262 -110.294674) (xy 239.403106 -110.267423)
			(xy 239.410862 -110.213475) (xy 239.426217 -110.16118) (xy 239.448859 -110.111603) (xy 239.478325 -110.065753)
			(xy 239.514016 -110.024562) (xy 239.555207 -109.988871) (xy 239.601057 -109.959405) (xy 239.650634 -109.936763)
			(xy 239.702929 -109.921408) (xy 239.756877 -109.913652) (xy 239.811379 -109.913652) (xy 239.865327 -109.921408)
			(xy 239.917622 -109.936763) (xy 239.967199 -109.959405) (xy 240.000574 -109.980854) (xy 256.88563 -109.980854)
			(xy 256.88563 -109.926346) (xy 256.893387 -109.872392) (xy 256.908744 -109.820091) (xy 256.931388 -109.770508)
			(xy 256.960857 -109.724652) (xy 256.996552 -109.683457) (xy 257.037747 -109.647761) (xy 257.083602 -109.61829)
			(xy 257.133185 -109.595646) (xy 257.185486 -109.580288) (xy 257.23944 -109.57253) (xy 257.266694 -109.572044)
			(xy 258.130294 -109.572044) (xy 258.157544 -109.572603) (xy 258.211488 -109.580358) (xy 258.26378 -109.595712)
			(xy 258.313355 -109.618351) (xy 258.359203 -109.647815) (xy 258.400391 -109.683504) (xy 258.436081 -109.724692)
			(xy 258.465546 -109.77054) (xy 258.488186 -109.820114) (xy 258.503541 -109.872406) (xy 258.511297 -109.92635)
			(xy 258.511297 -109.98085) (xy 258.503541 -110.034794) (xy 258.488186 -110.087086) (xy 258.465546 -110.13666)
			(xy 258.436081 -110.182508) (xy 258.400391 -110.223696) (xy 258.359203 -110.259385) (xy 258.313355 -110.288849)
			(xy 258.26378 -110.311488) (xy 258.211488 -110.326842) (xy 258.157544 -110.334597) (xy 258.130294 -110.33506)
			(xy 257.266694 -110.33506) (xy 257.23944 -110.33467) (xy 257.185486 -110.326912) (xy 257.133185 -110.311554)
			(xy 257.083602 -110.28891) (xy 257.037747 -110.259439) (xy 256.996552 -110.223743) (xy 256.960857 -110.182548)
			(xy 256.931388 -110.136692) (xy 256.908744 -110.087109) (xy 256.893387 -110.034808) (xy 256.88563 -109.980854)
			(xy 240.000574 -109.980854) (xy 240.013049 -109.988871) (xy 240.05424 -110.024562) (xy 240.089931 -110.065753)
			(xy 240.119397 -110.111603) (xy 240.142039 -110.16118) (xy 240.157394 -110.213475) (xy 240.16515 -110.267423)
			(xy 240.165636 -110.294674) (xy 240.165636 -111.158274) (xy 240.16515 -111.185525) (xy 240.157394 -111.239473)
			(xy 240.142039 -111.291768) (xy 240.119397 -111.341345) (xy 240.089931 -111.387195) (xy 240.05424 -111.428386)
			(xy 240.013049 -111.464077) (xy 239.967199 -111.493543) (xy 239.917622 -111.516185) (xy 239.865327 -111.53154)
			(xy 239.811379 -111.539296) (xy 239.756877 -111.539296) (xy 239.702929 -111.53154) (xy 239.650634 -111.516185)
			(xy 239.601057 -111.493543) (xy 239.555207 -111.464077) (xy 239.514016 -111.428386) (xy 239.478325 -111.387195)
			(xy 239.448859 -111.341345) (xy 239.426217 -111.291768) (xy 239.410862 -111.239473) (xy 239.403106 -111.185525)
			(xy 239.40262 -111.158274) (xy 2.509012 -111.158274) (xy 2.509012 -114.734161) (xy 11.255226 -114.734161)
			(xy 11.255226 -114.679659) (xy 11.262982 -114.625711) (xy 11.278337 -114.573416) (xy 11.300979 -114.523839)
			(xy 11.330445 -114.477988) (xy 11.366136 -114.436798) (xy 11.407326 -114.401106) (xy 11.453177 -114.371639)
			(xy 11.502754 -114.348998) (xy 11.555049 -114.333643) (xy 11.608997 -114.325886) (xy 11.636248 -114.3254)
			(xy 12.499848 -114.3254) (xy 12.527101 -114.325867) (xy 12.581052 -114.333624) (xy 12.633349 -114.34898)
			(xy 12.68293 -114.371622) (xy 12.728783 -114.40109) (xy 12.769975 -114.436783) (xy 12.805669 -114.477976)
			(xy 12.835137 -114.523829) (xy 12.85778 -114.573409) (xy 12.873136 -114.625706) (xy 12.880893 -114.679657)
			(xy 12.880893 -114.734163) (xy 12.873136 -114.788114) (xy 12.85778 -114.840411) (xy 12.835137 -114.889991)
			(xy 12.805669 -114.935844) (xy 12.769975 -114.977037) (xy 12.728783 -115.01273) (xy 12.68293 -115.042198)
			(xy 12.633349 -115.06484) (xy 12.581052 -115.080196) (xy 12.527101 -115.087953) (xy 12.499848 -115.088416)
			(xy 11.636248 -115.088416) (xy 11.608997 -115.087934) (xy 11.555049 -115.080177) (xy 11.502754 -115.064822)
			(xy 11.453177 -115.042181) (xy 11.407326 -115.012714) (xy 11.366136 -114.977022) (xy 11.330445 -114.935832)
			(xy 11.300979 -114.889981) (xy 11.278337 -114.840404) (xy 11.262982 -114.788109) (xy 11.255226 -114.734161)
			(xy 2.509012 -114.734161) (xy 2.509012 -116.393573) (xy 230.652992 -116.393573) (xy 230.652992 -116.339027)
			(xy 230.660755 -116.285035) (xy 230.676123 -116.232698) (xy 230.698784 -116.183081) (xy 230.728276 -116.137195)
			(xy 230.763998 -116.095973) (xy 230.805224 -116.060254) (xy 230.851113 -116.030767) (xy 230.900732 -116.008111)
			(xy 230.95307 -115.992747) (xy 231.007063 -115.984989) (xy 231.034336 -115.984528) (xy 231.897936 -115.984528)
			(xy 231.925203 -115.985037) (xy 231.979181 -115.992802) (xy 232.031505 -116.008171) (xy 232.081109 -116.030828)
			(xy 232.126985 -116.060314) (xy 232.168197 -116.096029) (xy 232.203907 -116.137244) (xy 232.233389 -116.183122)
			(xy 232.256042 -116.232729) (xy 232.271405 -116.285054) (xy 232.277026 -116.324151) (xy 236.866903 -116.324151)
			(xy 236.866903 -116.269649) (xy 236.87466 -116.215701) (xy 236.890016 -116.163407) (xy 236.912659 -116.113831)
			(xy 236.942127 -116.067981) (xy 236.97782 -116.026793) (xy 237.019012 -115.991104) (xy 237.064864 -115.961641)
			(xy 237.114443 -115.939003) (xy 237.166739 -115.923652) (xy 237.220687 -115.915901) (xy 237.247938 -115.91544)
			(xy 238.111538 -115.91544) (xy 238.138791 -115.915832) (xy 238.192741 -115.923594) (xy 238.245038 -115.938955)
			(xy 238.294617 -115.961601) (xy 238.340468 -115.991072) (xy 238.381659 -116.026768) (xy 238.417351 -116.067962)
			(xy 238.446817 -116.113817) (xy 238.469459 -116.163398) (xy 238.484814 -116.215696) (xy 238.49257 -116.269647)
			(xy 238.49257 -116.324153) (xy 238.484814 -116.378104) (xy 238.469459 -116.430402) (xy 238.446817 -116.479983)
			(xy 238.417351 -116.525838) (xy 238.381659 -116.567032) (xy 238.340468 -116.602728) (xy 238.294617 -116.632199)
			(xy 238.245038 -116.654845) (xy 238.192741 -116.670206) (xy 238.138791 -116.677968) (xy 238.111538 -116.678456)
			(xy 237.247938 -116.678456) (xy 237.220687 -116.677899) (xy 237.166739 -116.670148) (xy 237.114443 -116.654797)
			(xy 237.064864 -116.632159) (xy 237.019012 -116.602696) (xy 236.97782 -116.567007) (xy 236.942127 -116.525819)
			(xy 236.912659 -116.479969) (xy 236.890016 -116.430393) (xy 236.87466 -116.378099) (xy 236.866903 -116.324151)
			(xy 232.277026 -116.324151) (xy 232.279166 -116.339033) (xy 232.279166 -116.393567) (xy 232.271405 -116.447546)
			(xy 232.256042 -116.499871) (xy 232.233389 -116.549478) (xy 232.203907 -116.595356) (xy 232.168197 -116.636571)
			(xy 232.126985 -116.672286) (xy 232.081109 -116.701772) (xy 232.031505 -116.724429) (xy 231.979181 -116.739798)
			(xy 231.925203 -116.747563) (xy 231.897936 -116.748052) (xy 231.034336 -116.748052) (xy 231.007063 -116.747611)
			(xy 230.95307 -116.739853) (xy 230.900732 -116.724489) (xy 230.851113 -116.701833) (xy 230.805224 -116.672346)
			(xy 230.763998 -116.636627) (xy 230.728276 -116.595405) (xy 230.698784 -116.549519) (xy 230.676123 -116.499902)
			(xy 230.660755 -116.447565) (xy 230.652992 -116.393573) (xy 2.509012 -116.393573) (xy 2.509012 -117.632251)
			(xy 233.564903 -117.632251) (xy 233.564903 -117.577749) (xy 233.57266 -117.523801) (xy 233.588016 -117.471507)
			(xy 233.610659 -117.421931) (xy 233.640127 -117.376081) (xy 233.67582 -117.334893) (xy 233.717012 -117.299204)
			(xy 233.762864 -117.269741) (xy 233.812443 -117.247103) (xy 233.864739 -117.231752) (xy 233.918687 -117.224001)
			(xy 233.945938 -117.22354) (xy 234.809538 -117.22354) (xy 234.836791 -117.223932) (xy 234.890741 -117.231694)
			(xy 234.943038 -117.247055) (xy 234.992617 -117.269701) (xy 235.038468 -117.299172) (xy 235.079659 -117.334868)
			(xy 235.115351 -117.376062) (xy 235.144817 -117.421917) (xy 235.167459 -117.471498) (xy 235.182814 -117.523796)
			(xy 235.19057 -117.577747) (xy 235.19057 -117.632251) (xy 238.898903 -117.632251) (xy 238.898903 -117.577749)
			(xy 238.90666 -117.523801) (xy 238.922016 -117.471507) (xy 238.944659 -117.421931) (xy 238.974127 -117.376081)
			(xy 239.00982 -117.334893) (xy 239.051012 -117.299204) (xy 239.096864 -117.269741) (xy 239.146443 -117.247103)
			(xy 239.198739 -117.231752) (xy 239.252687 -117.224001) (xy 239.279938 -117.22354) (xy 240.143538 -117.22354)
			(xy 240.170791 -117.223932) (xy 240.224741 -117.231694) (xy 240.277038 -117.247055) (xy 240.326617 -117.269701)
			(xy 240.372468 -117.299172) (xy 240.413659 -117.334868) (xy 240.449351 -117.376062) (xy 240.478817 -117.421917)
			(xy 240.501459 -117.471498) (xy 240.516814 -117.523796) (xy 240.52457 -117.577747) (xy 240.52457 -117.632253)
			(xy 240.516814 -117.686204) (xy 240.501459 -117.738502) (xy 240.478817 -117.788083) (xy 240.449351 -117.833938)
			(xy 240.413659 -117.875132) (xy 240.372468 -117.910828) (xy 240.326617 -117.940299) (xy 240.277038 -117.962945)
			(xy 240.224741 -117.978306) (xy 240.170791 -117.986068) (xy 240.143538 -117.986556) (xy 239.279938 -117.986556)
			(xy 239.252687 -117.985999) (xy 239.198739 -117.978248) (xy 239.146443 -117.962897) (xy 239.096864 -117.940259)
			(xy 239.051012 -117.910796) (xy 239.00982 -117.875107) (xy 238.974127 -117.833919) (xy 238.944659 -117.788069)
			(xy 238.922016 -117.738493) (xy 238.90666 -117.686199) (xy 238.898903 -117.632251) (xy 235.19057 -117.632251)
			(xy 235.19057 -117.632253) (xy 235.182814 -117.686204) (xy 235.167459 -117.738502) (xy 235.144817 -117.788083)
			(xy 235.115351 -117.833938) (xy 235.079659 -117.875132) (xy 235.038468 -117.910828) (xy 234.992617 -117.940299)
			(xy 234.943038 -117.962945) (xy 234.890741 -117.978306) (xy 234.836791 -117.986068) (xy 234.809538 -117.986556)
			(xy 233.945938 -117.986556) (xy 233.918687 -117.985999) (xy 233.864739 -117.978248) (xy 233.812443 -117.962897)
			(xy 233.762864 -117.940259) (xy 233.717012 -117.910796) (xy 233.67582 -117.875107) (xy 233.640127 -117.833919)
			(xy 233.610659 -117.788069) (xy 233.588016 -117.738493) (xy 233.57266 -117.686199) (xy 233.564903 -117.632251)
			(xy 2.509012 -117.632251) (xy 2.509012 -123.093988) (xy 227.217732 -123.093988) (xy 227.217732 -122.230388)
			(xy 227.218218 -122.203137) (xy 227.225974 -122.149189) (xy 227.241329 -122.096894) (xy 227.263971 -122.047317)
			(xy 227.293437 -122.001467) (xy 227.329128 -121.960276) (xy 227.370319 -121.924585) (xy 227.416169 -121.895119)
			(xy 227.465746 -121.872477) (xy 227.518041 -121.857122) (xy 227.571989 -121.849366) (xy 227.626491 -121.849366)
			(xy 227.680439 -121.857122) (xy 227.732734 -121.872477) (xy 227.782311 -121.895119) (xy 227.828161 -121.924585)
			(xy 227.869352 -121.960276) (xy 227.905043 -122.001467) (xy 227.934509 -122.047317) (xy 227.957151 -122.096894)
			(xy 227.972506 -122.149189) (xy 227.980262 -122.203137) (xy 227.980748 -122.230388) (xy 227.980748 -122.921014)
			(xy 245.563136 -122.921014) (xy 245.563136 -122.057414) (xy 245.563622 -122.030163) (xy 245.571378 -121.976215)
			(xy 245.586733 -121.92392) (xy 245.609375 -121.874343) (xy 245.638841 -121.828493) (xy 245.674532 -121.787302)
			(xy 245.715723 -121.751611) (xy 245.761573 -121.722145) (xy 245.81115 -121.699503) (xy 245.863445 -121.684148)
			(xy 245.917393 -121.676392) (xy 245.971895 -121.676392) (xy 246.025843 -121.684148) (xy 246.078138 -121.699503)
			(xy 246.127715 -121.722145) (xy 246.173565 -121.751611) (xy 246.214756 -121.787302) (xy 246.250447 -121.828493)
			(xy 246.279913 -121.874343) (xy 246.302555 -121.92392) (xy 246.31791 -121.976215) (xy 246.325666 -122.030163)
			(xy 246.326152 -122.057414) (xy 246.326152 -122.921014) (xy 246.325666 -122.948265) (xy 246.31791 -123.002213)
			(xy 246.302555 -123.054508) (xy 246.279913 -123.104085) (xy 246.250447 -123.149935) (xy 246.214756 -123.191126)
			(xy 246.173565 -123.226817) (xy 246.127715 -123.256283) (xy 246.078138 -123.278925) (xy 246.025843 -123.29428)
			(xy 245.971895 -123.302036) (xy 245.917393 -123.302036) (xy 245.863445 -123.29428) (xy 245.81115 -123.278925)
			(xy 245.761573 -123.256283) (xy 245.715723 -123.226817) (xy 245.674532 -123.191126) (xy 245.638841 -123.149935)
			(xy 245.609375 -123.104085) (xy 245.586733 -123.054508) (xy 245.571378 -123.002213) (xy 245.563622 -122.948265)
			(xy 245.563136 -122.921014) (xy 227.980748 -122.921014) (xy 227.980748 -123.093988) (xy 227.980262 -123.121239)
			(xy 227.972506 -123.175187) (xy 227.957151 -123.227482) (xy 227.934509 -123.277059) (xy 227.905043 -123.322909)
			(xy 227.869352 -123.3641) (xy 227.828161 -123.399791) (xy 227.782311 -123.429257) (xy 227.732734 -123.451899)
			(xy 227.680439 -123.467254) (xy 227.626491 -123.47501) (xy 227.571989 -123.47501) (xy 227.518041 -123.467254)
			(xy 227.465746 -123.451899) (xy 227.416169 -123.429257) (xy 227.370319 -123.399791) (xy 227.329128 -123.3641)
			(xy 227.293437 -123.322909) (xy 227.263971 -123.277059) (xy 227.241329 -123.227482) (xy 227.225974 -123.175187)
			(xy 227.218218 -123.121239) (xy 227.217732 -123.093988) (xy 2.509012 -123.093988) (xy 2.509012 -125.221746)
			(xy 225.535744 -125.221746) (xy 225.535744 -124.358146) (xy 225.53623 -124.330877) (xy 225.543992 -124.276893)
			(xy 225.559357 -124.224563) (xy 225.582014 -124.174953) (xy 225.6115 -124.129072) (xy 225.647215 -124.087855)
			(xy 225.688432 -124.05214) (xy 225.734313 -124.022654) (xy 225.783923 -123.999997) (xy 225.836253 -123.984632)
			(xy 225.890237 -123.97687) (xy 225.944775 -123.97687) (xy 225.998759 -123.984632) (xy 226.051089 -123.999997)
			(xy 226.100699 -124.022654) (xy 226.14658 -124.05214) (xy 226.187797 -124.087855) (xy 226.223512 -124.129072)
			(xy 226.252998 -124.174953) (xy 226.275655 -124.224563) (xy 226.29102 -124.276893) (xy 226.298782 -124.330877)
			(xy 226.299268 -124.358146) (xy 226.299268 -125.221746) (xy 226.298782 -125.249015) (xy 226.29102 -125.302999)
			(xy 226.275655 -125.355329) (xy 226.252998 -125.404939) (xy 226.223512 -125.45082) (xy 226.187797 -125.492037)
			(xy 226.14658 -125.527752) (xy 226.100699 -125.557238) (xy 226.051089 -125.579895) (xy 225.998759 -125.59526)
			(xy 225.944775 -125.603022) (xy 225.890237 -125.603022) (xy 225.836253 -125.59526) (xy 225.783923 -125.579895)
			(xy 225.734313 -125.557238) (xy 225.688432 -125.527752) (xy 225.647215 -125.492037) (xy 225.6115 -125.45082)
			(xy 225.582014 -125.404939) (xy 225.559357 -125.355329) (xy 225.543992 -125.302999) (xy 225.53623 -125.249015)
			(xy 225.535744 -125.221746) (xy 2.509012 -125.221746) (xy 2.509012 -127.325628) (xy 227.034852 -127.325628)
			(xy 227.034852 -126.462028) (xy 227.035338 -126.434777) (xy 227.043094 -126.380829) (xy 227.058449 -126.328534)
			(xy 227.081091 -126.278957) (xy 227.110557 -126.233107) (xy 227.146248 -126.191916) (xy 227.187439 -126.156225)
			(xy 227.233289 -126.126759) (xy 227.282866 -126.104117) (xy 227.335161 -126.088762) (xy 227.389109 -126.081006)
			(xy 227.443611 -126.081006) (xy 227.497559 -126.088762) (xy 227.549854 -126.104117) (xy 227.599431 -126.126759)
			(xy 227.645281 -126.156225) (xy 227.686472 -126.191916) (xy 227.722163 -126.233107) (xy 227.751629 -126.278957)
			(xy 227.774271 -126.328534) (xy 227.789626 -126.380829) (xy 227.797382 -126.434777) (xy 227.797868 -126.462028)
			(xy 227.797868 -127.140208) (xy 242.041172 -127.140208) (xy 242.041172 -126.276608) (xy 242.041658 -126.249357)
			(xy 242.049414 -126.195409) (xy 242.064769 -126.143114) (xy 242.087411 -126.093537) (xy 242.116877 -126.047687)
			(xy 242.152568 -126.006496) (xy 242.193759 -125.970805) (xy 242.239609 -125.941339) (xy 242.289186 -125.918697)
			(xy 242.341481 -125.903342) (xy 242.395429 -125.895586) (xy 242.449931 -125.895586) (xy 242.503879 -125.903342)
			(xy 242.556174 -125.918697) (xy 242.605751 -125.941339) (xy 242.651601 -125.970805) (xy 242.692792 -126.006496)
			(xy 242.728483 -126.047687) (xy 242.757949 -126.093537) (xy 242.780591 -126.143114) (xy 242.795946 -126.195409)
			(xy 242.803702 -126.249357) (xy 242.804188 -126.276608) (xy 242.804188 -127.140208) (xy 242.803702 -127.167459)
			(xy 242.795946 -127.221407) (xy 242.780591 -127.273702) (xy 242.757949 -127.323279) (xy 242.728483 -127.369129)
			(xy 242.692792 -127.41032) (xy 242.651601 -127.446011) (xy 242.605751 -127.475477) (xy 242.556174 -127.498119)
			(xy 242.503879 -127.513474) (xy 242.449931 -127.52123) (xy 242.395429 -127.52123) (xy 242.341481 -127.513474)
			(xy 242.289186 -127.498119) (xy 242.239609 -127.475477) (xy 242.193759 -127.446011) (xy 242.152568 -127.41032)
			(xy 242.116877 -127.369129) (xy 242.087411 -127.323279) (xy 242.064769 -127.273702) (xy 242.049414 -127.221407)
			(xy 242.041658 -127.167459) (xy 242.041172 -127.140208) (xy 227.797868 -127.140208) (xy 227.797868 -127.325628)
			(xy 227.797382 -127.352879) (xy 227.789626 -127.406827) (xy 227.774271 -127.459122) (xy 227.751629 -127.508699)
			(xy 227.722163 -127.554549) (xy 227.686472 -127.59574) (xy 227.645281 -127.631431) (xy 227.599431 -127.660897)
			(xy 227.549854 -127.683539) (xy 227.519478 -127.692458) (xy 458.401155 -127.692458) (xy 458.401155 -127.563318)
			(xy 458.409105 -127.434423) (xy 458.424975 -127.306263) (xy 458.448704 -127.179322) (xy 458.480203 -127.054083)
			(xy 458.519352 -126.93102) (xy 458.566003 -126.810601) (xy 458.619978 -126.693282) (xy 458.681073 -126.579508)
			(xy 458.749056 -126.469711) (xy 458.82367 -126.364308) (xy 458.904631 -126.263698) (xy 458.991631 -126.168263)
			(xy 459.084342 -126.078364) (xy 459.182412 -125.994343) (xy 459.285467 -125.916519) (xy 459.393118 -125.845187)
			(xy 459.504957 -125.780617) (xy 459.620558 -125.723055) (xy 459.739483 -125.672718) (xy 459.861282 -125.629798)
			(xy 459.985492 -125.594457) (xy 460.111641 -125.56683) (xy 460.239253 -125.547021) (xy 460.367842 -125.535105)
			(xy 460.49692 -125.531129) (xy 460.625998 -125.535105) (xy 460.754587 -125.547021) (xy 460.882199 -125.56683)
			(xy 461.008348 -125.594457) (xy 461.132558 -125.629798) (xy 461.254357 -125.672718) (xy 461.373282 -125.723055)
			(xy 461.488883 -125.780617) (xy 461.600722 -125.845187) (xy 461.708373 -125.916519) (xy 461.811428 -125.994343)
			(xy 461.909498 -126.078364) (xy 462.002209 -126.168263) (xy 462.089209 -126.263698) (xy 462.17017 -126.364308)
			(xy 462.244784 -126.469711) (xy 462.312767 -126.579508) (xy 462.373862 -126.693282) (xy 462.427837 -126.810601)
			(xy 462.474488 -126.93102) (xy 462.513637 -127.054083) (xy 462.545136 -127.179322) (xy 462.568865 -127.306263)
			(xy 462.584735 -127.434423) (xy 462.592685 -127.563318) (xy 462.593182 -127.627888) (xy 462.592685 -127.692458)
			(xy 462.584735 -127.821353) (xy 462.568865 -127.949513) (xy 462.545136 -128.076454) (xy 462.513637 -128.201693)
			(xy 462.474488 -128.324756) (xy 462.427837 -128.445175) (xy 462.373862 -128.562494) (xy 462.312767 -128.676268)
			(xy 462.244784 -128.786065) (xy 462.17017 -128.891468) (xy 462.089209 -128.992078) (xy 462.002209 -129.087513)
			(xy 461.909498 -129.177412) (xy 461.811428 -129.261433) (xy 461.708373 -129.339257) (xy 461.600722 -129.410589)
			(xy 461.488883 -129.475159) (xy 461.373282 -129.532721) (xy 461.254357 -129.583058) (xy 461.132558 -129.625978)
			(xy 461.008348 -129.661319) (xy 460.882199 -129.688946) (xy 460.754587 -129.708755) (xy 460.625998 -129.720671)
			(xy 460.49692 -129.724648) (xy 460.367842 -129.720671) (xy 460.239253 -129.708755) (xy 460.111641 -129.688946)
			(xy 459.985492 -129.661319) (xy 459.861282 -129.625978) (xy 459.739483 -129.583058) (xy 459.620558 -129.532721)
			(xy 459.504957 -129.475159) (xy 459.393118 -129.410589) (xy 459.285467 -129.339257) (xy 459.182412 -129.261433)
			(xy 459.084342 -129.177412) (xy 458.991631 -129.087513) (xy 458.904631 -128.992078) (xy 458.82367 -128.891468)
			(xy 458.749056 -128.786065) (xy 458.681073 -128.676268) (xy 458.619978 -128.562494) (xy 458.566003 -128.445175)
			(xy 458.519352 -128.324756) (xy 458.480203 -128.201693) (xy 458.448704 -128.076454) (xy 458.424975 -127.949513)
			(xy 458.409105 -127.821353) (xy 458.401155 -127.692458) (xy 227.519478 -127.692458) (xy 227.497559 -127.698894)
			(xy 227.443611 -127.70665) (xy 227.389109 -127.70665) (xy 227.335161 -127.698894) (xy 227.282866 -127.683539)
			(xy 227.233289 -127.660897) (xy 227.187439 -127.631431) (xy 227.146248 -127.59574) (xy 227.110557 -127.554549)
			(xy 227.081091 -127.508699) (xy 227.058449 -127.459122) (xy 227.043094 -127.406827) (xy 227.035338 -127.352879)
			(xy 227.034852 -127.325628) (xy 2.509012 -127.325628) (xy 2.509012 -129.073148) (xy 223.562672 -129.073148)
			(xy 223.562672 -128.209548) (xy 223.563115 -128.182788) (xy 223.570596 -128.129795) (xy 223.585403 -128.078365)
			(xy 223.607247 -128.029506) (xy 223.621092 -128.006602) (xy 223.636032 -127.983032) (xy 223.671662 -127.940084)
			(xy 223.713174 -127.902792) (xy 223.759681 -127.871951) (xy 223.810187 -127.848221) (xy 223.863614 -127.832109)
			(xy 223.918819 -127.823961) (xy 223.94672 -127.823468) (xy 223.973934 -127.823967) (xy 224.027808 -127.831715)
			(xy 224.080031 -127.84705) (xy 224.12954 -127.869661) (xy 224.175327 -127.899088) (xy 224.216462 -127.93473)
			(xy 224.252105 -127.975863) (xy 224.281533 -128.02165) (xy 224.304145 -128.071158) (xy 224.319483 -128.123381)
			(xy 224.327232 -128.177254) (xy 224.32772 -128.204468) (xy 224.32772 -128.204722) (xy 224.325942 -128.241552)
			(xy 224.325688 -128.243838) (xy 224.325688 -129.019808) (xy 240.086896 -129.019808) (xy 240.086896 -128.156208)
			(xy 240.087382 -128.128939) (xy 240.095144 -128.074955) (xy 240.110509 -128.022625) (xy 240.133166 -127.973015)
			(xy 240.162652 -127.927134) (xy 240.198367 -127.885917) (xy 240.239584 -127.850202) (xy 240.285465 -127.820716)
			(xy 240.335075 -127.798059) (xy 240.387405 -127.782694) (xy 240.441389 -127.774932) (xy 240.495927 -127.774932)
			(xy 240.549911 -127.782694) (xy 240.602241 -127.798059) (xy 240.651851 -127.820716) (xy 240.697732 -127.850202)
			(xy 240.738949 -127.885917) (xy 240.774664 -127.927134) (xy 240.80415 -127.973015) (xy 240.826807 -128.022625)
			(xy 240.842172 -128.074955) (xy 240.849934 -128.128939) (xy 240.85042 -128.156208) (xy 240.85042 -129.019808)
			(xy 240.849934 -129.047077) (xy 240.842172 -129.101061) (xy 240.826807 -129.153391) (xy 240.80415 -129.203001)
			(xy 240.774664 -129.248882) (xy 240.738949 -129.290099) (xy 240.697732 -129.325814) (xy 240.651851 -129.3553)
			(xy 240.602241 -129.377957) (xy 240.549911 -129.393322) (xy 240.495927 -129.401084) (xy 240.441389 -129.401084)
			(xy 240.387405 -129.393322) (xy 240.335075 -129.377957) (xy 240.285465 -129.3553) (xy 240.239584 -129.325814)
			(xy 240.198367 -129.290099) (xy 240.162652 -129.248882) (xy 240.133166 -129.203001) (xy 240.110509 -129.153391)
			(xy 240.095144 -129.101061) (xy 240.087382 -129.047077) (xy 240.086896 -129.019808) (xy 224.325688 -129.019808)
			(xy 224.325942 -129.022602) (xy 224.327226 -129.033861) (xy 224.328622 -129.056482) (xy 224.328736 -129.067814)
			(xy 224.328736 -129.068068) (xy 224.328226 -129.095352) (xy 224.320425 -129.14936) (xy 224.305035 -129.201713)
			(xy 224.282367 -129.251351) (xy 224.26803 -129.27457) (xy 224.253042 -129.297814) (xy 224.217376 -129.340083)
			(xy 224.175977 -129.376756) (xy 224.129714 -129.407061) (xy 224.079557 -129.430365) (xy 224.026559 -129.446176)
			(xy 223.971833 -129.454165) (xy 223.94418 -129.454656) (xy 223.91693 -129.454141) (xy 223.862986 -129.446383)
			(xy 223.810695 -129.431028) (xy 223.761121 -129.408388) (xy 223.715273 -129.378924) (xy 223.674084 -129.343236)
			(xy 223.638393 -129.30205) (xy 223.608926 -129.256204) (xy 223.586282 -129.206631) (xy 223.570923 -129.154341)
			(xy 223.563161 -129.100398) (xy 223.562672 -129.073148) (xy 2.509012 -129.073148) (xy 2.509012 -131.09702)
			(xy 228.682804 -131.09702) (xy 228.682804 -130.23342) (xy 228.68329 -130.206151) (xy 228.691052 -130.152167)
			(xy 228.706417 -130.099837) (xy 228.729074 -130.050227) (xy 228.75856 -130.004346) (xy 228.794275 -129.963129)
			(xy 228.835492 -129.927414) (xy 228.881373 -129.897928) (xy 228.930983 -129.875271) (xy 228.983313 -129.859906)
			(xy 229.037297 -129.852144) (xy 229.091835 -129.852144) (xy 229.145819 -129.859906) (xy 229.198149 -129.875271)
			(xy 229.247759 -129.897928) (xy 229.29364 -129.927414) (xy 229.334857 -129.963129) (xy 229.370572 -130.004346)
			(xy 229.400058 -130.050227) (xy 229.422715 -130.099837) (xy 229.43808 -130.152167) (xy 229.445842 -130.206151)
			(xy 229.446328 -130.23342) (xy 229.446328 -130.721608) (xy 242.041172 -130.721608) (xy 242.041172 -129.858008)
			(xy 242.041658 -129.830757) (xy 242.049414 -129.776809) (xy 242.064769 -129.724514) (xy 242.087411 -129.674937)
			(xy 242.116877 -129.629087) (xy 242.152568 -129.587896) (xy 242.193759 -129.552205) (xy 242.239609 -129.522739)
			(xy 242.289186 -129.500097) (xy 242.341481 -129.484742) (xy 242.395429 -129.476986) (xy 242.449931 -129.476986)
			(xy 242.503879 -129.484742) (xy 242.556174 -129.500097) (xy 242.605751 -129.522739) (xy 242.651601 -129.552205)
			(xy 242.692792 -129.587896) (xy 242.728483 -129.629087) (xy 242.757949 -129.674937) (xy 242.780591 -129.724514)
			(xy 242.795946 -129.776809) (xy 242.803702 -129.830757) (xy 242.804188 -129.858008) (xy 242.804188 -130.721608)
			(xy 242.803702 -130.748859) (xy 242.795946 -130.802807) (xy 242.780591 -130.855102) (xy 242.757949 -130.904679)
			(xy 242.728483 -130.950529) (xy 242.692792 -130.99172) (xy 242.651601 -131.027411) (xy 242.605751 -131.056877)
			(xy 242.556174 -131.079519) (xy 242.503879 -131.094874) (xy 242.449931 -131.10263) (xy 242.395429 -131.10263)
			(xy 242.341481 -131.094874) (xy 242.289186 -131.079519) (xy 242.239609 -131.056877) (xy 242.193759 -131.027411)
			(xy 242.152568 -130.99172) (xy 242.116877 -130.950529) (xy 242.087411 -130.904679) (xy 242.064769 -130.855102)
			(xy 242.049414 -130.802807) (xy 242.041658 -130.748859) (xy 242.041172 -130.721608) (xy 229.446328 -130.721608)
			(xy 229.446328 -131.09702) (xy 229.445842 -131.124289) (xy 229.43808 -131.178273) (xy 229.422715 -131.230603)
			(xy 229.400058 -131.280213) (xy 229.370572 -131.326094) (xy 229.334857 -131.367311) (xy 229.29364 -131.403026)
			(xy 229.247759 -131.432512) (xy 229.198149 -131.455169) (xy 229.145819 -131.470534) (xy 229.091835 -131.478296)
			(xy 229.037297 -131.478296) (xy 228.983313 -131.470534) (xy 228.930983 -131.455169) (xy 228.881373 -131.432512)
			(xy 228.835492 -131.403026) (xy 228.794275 -131.367311) (xy 228.75856 -131.326094) (xy 228.729074 -131.280213)
			(xy 228.706417 -131.230603) (xy 228.691052 -131.178273) (xy 228.68329 -131.124289) (xy 228.682804 -131.09702)
			(xy 2.509012 -131.09702) (xy 2.509012 -132.529347) (xy 231.621126 -132.529347) (xy 231.621126 -132.474853)
			(xy 231.628881 -132.420915) (xy 231.644233 -132.368628) (xy 231.666869 -132.319059) (xy 231.69633 -132.273216)
			(xy 231.732014 -132.232031) (xy 231.773196 -132.196344) (xy 231.819038 -132.166881) (xy 231.868606 -132.144241)
			(xy 231.920891 -132.128886) (xy 231.974829 -132.121128) (xy 232.002076 -132.12064) (xy 232.865676 -132.12064)
			(xy 232.892933 -132.121005) (xy 232.946894 -132.128761) (xy 232.999201 -132.144116) (xy 233.048791 -132.16676)
			(xy 233.094653 -132.196231) (xy 233.135853 -132.23193) (xy 233.171554 -132.273128) (xy 233.201028 -132.318988)
			(xy 233.223675 -132.368576) (xy 233.239034 -132.420883) (xy 233.246793 -132.474843) (xy 233.246793 -132.529357)
			(xy 233.239034 -132.583317) (xy 233.223675 -132.635624) (xy 233.201028 -132.685212) (xy 233.171554 -132.731072)
			(xy 233.135853 -132.77227) (xy 233.094653 -132.807968) (xy 233.048791 -132.83744) (xy 232.999201 -132.860084)
			(xy 232.946894 -132.875439) (xy 232.892933 -132.883195) (xy 232.865676 -132.883656) (xy 232.002076 -132.883656)
			(xy 231.974829 -132.883072) (xy 231.920891 -132.875314) (xy 231.868606 -132.859959) (xy 231.819038 -132.837319)
			(xy 231.773196 -132.807856) (xy 231.732014 -132.772169) (xy 231.69633 -132.730984) (xy 231.666869 -132.685141)
			(xy 231.644233 -132.635572) (xy 231.628881 -132.583285) (xy 231.621126 -132.529347) (xy 2.509012 -132.529347)
			(xy 2.509012 -135.31065) (xy 225.204003 -135.31065) (xy 225.204003 -135.25615) (xy 225.21176 -135.202204)
			(xy 225.227115 -135.149911) (xy 225.249756 -135.100336) (xy 225.279222 -135.054487) (xy 225.314914 -135.013299)
			(xy 225.356103 -134.97761) (xy 225.401953 -134.948146) (xy 225.45153 -134.925508) (xy 225.503823 -134.910156)
			(xy 225.55777 -134.902402) (xy 225.58502 -134.90194) (xy 226.44862 -134.90194) (xy 226.475874 -134.902331)
			(xy 226.529826 -134.910091) (xy 226.582125 -134.92545) (xy 226.631706 -134.948095) (xy 226.67756 -134.977566)
			(xy 226.718753 -135.013262) (xy 226.754446 -135.054456) (xy 226.755856 -135.05665) (xy 228.531403 -135.05665)
			(xy 228.531403 -135.00215) (xy 228.53916 -134.948204) (xy 228.554515 -134.895911) (xy 228.577156 -134.846336)
			(xy 228.606622 -134.800487) (xy 228.642314 -134.759299) (xy 228.683503 -134.72361) (xy 228.729353 -134.694146)
			(xy 228.77893 -134.671508) (xy 228.831223 -134.656156) (xy 228.88517 -134.648402) (xy 228.91242 -134.64794)
			(xy 229.77602 -134.64794) (xy 229.803274 -134.648331) (xy 229.857226 -134.656091) (xy 229.909525 -134.67145)
			(xy 229.959106 -134.694095) (xy 230.00496 -134.723566) (xy 230.046153 -134.759262) (xy 230.081846 -134.800456)
			(xy 230.111315 -134.846312) (xy 230.133957 -134.895894) (xy 230.149313 -134.948193) (xy 230.15707 -135.002146)
			(xy 230.15707 -135.056654) (xy 230.149313 -135.110607) (xy 230.145996 -135.121904) (xy 234.029504 -135.121904)
			(xy 234.029504 -134.258304) (xy 234.02999 -134.231035) (xy 234.037752 -134.177051) (xy 234.053117 -134.124721)
			(xy 234.075774 -134.075111) (xy 234.10526 -134.02923) (xy 234.140975 -133.988013) (xy 234.182192 -133.952298)
			(xy 234.228073 -133.922812) (xy 234.277683 -133.900155) (xy 234.330013 -133.88479) (xy 234.383997 -133.877028)
			(xy 234.438535 -133.877028) (xy 234.492519 -133.88479) (xy 234.544849 -133.900155) (xy 234.594459 -133.922812)
			(xy 234.64034 -133.952298) (xy 234.681557 -133.988013) (xy 234.717272 -134.02923) (xy 234.746758 -134.075111)
			(xy 234.769415 -134.124721) (xy 234.78478 -134.177051) (xy 234.792542 -134.231035) (xy 234.793028 -134.258304)
			(xy 234.793028 -134.768971) (xy 236.02439 -134.768971) (xy 236.02439 -134.714429) (xy 236.032152 -134.660443)
			(xy 236.047518 -134.608111) (xy 236.070174 -134.558498) (xy 236.09966 -134.512615) (xy 236.135376 -134.471394)
			(xy 236.176594 -134.435676) (xy 236.222475 -134.406186) (xy 236.272087 -134.383527) (xy 236.324418 -134.368158)
			(xy 236.378403 -134.360392) (xy 236.405674 -134.359904) (xy 237.178342 -134.359904) (xy 237.205607 -134.360461)
			(xy 237.259581 -134.368227) (xy 237.311901 -134.383595) (xy 237.361502 -134.406251) (xy 237.407373 -134.435736)
			(xy 237.448582 -134.471448) (xy 237.48429 -134.512661) (xy 237.513769 -134.558535) (xy 237.53642 -134.608138)
			(xy 237.551782 -134.66046) (xy 237.559542 -134.714435) (xy 237.559542 -134.768965) (xy 237.551782 -134.82294)
			(xy 237.53642 -134.875262) (xy 237.513769 -134.924865) (xy 237.48429 -134.970739) (xy 237.448582 -135.011952)
			(xy 237.407373 -135.047664) (xy 237.361502 -135.077149) (xy 237.311901 -135.099805) (xy 237.259581 -135.115173)
			(xy 237.205607 -135.122939) (xy 237.178342 -135.123428) (xy 236.405674 -135.123428) (xy 236.378403 -135.123008)
			(xy 236.324418 -135.115242) (xy 236.272087 -135.099873) (xy 236.222475 -135.077214) (xy 236.176594 -135.047724)
			(xy 236.135376 -135.012006) (xy 236.09966 -134.970785) (xy 236.070174 -134.924902) (xy 236.047518 -134.875289)
			(xy 236.032152 -134.822957) (xy 236.02439 -134.768971) (xy 234.793028 -134.768971) (xy 234.793028 -135.121904)
			(xy 234.792542 -135.149173) (xy 234.786383 -135.192008) (xy 238.645192 -135.192008) (xy 238.645192 -134.328408)
			(xy 238.645678 -134.301157) (xy 238.653434 -134.247209) (xy 238.668789 -134.194914) (xy 238.691431 -134.145337)
			(xy 238.720897 -134.099487) (xy 238.756588 -134.058296) (xy 238.797779 -134.022605) (xy 238.843629 -133.993139)
			(xy 238.893206 -133.970497) (xy 238.945501 -133.955142) (xy 238.999449 -133.947386) (xy 239.053951 -133.947386)
			(xy 239.107899 -133.955142) (xy 239.160194 -133.970497) (xy 239.209771 -133.993139) (xy 239.255621 -134.022605)
			(xy 239.271831 -134.036651) (xy 242.034062 -134.036651) (xy 242.034062 -133.982149) (xy 242.041817 -133.928203)
			(xy 242.057171 -133.875909) (xy 242.07981 -133.826333) (xy 242.109274 -133.780482) (xy 242.144963 -133.739291)
			(xy 242.18615 -133.703598) (xy 242.231997 -133.67413) (xy 242.281572 -133.651485) (xy 242.333864 -133.636126)
			(xy 242.387809 -133.628365) (xy 242.41506 -133.627876) (xy 243.27866 -133.627876) (xy 243.305914 -133.628369)
			(xy 243.359867 -133.636121) (xy 243.412167 -133.651473) (xy 243.46175 -133.674112) (xy 243.507606 -133.703577)
			(xy 243.548802 -133.73927) (xy 243.584499 -133.780462) (xy 243.613969 -133.826315) (xy 243.636613 -133.875895)
			(xy 243.651971 -133.928194) (xy 243.659729 -133.982146) (xy 243.659729 -134.036654) (xy 243.651971 -134.090606)
			(xy 243.636613 -134.142905) (xy 243.613969 -134.192485) (xy 243.584499 -134.238338) (xy 243.548802 -134.27953)
			(xy 243.507606 -134.315223) (xy 243.46175 -134.344688) (xy 243.412167 -134.367327) (xy 243.359867 -134.382679)
			(xy 243.305914 -134.390431) (xy 243.27866 -134.390892) (xy 242.41506 -134.390892) (xy 242.387809 -134.390435)
			(xy 242.333864 -134.382674) (xy 242.281572 -134.367315) (xy 242.231997 -134.34467) (xy 242.18615 -134.315202)
			(xy 242.144963 -134.279509) (xy 242.109274 -134.238318) (xy 242.07981 -134.192467) (xy 242.057171 -134.142891)
			(xy 242.041817 -134.090597) (xy 242.034062 -134.036651) (xy 239.271831 -134.036651) (xy 239.296812 -134.058296)
			(xy 239.332503 -134.099487) (xy 239.361969 -134.145337) (xy 239.384611 -134.194914) (xy 239.399966 -134.247209)
			(xy 239.407722 -134.301157) (xy 239.408208 -134.328408) (xy 239.408208 -135.192008) (xy 239.407722 -135.219259)
			(xy 239.399966 -135.273207) (xy 239.384611 -135.325502) (xy 239.361969 -135.375079) (xy 239.332503 -135.420929)
			(xy 239.296812 -135.46212) (xy 239.255621 -135.497811) (xy 239.250425 -135.50115) (xy 244.457203 -135.50115)
			(xy 244.457203 -135.44665) (xy 244.46496 -135.392704) (xy 244.480315 -135.340411) (xy 244.502956 -135.290836)
			(xy 244.532422 -135.244987) (xy 244.568114 -135.203799) (xy 244.609303 -135.16811) (xy 244.655153 -135.138646)
			(xy 244.70473 -135.116008) (xy 244.757023 -135.100656) (xy 244.81097 -135.092902) (xy 244.83822 -135.09244)
			(xy 245.70182 -135.09244) (xy 245.729074 -135.092831) (xy 245.783026 -135.100591) (xy 245.835325 -135.11595)
			(xy 245.884906 -135.138595) (xy 245.93076 -135.168066) (xy 245.971953 -135.203762) (xy 246.007646 -135.244956)
			(xy 246.037115 -135.290812) (xy 246.059757 -135.340394) (xy 246.075113 -135.392693) (xy 246.08287 -135.446646)
			(xy 246.08287 -135.501154) (xy 246.075113 -135.555107) (xy 246.059757 -135.607406) (xy 246.037115 -135.656988)
			(xy 246.007646 -135.702844) (xy 245.971953 -135.744038) (xy 245.93076 -135.779734) (xy 245.884906 -135.809205)
			(xy 245.835325 -135.83185) (xy 245.783026 -135.847209) (xy 245.729074 -135.854969) (xy 245.70182 -135.855456)
			(xy 244.83822 -135.855456) (xy 244.81097 -135.854898) (xy 244.757023 -135.847144) (xy 244.70473 -135.831792)
			(xy 244.655153 -135.809154) (xy 244.609303 -135.77969) (xy 244.568114 -135.744001) (xy 244.532422 -135.702813)
			(xy 244.502956 -135.656964) (xy 244.480315 -135.607389) (xy 244.46496 -135.555096) (xy 244.457203 -135.50115)
			(xy 239.250425 -135.50115) (xy 239.209771 -135.527277) (xy 239.160194 -135.549919) (xy 239.107899 -135.565274)
			(xy 239.053951 -135.57303) (xy 238.999449 -135.57303) (xy 238.945501 -135.565274) (xy 238.893206 -135.549919)
			(xy 238.843629 -135.527277) (xy 238.797779 -135.497811) (xy 238.756588 -135.46212) (xy 238.720897 -135.420929)
			(xy 238.691431 -135.375079) (xy 238.668789 -135.325502) (xy 238.653434 -135.273207) (xy 238.645678 -135.219259)
			(xy 238.645192 -135.192008) (xy 234.786383 -135.192008) (xy 234.78478 -135.203157) (xy 234.769415 -135.255487)
			(xy 234.746758 -135.305097) (xy 234.717272 -135.350978) (xy 234.681557 -135.392195) (xy 234.64034 -135.42791)
			(xy 234.594459 -135.457396) (xy 234.544849 -135.480053) (xy 234.492519 -135.495418) (xy 234.438535 -135.50318)
			(xy 234.383997 -135.50318) (xy 234.330013 -135.495418) (xy 234.277683 -135.480053) (xy 234.228073 -135.457396)
			(xy 234.182192 -135.42791) (xy 234.140975 -135.392195) (xy 234.10526 -135.350978) (xy 234.075774 -135.305097)
			(xy 234.053117 -135.255487) (xy 234.037752 -135.203157) (xy 234.02999 -135.149173) (xy 234.029504 -135.121904)
			(xy 230.145996 -135.121904) (xy 230.133957 -135.162906) (xy 230.111315 -135.212488) (xy 230.081846 -135.258344)
			(xy 230.046153 -135.299538) (xy 230.00496 -135.335234) (xy 229.959106 -135.364705) (xy 229.909525 -135.38735)
			(xy 229.857226 -135.402709) (xy 229.803274 -135.410469) (xy 229.77602 -135.410956) (xy 228.91242 -135.410956)
			(xy 228.88517 -135.410398) (xy 228.831223 -135.402644) (xy 228.77893 -135.387292) (xy 228.729353 -135.364654)
			(xy 228.683503 -135.33519) (xy 228.642314 -135.299501) (xy 228.606622 -135.258313) (xy 228.577156 -135.212464)
			(xy 228.554515 -135.162889) (xy 228.53916 -135.110596) (xy 228.531403 -135.05665) (xy 226.755856 -135.05665)
			(xy 226.783915 -135.100312) (xy 226.806557 -135.149894) (xy 226.821913 -135.202193) (xy 226.82967 -135.256146)
			(xy 226.82967 -135.310654) (xy 226.821913 -135.364607) (xy 226.806557 -135.416906) (xy 226.783915 -135.466488)
			(xy 226.754446 -135.512344) (xy 226.718753 -135.553538) (xy 226.67756 -135.589234) (xy 226.631706 -135.618705)
			(xy 226.582125 -135.64135) (xy 226.529826 -135.656709) (xy 226.475874 -135.664469) (xy 226.44862 -135.664956)
			(xy 225.58502 -135.664956) (xy 225.55777 -135.664398) (xy 225.503823 -135.656644) (xy 225.45153 -135.641292)
			(xy 225.401953 -135.618654) (xy 225.356103 -135.58919) (xy 225.314914 -135.553501) (xy 225.279222 -135.512313)
			(xy 225.249756 -135.466464) (xy 225.227115 -135.416889) (xy 225.21176 -135.364596) (xy 225.204003 -135.31065)
			(xy 2.509012 -135.31065) (xy 2.509012 -137.199664) (xy 337.46447 -137.199664) (xy 337.46447 -137.145136)
			(xy 337.47223 -137.091163) (xy 337.487591 -137.038843) (xy 337.510241 -136.989242) (xy 337.539719 -136.943369)
			(xy 337.575425 -136.902158) (xy 337.616632 -136.866447) (xy 337.662502 -136.836963) (xy 337.7121 -136.814307)
			(xy 337.764418 -136.79894) (xy 337.81839 -136.791173) (xy 337.845654 -136.790684) (xy 338.618322 -136.790684)
			(xy 338.645594 -136.79108) (xy 338.699581 -136.798845) (xy 338.751915 -136.814214) (xy 338.801528 -136.836874)
			(xy 338.847412 -136.866364) (xy 338.888632 -136.902084) (xy 338.924349 -136.943306) (xy 338.953836 -136.989191)
			(xy 338.976493 -137.038806) (xy 338.991859 -137.09114) (xy 338.999622 -137.145128) (xy 338.999622 -137.199672)
			(xy 338.991859 -137.25366) (xy 338.976493 -137.305994) (xy 338.953836 -137.355609) (xy 338.924349 -137.401494)
			(xy 338.888632 -137.442716) (xy 338.847412 -137.478436) (xy 338.801528 -137.507926) (xy 338.751915 -137.530586)
			(xy 338.699581 -137.545955) (xy 338.645594 -137.55372) (xy 338.618322 -137.554208) (xy 337.845654 -137.554208)
			(xy 337.81839 -137.553627) (xy 337.764418 -137.54586) (xy 337.7121 -137.530493) (xy 337.662502 -137.507837)
			(xy 337.616632 -137.478353) (xy 337.575425 -137.442642) (xy 337.539719 -137.401431) (xy 337.510241 -137.355558)
			(xy 337.487591 -137.305957) (xy 337.47223 -137.253637) (xy 337.46447 -137.199664) (xy 2.509012 -137.199664)
			(xy 2.509012 -137.622788) (xy 340.085172 -137.622788) (xy 340.085172 -136.759188) (xy 340.085658 -136.731937)
			(xy 340.093414 -136.677989) (xy 340.108769 -136.625694) (xy 340.131411 -136.576117) (xy 340.160877 -136.530267)
			(xy 340.196568 -136.489076) (xy 340.237759 -136.453385) (xy 340.283609 -136.423919) (xy 340.333186 -136.401277)
			(xy 340.385481 -136.385922) (xy 340.439429 -136.378166) (xy 340.493931 -136.378166) (xy 340.547879 -136.385922)
			(xy 340.600174 -136.401277) (xy 340.649751 -136.423919) (xy 340.695601 -136.453385) (xy 340.736792 -136.489076)
			(xy 340.772483 -136.530267) (xy 340.801949 -136.576117) (xy 340.824591 -136.625694) (xy 340.839946 -136.677989)
			(xy 340.847702 -136.731937) (xy 340.848188 -136.759188) (xy 340.848188 -137.622788) (xy 340.847702 -137.650039)
			(xy 340.839946 -137.703987) (xy 340.824591 -137.756282) (xy 340.801949 -137.805859) (xy 340.772483 -137.851709)
			(xy 340.736792 -137.8929) (xy 340.695601 -137.928591) (xy 340.649751 -137.958057) (xy 340.600174 -137.980699)
			(xy 340.547879 -137.996054) (xy 340.493931 -138.00381) (xy 340.439429 -138.00381) (xy 340.385481 -137.996054)
			(xy 340.333186 -137.980699) (xy 340.283609 -137.958057) (xy 340.237759 -137.928591) (xy 340.196568 -137.8929)
			(xy 340.160877 -137.851709) (xy 340.131411 -137.805859) (xy 340.108769 -137.756282) (xy 340.093414 -137.703987)
			(xy 340.085658 -137.650039) (xy 340.085172 -137.622788) (xy 2.509012 -137.622788) (xy 2.509012 -153.766012)
			(xy 24.445731 -153.766012) (xy 24.449724 -153.556271) (xy 24.4617 -153.346834) (xy 24.481641 -153.138005)
			(xy 24.509518 -152.930086) (xy 24.54529 -152.723379) (xy 24.588905 -152.518184) (xy 24.640301 -152.314799)
			(xy 24.699403 -152.113517) (xy 24.766125 -151.914631) (xy 24.84037 -151.71843) (xy 24.92203 -151.525198)
			(xy 25.010988 -151.335214) (xy 25.107115 -151.148755) (xy 25.21027 -150.966091) (xy 25.320305 -150.787486)
			(xy 25.437059 -150.6132) (xy 25.560364 -150.443485) (xy 25.690041 -150.278587) (xy 25.825902 -150.118746)
			(xy 25.967749 -149.964193) (xy 26.115378 -149.815153) (xy 26.268573 -149.67184) (xy 26.427114 -149.534464)
			(xy 26.590769 -149.403223) (xy 26.759303 -149.278308) (xy 26.932469 -149.1599) (xy 27.110019 -149.04817)
			(xy 27.291693 -148.94328) (xy 27.477228 -148.845383) (xy 27.666356 -148.754621) (xy 27.858803 -148.671124)
			(xy 28.054288 -148.595014) (xy 28.25253 -148.526402) (xy 28.45324 -148.465387) (xy 28.656127 -148.412058)
			(xy 28.860897 -148.366491) (xy 29.067254 -148.328752) (xy 29.274898 -148.298898) (xy 29.483528 -148.27697)
			(xy 29.692841 -148.263001) (xy 29.902535 -148.25701) (xy 30.112304 -148.259007) (xy 30.321846 -148.268989)
			(xy 30.530856 -148.286941) (xy 30.73903 -148.312837) (xy 30.946068 -148.346639) (xy 31.151669 -148.388299)
			(xy 31.355535 -148.437757) (xy 31.55737 -148.49494) (xy 31.756882 -148.559765) (xy 31.953781 -148.632139)
			(xy 32.147782 -148.711956) (xy 32.338604 -148.799102) (xy 32.52597 -148.893449) (xy 32.709608 -148.99486)
			(xy 32.889252 -149.10319) (xy 33.064642 -149.21828) (xy 33.235523 -149.339964) (xy 33.401647 -149.468065)
			(xy 33.562774 -149.602398) (xy 33.718671 -149.742767) (xy 33.86911 -149.88897) (xy 34.013874 -150.040794)
			(xy 34.152753 -150.19802) (xy 34.285546 -150.360419) (xy 34.41206 -150.527755) (xy 34.532112 -150.699787)
			(xy 34.645527 -150.876264) (xy 34.752141 -151.056932) (xy 34.8518 -151.241527) (xy 34.944359 -151.429782)
			(xy 35.029684 -151.621425) (xy 35.107651 -151.816177) (xy 35.178147 -152.013757) (xy 35.24107 -152.213876)
			(xy 35.296329 -152.416247) (xy 35.343843 -152.620574) (xy 35.383544 -152.826562) (xy 35.415374 -153.033913)
			(xy 35.439287 -153.242324) (xy 35.455248 -153.451495) (xy 35.463235 -153.661122) (xy 35.463734 -153.766012)
			(xy 35.463235 -153.870902) (xy 35.455248 -154.080529) (xy 35.44312 -154.239468) (xy 186.742832 -154.239468)
			(xy 186.742832 -153.375868) (xy 186.743318 -153.348617) (xy 186.751074 -153.294669) (xy 186.766429 -153.242374)
			(xy 186.789071 -153.192797) (xy 186.818537 -153.146947) (xy 186.854228 -153.105756) (xy 186.895419 -153.070065)
			(xy 186.941269 -153.040599) (xy 186.990846 -153.017957) (xy 187.043141 -153.002602) (xy 187.097089 -152.994846)
			(xy 187.151591 -152.994846) (xy 187.205539 -153.002602) (xy 187.257834 -153.017957) (xy 187.307411 -153.040599)
			(xy 187.353261 -153.070065) (xy 187.394452 -153.105756) (xy 187.430143 -153.146947) (xy 187.459609 -153.192797)
			(xy 187.482251 -153.242374) (xy 187.497606 -153.294669) (xy 187.505362 -153.348617) (xy 187.505848 -153.375868)
			(xy 187.505848 -153.774902) (xy 188.445657 -153.774902) (xy 188.44965 -153.565161) (xy 188.461626 -153.355724)
			(xy 188.481567 -153.146895) (xy 188.509444 -152.938976) (xy 188.545216 -152.732269) (xy 188.588831 -152.527074)
			(xy 188.640227 -152.323689) (xy 188.699329 -152.122407) (xy 188.766051 -151.923521) (xy 188.840296 -151.72732)
			(xy 188.921956 -151.534088) (xy 189.010914 -151.344104) (xy 189.107041 -151.157645) (xy 189.210196 -150.974981)
			(xy 189.320231 -150.796376) (xy 189.436985 -150.62209) (xy 189.56029 -150.452375) (xy 189.689967 -150.287477)
			(xy 189.825828 -150.127636) (xy 189.967675 -149.973083) (xy 190.115304 -149.824043) (xy 190.268499 -149.68073)
			(xy 190.42704 -149.543354) (xy 190.590695 -149.412113) (xy 190.759229 -149.287198) (xy 190.932395 -149.16879)
			(xy 191.109945 -149.05706) (xy 191.291619 -148.95217) (xy 191.477154 -148.854273) (xy 191.666282 -148.763511)
			(xy 191.858729 -148.680014) (xy 192.054214 -148.603904) (xy 192.252456 -148.535292) (xy 192.453166 -148.474277)
			(xy 192.656053 -148.420948) (xy 192.860823 -148.375381) (xy 193.06718 -148.337642) (xy 193.274824 -148.307788)
			(xy 193.483454 -148.28586) (xy 193.692767 -148.271891) (xy 193.902461 -148.2659) (xy 194.11223 -148.267897)
			(xy 194.321772 -148.277879) (xy 194.530782 -148.295831) (xy 194.738956 -148.321727) (xy 194.945994 -148.355529)
			(xy 195.151595 -148.397189) (xy 195.355461 -148.446647) (xy 195.557296 -148.50383) (xy 195.756808 -148.568655)
			(xy 195.953707 -148.641029) (xy 196.147708 -148.720846) (xy 196.33853 -148.807992) (xy 196.525896 -148.902339)
			(xy 196.709534 -149.00375) (xy 196.889178 -149.11208) (xy 197.064568 -149.22717) (xy 197.235449 -149.348854)
			(xy 197.401573 -149.476955) (xy 197.5627 -149.611288) (xy 197.718597 -149.751657) (xy 197.869036 -149.89786)
			(xy 198.0138 -150.049684) (xy 198.152679 -150.20691) (xy 198.285472 -150.369309) (xy 198.411986 -150.536645)
			(xy 198.532038 -150.708677) (xy 198.645453 -150.885154) (xy 198.752067 -151.065822) (xy 198.851726 -151.250417)
			(xy 198.944285 -151.438672) (xy 199.02961 -151.630315) (xy 199.107577 -151.825067) (xy 199.178073 -152.022647)
			(xy 199.240996 -152.222766) (xy 199.296255 -152.425137) (xy 199.343769 -152.629464) (xy 199.38347 -152.835452)
			(xy 199.4153 -153.042803) (xy 199.439213 -153.251214) (xy 199.455174 -153.460385) (xy 199.463161 -153.670012)
			(xy 199.463618 -153.766012) (xy 272.385799 -153.766012) (xy 272.389792 -153.556271) (xy 272.401768 -153.346834)
			(xy 272.421709 -153.138005) (xy 272.449586 -152.930086) (xy 272.485358 -152.723379) (xy 272.528973 -152.518184)
			(xy 272.580369 -152.314799) (xy 272.639471 -152.113517) (xy 272.706193 -151.914631) (xy 272.780438 -151.71843)
			(xy 272.862098 -151.525198) (xy 272.951056 -151.335214) (xy 273.047183 -151.148755) (xy 273.150338 -150.966091)
			(xy 273.260373 -150.787486) (xy 273.377127 -150.6132) (xy 273.500432 -150.443485) (xy 273.630109 -150.278587)
			(xy 273.76597 -150.118746) (xy 273.907817 -149.964193) (xy 274.055446 -149.815153) (xy 274.208641 -149.67184)
			(xy 274.367182 -149.534464) (xy 274.530837 -149.403223) (xy 274.699371 -149.278308) (xy 274.872537 -149.1599)
			(xy 275.050087 -149.04817) (xy 275.231761 -148.94328) (xy 275.417296 -148.845383) (xy 275.606424 -148.754621)
			(xy 275.798871 -148.671124) (xy 275.994356 -148.595014) (xy 276.192598 -148.526402) (xy 276.393308 -148.465387)
			(xy 276.596195 -148.412058) (xy 276.800965 -148.366491) (xy 277.007322 -148.328752) (xy 277.214966 -148.298898)
			(xy 277.423596 -148.27697) (xy 277.632909 -148.263001) (xy 277.842603 -148.25701) (xy 278.052372 -148.259007)
			(xy 278.261914 -148.268989) (xy 278.470924 -148.286941) (xy 278.679098 -148.312837) (xy 278.886136 -148.346639)
			(xy 279.091737 -148.388299) (xy 279.295603 -148.437757) (xy 279.497438 -148.49494) (xy 279.69695 -148.559765)
			(xy 279.893849 -148.632139) (xy 280.08785 -148.711956) (xy 280.278672 -148.799102) (xy 280.466038 -148.893449)
			(xy 280.649676 -148.99486) (xy 280.82932 -149.10319) (xy 281.00471 -149.21828) (xy 281.175591 -149.339964)
			(xy 281.341715 -149.468065) (xy 281.502842 -149.602398) (xy 281.658739 -149.742767) (xy 281.809178 -149.88897)
			(xy 281.953942 -150.040794) (xy 282.092821 -150.19802) (xy 282.225614 -150.360419) (xy 282.352128 -150.527755)
			(xy 282.47218 -150.699787) (xy 282.585595 -150.876264) (xy 282.692209 -151.056932) (xy 282.791868 -151.241527)
			(xy 282.884427 -151.429782) (xy 282.969752 -151.621425) (xy 283.047719 -151.816177) (xy 283.118215 -152.013757)
			(xy 283.181138 -152.213876) (xy 283.236397 -152.416247) (xy 283.283911 -152.620574) (xy 283.323612 -152.826562)
			(xy 283.355442 -153.033913) (xy 283.379355 -153.242324) (xy 283.395316 -153.451495) (xy 283.403303 -153.661122)
			(xy 283.403802 -153.766012) (xy 283.40376 -153.774902) (xy 436.385725 -153.774902) (xy 436.389718 -153.565161)
			(xy 436.401694 -153.355724) (xy 436.421635 -153.146895) (xy 436.449512 -152.938976) (xy 436.485284 -152.732269)
			(xy 436.528899 -152.527074) (xy 436.580295 -152.323689) (xy 436.639397 -152.122407) (xy 436.706119 -151.923521)
			(xy 436.780364 -151.72732) (xy 436.862024 -151.534088) (xy 436.950982 -151.344104) (xy 437.047109 -151.157645)
			(xy 437.150264 -150.974981) (xy 437.260299 -150.796376) (xy 437.377053 -150.62209) (xy 437.500358 -150.452375)
			(xy 437.630035 -150.287477) (xy 437.765896 -150.127636) (xy 437.907743 -149.973083) (xy 438.055372 -149.824043)
			(xy 438.208567 -149.68073) (xy 438.367108 -149.543354) (xy 438.530763 -149.412113) (xy 438.699297 -149.287198)
			(xy 438.872463 -149.16879) (xy 439.050013 -149.05706) (xy 439.231687 -148.95217) (xy 439.417222 -148.854273)
			(xy 439.60635 -148.763511) (xy 439.798797 -148.680014) (xy 439.994282 -148.603904) (xy 440.192524 -148.535292)
			(xy 440.393234 -148.474277) (xy 440.596121 -148.420948) (xy 440.800891 -148.375381) (xy 441.007248 -148.337642)
			(xy 441.214892 -148.307788) (xy 441.423522 -148.28586) (xy 441.632835 -148.271891) (xy 441.842529 -148.2659)
			(xy 442.052298 -148.267897) (xy 442.26184 -148.277879) (xy 442.47085 -148.295831) (xy 442.679024 -148.321727)
			(xy 442.886062 -148.355529) (xy 443.091663 -148.397189) (xy 443.295529 -148.446647) (xy 443.497364 -148.50383)
			(xy 443.696876 -148.568655) (xy 443.893775 -148.641029) (xy 444.087776 -148.720846) (xy 444.278598 -148.807992)
			(xy 444.465964 -148.902339) (xy 444.649602 -149.00375) (xy 444.829246 -149.11208) (xy 445.004636 -149.22717)
			(xy 445.175517 -149.348854) (xy 445.341641 -149.476955) (xy 445.502768 -149.611288) (xy 445.658665 -149.751657)
			(xy 445.809104 -149.89786) (xy 445.953868 -150.049684) (xy 446.092747 -150.20691) (xy 446.22554 -150.369309)
			(xy 446.352054 -150.536645) (xy 446.472106 -150.708677) (xy 446.585521 -150.885154) (xy 446.692135 -151.065822)
			(xy 446.791794 -151.250417) (xy 446.884353 -151.438672) (xy 446.969678 -151.630315) (xy 447.047645 -151.825067)
			(xy 447.118141 -152.022647) (xy 447.181064 -152.222766) (xy 447.236323 -152.425137) (xy 447.283837 -152.629464)
			(xy 447.323538 -152.835452) (xy 447.355368 -153.042803) (xy 447.379281 -153.251214) (xy 447.395242 -153.460385)
			(xy 447.403229 -153.670012) (xy 447.403728 -153.774902) (xy 447.403229 -153.879792) (xy 447.395242 -154.089419)
			(xy 447.379281 -154.29859) (xy 447.355368 -154.507001) (xy 447.323538 -154.714352) (xy 447.283837 -154.92034)
			(xy 447.236323 -155.124667) (xy 447.181064 -155.327038) (xy 447.118141 -155.527157) (xy 447.047645 -155.724737)
			(xy 446.969678 -155.919489) (xy 446.884353 -156.111132) (xy 446.791794 -156.299387) (xy 446.692135 -156.483982)
			(xy 446.585521 -156.66465) (xy 446.472106 -156.841127) (xy 446.352054 -157.013159) (xy 446.22554 -157.180495)
			(xy 446.092747 -157.342894) (xy 445.953868 -157.50012) (xy 445.809104 -157.651944) (xy 445.658665 -157.798147)
			(xy 445.502768 -157.938516) (xy 445.341641 -158.072849) (xy 445.175517 -158.20095) (xy 445.004636 -158.322634)
			(xy 444.829246 -158.437724) (xy 444.649602 -158.546054) (xy 444.465964 -158.647465) (xy 444.278598 -158.741812)
			(xy 444.087776 -158.828958) (xy 443.893775 -158.908775) (xy 443.696876 -158.981149) (xy 443.497364 -159.045974)
			(xy 443.295529 -159.103157) (xy 443.091663 -159.152615) (xy 442.886062 -159.194275) (xy 442.679024 -159.228077)
			(xy 442.47085 -159.253973) (xy 442.26184 -159.271925) (xy 442.052298 -159.281907) (xy 441.842529 -159.283904)
			(xy 441.632835 -159.277913) (xy 441.423522 -159.263944) (xy 441.214892 -159.242016) (xy 441.007248 -159.212162)
			(xy 440.800891 -159.174423) (xy 440.596121 -159.128856) (xy 440.393234 -159.075527) (xy 440.192524 -159.014512)
			(xy 439.994282 -158.9459) (xy 439.798797 -158.86979) (xy 439.60635 -158.786293) (xy 439.417222 -158.695531)
			(xy 439.231687 -158.597634) (xy 439.050013 -158.492744) (xy 438.872463 -158.381014) (xy 438.699297 -158.262606)
			(xy 438.530763 -158.137691) (xy 438.367108 -158.00645) (xy 438.208567 -157.869074) (xy 438.055372 -157.725761)
			(xy 437.907743 -157.576721) (xy 437.765896 -157.422168) (xy 437.630035 -157.262327) (xy 437.500358 -157.097429)
			(xy 437.377053 -156.927714) (xy 437.260299 -156.753428) (xy 437.150264 -156.574823) (xy 437.047109 -156.392159)
			(xy 436.950982 -156.2057) (xy 436.862024 -156.015716) (xy 436.780364 -155.822484) (xy 436.706119 -155.626283)
			(xy 436.639397 -155.427397) (xy 436.580295 -155.226115) (xy 436.528899 -155.02273) (xy 436.485284 -154.817535)
			(xy 436.449512 -154.610828) (xy 436.421635 -154.402909) (xy 436.401694 -154.19408) (xy 436.389718 -153.984643)
			(xy 436.385725 -153.774902) (xy 283.40376 -153.774902) (xy 283.403303 -153.870902) (xy 283.395316 -154.080529)
			(xy 283.379355 -154.2897) (xy 283.355442 -154.498111) (xy 283.323612 -154.705462) (xy 283.283911 -154.91145)
			(xy 283.236397 -155.115777) (xy 283.181138 -155.318148) (xy 283.118215 -155.518267) (xy 283.047719 -155.715847)
			(xy 282.969752 -155.910599) (xy 282.884427 -156.102242) (xy 282.791868 -156.290497) (xy 282.692209 -156.475092)
			(xy 282.585595 -156.65576) (xy 282.47218 -156.832237) (xy 282.352128 -157.004269) (xy 282.225614 -157.171605)
			(xy 282.092821 -157.334004) (xy 281.953942 -157.49123) (xy 281.809178 -157.643054) (xy 281.658739 -157.789257)
			(xy 281.502842 -157.929626) (xy 281.341715 -158.063959) (xy 281.175591 -158.19206) (xy 281.00471 -158.313744)
			(xy 280.82932 -158.428834) (xy 280.649676 -158.537164) (xy 280.466038 -158.638575) (xy 280.278672 -158.732922)
			(xy 280.08785 -158.820068) (xy 279.893849 -158.899885) (xy 279.69695 -158.972259) (xy 279.497438 -159.037084)
			(xy 279.295603 -159.094267) (xy 279.091737 -159.143725) (xy 278.886136 -159.185385) (xy 278.679098 -159.219187)
			(xy 278.470924 -159.245083) (xy 278.261914 -159.263035) (xy 278.052372 -159.273017) (xy 277.842603 -159.275014)
			(xy 277.632909 -159.269023) (xy 277.423596 -159.255054) (xy 277.214966 -159.233126) (xy 277.007322 -159.203272)
			(xy 276.800965 -159.165533) (xy 276.596195 -159.119966) (xy 276.393308 -159.066637) (xy 276.192598 -159.005622)
			(xy 275.994356 -158.93701) (xy 275.798871 -158.8609) (xy 275.606424 -158.777403) (xy 275.417296 -158.686641)
			(xy 275.231761 -158.588744) (xy 275.050087 -158.483854) (xy 274.872537 -158.372124) (xy 274.699371 -158.253716)
			(xy 274.530837 -158.128801) (xy 274.367182 -157.99756) (xy 274.208641 -157.860184) (xy 274.055446 -157.716871)
			(xy 273.907817 -157.567831) (xy 273.76597 -157.413278) (xy 273.630109 -157.253437) (xy 273.500432 -157.088539)
			(xy 273.377127 -156.918824) (xy 273.260373 -156.744538) (xy 273.150338 -156.565933) (xy 273.047183 -156.383269)
			(xy 272.951056 -156.19681) (xy 272.862098 -156.006826) (xy 272.780438 -155.813594) (xy 272.706193 -155.617393)
			(xy 272.639471 -155.418507) (xy 272.580369 -155.217225) (xy 272.528973 -155.01384) (xy 272.485358 -154.808645)
			(xy 272.449586 -154.601938) (xy 272.421709 -154.394019) (xy 272.401768 -154.18519) (xy 272.389792 -153.975753)
			(xy 272.385799 -153.766012) (xy 199.463618 -153.766012) (xy 199.46366 -153.774902) (xy 199.463161 -153.879792)
			(xy 199.455174 -154.089419) (xy 199.439213 -154.29859) (xy 199.4153 -154.507001) (xy 199.38347 -154.714352)
			(xy 199.343769 -154.92034) (xy 199.296255 -155.124667) (xy 199.240996 -155.327038) (xy 199.178073 -155.527157)
			(xy 199.107577 -155.724737) (xy 199.02961 -155.919489) (xy 198.944285 -156.111132) (xy 198.851726 -156.299387)
			(xy 198.752067 -156.483982) (xy 198.645453 -156.66465) (xy 198.532038 -156.841127) (xy 198.411986 -157.013159)
			(xy 198.285472 -157.180495) (xy 198.152679 -157.342894) (xy 198.0138 -157.50012) (xy 197.869036 -157.651944)
			(xy 197.718597 -157.798147) (xy 197.5627 -157.938516) (xy 197.401573 -158.072849) (xy 197.235449 -158.20095)
			(xy 197.064568 -158.322634) (xy 196.889178 -158.437724) (xy 196.709534 -158.546054) (xy 196.525896 -158.647465)
			(xy 196.33853 -158.741812) (xy 196.147708 -158.828958) (xy 195.953707 -158.908775) (xy 195.756808 -158.981149)
			(xy 195.557296 -159.045974) (xy 195.355461 -159.103157) (xy 195.151595 -159.152615) (xy 194.945994 -159.194275)
			(xy 194.738956 -159.228077) (xy 194.530782 -159.253973) (xy 194.321772 -159.271925) (xy 194.11223 -159.281907)
			(xy 193.902461 -159.283904) (xy 193.692767 -159.277913) (xy 193.483454 -159.263944) (xy 193.274824 -159.242016)
			(xy 193.06718 -159.212162) (xy 192.860823 -159.174423) (xy 192.656053 -159.128856) (xy 192.453166 -159.075527)
			(xy 192.252456 -159.014512) (xy 192.054214 -158.9459) (xy 191.858729 -158.86979) (xy 191.666282 -158.786293)
			(xy 191.477154 -158.695531) (xy 191.291619 -158.597634) (xy 191.109945 -158.492744) (xy 190.932395 -158.381014)
			(xy 190.759229 -158.262606) (xy 190.590695 -158.137691) (xy 190.42704 -158.00645) (xy 190.268499 -157.869074)
			(xy 190.115304 -157.725761) (xy 189.967675 -157.576721) (xy 189.825828 -157.422168) (xy 189.689967 -157.262327)
			(xy 189.56029 -157.097429) (xy 189.436985 -156.927714) (xy 189.320231 -156.753428) (xy 189.210196 -156.574823)
			(xy 189.107041 -156.392159) (xy 189.010914 -156.2057) (xy 188.921956 -156.015716) (xy 188.840296 -155.822484)
			(xy 188.766051 -155.626283) (xy 188.699329 -155.427397) (xy 188.640227 -155.226115) (xy 188.588831 -155.02273)
			(xy 188.545216 -154.817535) (xy 188.509444 -154.610828) (xy 188.481567 -154.402909) (xy 188.461626 -154.19408)
			(xy 188.44965 -153.984643) (xy 188.445657 -153.774902) (xy 187.505848 -153.774902) (xy 187.505848 -154.239468)
			(xy 187.505362 -154.266719) (xy 187.497606 -154.320667) (xy 187.482251 -154.372962) (xy 187.459609 -154.422539)
			(xy 187.430143 -154.468389) (xy 187.394452 -154.50958) (xy 187.353261 -154.545271) (xy 187.307411 -154.574737)
			(xy 187.257834 -154.597379) (xy 187.205539 -154.612734) (xy 187.151591 -154.62049) (xy 187.097089 -154.62049)
			(xy 187.043141 -154.612734) (xy 186.990846 -154.597379) (xy 186.941269 -154.574737) (xy 186.895419 -154.545271)
			(xy 186.854228 -154.50958) (xy 186.818537 -154.468389) (xy 186.789071 -154.422539) (xy 186.766429 -154.372962)
			(xy 186.751074 -154.320667) (xy 186.743318 -154.266719) (xy 186.742832 -154.239468) (xy 35.44312 -154.239468)
			(xy 35.439287 -154.2897) (xy 35.415374 -154.498111) (xy 35.383544 -154.705462) (xy 35.343843 -154.91145)
			(xy 35.296329 -155.115777) (xy 35.24107 -155.318148) (xy 35.178147 -155.518267) (xy 35.107651 -155.715847)
			(xy 35.029684 -155.910599) (xy 34.944359 -156.102242) (xy 34.8518 -156.290497) (xy 34.752141 -156.475092)
			(xy 34.645527 -156.65576) (xy 34.532112 -156.832237) (xy 34.41206 -157.004269) (xy 34.285546 -157.171605)
			(xy 34.152753 -157.334004) (xy 34.013874 -157.49123) (xy 33.86911 -157.643054) (xy 33.718671 -157.789257)
			(xy 33.562774 -157.929626) (xy 33.401647 -158.063959) (xy 33.235523 -158.19206) (xy 33.064642 -158.313744)
			(xy 32.889252 -158.428834) (xy 32.709608 -158.537164) (xy 32.52597 -158.638575) (xy 32.338604 -158.732922)
			(xy 32.147782 -158.820068) (xy 31.953781 -158.899885) (xy 31.756882 -158.972259) (xy 31.55737 -159.037084)
			(xy 31.355535 -159.094267) (xy 31.151669 -159.143725) (xy 30.946068 -159.185385) (xy 30.73903 -159.219187)
			(xy 30.530856 -159.245083) (xy 30.321846 -159.263035) (xy 30.112304 -159.273017) (xy 29.902535 -159.275014)
			(xy 29.692841 -159.269023) (xy 29.483528 -159.255054) (xy 29.274898 -159.233126) (xy 29.067254 -159.203272)
			(xy 28.860897 -159.165533) (xy 28.656127 -159.119966) (xy 28.45324 -159.066637) (xy 28.25253 -159.005622)
			(xy 28.054288 -158.93701) (xy 27.858803 -158.8609) (xy 27.666356 -158.777403) (xy 27.477228 -158.686641)
			(xy 27.291693 -158.588744) (xy 27.110019 -158.483854) (xy 26.932469 -158.372124) (xy 26.759303 -158.253716)
			(xy 26.590769 -158.128801) (xy 26.427114 -157.99756) (xy 26.268573 -157.860184) (xy 26.115378 -157.716871)
			(xy 25.967749 -157.567831) (xy 25.825902 -157.413278) (xy 25.690041 -157.253437) (xy 25.560364 -157.088539)
			(xy 25.437059 -156.918824) (xy 25.320305 -156.744538) (xy 25.21027 -156.565933) (xy 25.107115 -156.383269)
			(xy 25.010988 -156.19681) (xy 24.92203 -156.006826) (xy 24.84037 -155.813594) (xy 24.766125 -155.617393)
			(xy 24.699403 -155.418507) (xy 24.640301 -155.217225) (xy 24.588905 -155.01384) (xy 24.54529 -154.808645)
			(xy 24.509518 -154.601938) (xy 24.481641 -154.394019) (xy 24.4617 -154.18519) (xy 24.449724 -153.975753)
			(xy 24.445731 -153.766012) (xy 2.509012 -153.766012) (xy 2.509012 -160.911354) (xy 372.506163 -160.911354)
			(xy 372.506163 -160.856846) (xy 372.513921 -160.802893) (xy 372.529279 -160.750593) (xy 372.551924 -160.701011)
			(xy 372.581395 -160.655157) (xy 372.617092 -160.613964) (xy 372.658289 -160.578271) (xy 372.704146 -160.548805)
			(xy 372.75373 -160.526165) (xy 372.806032 -160.510813) (xy 372.859986 -160.503061) (xy 372.88724 -160.5026)
			(xy 373.75084 -160.5026) (xy 373.77809 -160.503073) (xy 373.832034 -160.510834) (xy 373.884326 -160.526193)
			(xy 373.933899 -160.548837) (xy 373.979745 -160.578305) (xy 374.020931 -160.613997) (xy 374.056619 -160.655187)
			(xy 374.086083 -160.701036) (xy 374.108721 -160.750612) (xy 374.124075 -160.802905) (xy 374.13183 -160.85685)
			(xy 374.13183 -160.91135) (xy 374.124075 -160.965295) (xy 374.108721 -161.017588) (xy 374.086083 -161.067164)
			(xy 374.056619 -161.113013) (xy 374.020931 -161.154203) (xy 373.979745 -161.189895) (xy 373.933899 -161.219363)
			(xy 373.884326 -161.242007) (xy 373.832034 -161.257366) (xy 373.77809 -161.265127) (xy 373.75084 -161.265616)
			(xy 372.88724 -161.265616) (xy 372.859986 -161.265139) (xy 372.806032 -161.257387) (xy 372.75373 -161.242035)
			(xy 372.704146 -161.219395) (xy 372.658289 -161.189929) (xy 372.617092 -161.154236) (xy 372.581395 -161.113043)
			(xy 372.551924 -161.067189) (xy 372.529279 -161.017607) (xy 372.513921 -160.965307) (xy 372.506163 -160.911354)
			(xy 2.509012 -160.911354) (xy 2.509012 -161.58445) (xy 296.753286 -161.58445) (xy 296.753286 -161.52995)
			(xy 296.761042 -161.476005) (xy 296.776395 -161.423713) (xy 296.799035 -161.374138) (xy 296.828498 -161.32829)
			(xy 296.864187 -161.287101) (xy 296.905374 -161.25141) (xy 296.951221 -161.221944) (xy 297.000795 -161.199302)
			(xy 297.053086 -161.183946) (xy 297.10703 -161.176187) (xy 297.13428 -161.1757) (xy 297.99788 -161.1757)
			(xy 298.025134 -161.176146) (xy 298.079089 -161.183901) (xy 298.13139 -161.199255) (xy 298.180974 -161.221897)
			(xy 298.22683 -161.251365) (xy 298.268026 -161.28706) (xy 298.303723 -161.328254) (xy 298.333193 -161.374109)
			(xy 298.355838 -161.423691) (xy 298.371195 -161.475992) (xy 298.378953 -161.529946) (xy 298.378953 -161.584454)
			(xy 298.371195 -161.638408) (xy 298.355838 -161.690709) (xy 298.333193 -161.740291) (xy 298.303723 -161.786146)
			(xy 298.268026 -161.82734) (xy 298.22683 -161.863035) (xy 298.180974 -161.892503) (xy 298.13139 -161.915145)
			(xy 298.079089 -161.930499) (xy 298.025134 -161.938254) (xy 297.99788 -161.938716) (xy 297.13428 -161.938716)
			(xy 297.10703 -161.938213) (xy 297.053086 -161.930454) (xy 297.000795 -161.915098) (xy 296.951221 -161.892456)
			(xy 296.905374 -161.86299) (xy 296.864187 -161.827299) (xy 296.828498 -161.78611) (xy 296.799035 -161.740262)
			(xy 296.776395 -161.690687) (xy 296.761042 -161.638395) (xy 296.753286 -161.58445) (xy 2.509012 -161.58445)
			(xy 2.509012 -162.128053) (xy 292.574946 -162.128053) (xy 292.574946 -162.073547) (xy 292.582702 -162.019597)
			(xy 292.598058 -161.967299) (xy 292.620699 -161.917719) (xy 292.650166 -161.871866) (xy 292.685859 -161.830673)
			(xy 292.72705 -161.794978) (xy 292.772902 -161.765509) (xy 292.822481 -161.742865) (xy 292.874777 -161.727507)
			(xy 292.928727 -161.719747) (xy 292.95598 -161.71926) (xy 293.81958 -161.71926) (xy 293.846832 -161.719786)
			(xy 293.90078 -161.72754) (xy 293.953076 -161.742893) (xy 294.002654 -161.765532) (xy 294.048506 -161.794997)
			(xy 294.089698 -161.830688) (xy 294.125391 -161.871878) (xy 294.154858 -161.917728) (xy 294.1775 -161.967305)
			(xy 294.192856 -162.0196) (xy 294.200613 -162.073549) (xy 294.200613 -162.128051) (xy 294.192856 -162.182)
			(xy 294.1775 -162.234295) (xy 294.154858 -162.283872) (xy 294.125391 -162.329722) (xy 294.089698 -162.370912)
			(xy 294.048506 -162.406603) (xy 294.002654 -162.436068) (xy 293.953076 -162.458707) (xy 293.90078 -162.47406)
			(xy 293.846832 -162.481814) (xy 293.81958 -162.482276) (xy 292.95598 -162.482276) (xy 292.928727 -162.481853)
			(xy 292.874777 -162.474093) (xy 292.822481 -162.458735) (xy 292.772902 -162.436091) (xy 292.72705 -162.406622)
			(xy 292.685859 -162.370927) (xy 292.650166 -162.329734) (xy 292.620699 -162.283881) (xy 292.598058 -162.234301)
			(xy 292.582702 -162.182003) (xy 292.574946 -162.128053) (xy 2.509012 -162.128053) (xy 2.509012 -163.123651)
			(xy 294.731403 -163.123651) (xy 294.731403 -163.069149) (xy 294.73916 -163.015201) (xy 294.754516 -162.962907)
			(xy 294.777159 -162.91333) (xy 294.806627 -162.867481) (xy 294.842321 -162.826292) (xy 294.883513 -162.790603)
			(xy 294.929365 -162.76114) (xy 294.978944 -162.738502) (xy 295.03124 -162.723152) (xy 295.085189 -162.7154)
			(xy 295.11244 -162.71494) (xy 295.97604 -162.71494) (xy 296.003293 -162.715333) (xy 296.057243 -162.723095)
			(xy 296.10954 -162.738455) (xy 296.159118 -162.761102) (xy 296.204969 -162.790573) (xy 296.24616 -162.826269)
			(xy 296.281851 -162.867463) (xy 296.311318 -162.913317) (xy 296.333959 -162.962898) (xy 296.349314 -163.015196)
			(xy 296.35707 -163.069147) (xy 296.35707 -163.110951) (xy 300.192403 -163.110951) (xy 300.192403 -163.056449)
			(xy 300.20016 -163.002501) (xy 300.215516 -162.950207) (xy 300.238159 -162.90063) (xy 300.267627 -162.854781)
			(xy 300.303321 -162.813592) (xy 300.344513 -162.777903) (xy 300.390365 -162.74844) (xy 300.439944 -162.725802)
			(xy 300.49224 -162.710452) (xy 300.546189 -162.7027) (xy 300.57344 -162.70224) (xy 301.43704 -162.70224)
			(xy 301.464293 -162.702633) (xy 301.518243 -162.710395) (xy 301.57054 -162.725755) (xy 301.620118 -162.748402)
			(xy 301.665969 -162.777873) (xy 301.70716 -162.813569) (xy 301.742851 -162.854763) (xy 301.772318 -162.900617)
			(xy 301.794959 -162.950198) (xy 301.810314 -163.002496) (xy 301.81807 -163.056447) (xy 301.81807 -163.110953)
			(xy 301.810314 -163.164904) (xy 301.794959 -163.217202) (xy 301.772318 -163.266783) (xy 301.742851 -163.312637)
			(xy 301.70716 -163.353831) (xy 301.665969 -163.389527) (xy 301.620118 -163.418998) (xy 301.57054 -163.441645)
			(xy 301.518243 -163.457005) (xy 301.464293 -163.464767) (xy 301.43704 -163.465256) (xy 300.57344 -163.465256)
			(xy 300.546189 -163.4647) (xy 300.49224 -163.456948) (xy 300.439944 -163.441598) (xy 300.390365 -163.41896)
			(xy 300.344513 -163.389497) (xy 300.303321 -163.353808) (xy 300.267627 -163.312619) (xy 300.238159 -163.26677)
			(xy 300.215516 -163.217193) (xy 300.20016 -163.164899) (xy 300.192403 -163.110951) (xy 296.35707 -163.110951)
			(xy 296.35707 -163.123653) (xy 296.349314 -163.177604) (xy 296.333959 -163.229902) (xy 296.311318 -163.279483)
			(xy 296.281851 -163.325337) (xy 296.24616 -163.366531) (xy 296.204969 -163.402227) (xy 296.159118 -163.431698)
			(xy 296.10954 -163.454345) (xy 296.057243 -163.469705) (xy 296.003293 -163.477467) (xy 295.97604 -163.477956)
			(xy 295.11244 -163.477956) (xy 295.085189 -163.4774) (xy 295.03124 -163.469648) (xy 294.978944 -163.454298)
			(xy 294.929365 -163.43166) (xy 294.883513 -163.402197) (xy 294.842321 -163.366508) (xy 294.806627 -163.325319)
			(xy 294.777159 -163.27947) (xy 294.754516 -163.229893) (xy 294.73916 -163.177599) (xy 294.731403 -163.123651)
			(xy 2.509012 -163.123651) (xy 2.509012 -167.565832) (xy 348.657164 -167.565832) (xy 348.657658 -167.532531)
			(xy 348.666337 -167.466499) (xy 348.683566 -167.402165) (xy 348.709048 -167.340632) (xy 348.742347 -167.282953)
			(xy 348.782893 -167.230117) (xy 348.829992 -167.183027) (xy 348.882836 -167.142492) (xy 348.911418 -167.125396)
			(xy 349.83547 -166.591742) (xy 349.864533 -166.575642) (xy 349.925937 -166.550271) (xy 349.990123 -166.533114)
			(xy 350.055996 -166.524463) (xy 350.089216 -166.523924) (xy 350.089724 -166.523924) (xy 350.120458 -166.524315)
			(xy 350.181477 -166.531727) (xy 350.241158 -166.54644) (xy 350.29863 -166.56824) (xy 350.353056 -166.596808)
			(xy 350.403641 -166.631729) (xy 350.449648 -166.672492) (xy 350.490406 -166.718503) (xy 350.525321 -166.769092)
			(xy 350.553883 -166.823521) (xy 350.57377 -166.875968) (xy 369.614196 -166.875968) (xy 369.614752 -166.84267)
			(xy 369.623426 -166.776641) (xy 369.640648 -166.71231) (xy 369.666122 -166.650779) (xy 369.699412 -166.593101)
			(xy 369.739949 -166.540263) (xy 369.787038 -166.493171) (xy 369.839873 -166.452631) (xy 369.86845 -166.435532)
			(xy 370.792502 -165.901878) (xy 370.82156 -165.885769) (xy 370.882966 -165.8604) (xy 370.947153 -165.843245)
			(xy 371.013028 -165.834597) (xy 371.046248 -165.83406) (xy 371.046756 -165.83406) (xy 371.077486 -165.834579)
			(xy 371.138498 -165.841982) (xy 371.198173 -165.856685) (xy 371.255641 -165.878475) (xy 371.310063 -165.907032)
			(xy 371.360647 -165.941941) (xy 371.406653 -165.982693) (xy 371.447412 -166.028694) (xy 371.482329 -166.079272)
			(xy 371.510894 -166.133689) (xy 371.532692 -166.191154) (xy 371.547404 -166.250827) (xy 371.554816 -166.311838)
			(xy 371.555264 -166.342568) (xy 371.554757 -166.375868) (xy 371.546077 -166.4419) (xy 371.52885 -166.506232)
			(xy 371.503369 -166.567765) (xy 371.470072 -166.625443) (xy 371.429528 -166.67828) (xy 371.382432 -166.72537)
			(xy 371.329591 -166.765907) (xy 371.30101 -166.783004) (xy 370.964111 -166.977568) (xy 373.398796 -166.977568)
			(xy 373.399226 -166.946836) (xy 373.406638 -166.885821) (xy 373.421351 -166.826144) (xy 373.443149 -166.768676)
			(xy 373.471715 -166.714254) (xy 373.506633 -166.663671) (xy 373.547392 -166.617667) (xy 373.5934 -166.57691)
			(xy 373.643984 -166.541996) (xy 373.698409 -166.513434) (xy 373.755879 -166.49164) (xy 373.815556 -166.476932)
			(xy 373.876572 -166.469524) (xy 373.907304 -166.46906) (xy 373.907812 -166.46906) (xy 373.941031 -166.469606)
			(xy 374.006903 -166.478264) (xy 374.071088 -166.495419) (xy 374.132496 -166.520778) (xy 374.161558 -166.536878)
			(xy 375.08561 -167.070532) (xy 375.114171 -167.087654) (xy 375.166997 -167.128201) (xy 375.214079 -167.175295)
			(xy 375.254613 -167.22813) (xy 375.287906 -167.285802) (xy 375.313388 -167.347326) (xy 375.330623 -167.411649)
			(xy 375.339318 -167.477672) (xy 375.339864 -167.510968) (xy 375.339432 -167.541701) (xy 375.332026 -167.60272)
			(xy 375.317319 -167.6624) (xy 375.295524 -167.719873) (xy 375.266961 -167.774299) (xy 375.232044 -167.824885)
			(xy 375.191284 -167.870893) (xy 375.145275 -167.911651) (xy 375.094689 -167.946567) (xy 375.040262 -167.975129)
			(xy 374.982789 -167.996923) (xy 374.923108 -168.011629) (xy 374.862089 -168.019033) (xy 374.831356 -168.019476)
			(xy 374.830848 -168.019476) (xy 374.797629 -168.018942) (xy 374.731757 -168.01028) (xy 374.667571 -167.993122)
			(xy 374.606164 -167.967759) (xy 374.577102 -167.951658) (xy 373.65305 -167.418004) (xy 373.624495 -167.400872)
			(xy 373.571672 -167.360325) (xy 373.524591 -167.313232) (xy 373.484057 -167.260398) (xy 373.450764 -167.202727)
			(xy 373.42528 -167.141205) (xy 373.408042 -167.076884) (xy 373.399344 -167.010863) (xy 373.398796 -166.977568)
			(xy 370.964111 -166.977568) (xy 370.376958 -167.316658) (xy 370.34791 -167.332786) (xy 370.2865 -167.35815)
			(xy 370.22231 -167.375299) (xy 370.156433 -167.383942) (xy 370.123212 -167.384476) (xy 370.122704 -167.384476)
			(xy 370.091971 -167.384059) (xy 370.030952 -167.37665) (xy 369.971272 -167.36194) (xy 369.9138 -167.340143)
			(xy 369.859375 -167.311577) (xy 369.808789 -167.276659) (xy 369.762782 -167.235898) (xy 369.722023 -167.189889)
			(xy 369.687108 -167.139301) (xy 369.658546 -167.084874) (xy 369.636752 -167.027401) (xy 369.622045 -166.96772)
			(xy 369.61464 -166.906701) (xy 369.614196 -166.875968) (xy 350.57377 -166.875968) (xy 350.575676 -166.880996)
			(xy 350.590383 -166.940678) (xy 350.597788 -167.001698) (xy 350.598232 -167.032432) (xy 350.597712 -167.065732)
			(xy 350.589036 -167.131763) (xy 350.571812 -167.196097) (xy 350.546334 -167.25763) (xy 350.513038 -167.315309)
			(xy 350.472496 -167.368145) (xy 350.4254 -167.415235) (xy 350.372559 -167.455772) (xy 350.343978 -167.472868)
			(xy 349.419926 -168.006522) (xy 349.390862 -168.02262) (xy 349.329459 -168.047992) (xy 349.265273 -168.06515)
			(xy 349.1994 -168.073802) (xy 349.16618 -168.07434) (xy 349.165672 -168.07434) (xy 349.134942 -168.07387)
			(xy 349.073929 -168.066459) (xy 349.014255 -168.051748) (xy 348.956789 -168.029953) (xy 348.902369 -168.001389)
			(xy 348.851788 -167.966475) (xy 348.805784 -167.925719) (xy 348.765027 -167.879715) (xy 348.730113 -167.829135)
			(xy 348.701549 -167.774715) (xy 348.679753 -167.717249) (xy 348.665041 -167.657575) (xy 348.65763 -167.596562)
			(xy 348.657164 -167.565832) (xy 2.509012 -167.565832) (xy 2.509012 -168.302432) (xy 352.441764 -168.302432)
			(xy 352.442268 -168.271702) (xy 352.449672 -168.210689) (xy 352.464377 -168.151013) (xy 352.486168 -168.093545)
			(xy 352.514727 -168.039122) (xy 352.549637 -167.988539) (xy 352.59039 -167.942533) (xy 352.636392 -167.901774)
			(xy 352.686971 -167.866858) (xy 352.74139 -167.838292) (xy 352.798856 -167.816495) (xy 352.85853 -167.801783)
			(xy 352.919542 -167.794371) (xy 352.950272 -167.793924) (xy 352.95078 -167.793924) (xy 352.983998 -167.794489)
			(xy 353.049869 -167.803142) (xy 353.114055 -167.820291) (xy 353.175463 -167.845645) (xy 353.204526 -167.861742)
			(xy 354.128578 -168.395396) (xy 354.157139 -168.412518) (xy 354.209962 -168.453067) (xy 354.257042 -168.500162)
			(xy 354.297574 -168.552998) (xy 354.330866 -168.61067) (xy 354.356349 -168.672193) (xy 354.373586 -168.736515)
			(xy 354.382284 -168.802536) (xy 354.382832 -168.835832) (xy 354.382374 -168.866563) (xy 354.374962 -168.927576)
			(xy 354.360251 -168.987251) (xy 354.338454 -169.044717) (xy 354.30989 -169.099138) (xy 354.274975 -169.149719)
			(xy 354.234218 -169.195723) (xy 354.188213 -169.23648) (xy 354.137631 -169.271394) (xy 354.08321 -169.299957)
			(xy 354.025743 -169.321753) (xy 353.966068 -169.336464) (xy 353.905055 -169.343875) (xy 353.874324 -169.34434)
			(xy 353.873816 -169.34434) (xy 353.840597 -169.343782) (xy 353.774726 -169.335127) (xy 353.710541 -169.317976)
			(xy 353.649132 -169.292621) (xy 353.62007 -169.276522) (xy 352.696018 -168.742868) (xy 352.667463 -168.725735)
			(xy 352.614637 -168.685191) (xy 352.567553 -168.638099) (xy 352.527018 -168.585266) (xy 352.493724 -168.527595)
			(xy 352.468241 -168.466072) (xy 352.451005 -168.40175) (xy 352.44231 -168.335728) (xy 352.441764 -168.302432)
			(xy 2.509012 -168.302432) (xy 2.509012 -170.613832) (xy 348.657164 -170.613832) (xy 348.657658 -170.580531)
			(xy 348.666337 -170.514499) (xy 348.683566 -170.450165) (xy 348.709048 -170.388632) (xy 348.742347 -170.330953)
			(xy 348.782893 -170.278117) (xy 348.829992 -170.231027) (xy 348.882836 -170.190492) (xy 348.911418 -170.173396)
			(xy 349.83547 -169.639742) (xy 349.864533 -169.623642) (xy 349.925937 -169.598271) (xy 349.990123 -169.581114)
			(xy 350.055996 -169.572463) (xy 350.089216 -169.571924) (xy 350.089724 -169.571924) (xy 350.120458 -169.572315)
			(xy 350.181477 -169.579727) (xy 350.241158 -169.59444) (xy 350.29863 -169.61624) (xy 350.353056 -169.644808)
			(xy 350.403641 -169.679729) (xy 350.449648 -169.720492) (xy 350.490406 -169.766503) (xy 350.525321 -169.817092)
			(xy 350.553883 -169.871521) (xy 350.57377 -169.923968) (xy 369.614196 -169.923968) (xy 369.614752 -169.89067)
			(xy 369.623426 -169.824641) (xy 369.640648 -169.76031) (xy 369.666122 -169.698779) (xy 369.699412 -169.641101)
			(xy 369.739949 -169.588263) (xy 369.787038 -169.541171) (xy 369.839873 -169.500631) (xy 369.86845 -169.483532)
			(xy 370.792502 -168.949878) (xy 370.82156 -168.933769) (xy 370.882966 -168.9084) (xy 370.947153 -168.891245)
			(xy 371.013028 -168.882597) (xy 371.046248 -168.88206) (xy 371.046756 -168.88206) (xy 371.077486 -168.882579)
			(xy 371.138498 -168.889982) (xy 371.198173 -168.904685) (xy 371.255641 -168.926475) (xy 371.310063 -168.955032)
			(xy 371.360647 -168.989941) (xy 371.406653 -169.030693) (xy 371.447412 -169.076694) (xy 371.482329 -169.127272)
			(xy 371.510894 -169.181689) (xy 371.532692 -169.239154) (xy 371.547404 -169.298827) (xy 371.554816 -169.359838)
			(xy 371.555264 -169.390568) (xy 371.554757 -169.423868) (xy 371.546077 -169.4899) (xy 371.52885 -169.554232)
			(xy 371.503369 -169.615765) (xy 371.470072 -169.673443) (xy 371.429528 -169.72628) (xy 371.382432 -169.77337)
			(xy 371.329591 -169.813907) (xy 371.30101 -169.831004) (xy 370.376958 -170.364658) (xy 370.34791 -170.380786)
			(xy 370.2865 -170.40615) (xy 370.22231 -170.423299) (xy 370.156433 -170.431942) (xy 370.123212 -170.432476)
			(xy 370.122704 -170.432476) (xy 370.091971 -170.432059) (xy 370.030952 -170.42465) (xy 369.971272 -170.40994)
			(xy 369.9138 -170.388143) (xy 369.859375 -170.359577) (xy 369.808789 -170.324659) (xy 369.762782 -170.283898)
			(xy 369.722023 -170.237889) (xy 369.687108 -170.187301) (xy 369.658546 -170.132874) (xy 369.636752 -170.075401)
			(xy 369.622045 -170.01572) (xy 369.61464 -169.954701) (xy 369.614196 -169.923968) (xy 350.57377 -169.923968)
			(xy 350.575676 -169.928996) (xy 350.590383 -169.988678) (xy 350.597788 -170.049698) (xy 350.598232 -170.080432)
			(xy 350.597712 -170.113732) (xy 350.589036 -170.179763) (xy 350.571812 -170.244097) (xy 350.546334 -170.30563)
			(xy 350.513038 -170.363309) (xy 350.472496 -170.416145) (xy 350.4254 -170.463235) (xy 350.372559 -170.503772)
			(xy 350.343978 -170.520868) (xy 350.10208 -170.660568) (xy 373.398796 -170.660568) (xy 373.399226 -170.629836)
			(xy 373.406638 -170.568821) (xy 373.421351 -170.509144) (xy 373.443149 -170.451676) (xy 373.471715 -170.397254)
			(xy 373.506633 -170.346671) (xy 373.547392 -170.300667) (xy 373.5934 -170.25991) (xy 373.643984 -170.224996)
			(xy 373.698409 -170.196434) (xy 373.755879 -170.17464) (xy 373.815556 -170.159932) (xy 373.876572 -170.152524)
			(xy 373.907304 -170.15206) (xy 373.907812 -170.15206) (xy 373.941031 -170.152606) (xy 374.006903 -170.161264)
			(xy 374.071088 -170.178419) (xy 374.132496 -170.203778) (xy 374.161558 -170.219878) (xy 375.08561 -170.753532)
			(xy 375.114171 -170.770654) (xy 375.166997 -170.811201) (xy 375.214079 -170.858295) (xy 375.254613 -170.91113)
			(xy 375.287906 -170.968802) (xy 375.313388 -171.030326) (xy 375.330623 -171.094649) (xy 375.339318 -171.160672)
			(xy 375.339864 -171.193968) (xy 375.339432 -171.224701) (xy 375.332026 -171.28572) (xy 375.317319 -171.3454)
			(xy 375.295524 -171.402873) (xy 375.266961 -171.457299) (xy 375.232044 -171.507885) (xy 375.191284 -171.553893)
			(xy 375.145275 -171.594651) (xy 375.094689 -171.629567) (xy 375.040262 -171.658129) (xy 374.982789 -171.679923)
			(xy 374.923108 -171.694629) (xy 374.862089 -171.702033) (xy 374.831356 -171.702476) (xy 374.830848 -171.702476)
			(xy 374.797629 -171.701942) (xy 374.731757 -171.69328) (xy 374.667571 -171.676122) (xy 374.606164 -171.650759)
			(xy 374.577102 -171.634658) (xy 373.65305 -171.101004) (xy 373.624495 -171.083872) (xy 373.571672 -171.043325)
			(xy 373.524591 -170.996232) (xy 373.484057 -170.943398) (xy 373.450764 -170.885727) (xy 373.42528 -170.824205)
			(xy 373.408042 -170.759884) (xy 373.399344 -170.693863) (xy 373.398796 -170.660568) (xy 350.10208 -170.660568)
			(xy 349.419926 -171.054522) (xy 349.390862 -171.07062) (xy 349.329459 -171.095992) (xy 349.265273 -171.11315)
			(xy 349.1994 -171.121802) (xy 349.16618 -171.12234) (xy 349.165672 -171.12234) (xy 349.134942 -171.12187)
			(xy 349.073929 -171.114459) (xy 349.014255 -171.099748) (xy 348.956789 -171.077953) (xy 348.902369 -171.049389)
			(xy 348.851788 -171.014475) (xy 348.805784 -170.973719) (xy 348.765027 -170.927715) (xy 348.730113 -170.877135)
			(xy 348.701549 -170.822715) (xy 348.679753 -170.765249) (xy 348.665041 -170.705575) (xy 348.65763 -170.644562)
			(xy 348.657164 -170.613832) (xy 2.509012 -170.613832) (xy 2.509012 -171.985432) (xy 352.441764 -171.985432)
			(xy 352.442268 -171.954702) (xy 352.449672 -171.893689) (xy 352.464377 -171.834013) (xy 352.486168 -171.776545)
			(xy 352.514727 -171.722122) (xy 352.549637 -171.671539) (xy 352.59039 -171.625533) (xy 352.636392 -171.584774)
			(xy 352.686971 -171.549858) (xy 352.74139 -171.521292) (xy 352.798856 -171.499495) (xy 352.85853 -171.484783)
			(xy 352.919542 -171.477371) (xy 352.950272 -171.476924) (xy 352.95078 -171.476924) (xy 352.983998 -171.477489)
			(xy 353.049869 -171.486142) (xy 353.114055 -171.503291) (xy 353.175463 -171.528645) (xy 353.204526 -171.544742)
			(xy 354.128578 -172.078396) (xy 354.157139 -172.095518) (xy 354.209962 -172.136067) (xy 354.257042 -172.183162)
			(xy 354.297574 -172.235998) (xy 354.330866 -172.29367) (xy 354.356349 -172.355193) (xy 354.373586 -172.419515)
			(xy 354.382284 -172.485536) (xy 354.382832 -172.518832) (xy 354.382374 -172.549563) (xy 354.374962 -172.610576)
			(xy 354.360251 -172.670251) (xy 354.338454 -172.727717) (xy 354.30989 -172.782138) (xy 354.274975 -172.832719)
			(xy 354.234218 -172.878723) (xy 354.188213 -172.91948) (xy 354.137631 -172.954394) (xy 354.104147 -172.971968)
			(xy 369.614196 -172.971968) (xy 369.614752 -172.93867) (xy 369.623426 -172.872641) (xy 369.640648 -172.80831)
			(xy 369.666122 -172.746779) (xy 369.699412 -172.689101) (xy 369.739949 -172.636263) (xy 369.787038 -172.589171)
			(xy 369.839873 -172.548631) (xy 369.86845 -172.531532) (xy 370.792502 -171.997878) (xy 370.82156 -171.981769)
			(xy 370.882966 -171.9564) (xy 370.947153 -171.939245) (xy 371.013028 -171.930597) (xy 371.046248 -171.93006)
			(xy 371.046756 -171.93006) (xy 371.077486 -171.930579) (xy 371.138498 -171.937982) (xy 371.198173 -171.952685)
			(xy 371.255641 -171.974475) (xy 371.310063 -172.003032) (xy 371.360647 -172.037941) (xy 371.406653 -172.078693)
			(xy 371.447412 -172.124694) (xy 371.482329 -172.175272) (xy 371.510894 -172.229689) (xy 371.532692 -172.287154)
			(xy 371.547404 -172.346827) (xy 371.554816 -172.407838) (xy 371.555264 -172.438568) (xy 371.554757 -172.471868)
			(xy 371.546077 -172.5379) (xy 371.52885 -172.602232) (xy 371.503369 -172.663765) (xy 371.470072 -172.721443)
			(xy 371.429528 -172.77428) (xy 371.382432 -172.82137) (xy 371.329591 -172.861907) (xy 371.30101 -172.879004)
			(xy 370.376958 -173.412658) (xy 370.34791 -173.428786) (xy 370.2865 -173.45415) (xy 370.22231 -173.471299)
			(xy 370.156433 -173.479942) (xy 370.123212 -173.480476) (xy 370.122704 -173.480476) (xy 370.091971 -173.480059)
			(xy 370.030952 -173.47265) (xy 369.971272 -173.45794) (xy 369.9138 -173.436143) (xy 369.859375 -173.407577)
			(xy 369.808789 -173.372659) (xy 369.762782 -173.331898) (xy 369.722023 -173.285889) (xy 369.687108 -173.235301)
			(xy 369.658546 -173.180874) (xy 369.636752 -173.123401) (xy 369.622045 -173.06372) (xy 369.61464 -173.002701)
			(xy 369.614196 -172.971968) (xy 354.104147 -172.971968) (xy 354.08321 -172.982957) (xy 354.025743 -173.004753)
			(xy 353.966068 -173.019464) (xy 353.905055 -173.026875) (xy 353.874324 -173.02734) (xy 353.873816 -173.02734)
			(xy 353.840597 -173.026782) (xy 353.774726 -173.018127) (xy 353.710541 -173.000976) (xy 353.649132 -172.975621)
			(xy 353.62007 -172.959522) (xy 352.696018 -172.425868) (xy 352.667463 -172.408735) (xy 352.614637 -172.368191)
			(xy 352.567553 -172.321099) (xy 352.527018 -172.268266) (xy 352.493724 -172.210595) (xy 352.468241 -172.149072)
			(xy 352.451005 -172.08475) (xy 352.44231 -172.018728) (xy 352.441764 -171.985432) (xy 2.509012 -171.985432)
			(xy 2.509012 -173.661832) (xy 348.657164 -173.661832) (xy 348.657658 -173.628531) (xy 348.666337 -173.562499)
			(xy 348.683566 -173.498165) (xy 348.709048 -173.436632) (xy 348.742347 -173.378953) (xy 348.782893 -173.326117)
			(xy 348.829992 -173.279027) (xy 348.882836 -173.238492) (xy 348.911418 -173.221396) (xy 349.83547 -172.687742)
			(xy 349.864533 -172.671642) (xy 349.925937 -172.646271) (xy 349.990123 -172.629114) (xy 350.055996 -172.620463)
			(xy 350.089216 -172.619924) (xy 350.089724 -172.619924) (xy 350.120458 -172.620315) (xy 350.181477 -172.627727)
			(xy 350.241158 -172.64244) (xy 350.29863 -172.66424) (xy 350.353056 -172.692808) (xy 350.403641 -172.727729)
			(xy 350.449648 -172.768492) (xy 350.490406 -172.814503) (xy 350.525321 -172.865092) (xy 350.553883 -172.919521)
			(xy 350.575676 -172.976996) (xy 350.590383 -173.036678) (xy 350.597788 -173.097698) (xy 350.598232 -173.128432)
			(xy 350.597712 -173.161732) (xy 350.589036 -173.227763) (xy 350.571812 -173.292097) (xy 350.546334 -173.35363)
			(xy 350.513038 -173.411309) (xy 350.472496 -173.464145) (xy 350.4254 -173.511235) (xy 350.372559 -173.551772)
			(xy 350.343978 -173.568868) (xy 349.419926 -174.102522) (xy 349.390862 -174.11862) (xy 349.329459 -174.143992)
			(xy 349.265273 -174.16115) (xy 349.1994 -174.169802) (xy 349.16618 -174.17034) (xy 349.165672 -174.17034)
			(xy 349.134942 -174.16987) (xy 349.073929 -174.162459) (xy 349.014255 -174.147748) (xy 348.956789 -174.125953)
			(xy 348.902369 -174.097389) (xy 348.851788 -174.062475) (xy 348.805784 -174.021719) (xy 348.765027 -173.975715)
			(xy 348.730113 -173.925135) (xy 348.701549 -173.870715) (xy 348.679753 -173.813249) (xy 348.665041 -173.753575)
			(xy 348.65763 -173.692562) (xy 348.657164 -173.661832) (xy 2.509012 -173.661832) (xy 2.509012 -174.343568)
			(xy 373.398796 -174.343568) (xy 373.399226 -174.312836) (xy 373.406638 -174.251821) (xy 373.421351 -174.192144)
			(xy 373.443149 -174.134676) (xy 373.471715 -174.080254) (xy 373.506633 -174.029671) (xy 373.547392 -173.983667)
			(xy 373.5934 -173.94291) (xy 373.643984 -173.907996) (xy 373.698409 -173.879434) (xy 373.755879 -173.85764)
			(xy 373.815556 -173.842932) (xy 373.876572 -173.835524) (xy 373.907304 -173.83506) (xy 373.907812 -173.83506)
			(xy 373.941031 -173.835606) (xy 374.006903 -173.844264) (xy 374.071088 -173.861419) (xy 374.132496 -173.886778)
			(xy 374.161558 -173.902878) (xy 375.08561 -174.436532) (xy 375.114171 -174.453654) (xy 375.166997 -174.494201)
			(xy 375.214079 -174.541295) (xy 375.254613 -174.59413) (xy 375.287906 -174.651802) (xy 375.313388 -174.713326)
			(xy 375.330623 -174.777649) (xy 375.339318 -174.843672) (xy 375.339864 -174.876968) (xy 375.339432 -174.907701)
			(xy 375.332026 -174.96872) (xy 375.317319 -175.0284) (xy 375.295524 -175.085873) (xy 375.266961 -175.140299)
			(xy 375.232044 -175.190885) (xy 375.191284 -175.236893) (xy 375.145275 -175.277651) (xy 375.094689 -175.312567)
			(xy 375.040262 -175.341129) (xy 374.982789 -175.362923) (xy 374.923108 -175.377629) (xy 374.862089 -175.385033)
			(xy 374.831356 -175.385476) (xy 374.830848 -175.385476) (xy 374.797629 -175.384942) (xy 374.731757 -175.37628)
			(xy 374.667571 -175.359122) (xy 374.606164 -175.333759) (xy 374.577102 -175.317658) (xy 373.65305 -174.784004)
			(xy 373.624495 -174.766872) (xy 373.571672 -174.726325) (xy 373.524591 -174.679232) (xy 373.484057 -174.626398)
			(xy 373.450764 -174.568727) (xy 373.42528 -174.507205) (xy 373.408042 -174.442884) (xy 373.399344 -174.376863)
			(xy 373.398796 -174.343568) (xy 2.509012 -174.343568) (xy 2.509012 -175.83404) (xy 23.37714 -175.83404)
			(xy 23.381229 -175.778158) (xy 23.393412 -175.723468) (xy 23.413428 -175.671134) (xy 23.440851 -175.622272)
			(xy 23.475096 -175.577924) (xy 23.515432 -175.539034) (xy 23.561002 -175.506432) (xy 23.610833 -175.480813)
			(xy 23.663863 -175.462721) (xy 23.718961 -175.452544) (xy 23.774955 -175.450498) (xy 23.83065 -175.456626)
			(xy 23.884859 -175.470798) (xy 23.936427 -175.492712) (xy 23.984255 -175.521901) (xy 24.027323 -175.557742)
			(xy 24.064713 -175.599472) (xy 24.095629 -175.646202) (xy 24.119412 -175.696935) (xy 24.135554 -175.750591)
			(xy 24.143713 -175.806025) (xy 24.144224 -175.83404) (xy 24.143713 -175.862055) (xy 24.135554 -175.917489)
			(xy 24.119412 -175.971145) (xy 24.095629 -176.021878) (xy 24.064713 -176.068608) (xy 24.027323 -176.110338)
			(xy 23.984255 -176.146179) (xy 23.936427 -176.175368) (xy 23.884859 -176.197282) (xy 23.83065 -176.211454)
			(xy 23.774955 -176.217582) (xy 23.718961 -176.215536) (xy 23.663863 -176.205359) (xy 23.610833 -176.187267)
			(xy 23.561002 -176.161648) (xy 23.515432 -176.129046) (xy 23.475096 -176.090156) (xy 23.440851 -176.045808)
			(xy 23.413428 -175.996946) (xy 23.393412 -175.944612) (xy 23.381229 -175.889922) (xy 23.37714 -175.83404)
			(xy 2.509012 -175.83404) (xy 2.509012 -176.709832) (xy 348.657164 -176.709832) (xy 348.657658 -176.676531)
			(xy 348.666337 -176.610499) (xy 348.683566 -176.546165) (xy 348.709048 -176.484632) (xy 348.742347 -176.426953)
			(xy 348.782893 -176.374117) (xy 348.829992 -176.327027) (xy 348.882836 -176.286492) (xy 348.911418 -176.269396)
			(xy 349.83547 -175.735742) (xy 349.864533 -175.719642) (xy 349.925937 -175.694271) (xy 349.990123 -175.677114)
			(xy 350.055996 -175.668463) (xy 350.089216 -175.667924) (xy 350.089724 -175.667924) (xy 350.120458 -175.668315)
			(xy 350.121421 -175.668432) (xy 352.441764 -175.668432) (xy 352.442268 -175.637702) (xy 352.449672 -175.576689)
			(xy 352.464377 -175.517013) (xy 352.486168 -175.459545) (xy 352.514727 -175.405122) (xy 352.549637 -175.354539)
			(xy 352.59039 -175.308533) (xy 352.636392 -175.267774) (xy 352.686971 -175.232858) (xy 352.74139 -175.204292)
			(xy 352.798856 -175.182495) (xy 352.85853 -175.167783) (xy 352.919542 -175.160371) (xy 352.950272 -175.159924)
			(xy 352.95078 -175.159924) (xy 352.983998 -175.160489) (xy 353.049869 -175.169142) (xy 353.114055 -175.186291)
			(xy 353.175463 -175.211645) (xy 353.204526 -175.227742) (xy 354.128578 -175.761396) (xy 354.157139 -175.778518)
			(xy 354.209962 -175.819067) (xy 354.257042 -175.866162) (xy 354.297574 -175.918998) (xy 354.330866 -175.97667)
			(xy 354.3488 -176.019968) (xy 369.614196 -176.019968) (xy 369.614752 -175.98667) (xy 369.623426 -175.920641)
			(xy 369.640648 -175.85631) (xy 369.666122 -175.794779) (xy 369.699412 -175.737101) (xy 369.739949 -175.684263)
			(xy 369.787038 -175.637171) (xy 369.839873 -175.596631) (xy 369.86845 -175.579532) (xy 370.792502 -175.045878)
			(xy 370.82156 -175.029769) (xy 370.882966 -175.0044) (xy 370.947153 -174.987245) (xy 371.013028 -174.978597)
			(xy 371.046248 -174.97806) (xy 371.046756 -174.97806) (xy 371.077486 -174.978579) (xy 371.138498 -174.985982)
			(xy 371.198173 -175.000685) (xy 371.255641 -175.022475) (xy 371.310063 -175.051032) (xy 371.360647 -175.085941)
			(xy 371.406653 -175.126693) (xy 371.447412 -175.172694) (xy 371.482329 -175.223272) (xy 371.510894 -175.277689)
			(xy 371.532692 -175.335154) (xy 371.547404 -175.394827) (xy 371.554816 -175.455838) (xy 371.555264 -175.486568)
			(xy 371.554757 -175.519868) (xy 371.546077 -175.5859) (xy 371.543089 -175.597058) (xy 434.095902 -175.597058)
			(xy 434.099991 -175.541176) (xy 434.112174 -175.486486) (xy 434.13219 -175.434152) (xy 434.159613 -175.38529)
			(xy 434.193858 -175.340942) (xy 434.234194 -175.302052) (xy 434.279764 -175.26945) (xy 434.329595 -175.243831)
			(xy 434.382625 -175.225739) (xy 434.437723 -175.215562) (xy 434.493717 -175.213516) (xy 434.549412 -175.219644)
			(xy 434.603621 -175.233816) (xy 434.655189 -175.25573) (xy 434.703017 -175.284919) (xy 434.746085 -175.32076)
			(xy 434.783475 -175.36249) (xy 434.814391 -175.40922) (xy 434.838174 -175.459953) (xy 434.854316 -175.513609)
			(xy 434.862475 -175.569043) (xy 434.862986 -175.597058) (xy 434.862475 -175.625073) (xy 434.854316 -175.680507)
			(xy 434.838174 -175.734163) (xy 434.814391 -175.784896) (xy 434.783475 -175.831626) (xy 434.746085 -175.873356)
			(xy 434.703017 -175.909197) (xy 434.655189 -175.938386) (xy 434.603621 -175.9603) (xy 434.549412 -175.974472)
			(xy 434.493717 -175.9806) (xy 434.437723 -175.978554) (xy 434.382625 -175.968377) (xy 434.329595 -175.950285)
			(xy 434.279764 -175.924666) (xy 434.234194 -175.892064) (xy 434.193858 -175.853174) (xy 434.159613 -175.808826)
			(xy 434.13219 -175.759964) (xy 434.112174 -175.70763) (xy 434.099991 -175.65294) (xy 434.095902 -175.597058)
			(xy 371.543089 -175.597058) (xy 371.52885 -175.650232) (xy 371.503369 -175.711765) (xy 371.470072 -175.769443)
			(xy 371.429528 -175.82228) (xy 371.382432 -175.86937) (xy 371.329591 -175.909907) (xy 371.30101 -175.927004)
			(xy 370.376958 -176.460658) (xy 370.34791 -176.476786) (xy 370.2865 -176.50215) (xy 370.22231 -176.519299)
			(xy 370.156433 -176.527942) (xy 370.123212 -176.528476) (xy 370.122704 -176.528476) (xy 370.091971 -176.528059)
			(xy 370.030952 -176.52065) (xy 369.971272 -176.50594) (xy 369.9138 -176.484143) (xy 369.859375 -176.455577)
			(xy 369.808789 -176.420659) (xy 369.762782 -176.379898) (xy 369.722023 -176.333889) (xy 369.687108 -176.283301)
			(xy 369.658546 -176.228874) (xy 369.636752 -176.171401) (xy 369.622045 -176.11172) (xy 369.61464 -176.050701)
			(xy 369.614196 -176.019968) (xy 354.3488 -176.019968) (xy 354.356349 -176.038193) (xy 354.373586 -176.102515)
			(xy 354.382284 -176.168536) (xy 354.382832 -176.201832) (xy 354.382374 -176.232563) (xy 354.374962 -176.293576)
			(xy 354.360251 -176.353251) (xy 354.338454 -176.410717) (xy 354.30989 -176.465138) (xy 354.274975 -176.515719)
			(xy 354.234218 -176.561723) (xy 354.188213 -176.60248) (xy 354.137631 -176.637394) (xy 354.08321 -176.665957)
			(xy 354.025743 -176.687753) (xy 353.966068 -176.702464) (xy 353.905055 -176.709875) (xy 353.874324 -176.71034)
			(xy 353.873816 -176.71034) (xy 353.840597 -176.709782) (xy 353.774726 -176.701127) (xy 353.710541 -176.683976)
			(xy 353.649132 -176.658621) (xy 353.62007 -176.642522) (xy 352.696018 -176.108868) (xy 352.667463 -176.091735)
			(xy 352.614637 -176.051191) (xy 352.567553 -176.004099) (xy 352.527018 -175.951266) (xy 352.493724 -175.893595)
			(xy 352.468241 -175.832072) (xy 352.451005 -175.76775) (xy 352.44231 -175.701728) (xy 352.441764 -175.668432)
			(xy 350.121421 -175.668432) (xy 350.181477 -175.675727) (xy 350.241158 -175.69044) (xy 350.29863 -175.71224)
			(xy 350.353056 -175.740808) (xy 350.403641 -175.775729) (xy 350.449648 -175.816492) (xy 350.490406 -175.862503)
			(xy 350.525321 -175.913092) (xy 350.553883 -175.967521) (xy 350.575676 -176.024996) (xy 350.590383 -176.084678)
			(xy 350.597788 -176.145698) (xy 350.598232 -176.176432) (xy 350.597712 -176.209732) (xy 350.589036 -176.275763)
			(xy 350.571812 -176.340097) (xy 350.546334 -176.40163) (xy 350.513038 -176.459309) (xy 350.472496 -176.512145)
			(xy 350.4254 -176.559235) (xy 350.372559 -176.599772) (xy 350.343978 -176.616868) (xy 349.419926 -177.150522)
			(xy 349.390862 -177.16662) (xy 349.329459 -177.191992) (xy 349.265273 -177.20915) (xy 349.1994 -177.217802)
			(xy 349.16618 -177.21834) (xy 349.165672 -177.21834) (xy 349.134942 -177.21787) (xy 349.073929 -177.210459)
			(xy 349.014255 -177.195748) (xy 348.956789 -177.173953) (xy 348.902369 -177.145389) (xy 348.851788 -177.110475)
			(xy 348.805784 -177.069719) (xy 348.765027 -177.023715) (xy 348.730113 -176.973135) (xy 348.701549 -176.918715)
			(xy 348.679753 -176.861249) (xy 348.665041 -176.801575) (xy 348.65763 -176.740562) (xy 348.657164 -176.709832)
			(xy 2.509012 -176.709832) (xy 2.509012 -179.757832) (xy 348.657164 -179.757832) (xy 348.657658 -179.724531)
			(xy 348.666337 -179.658499) (xy 348.683566 -179.594165) (xy 348.709048 -179.532632) (xy 348.742347 -179.474953)
			(xy 348.782893 -179.422117) (xy 348.829992 -179.375027) (xy 348.882836 -179.334492) (xy 348.911418 -179.317396)
			(xy 349.83547 -178.783742) (xy 349.864533 -178.767642) (xy 349.925937 -178.742271) (xy 349.990123 -178.725114)
			(xy 350.055996 -178.716463) (xy 350.089216 -178.715924) (xy 350.089724 -178.715924) (xy 350.120458 -178.716315)
			(xy 350.181477 -178.723727) (xy 350.241158 -178.73844) (xy 350.29863 -178.76024) (xy 350.353056 -178.788808)
			(xy 350.403641 -178.823729) (xy 350.449648 -178.864492) (xy 350.490406 -178.910503) (xy 350.525321 -178.961092)
			(xy 350.553883 -179.015521) (xy 350.575676 -179.072996) (xy 350.590383 -179.132678) (xy 350.597788 -179.193698)
			(xy 350.598232 -179.224432) (xy 350.597712 -179.257732) (xy 350.589036 -179.323763) (xy 350.581628 -179.351432)
			(xy 352.441764 -179.351432) (xy 352.442268 -179.320702) (xy 352.449672 -179.259689) (xy 352.464377 -179.200013)
			(xy 352.486168 -179.142545) (xy 352.514727 -179.088122) (xy 352.549637 -179.037539) (xy 352.59039 -178.991533)
			(xy 352.636392 -178.950774) (xy 352.686971 -178.915858) (xy 352.74139 -178.887292) (xy 352.798856 -178.865495)
			(xy 352.85853 -178.850783) (xy 352.919542 -178.843371) (xy 352.950272 -178.842924) (xy 352.95078 -178.842924)
			(xy 352.983998 -178.843489) (xy 353.049869 -178.852142) (xy 353.114055 -178.869291) (xy 353.175463 -178.894645)
			(xy 353.204526 -178.910742) (xy 353.476772 -179.067968) (xy 369.614196 -179.067968) (xy 369.614752 -179.03467)
			(xy 369.623426 -178.968641) (xy 369.640648 -178.90431) (xy 369.666122 -178.842779) (xy 369.699412 -178.785101)
			(xy 369.739949 -178.732263) (xy 369.787038 -178.685171) (xy 369.839873 -178.644631) (xy 369.86845 -178.627532)
			(xy 370.792502 -178.093878) (xy 370.82156 -178.077769) (xy 370.882966 -178.0524) (xy 370.947153 -178.035245)
			(xy 371.013028 -178.026597) (xy 371.046248 -178.02606) (xy 371.046756 -178.02606) (xy 371.076835 -178.026568)
			(xy 373.398796 -178.026568) (xy 373.399226 -177.995836) (xy 373.406638 -177.934821) (xy 373.421351 -177.875144)
			(xy 373.443149 -177.817676) (xy 373.471715 -177.763254) (xy 373.506633 -177.712671) (xy 373.547392 -177.666667)
			(xy 373.5934 -177.62591) (xy 373.643984 -177.590996) (xy 373.698409 -177.562434) (xy 373.755879 -177.54064)
			(xy 373.815556 -177.525932) (xy 373.876572 -177.518524) (xy 373.907304 -177.51806) (xy 373.907812 -177.51806)
			(xy 373.941031 -177.518606) (xy 374.006903 -177.527264) (xy 374.071088 -177.544419) (xy 374.132496 -177.569778)
			(xy 374.161558 -177.585878) (xy 375.08561 -178.119532) (xy 375.114171 -178.136654) (xy 375.166997 -178.177201)
			(xy 375.214079 -178.224295) (xy 375.254613 -178.27713) (xy 375.287906 -178.334802) (xy 375.313388 -178.396326)
			(xy 375.330623 -178.460649) (xy 375.339318 -178.526672) (xy 375.339864 -178.559968) (xy 375.339432 -178.590701)
			(xy 375.332026 -178.65172) (xy 375.317319 -178.7114) (xy 375.295524 -178.768873) (xy 375.266961 -178.823299)
			(xy 375.232044 -178.873885) (xy 375.191284 -178.919893) (xy 375.145275 -178.960651) (xy 375.094689 -178.995567)
			(xy 375.040262 -179.024129) (xy 374.982789 -179.045923) (xy 374.923108 -179.060629) (xy 374.862089 -179.068033)
			(xy 374.831356 -179.068476) (xy 374.830848 -179.068476) (xy 374.797629 -179.067942) (xy 374.731757 -179.05928)
			(xy 374.667571 -179.042122) (xy 374.606164 -179.016759) (xy 374.577102 -179.000658) (xy 373.65305 -178.467004)
			(xy 373.624495 -178.449872) (xy 373.571672 -178.409325) (xy 373.524591 -178.362232) (xy 373.484057 -178.309398)
			(xy 373.450764 -178.251727) (xy 373.42528 -178.190205) (xy 373.408042 -178.125884) (xy 373.399344 -178.059863)
			(xy 373.398796 -178.026568) (xy 371.076835 -178.026568) (xy 371.077486 -178.026579) (xy 371.138498 -178.033982)
			(xy 371.198173 -178.048685) (xy 371.255641 -178.070475) (xy 371.310063 -178.099032) (xy 371.360647 -178.133941)
			(xy 371.406653 -178.174693) (xy 371.447412 -178.220694) (xy 371.482329 -178.271272) (xy 371.510894 -178.325689)
			(xy 371.532692 -178.383154) (xy 371.547404 -178.442827) (xy 371.554816 -178.503838) (xy 371.555264 -178.534568)
			(xy 371.554757 -178.567868) (xy 371.546077 -178.6339) (xy 371.52885 -178.698232) (xy 371.503369 -178.759765)
			(xy 371.470072 -178.817443) (xy 371.429528 -178.87028) (xy 371.382432 -178.91737) (xy 371.329591 -178.957907)
			(xy 371.30101 -178.975004) (xy 370.376958 -179.508658) (xy 370.34791 -179.524786) (xy 370.2865 -179.55015)
			(xy 370.22231 -179.567299) (xy 370.156433 -179.575942) (xy 370.123212 -179.576476) (xy 370.122704 -179.576476)
			(xy 370.091971 -179.576059) (xy 370.030952 -179.56865) (xy 369.971272 -179.55394) (xy 369.9138 -179.532143)
			(xy 369.859375 -179.503577) (xy 369.808789 -179.468659) (xy 369.762782 -179.427898) (xy 369.722023 -179.381889)
			(xy 369.687108 -179.331301) (xy 369.658546 -179.276874) (xy 369.636752 -179.219401) (xy 369.622045 -179.15972)
			(xy 369.61464 -179.098701) (xy 369.614196 -179.067968) (xy 353.476772 -179.067968) (xy 354.128578 -179.444396)
			(xy 354.157139 -179.461518) (xy 354.209962 -179.502067) (xy 354.257042 -179.549162) (xy 354.297574 -179.601998)
			(xy 354.330866 -179.65967) (xy 354.356349 -179.721193) (xy 354.373586 -179.785515) (xy 354.382284 -179.851536)
			(xy 354.382832 -179.884832) (xy 354.382374 -179.915563) (xy 354.374962 -179.976576) (xy 354.360251 -180.036251)
			(xy 354.338454 -180.093717) (xy 354.30989 -180.148138) (xy 354.274975 -180.198719) (xy 354.234218 -180.244723)
			(xy 354.188213 -180.28548) (xy 354.137631 -180.320394) (xy 354.08321 -180.348957) (xy 354.025743 -180.370753)
			(xy 353.966068 -180.385464) (xy 353.905055 -180.392875) (xy 353.874324 -180.39334) (xy 353.873816 -180.39334)
			(xy 353.840597 -180.392782) (xy 353.774726 -180.384127) (xy 353.710541 -180.366976) (xy 353.649132 -180.341621)
			(xy 353.62007 -180.325522) (xy 352.696018 -179.791868) (xy 352.667463 -179.774735) (xy 352.614637 -179.734191)
			(xy 352.567553 -179.687099) (xy 352.527018 -179.634266) (xy 352.493724 -179.576595) (xy 352.468241 -179.515072)
			(xy 352.451005 -179.45075) (xy 352.44231 -179.384728) (xy 352.441764 -179.351432) (xy 350.581628 -179.351432)
			(xy 350.571812 -179.388097) (xy 350.546334 -179.44963) (xy 350.513038 -179.507309) (xy 350.472496 -179.560145)
			(xy 350.4254 -179.607235) (xy 350.372559 -179.647772) (xy 350.343978 -179.664868) (xy 349.419926 -180.198522)
			(xy 349.390862 -180.21462) (xy 349.329459 -180.239992) (xy 349.265273 -180.25715) (xy 349.1994 -180.265802)
			(xy 349.16618 -180.26634) (xy 349.165672 -180.26634) (xy 349.134942 -180.26587) (xy 349.073929 -180.258459)
			(xy 349.014255 -180.243748) (xy 348.956789 -180.221953) (xy 348.902369 -180.193389) (xy 348.851788 -180.158475)
			(xy 348.805784 -180.117719) (xy 348.765027 -180.071715) (xy 348.730113 -180.021135) (xy 348.701549 -179.966715)
			(xy 348.679753 -179.909249) (xy 348.665041 -179.849575) (xy 348.65763 -179.788562) (xy 348.657164 -179.757832)
			(xy 2.509012 -179.757832) (xy 2.509012 -182.805832) (xy 348.657164 -182.805832) (xy 348.657658 -182.772531)
			(xy 348.666337 -182.706499) (xy 348.683566 -182.642165) (xy 348.709048 -182.580632) (xy 348.742347 -182.522953)
			(xy 348.782893 -182.470117) (xy 348.829992 -182.423027) (xy 348.882836 -182.382492) (xy 348.911418 -182.365396)
			(xy 349.83547 -181.831742) (xy 349.864533 -181.815642) (xy 349.925937 -181.790271) (xy 349.990123 -181.773114)
			(xy 350.055996 -181.764463) (xy 350.089216 -181.763924) (xy 350.089724 -181.763924) (xy 350.120458 -181.764315)
			(xy 350.181477 -181.771727) (xy 350.241158 -181.78644) (xy 350.29863 -181.80824) (xy 350.353056 -181.836808)
			(xy 350.403641 -181.871729) (xy 350.449648 -181.912492) (xy 350.490406 -181.958503) (xy 350.525321 -182.009092)
			(xy 350.553883 -182.063521) (xy 350.57377 -182.115968) (xy 369.614196 -182.115968) (xy 369.614752 -182.08267)
			(xy 369.623426 -182.016641) (xy 369.640648 -181.95231) (xy 369.666122 -181.890779) (xy 369.699412 -181.833101)
			(xy 369.739949 -181.780263) (xy 369.787038 -181.733171) (xy 369.839873 -181.692631) (xy 369.86845 -181.675532)
			(xy 370.792502 -181.141878) (xy 370.82156 -181.125769) (xy 370.882966 -181.1004) (xy 370.947153 -181.083245)
			(xy 371.013028 -181.074597) (xy 371.046248 -181.07406) (xy 371.046756 -181.07406) (xy 371.077486 -181.074579)
			(xy 371.138498 -181.081982) (xy 371.198173 -181.096685) (xy 371.255641 -181.118475) (xy 371.310063 -181.147032)
			(xy 371.360647 -181.181941) (xy 371.406653 -181.222693) (xy 371.447412 -181.268694) (xy 371.482329 -181.319272)
			(xy 371.510894 -181.373689) (xy 371.532692 -181.431154) (xy 371.547404 -181.490827) (xy 371.554816 -181.551838)
			(xy 371.555264 -181.582568) (xy 371.554757 -181.615868) (xy 371.546077 -181.6819) (xy 371.538668 -181.709568)
			(xy 373.398796 -181.709568) (xy 373.399226 -181.678836) (xy 373.406638 -181.617821) (xy 373.421351 -181.558144)
			(xy 373.443149 -181.500676) (xy 373.471715 -181.446254) (xy 373.506633 -181.395671) (xy 373.547392 -181.349667)
			(xy 373.5934 -181.30891) (xy 373.643984 -181.273996) (xy 373.698409 -181.245434) (xy 373.755879 -181.22364)
			(xy 373.815556 -181.208932) (xy 373.876572 -181.201524) (xy 373.907304 -181.20106) (xy 373.907812 -181.20106)
			(xy 373.941031 -181.201606) (xy 374.006903 -181.210264) (xy 374.071088 -181.227419) (xy 374.132496 -181.252778)
			(xy 374.161558 -181.268878) (xy 375.08561 -181.802532) (xy 375.114171 -181.819654) (xy 375.166997 -181.860201)
			(xy 375.214079 -181.907295) (xy 375.254613 -181.96013) (xy 375.287906 -182.017802) (xy 375.313388 -182.079326)
			(xy 375.330623 -182.143649) (xy 375.339318 -182.209672) (xy 375.339864 -182.242968) (xy 375.339432 -182.273701)
			(xy 375.332026 -182.33472) (xy 375.317319 -182.3944) (xy 375.295524 -182.451873) (xy 375.266961 -182.506299)
			(xy 375.232044 -182.556885) (xy 375.191284 -182.602893) (xy 375.145275 -182.643651) (xy 375.094689 -182.678567)
			(xy 375.040262 -182.707129) (xy 374.982789 -182.728923) (xy 374.923108 -182.743629) (xy 374.862089 -182.751033)
			(xy 374.831356 -182.751476) (xy 374.830848 -182.751476) (xy 374.797629 -182.750942) (xy 374.731757 -182.74228)
			(xy 374.667571 -182.725122) (xy 374.606164 -182.699759) (xy 374.577102 -182.683658) (xy 373.65305 -182.150004)
			(xy 373.624495 -182.132872) (xy 373.571672 -182.092325) (xy 373.524591 -182.045232) (xy 373.484057 -181.992398)
			(xy 373.450764 -181.934727) (xy 373.42528 -181.873205) (xy 373.408042 -181.808884) (xy 373.399344 -181.742863)
			(xy 373.398796 -181.709568) (xy 371.538668 -181.709568) (xy 371.52885 -181.746232) (xy 371.503369 -181.807765)
			(xy 371.470072 -181.865443) (xy 371.429528 -181.91828) (xy 371.382432 -181.96537) (xy 371.329591 -182.005907)
			(xy 371.30101 -182.023004) (xy 370.376958 -182.556658) (xy 370.34791 -182.572786) (xy 370.2865 -182.59815)
			(xy 370.22231 -182.615299) (xy 370.156433 -182.623942) (xy 370.123212 -182.624476) (xy 370.122704 -182.624476)
			(xy 370.091971 -182.624059) (xy 370.030952 -182.61665) (xy 369.971272 -182.60194) (xy 369.9138 -182.580143)
			(xy 369.859375 -182.551577) (xy 369.808789 -182.516659) (xy 369.762782 -182.475898) (xy 369.722023 -182.429889)
			(xy 369.687108 -182.379301) (xy 369.658546 -182.324874) (xy 369.636752 -182.267401) (xy 369.622045 -182.20772)
			(xy 369.61464 -182.146701) (xy 369.614196 -182.115968) (xy 350.57377 -182.115968) (xy 350.575676 -182.120996)
			(xy 350.590383 -182.180678) (xy 350.597788 -182.241698) (xy 350.598232 -182.272432) (xy 350.597712 -182.305732)
			(xy 350.589036 -182.371763) (xy 350.571812 -182.436097) (xy 350.546334 -182.49763) (xy 350.513038 -182.555309)
			(xy 350.472496 -182.608145) (xy 350.4254 -182.655235) (xy 350.372559 -182.695772) (xy 350.343978 -182.712868)
			(xy 349.775297 -183.04129) (xy 352.441764 -183.04129) (xy 352.442192 -183.010552) (xy 352.449601 -182.949525)
			(xy 352.46431 -182.889835) (xy 352.486105 -182.832352) (xy 352.514667 -182.777914) (xy 352.549581 -182.727315)
			(xy 352.590338 -182.681292) (xy 352.636344 -182.640516) (xy 352.686928 -182.60558) (xy 352.741353 -182.576994)
			(xy 352.798826 -182.555175) (xy 352.85851 -182.540441) (xy 352.919534 -182.533005) (xy 352.950272 -182.532528)
			(xy 352.95078 -182.532528) (xy 352.984007 -182.533118) (xy 353.049889 -182.541823) (xy 353.114077 -182.559036)
			(xy 353.175475 -182.584464) (xy 353.204526 -182.6006) (xy 354.128578 -183.134254) (xy 354.157165 -183.151335)
			(xy 354.209988 -183.19189) (xy 354.257067 -183.238991) (xy 354.297597 -183.291832) (xy 354.330886 -183.34951)
			(xy 354.356365 -183.411039) (xy 354.373597 -183.475367) (xy 354.382288 -183.541392) (xy 354.382832 -183.57469)
			(xy 354.382389 -183.605428) (xy 354.374982 -183.666455) (xy 354.360275 -183.726145) (xy 354.338483 -183.783627)
			(xy 354.309922 -183.838065) (xy 354.275009 -183.888665) (xy 354.234254 -183.934688) (xy 354.188249 -183.975465)
			(xy 354.137666 -184.010401) (xy 354.083241 -184.038987) (xy 354.025768 -184.060806) (xy 353.966085 -184.07554)
			(xy 353.905061 -184.082975) (xy 353.874324 -184.083452) (xy 353.873816 -184.083452) (xy 353.840589 -184.082867)
			(xy 353.774706 -184.07416) (xy 353.710519 -184.056946) (xy 353.649121 -184.031517) (xy 353.62007 -184.01538)
			(xy 352.696018 -183.481726) (xy 352.667489 -183.464552) (xy 352.614663 -183.424014) (xy 352.567578 -183.376928)
			(xy 352.527041 -183.324101) (xy 352.493744 -183.266436) (xy 352.468257 -183.204918) (xy 352.451015 -183.140601)
			(xy 352.442314 -183.074584) (xy 352.441764 -183.04129) (xy 349.775297 -183.04129) (xy 349.419926 -183.246522)
			(xy 349.390862 -183.26262) (xy 349.329459 -183.287992) (xy 349.265273 -183.30515) (xy 349.1994 -183.313802)
			(xy 349.16618 -183.31434) (xy 349.165672 -183.31434) (xy 349.134942 -183.31387) (xy 349.073929 -183.306459)
			(xy 349.014255 -183.291748) (xy 348.956789 -183.269953) (xy 348.902369 -183.241389) (xy 348.851788 -183.206475)
			(xy 348.805784 -183.165719) (xy 348.765027 -183.119715) (xy 348.730113 -183.069135) (xy 348.701549 -183.014715)
			(xy 348.679753 -182.957249) (xy 348.665041 -182.897575) (xy 348.65763 -182.836562) (xy 348.657164 -182.805832)
			(xy 2.509012 -182.805832) (xy 2.509012 -185.011568) (xy 372.585996 -185.011568) (xy 372.586426 -184.980836)
			(xy 372.593838 -184.919821) (xy 372.608551 -184.860144) (xy 372.630349 -184.802676) (xy 372.658915 -184.748254)
			(xy 372.693833 -184.697671) (xy 372.734592 -184.651667) (xy 372.7806 -184.61091) (xy 372.831184 -184.575996)
			(xy 372.885609 -184.547434) (xy 372.943079 -184.52564) (xy 373.002756 -184.510932) (xy 373.063772 -184.503524)
			(xy 373.094504 -184.50306) (xy 373.095012 -184.50306) (xy 373.128231 -184.503606) (xy 373.194103 -184.512264)
			(xy 373.258288 -184.529419) (xy 373.319696 -184.554778) (xy 373.348758 -184.570878) (xy 374.27281 -185.104532)
			(xy 374.301371 -185.121654) (xy 374.354197 -185.162201) (xy 374.401279 -185.209295) (xy 374.441813 -185.26213)
			(xy 374.475106 -185.319802) (xy 374.500588 -185.381326) (xy 374.517823 -185.445649) (xy 374.526518 -185.511672)
			(xy 374.527064 -185.544968) (xy 374.526632 -185.575701) (xy 374.519226 -185.63672) (xy 374.504519 -185.6964)
			(xy 374.482724 -185.753873) (xy 374.454161 -185.808299) (xy 374.419244 -185.858885) (xy 374.378484 -185.904893)
			(xy 374.332475 -185.945651) (xy 374.281889 -185.980567) (xy 374.227462 -186.009129) (xy 374.169989 -186.030923)
			(xy 374.110308 -186.045629) (xy 374.049289 -186.053033) (xy 374.018556 -186.053476) (xy 374.018048 -186.053476)
			(xy 373.984829 -186.052942) (xy 373.918957 -186.04428) (xy 373.854771 -186.027122) (xy 373.793364 -186.001759)
			(xy 373.764302 -185.985658) (xy 372.84025 -185.452004) (xy 372.811695 -185.434872) (xy 372.758872 -185.394325)
			(xy 372.711791 -185.347232) (xy 372.671257 -185.294398) (xy 372.637964 -185.236727) (xy 372.61248 -185.175205)
			(xy 372.595242 -185.110884) (xy 372.586544 -185.044863) (xy 372.585996 -185.011568) (xy 2.509012 -185.011568)
			(xy 2.509012 -186.714892) (xy 351.367344 -186.714892) (xy 351.367848 -186.684163) (xy 351.375257 -186.623152)
			(xy 351.389965 -186.563479) (xy 351.411758 -186.506014) (xy 351.440318 -186.451595) (xy 351.475229 -186.401014)
			(xy 351.515982 -186.355011) (xy 351.561983 -186.314254) (xy 351.612561 -186.279339) (xy 351.666978 -186.250774)
			(xy 351.724441 -186.228977) (xy 351.784113 -186.214264) (xy 351.845123 -186.206851) (xy 351.875852 -186.206384)
			(xy 351.87636 -186.206384) (xy 351.90958 -186.206906) (xy 351.975453 -186.215571) (xy 352.039638 -186.232732)
			(xy 352.101045 -186.258098) (xy 352.130106 -186.274202) (xy 353.054158 -186.807856) (xy 353.082741 -186.824943)
			(xy 353.135565 -186.865496) (xy 353.182645 -186.912596) (xy 353.223176 -186.965436) (xy 353.256466 -187.023114)
			(xy 353.281945 -187.084642) (xy 353.299177 -187.148969) (xy 353.307868 -187.214995) (xy 353.308412 -187.248292)
			(xy 353.307955 -187.279024) (xy 353.300547 -187.340039) (xy 353.285839 -187.399717) (xy 353.264044 -187.457187)
			(xy 353.235482 -187.51161) (xy 353.200567 -187.562194) (xy 353.15981 -187.608201) (xy 353.113804 -187.648959)
			(xy 353.063221 -187.683875) (xy 353.008798 -187.712439) (xy 352.951329 -187.734235) (xy 352.891651 -187.748945)
			(xy 352.830636 -187.756354) (xy 352.799904 -187.7568) (xy 352.799396 -187.7568) (xy 352.766177 -187.756256)
			(xy 352.700305 -187.747598) (xy 352.636119 -187.730443) (xy 352.574711 -187.705083) (xy 352.54565 -187.688982)
			(xy 351.621598 -187.155328) (xy 351.593065 -187.13816) (xy 351.54024 -187.09762) (xy 351.493156 -187.050533)
			(xy 351.45262 -186.997705) (xy 351.419323 -186.940039) (xy 351.393837 -186.878521) (xy 351.376595 -186.814204)
			(xy 351.367894 -186.748186) (xy 351.367344 -186.714892) (xy 2.509012 -186.714892) (xy 2.509012 -206.024988)
			(xy 86.700624 -206.024988) (xy 86.704605 -205.891968) (xy 86.716534 -205.759423) (xy 86.736369 -205.62783)
			(xy 86.764038 -205.497658) (xy 86.799442 -205.369373) (xy 86.842455 -205.243436) (xy 86.892922 -205.120297)
			(xy 86.950663 -205.000396) (xy 87.015472 -204.884163) (xy 87.087116 -204.772013) (xy 87.165338 -204.664349)
			(xy 87.249859 -204.561556) (xy 87.340377 -204.464001) (xy 87.436566 -204.372035) (xy 87.538084 -204.285985)
			(xy 87.644565 -204.206161) (xy 87.75563 -204.132848) (xy 87.870881 -204.066308) (xy 87.989905 -204.006779)
			(xy 88.112276 -203.954475) (xy 88.237555 -203.909583) (xy 88.365296 -203.872264) (xy 88.495039 -203.842651)
			(xy 88.626321 -203.82085) (xy 88.758672 -203.80694) (xy 88.891618 -203.800969) (xy 89.024683 -203.80296)
			(xy 89.157391 -203.812905) (xy 89.289267 -203.830769) (xy 89.419838 -203.856487) (xy 89.548638 -203.889968)
			(xy 89.675204 -203.931092) (xy 89.799085 -203.979712) (xy 89.919836 -204.035653) (xy 90.037026 -204.098715)
			(xy 90.150235 -204.168673) (xy 90.259057 -204.245277) (xy 90.363103 -204.328251) (xy 90.462001 -204.417299)
			(xy 90.555396 -204.512102) (xy 90.642954 -204.61232) (xy 90.724363 -204.717596) (xy 90.799329 -204.827552)
			(xy 90.867586 -204.941794) (xy 90.928888 -205.059914) (xy 90.983017 -205.181489) (xy 91.029778 -205.306083)
			(xy 91.069004 -205.433251) (xy 91.100554 -205.562537) (xy 91.124317 -205.693478) (xy 91.140206 -205.825606)
			(xy 91.148164 -205.958448) (xy 91.148662 -206.024988) (xy 132.710692 -206.024988) (xy 132.714673 -205.891968)
			(xy 132.726602 -205.759423) (xy 132.746437 -205.62783) (xy 132.774106 -205.497658) (xy 132.80951 -205.369373)
			(xy 132.852523 -205.243436) (xy 132.90299 -205.120297) (xy 132.960731 -205.000396) (xy 133.02554 -204.884163)
			(xy 133.097184 -204.772013) (xy 133.175406 -204.664349) (xy 133.259927 -204.561556) (xy 133.350445 -204.464001)
			(xy 133.446634 -204.372035) (xy 133.548152 -204.285985) (xy 133.654633 -204.206161) (xy 133.765698 -204.132848)
			(xy 133.880949 -204.066308) (xy 133.999973 -204.006779) (xy 134.122344 -203.954475) (xy 134.247623 -203.909583)
			(xy 134.375364 -203.872264) (xy 134.505107 -203.842651) (xy 134.636389 -203.82085) (xy 134.76874 -203.80694)
			(xy 134.901686 -203.800969) (xy 135.034751 -203.80296) (xy 135.167459 -203.812905) (xy 135.299335 -203.830769)
			(xy 135.429906 -203.856487) (xy 135.558706 -203.889968) (xy 135.685272 -203.931092) (xy 135.809153 -203.979712)
			(xy 135.929904 -204.035653) (xy 136.047094 -204.098715) (xy 136.160303 -204.168673) (xy 136.269125 -204.245277)
			(xy 136.373171 -204.328251) (xy 136.472069 -204.417299) (xy 136.565464 -204.512102) (xy 136.653022 -204.61232)
			(xy 136.734431 -204.717596) (xy 136.809397 -204.827552) (xy 136.877654 -204.941794) (xy 136.938956 -205.059914)
			(xy 136.993085 -205.181489) (xy 137.039846 -205.306083) (xy 137.079072 -205.433251) (xy 137.110622 -205.562537)
			(xy 137.134385 -205.693478) (xy 137.150274 -205.825606) (xy 137.158232 -205.958448) (xy 137.15873 -206.024988)
			(xy 334.640692 -206.024988) (xy 334.644673 -205.891968) (xy 334.656602 -205.759423) (xy 334.676437 -205.62783)
			(xy 334.704106 -205.497658) (xy 334.73951 -205.369373) (xy 334.782523 -205.243436) (xy 334.83299 -205.120297)
			(xy 334.890731 -205.000396) (xy 334.95554 -204.884163) (xy 335.027184 -204.772013) (xy 335.105406 -204.664349)
			(xy 335.189927 -204.561556) (xy 335.280445 -204.464001) (xy 335.376634 -204.372035) (xy 335.478152 -204.285985)
			(xy 335.584633 -204.206161) (xy 335.695698 -204.132848) (xy 335.810949 -204.066308) (xy 335.929973 -204.006779)
			(xy 336.052344 -203.954475) (xy 336.177623 -203.909583) (xy 336.305364 -203.872264) (xy 336.435107 -203.842651)
			(xy 336.566389 -203.82085) (xy 336.69874 -203.80694) (xy 336.831686 -203.800969) (xy 336.964751 -203.80296)
			(xy 337.097459 -203.812905) (xy 337.229335 -203.830769) (xy 337.359906 -203.856487) (xy 337.488706 -203.889968)
			(xy 337.615272 -203.931092) (xy 337.739153 -203.979712) (xy 337.859904 -204.035653) (xy 337.977094 -204.098715)
			(xy 338.090303 -204.168673) (xy 338.199125 -204.245277) (xy 338.303171 -204.328251) (xy 338.402069 -204.417299)
			(xy 338.495464 -204.512102) (xy 338.583022 -204.61232) (xy 338.664431 -204.717596) (xy 338.739397 -204.827552)
			(xy 338.807654 -204.941794) (xy 338.868956 -205.059914) (xy 338.923085 -205.181489) (xy 338.969846 -205.306083)
			(xy 339.009072 -205.433251) (xy 339.040622 -205.562537) (xy 339.064385 -205.693478) (xy 339.080274 -205.825606)
			(xy 339.088232 -205.958448) (xy 339.08873 -206.024988) (xy 380.650506 -206.024988) (xy 380.654487 -205.891968)
			(xy 380.666416 -205.759423) (xy 380.686251 -205.62783) (xy 380.71392 -205.497658) (xy 380.749324 -205.369373)
			(xy 380.792337 -205.243436) (xy 380.842804 -205.120297) (xy 380.900545 -205.000396) (xy 380.965354 -204.884163)
			(xy 381.036998 -204.772013) (xy 381.11522 -204.664349) (xy 381.199741 -204.561556) (xy 381.290259 -204.464001)
			(xy 381.386448 -204.372035) (xy 381.487966 -204.285985) (xy 381.594447 -204.206161) (xy 381.705512 -204.132848)
			(xy 381.820763 -204.066308) (xy 381.939787 -204.006779) (xy 382.062158 -203.954475) (xy 382.187437 -203.909583)
			(xy 382.315178 -203.872264) (xy 382.444921 -203.842651) (xy 382.576203 -203.82085) (xy 382.708554 -203.80694)
			(xy 382.8415 -203.800969) (xy 382.974565 -203.80296) (xy 383.107273 -203.812905) (xy 383.239149 -203.830769)
			(xy 383.36972 -203.856487) (xy 383.49852 -203.889968) (xy 383.625086 -203.931092) (xy 383.748967 -203.979712)
			(xy 383.869718 -204.035653) (xy 383.986908 -204.098715) (xy 384.100117 -204.168673) (xy 384.208939 -204.245277)
			(xy 384.312985 -204.328251) (xy 384.411883 -204.417299) (xy 384.505278 -204.512102) (xy 384.592836 -204.61232)
			(xy 384.674245 -204.717596) (xy 384.749211 -204.827552) (xy 384.817468 -204.941794) (xy 384.87877 -205.059914)
			(xy 384.932899 -205.181489) (xy 384.97966 -205.306083) (xy 385.018886 -205.433251) (xy 385.050436 -205.562537)
			(xy 385.074199 -205.693478) (xy 385.090088 -205.825606) (xy 385.098046 -205.958448) (xy 385.098544 -206.024988)
			(xy 385.098046 -206.091528) (xy 385.090088 -206.22437) (xy 385.074199 -206.356498) (xy 385.050436 -206.487439)
			(xy 385.018886 -206.616725) (xy 384.97966 -206.743893) (xy 384.932899 -206.868487) (xy 384.87877 -206.990062)
			(xy 384.817468 -207.108182) (xy 384.749211 -207.222424) (xy 384.674245 -207.33238) (xy 384.592836 -207.437656)
			(xy 384.505278 -207.537874) (xy 384.411883 -207.632677) (xy 384.312985 -207.721725) (xy 384.208939 -207.804699)
			(xy 384.100117 -207.881303) (xy 383.986908 -207.951261) (xy 383.869718 -208.014323) (xy 383.748967 -208.070264)
			(xy 383.625086 -208.118884) (xy 383.49852 -208.160008) (xy 383.36972 -208.193489) (xy 383.239149 -208.219207)
			(xy 383.107273 -208.237071) (xy 382.974565 -208.247016) (xy 382.8415 -208.249007) (xy 382.708554 -208.243036)
			(xy 382.576203 -208.229126) (xy 382.444921 -208.207325) (xy 382.315178 -208.177712) (xy 382.187437 -208.140393)
			(xy 382.062158 -208.095501) (xy 381.939787 -208.043197) (xy 381.820763 -207.983668) (xy 381.705512 -207.917128)
			(xy 381.594447 -207.843815) (xy 381.487966 -207.763991) (xy 381.386448 -207.677941) (xy 381.290259 -207.585975)
			(xy 381.199741 -207.48842) (xy 381.11522 -207.385627) (xy 381.036998 -207.277963) (xy 380.965354 -207.165813)
			(xy 380.900545 -207.04958) (xy 380.842804 -206.929679) (xy 380.792337 -206.80654) (xy 380.749324 -206.680603)
			(xy 380.71392 -206.552318) (xy 380.686251 -206.422146) (xy 380.666416 -206.290553) (xy 380.654487 -206.158008)
			(xy 380.650506 -206.024988) (xy 339.08873 -206.024988) (xy 339.088232 -206.091528) (xy 339.080274 -206.22437)
			(xy 339.064385 -206.356498) (xy 339.040622 -206.487439) (xy 339.009072 -206.616725) (xy 338.969846 -206.743893)
			(xy 338.923085 -206.868487) (xy 338.868956 -206.990062) (xy 338.807654 -207.108182) (xy 338.739397 -207.222424)
			(xy 338.664431 -207.33238) (xy 338.583022 -207.437656) (xy 338.495464 -207.537874) (xy 338.402069 -207.632677)
			(xy 338.303171 -207.721725) (xy 338.199125 -207.804699) (xy 338.090303 -207.881303) (xy 337.977094 -207.951261)
			(xy 337.859904 -208.014323) (xy 337.739153 -208.070264) (xy 337.615272 -208.118884) (xy 337.488706 -208.160008)
			(xy 337.359906 -208.193489) (xy 337.229335 -208.219207) (xy 337.097459 -208.237071) (xy 336.964751 -208.247016)
			(xy 336.831686 -208.249007) (xy 336.69874 -208.243036) (xy 336.566389 -208.229126) (xy 336.435107 -208.207325)
			(xy 336.305364 -208.177712) (xy 336.177623 -208.140393) (xy 336.052344 -208.095501) (xy 335.929973 -208.043197)
			(xy 335.810949 -207.983668) (xy 335.695698 -207.917128) (xy 335.584633 -207.843815) (xy 335.478152 -207.763991)
			(xy 335.376634 -207.677941) (xy 335.280445 -207.585975) (xy 335.189927 -207.48842) (xy 335.105406 -207.385627)
			(xy 335.027184 -207.277963) (xy 334.95554 -207.165813) (xy 334.890731 -207.04958) (xy 334.83299 -206.929679)
			(xy 334.782523 -206.80654) (xy 334.73951 -206.680603) (xy 334.704106 -206.552318) (xy 334.676437 -206.422146)
			(xy 334.656602 -206.290553) (xy 334.644673 -206.158008) (xy 334.640692 -206.024988) (xy 137.15873 -206.024988)
			(xy 137.158232 -206.091528) (xy 137.150274 -206.22437) (xy 137.134385 -206.356498) (xy 137.110622 -206.487439)
			(xy 137.079072 -206.616725) (xy 137.039846 -206.743893) (xy 136.993085 -206.868487) (xy 136.938956 -206.990062)
			(xy 136.877654 -207.108182) (xy 136.809397 -207.222424) (xy 136.734431 -207.33238) (xy 136.653022 -207.437656)
			(xy 136.565464 -207.537874) (xy 136.472069 -207.632677) (xy 136.373171 -207.721725) (xy 136.269125 -207.804699)
			(xy 136.160303 -207.881303) (xy 136.047094 -207.951261) (xy 135.929904 -208.014323) (xy 135.809153 -208.070264)
			(xy 135.685272 -208.118884) (xy 135.558706 -208.160008) (xy 135.429906 -208.193489) (xy 135.299335 -208.219207)
			(xy 135.167459 -208.237071) (xy 135.034751 -208.247016) (xy 134.901686 -208.249007) (xy 134.76874 -208.243036)
			(xy 134.636389 -208.229126) (xy 134.505107 -208.207325) (xy 134.375364 -208.177712) (xy 134.247623 -208.140393)
			(xy 134.122344 -208.095501) (xy 133.999973 -208.043197) (xy 133.880949 -207.983668) (xy 133.765698 -207.917128)
			(xy 133.654633 -207.843815) (xy 133.548152 -207.763991) (xy 133.446634 -207.677941) (xy 133.350445 -207.585975)
			(xy 133.259927 -207.48842) (xy 133.175406 -207.385627) (xy 133.097184 -207.277963) (xy 133.02554 -207.165813)
			(xy 132.960731 -207.04958) (xy 132.90299 -206.929679) (xy 132.852523 -206.80654) (xy 132.80951 -206.680603)
			(xy 132.774106 -206.552318) (xy 132.746437 -206.422146) (xy 132.726602 -206.290553) (xy 132.714673 -206.158008)
			(xy 132.710692 -206.024988) (xy 91.148662 -206.024988) (xy 91.148164 -206.091528) (xy 91.140206 -206.22437)
			(xy 91.124317 -206.356498) (xy 91.100554 -206.487439) (xy 91.069004 -206.616725) (xy 91.029778 -206.743893)
			(xy 90.983017 -206.868487) (xy 90.928888 -206.990062) (xy 90.867586 -207.108182) (xy 90.799329 -207.222424)
			(xy 90.724363 -207.33238) (xy 90.642954 -207.437656) (xy 90.555396 -207.537874) (xy 90.462001 -207.632677)
			(xy 90.363103 -207.721725) (xy 90.259057 -207.804699) (xy 90.150235 -207.881303) (xy 90.037026 -207.951261)
			(xy 89.919836 -208.014323) (xy 89.799085 -208.070264) (xy 89.675204 -208.118884) (xy 89.548638 -208.160008)
			(xy 89.419838 -208.193489) (xy 89.289267 -208.219207) (xy 89.157391 -208.237071) (xy 89.024683 -208.247016)
			(xy 88.891618 -208.249007) (xy 88.758672 -208.243036) (xy 88.626321 -208.229126) (xy 88.495039 -208.207325)
			(xy 88.365296 -208.177712) (xy 88.237555 -208.140393) (xy 88.112276 -208.095501) (xy 87.989905 -208.043197)
			(xy 87.870881 -207.983668) (xy 87.75563 -207.917128) (xy 87.644565 -207.843815) (xy 87.538084 -207.763991)
			(xy 87.436566 -207.677941) (xy 87.340377 -207.585975) (xy 87.249859 -207.48842) (xy 87.165338 -207.385627)
			(xy 87.087116 -207.277963) (xy 87.015472 -207.165813) (xy 86.950663 -207.04958) (xy 86.892922 -206.929679)
			(xy 86.842455 -206.80654) (xy 86.799442 -206.680603) (xy 86.764038 -206.552318) (xy 86.736369 -206.422146)
			(xy 86.716534 -206.290553) (xy 86.704605 -206.158008) (xy 86.700624 -206.024988) (xy 2.509012 -206.024988)
			(xy 2.509012 -213.732618) (xy 90.165428 -213.732618) (xy 90.165936 -213.706731) (xy 90.174035 -213.655593)
			(xy 90.190034 -213.606353) (xy 90.21354 -213.560221) (xy 90.243972 -213.518334) (xy 90.280582 -213.481724)
			(xy 90.322469 -213.451292) (xy 90.368601 -213.427786) (xy 90.417841 -213.411787) (xy 90.468979 -213.403688)
			(xy 90.520753 -213.403688) (xy 90.571891 -213.411787) (xy 90.621131 -213.427786) (xy 90.667263 -213.451292)
			(xy 90.70915 -213.481724) (xy 90.74576 -213.518334) (xy 90.776192 -213.560221) (xy 90.799698 -213.606353)
			(xy 90.815697 -213.655593) (xy 90.823796 -213.706731) (xy 90.824304 -213.732618) (xy 92.045028 -213.732618)
			(xy 92.045536 -213.706731) (xy 92.053635 -213.655593) (xy 92.069634 -213.606353) (xy 92.09314 -213.560221)
			(xy 92.123572 -213.518334) (xy 92.160182 -213.481724) (xy 92.202069 -213.451292) (xy 92.248201 -213.427786)
			(xy 92.297441 -213.411787) (xy 92.348579 -213.403688) (xy 92.400353 -213.403688) (xy 92.451491 -213.411787)
			(xy 92.500731 -213.427786) (xy 92.546863 -213.451292) (xy 92.58875 -213.481724) (xy 92.62536 -213.518334)
			(xy 92.655792 -213.560221) (xy 92.679298 -213.606353) (xy 92.695297 -213.655593) (xy 92.703396 -213.706731)
			(xy 92.703904 -213.732618) (xy 93.924628 -213.732618) (xy 93.925136 -213.706731) (xy 93.933235 -213.655593)
			(xy 93.949234 -213.606353) (xy 93.97274 -213.560221) (xy 94.003172 -213.518334) (xy 94.039782 -213.481724)
			(xy 94.081669 -213.451292) (xy 94.127801 -213.427786) (xy 94.177041 -213.411787) (xy 94.228179 -213.403688)
			(xy 94.279953 -213.403688) (xy 94.331091 -213.411787) (xy 94.380331 -213.427786) (xy 94.426463 -213.451292)
			(xy 94.46835 -213.481724) (xy 94.50496 -213.518334) (xy 94.535392 -213.560221) (xy 94.558898 -213.606353)
			(xy 94.574897 -213.655593) (xy 94.582996 -213.706731) (xy 94.583504 -213.732618) (xy 95.804228 -213.732618)
			(xy 95.804736 -213.706731) (xy 95.812835 -213.655593) (xy 95.828834 -213.606353) (xy 95.85234 -213.560221)
			(xy 95.882772 -213.518334) (xy 95.919382 -213.481724) (xy 95.961269 -213.451292) (xy 96.007401 -213.427786)
			(xy 96.056641 -213.411787) (xy 96.107779 -213.403688) (xy 96.159553 -213.403688) (xy 96.210691 -213.411787)
			(xy 96.259931 -213.427786) (xy 96.306063 -213.451292) (xy 96.34795 -213.481724) (xy 96.38456 -213.518334)
			(xy 96.414992 -213.560221) (xy 96.438498 -213.606353) (xy 96.454497 -213.655593) (xy 96.462596 -213.706731)
			(xy 96.463104 -213.732618) (xy 97.683828 -213.732618) (xy 97.684336 -213.706731) (xy 97.692435 -213.655593)
			(xy 97.708434 -213.606353) (xy 97.73194 -213.560221) (xy 97.762372 -213.518334) (xy 97.798982 -213.481724)
			(xy 97.840869 -213.451292) (xy 97.887001 -213.427786) (xy 97.936241 -213.411787) (xy 97.987379 -213.403688)
			(xy 98.039153 -213.403688) (xy 98.090291 -213.411787) (xy 98.139531 -213.427786) (xy 98.185663 -213.451292)
			(xy 98.22755 -213.481724) (xy 98.26416 -213.518334) (xy 98.294592 -213.560221) (xy 98.318098 -213.606353)
			(xy 98.334097 -213.655593) (xy 98.342196 -213.706731) (xy 98.342704 -213.732618) (xy 99.563428 -213.732618)
			(xy 99.563936 -213.706731) (xy 99.572035 -213.655593) (xy 99.588034 -213.606353) (xy 99.61154 -213.560221)
			(xy 99.641972 -213.518334) (xy 99.678582 -213.481724) (xy 99.720469 -213.451292) (xy 99.766601 -213.427786)
			(xy 99.815841 -213.411787) (xy 99.866979 -213.403688) (xy 99.918753 -213.403688) (xy 99.969891 -213.411787)
			(xy 100.019131 -213.427786) (xy 100.065263 -213.451292) (xy 100.10715 -213.481724) (xy 100.14376 -213.518334)
			(xy 100.174192 -213.560221) (xy 100.197698 -213.606353) (xy 100.213697 -213.655593) (xy 100.221796 -213.706731)
			(xy 100.222304 -213.732618) (xy 101.443028 -213.732618) (xy 101.443536 -213.706731) (xy 101.451635 -213.655593)
			(xy 101.467634 -213.606353) (xy 101.49114 -213.560221) (xy 101.521572 -213.518334) (xy 101.558182 -213.481724)
			(xy 101.600069 -213.451292) (xy 101.646201 -213.427786) (xy 101.695441 -213.411787) (xy 101.746579 -213.403688)
			(xy 101.798353 -213.403688) (xy 101.849491 -213.411787) (xy 101.898731 -213.427786) (xy 101.944863 -213.451292)
			(xy 101.98675 -213.481724) (xy 102.02336 -213.518334) (xy 102.053792 -213.560221) (xy 102.077298 -213.606353)
			(xy 102.093297 -213.655593) (xy 102.101396 -213.706731) (xy 102.101904 -213.732618) (xy 103.322628 -213.732618)
			(xy 103.323136 -213.706731) (xy 103.331235 -213.655593) (xy 103.347234 -213.606353) (xy 103.37074 -213.560221)
			(xy 103.401172 -213.518334) (xy 103.437782 -213.481724) (xy 103.479669 -213.451292) (xy 103.525801 -213.427786)
			(xy 103.575041 -213.411787) (xy 103.626179 -213.403688) (xy 103.677953 -213.403688) (xy 103.729091 -213.411787)
			(xy 103.778331 -213.427786) (xy 103.824463 -213.451292) (xy 103.86635 -213.481724) (xy 103.90296 -213.518334)
			(xy 103.933392 -213.560221) (xy 103.956898 -213.606353) (xy 103.972897 -213.655593) (xy 103.980996 -213.706731)
			(xy 103.981504 -213.732618) (xy 105.202228 -213.732618) (xy 105.202736 -213.706731) (xy 105.210835 -213.655593)
			(xy 105.226834 -213.606353) (xy 105.25034 -213.560221) (xy 105.280772 -213.518334) (xy 105.317382 -213.481724)
			(xy 105.359269 -213.451292) (xy 105.405401 -213.427786) (xy 105.454641 -213.411787) (xy 105.505779 -213.403688)
			(xy 105.557553 -213.403688) (xy 105.608691 -213.411787) (xy 105.657931 -213.427786) (xy 105.704063 -213.451292)
			(xy 105.74595 -213.481724) (xy 105.78256 -213.518334) (xy 105.812992 -213.560221) (xy 105.836498 -213.606353)
			(xy 105.852497 -213.655593) (xy 105.860596 -213.706731) (xy 105.861104 -213.732618) (xy 107.081828 -213.732618)
			(xy 107.082336 -213.706731) (xy 107.090435 -213.655593) (xy 107.106434 -213.606353) (xy 107.12994 -213.560221)
			(xy 107.160372 -213.518334) (xy 107.196982 -213.481724) (xy 107.238869 -213.451292) (xy 107.285001 -213.427786)
			(xy 107.334241 -213.411787) (xy 107.385379 -213.403688) (xy 107.437153 -213.403688) (xy 107.488291 -213.411787)
			(xy 107.537531 -213.427786) (xy 107.583663 -213.451292) (xy 107.62555 -213.481724) (xy 107.66216 -213.518334)
			(xy 107.692592 -213.560221) (xy 107.716098 -213.606353) (xy 107.732097 -213.655593) (xy 107.740196 -213.706731)
			(xy 107.740704 -213.732618) (xy 114.600228 -213.732618) (xy 114.600736 -213.706731) (xy 114.608835 -213.655593)
			(xy 114.624834 -213.606353) (xy 114.64834 -213.560221) (xy 114.678772 -213.518334) (xy 114.715382 -213.481724)
			(xy 114.757269 -213.451292) (xy 114.803401 -213.427786) (xy 114.852641 -213.411787) (xy 114.903779 -213.403688)
			(xy 114.955553 -213.403688) (xy 115.006691 -213.411787) (xy 115.055931 -213.427786) (xy 115.102063 -213.451292)
			(xy 115.14395 -213.481724) (xy 115.18056 -213.518334) (xy 115.210992 -213.560221) (xy 115.234498 -213.606353)
			(xy 115.250497 -213.655593) (xy 115.258596 -213.706731) (xy 115.259104 -213.732618) (xy 116.479828 -213.732618)
			(xy 116.480336 -213.706731) (xy 116.488435 -213.655593) (xy 116.504434 -213.606353) (xy 116.52794 -213.560221)
			(xy 116.558372 -213.518334) (xy 116.594982 -213.481724) (xy 116.636869 -213.451292) (xy 116.683001 -213.427786)
			(xy 116.732241 -213.411787) (xy 116.783379 -213.403688) (xy 116.835153 -213.403688) (xy 116.886291 -213.411787)
			(xy 116.935531 -213.427786) (xy 116.981663 -213.451292) (xy 117.02355 -213.481724) (xy 117.06016 -213.518334)
			(xy 117.090592 -213.560221) (xy 117.114098 -213.606353) (xy 117.130097 -213.655593) (xy 117.138196 -213.706731)
			(xy 117.138704 -213.732618) (xy 118.359428 -213.732618) (xy 118.359936 -213.706731) (xy 118.368035 -213.655593)
			(xy 118.384034 -213.606353) (xy 118.40754 -213.560221) (xy 118.437972 -213.518334) (xy 118.474582 -213.481724)
			(xy 118.516469 -213.451292) (xy 118.562601 -213.427786) (xy 118.611841 -213.411787) (xy 118.662979 -213.403688)
			(xy 118.714753 -213.403688) (xy 118.765891 -213.411787) (xy 118.815131 -213.427786) (xy 118.861263 -213.451292)
			(xy 118.90315 -213.481724) (xy 118.93976 -213.518334) (xy 118.970192 -213.560221) (xy 118.993698 -213.606353)
			(xy 119.009697 -213.655593) (xy 119.017796 -213.706731) (xy 119.018304 -213.732618) (xy 120.239028 -213.732618)
			(xy 120.239536 -213.706731) (xy 120.247635 -213.655593) (xy 120.263634 -213.606353) (xy 120.28714 -213.560221)
			(xy 120.317572 -213.518334) (xy 120.354182 -213.481724) (xy 120.396069 -213.451292) (xy 120.442201 -213.427786)
			(xy 120.491441 -213.411787) (xy 120.542579 -213.403688) (xy 120.594353 -213.403688) (xy 120.645491 -213.411787)
			(xy 120.694731 -213.427786) (xy 120.740863 -213.451292) (xy 120.78275 -213.481724) (xy 120.81936 -213.518334)
			(xy 120.849792 -213.560221) (xy 120.873298 -213.606353) (xy 120.889297 -213.655593) (xy 120.897396 -213.706731)
			(xy 120.897904 -213.732618) (xy 122.118628 -213.732618) (xy 122.119136 -213.706731) (xy 122.127235 -213.655593)
			(xy 122.143234 -213.606353) (xy 122.16674 -213.560221) (xy 122.197172 -213.518334) (xy 122.233782 -213.481724)
			(xy 122.275669 -213.451292) (xy 122.321801 -213.427786) (xy 122.371041 -213.411787) (xy 122.422179 -213.403688)
			(xy 122.473953 -213.403688) (xy 122.525091 -213.411787) (xy 122.574331 -213.427786) (xy 122.620463 -213.451292)
			(xy 122.66235 -213.481724) (xy 122.69896 -213.518334) (xy 122.729392 -213.560221) (xy 122.752898 -213.606353)
			(xy 122.768897 -213.655593) (xy 122.776996 -213.706731) (xy 122.777504 -213.732618) (xy 123.99772 -213.732618)
			(xy 123.998228 -213.706711) (xy 124.006334 -213.655534) (xy 124.022346 -213.606255) (xy 124.045869 -213.560088)
			(xy 124.076325 -213.518169) (xy 124.112963 -213.481531) (xy 124.154882 -213.451075) (xy 124.201049 -213.427552)
			(xy 124.250328 -213.41154) (xy 124.301505 -213.403434) (xy 124.353319 -213.403434) (xy 124.404496 -213.41154)
			(xy 124.453775 -213.427552) (xy 124.499942 -213.451075) (xy 124.541861 -213.481531) (xy 124.578499 -213.518169)
			(xy 124.608955 -213.560088) (xy 124.632478 -213.606255) (xy 124.64849 -213.655534) (xy 124.656596 -213.706711)
			(xy 124.657104 -213.732618) (xy 125.87732 -213.732618) (xy 125.877828 -213.706711) (xy 125.885934 -213.655534)
			(xy 125.901946 -213.606255) (xy 125.925469 -213.560088) (xy 125.955925 -213.518169) (xy 125.992563 -213.481531)
			(xy 126.034482 -213.451075) (xy 126.080649 -213.427552) (xy 126.129928 -213.41154) (xy 126.181105 -213.403434)
			(xy 126.232919 -213.403434) (xy 126.284096 -213.41154) (xy 126.333375 -213.427552) (xy 126.379542 -213.451075)
			(xy 126.421461 -213.481531) (xy 126.458099 -213.518169) (xy 126.488555 -213.560088) (xy 126.512078 -213.606255)
			(xy 126.52809 -213.655534) (xy 126.536196 -213.706711) (xy 126.536704 -213.732618) (xy 127.757428 -213.732618)
			(xy 127.757936 -213.706731) (xy 127.766035 -213.655593) (xy 127.782034 -213.606353) (xy 127.80554 -213.560221)
			(xy 127.835972 -213.518334) (xy 127.872582 -213.481724) (xy 127.914469 -213.451292) (xy 127.960601 -213.427786)
			(xy 128.009841 -213.411787) (xy 128.060979 -213.403688) (xy 128.112753 -213.403688) (xy 128.163891 -213.411787)
			(xy 128.213131 -213.427786) (xy 128.259263 -213.451292) (xy 128.30115 -213.481724) (xy 128.33776 -213.518334)
			(xy 128.368192 -213.560221) (xy 128.391698 -213.606353) (xy 128.407697 -213.655593) (xy 128.415796 -213.706731)
			(xy 128.416304 -213.732618) (xy 129.637028 -213.732618) (xy 129.637536 -213.706731) (xy 129.645635 -213.655593)
			(xy 129.661634 -213.606353) (xy 129.68514 -213.560221) (xy 129.715572 -213.518334) (xy 129.752182 -213.481724)
			(xy 129.794069 -213.451292) (xy 129.840201 -213.427786) (xy 129.889441 -213.411787) (xy 129.940579 -213.403688)
			(xy 129.992353 -213.403688) (xy 130.043491 -213.411787) (xy 130.092731 -213.427786) (xy 130.138863 -213.451292)
			(xy 130.18075 -213.481724) (xy 130.21736 -213.518334) (xy 130.247792 -213.560221) (xy 130.271298 -213.606353)
			(xy 130.287297 -213.655593) (xy 130.295396 -213.706731) (xy 130.295904 -213.732618) (xy 131.516628 -213.732618)
			(xy 131.517136 -213.706731) (xy 131.525235 -213.655593) (xy 131.541234 -213.606353) (xy 131.56474 -213.560221)
			(xy 131.595172 -213.518334) (xy 131.631782 -213.481724) (xy 131.673669 -213.451292) (xy 131.719801 -213.427786)
			(xy 131.769041 -213.411787) (xy 131.820179 -213.403688) (xy 131.871953 -213.403688) (xy 131.923091 -213.411787)
			(xy 131.972331 -213.427786) (xy 132.018463 -213.451292) (xy 132.06035 -213.481724) (xy 132.09696 -213.518334)
			(xy 132.127392 -213.560221) (xy 132.150898 -213.606353) (xy 132.166897 -213.655593) (xy 132.174996 -213.706731)
			(xy 132.175504 -213.732618) (xy 338.105496 -213.732618) (xy 338.106004 -213.706731) (xy 338.114103 -213.655593)
			(xy 338.130102 -213.606353) (xy 338.153608 -213.560221) (xy 338.18404 -213.518334) (xy 338.22065 -213.481724)
			(xy 338.262537 -213.451292) (xy 338.308669 -213.427786) (xy 338.357909 -213.411787) (xy 338.409047 -213.403688)
			(xy 338.460821 -213.403688) (xy 338.511959 -213.411787) (xy 338.561199 -213.427786) (xy 338.607331 -213.451292)
			(xy 338.649218 -213.481724) (xy 338.685828 -213.518334) (xy 338.71626 -213.560221) (xy 338.739766 -213.606353)
			(xy 338.755765 -213.655593) (xy 338.763864 -213.706731) (xy 338.764372 -213.732618) (xy 339.985096 -213.732618)
			(xy 339.985604 -213.706731) (xy 339.993703 -213.655593) (xy 340.009702 -213.606353) (xy 340.033208 -213.560221)
			(xy 340.06364 -213.518334) (xy 340.10025 -213.481724) (xy 340.142137 -213.451292) (xy 340.188269 -213.427786)
			(xy 340.237509 -213.411787) (xy 340.288647 -213.403688) (xy 340.340421 -213.403688) (xy 340.391559 -213.411787)
			(xy 340.440799 -213.427786) (xy 340.486931 -213.451292) (xy 340.528818 -213.481724) (xy 340.565428 -213.518334)
			(xy 340.59586 -213.560221) (xy 340.619366 -213.606353) (xy 340.635365 -213.655593) (xy 340.643464 -213.706731)
			(xy 340.643972 -213.732618) (xy 341.864696 -213.732618) (xy 341.865204 -213.706731) (xy 341.873303 -213.655593)
			(xy 341.889302 -213.606353) (xy 341.912808 -213.560221) (xy 341.94324 -213.518334) (xy 341.97985 -213.481724)
			(xy 342.021737 -213.451292) (xy 342.067869 -213.427786) (xy 342.117109 -213.411787) (xy 342.168247 -213.403688)
			(xy 342.220021 -213.403688) (xy 342.271159 -213.411787) (xy 342.320399 -213.427786) (xy 342.366531 -213.451292)
			(xy 342.408418 -213.481724) (xy 342.445028 -213.518334) (xy 342.47546 -213.560221) (xy 342.498966 -213.606353)
			(xy 342.514965 -213.655593) (xy 342.523064 -213.706731) (xy 342.523572 -213.732618) (xy 343.744296 -213.732618)
			(xy 343.744804 -213.706731) (xy 343.752903 -213.655593) (xy 343.768902 -213.606353) (xy 343.792408 -213.560221)
			(xy 343.82284 -213.518334) (xy 343.85945 -213.481724) (xy 343.901337 -213.451292) (xy 343.947469 -213.427786)
			(xy 343.996709 -213.411787) (xy 344.047847 -213.403688) (xy 344.099621 -213.403688) (xy 344.150759 -213.411787)
			(xy 344.199999 -213.427786) (xy 344.246131 -213.451292) (xy 344.288018 -213.481724) (xy 344.324628 -213.518334)
			(xy 344.35506 -213.560221) (xy 344.378566 -213.606353) (xy 344.394565 -213.655593) (xy 344.402664 -213.706731)
			(xy 344.403172 -213.732618) (xy 345.623896 -213.732618) (xy 345.624404 -213.706731) (xy 345.632503 -213.655593)
			(xy 345.648502 -213.606353) (xy 345.672008 -213.560221) (xy 345.70244 -213.518334) (xy 345.73905 -213.481724)
			(xy 345.780937 -213.451292) (xy 345.827069 -213.427786) (xy 345.876309 -213.411787) (xy 345.927447 -213.403688)
			(xy 345.979221 -213.403688) (xy 346.030359 -213.411787) (xy 346.079599 -213.427786) (xy 346.125731 -213.451292)
			(xy 346.167618 -213.481724) (xy 346.204228 -213.518334) (xy 346.23466 -213.560221) (xy 346.258166 -213.606353)
			(xy 346.274165 -213.655593) (xy 346.282264 -213.706731) (xy 346.282772 -213.732618) (xy 347.503496 -213.732618)
			(xy 347.504004 -213.706731) (xy 347.512103 -213.655593) (xy 347.528102 -213.606353) (xy 347.551608 -213.560221)
			(xy 347.58204 -213.518334) (xy 347.61865 -213.481724) (xy 347.660537 -213.451292) (xy 347.706669 -213.427786)
			(xy 347.755909 -213.411787) (xy 347.807047 -213.403688) (xy 347.858821 -213.403688) (xy 347.909959 -213.411787)
			(xy 347.959199 -213.427786) (xy 348.005331 -213.451292) (xy 348.047218 -213.481724) (xy 348.083828 -213.518334)
			(xy 348.11426 -213.560221) (xy 348.137766 -213.606353) (xy 348.153765 -213.655593) (xy 348.161864 -213.706731)
			(xy 348.162372 -213.732618) (xy 349.383096 -213.732618) (xy 349.383604 -213.706731) (xy 349.391703 -213.655593)
			(xy 349.407702 -213.606353) (xy 349.431208 -213.560221) (xy 349.46164 -213.518334) (xy 349.49825 -213.481724)
			(xy 349.540137 -213.451292) (xy 349.586269 -213.427786) (xy 349.635509 -213.411787) (xy 349.686647 -213.403688)
			(xy 349.738421 -213.403688) (xy 349.789559 -213.411787) (xy 349.838799 -213.427786) (xy 349.884931 -213.451292)
			(xy 349.926818 -213.481724) (xy 349.963428 -213.518334) (xy 349.99386 -213.560221) (xy 350.017366 -213.606353)
			(xy 350.033365 -213.655593) (xy 350.041464 -213.706731) (xy 350.041972 -213.732618) (xy 351.262696 -213.732618)
			(xy 351.263204 -213.706731) (xy 351.271303 -213.655593) (xy 351.287302 -213.606353) (xy 351.310808 -213.560221)
			(xy 351.34124 -213.518334) (xy 351.37785 -213.481724) (xy 351.419737 -213.451292) (xy 351.465869 -213.427786)
			(xy 351.515109 -213.411787) (xy 351.566247 -213.403688) (xy 351.618021 -213.403688) (xy 351.669159 -213.411787)
			(xy 351.718399 -213.427786) (xy 351.764531 -213.451292) (xy 351.806418 -213.481724) (xy 351.843028 -213.518334)
			(xy 351.87346 -213.560221) (xy 351.896966 -213.606353) (xy 351.912965 -213.655593) (xy 351.921064 -213.706731)
			(xy 351.921572 -213.732618) (xy 353.142296 -213.732618) (xy 353.142804 -213.706731) (xy 353.150903 -213.655593)
			(xy 353.166902 -213.606353) (xy 353.190408 -213.560221) (xy 353.22084 -213.518334) (xy 353.25745 -213.481724)
			(xy 353.299337 -213.451292) (xy 353.345469 -213.427786) (xy 353.394709 -213.411787) (xy 353.445847 -213.403688)
			(xy 353.497621 -213.403688) (xy 353.548759 -213.411787) (xy 353.597999 -213.427786) (xy 353.644131 -213.451292)
			(xy 353.686018 -213.481724) (xy 353.722628 -213.518334) (xy 353.75306 -213.560221) (xy 353.776566 -213.606353)
			(xy 353.792565 -213.655593) (xy 353.800664 -213.706731) (xy 353.801172 -213.732618) (xy 355.021896 -213.732618)
			(xy 355.022404 -213.706731) (xy 355.030503 -213.655593) (xy 355.046502 -213.606353) (xy 355.070008 -213.560221)
			(xy 355.10044 -213.518334) (xy 355.13705 -213.481724) (xy 355.178937 -213.451292) (xy 355.225069 -213.427786)
			(xy 355.274309 -213.411787) (xy 355.325447 -213.403688) (xy 355.377221 -213.403688) (xy 355.428359 -213.411787)
			(xy 355.477599 -213.427786) (xy 355.523731 -213.451292) (xy 355.565618 -213.481724) (xy 355.602228 -213.518334)
			(xy 355.63266 -213.560221) (xy 355.656166 -213.606353) (xy 355.672165 -213.655593) (xy 355.680264 -213.706731)
			(xy 355.680772 -213.732618) (xy 355.680423 -213.755595) (xy 355.674102 -213.801111) (xy 355.661516 -213.845306)
			(xy 355.652578 -213.866476) (xy 355.642672 -213.888828) (xy 355.856286 -214.293958) (xy 355.880416 -214.29853)
			(xy 355.90533 -214.303664) (xy 355.95334 -214.320459) (xy 355.998199 -214.344434) (xy 356.038841 -214.375017)
			(xy 356.074299 -214.411484) (xy 356.103732 -214.452967) (xy 356.12644 -214.49848) (xy 356.141883 -214.546942)
			(xy 356.149695 -214.597202) (xy 356.150164 -214.622634) (xy 356.149656 -214.648521) (xy 356.141557 -214.699659)
			(xy 356.125558 -214.748899) (xy 356.102052 -214.795031) (xy 356.07162 -214.836918) (xy 356.03501 -214.873528)
			(xy 355.993123 -214.90396) (xy 355.946991 -214.927466) (xy 355.897751 -214.943465) (xy 355.846613 -214.951564)
			(xy 355.794839 -214.951564) (xy 355.743701 -214.943465) (xy 355.694461 -214.927466) (xy 355.648329 -214.90396)
			(xy 355.606442 -214.873528) (xy 355.569832 -214.836918) (xy 355.5394 -214.795031) (xy 355.515894 -214.748899)
			(xy 355.499895 -214.699659) (xy 355.491796 -214.648521) (xy 355.491288 -214.622634) (xy 355.491658 -214.599658)
			(xy 355.49797 -214.554143) (xy 355.510548 -214.509947) (xy 355.519482 -214.488776) (xy 355.529388 -214.466424)
			(xy 355.315774 -214.061294) (xy 355.291644 -214.056722) (xy 355.266713 -214.051663) (xy 355.218699 -214.034858)
			(xy 355.173839 -214.010874) (xy 355.133197 -213.980281) (xy 355.097739 -213.943805) (xy 355.068309 -213.902313)
			(xy 355.045605 -213.856791) (xy 355.030167 -213.80832) (xy 355.022362 -213.758053) (xy 355.021896 -213.732618)
			(xy 353.801172 -213.732618) (xy 353.800823 -213.755595) (xy 353.794502 -213.801111) (xy 353.781916 -213.845306)
			(xy 353.772978 -213.866476) (xy 353.763072 -213.888828) (xy 353.976686 -214.293958) (xy 354.000816 -214.29853)
			(xy 354.02573 -214.303664) (xy 354.07374 -214.320459) (xy 354.118599 -214.344434) (xy 354.159241 -214.375017)
			(xy 354.194699 -214.411484) (xy 354.224132 -214.452967) (xy 354.24684 -214.49848) (xy 354.262283 -214.546942)
			(xy 354.270095 -214.597202) (xy 354.270564 -214.622634) (xy 354.270056 -214.648521) (xy 354.261957 -214.699659)
			(xy 354.245958 -214.748899) (xy 354.222452 -214.795031) (xy 354.19202 -214.836918) (xy 354.15541 -214.873528)
			(xy 354.113523 -214.90396) (xy 354.067391 -214.927466) (xy 354.018151 -214.943465) (xy 353.967013 -214.951564)
			(xy 353.915239 -214.951564) (xy 353.864101 -214.943465) (xy 353.814861 -214.927466) (xy 353.768729 -214.90396)
			(xy 353.726842 -214.873528) (xy 353.690232 -214.836918) (xy 353.6598 -214.795031) (xy 353.636294 -214.748899)
			(xy 353.620295 -214.699659) (xy 353.612196 -214.648521) (xy 353.611688 -214.622634) (xy 353.612058 -214.599658)
			(xy 353.61837 -214.554143) (xy 353.630948 -214.509947) (xy 353.639882 -214.488776) (xy 353.649788 -214.466424)
			(xy 353.436174 -214.061294) (xy 353.412044 -214.056722) (xy 353.387113 -214.051663) (xy 353.339099 -214.034858)
			(xy 353.294239 -214.010874) (xy 353.253597 -213.980281) (xy 353.218139 -213.943805) (xy 353.188709 -213.902313)
			(xy 353.166005 -213.856791) (xy 353.150567 -213.80832) (xy 353.142762 -213.758053) (xy 353.142296 -213.732618)
			(xy 351.921572 -213.732618) (xy 351.921223 -213.755595) (xy 351.914902 -213.801111) (xy 351.902316 -213.845306)
			(xy 351.893378 -213.866476) (xy 351.883472 -213.888828) (xy 352.097086 -214.293958) (xy 352.121216 -214.29853)
			(xy 352.14613 -214.303664) (xy 352.19414 -214.320459) (xy 352.238999 -214.344434) (xy 352.279641 -214.375017)
			(xy 352.315099 -214.411484) (xy 352.344532 -214.452967) (xy 352.36724 -214.49848) (xy 352.382683 -214.546942)
			(xy 352.390495 -214.597202) (xy 352.390964 -214.622634) (xy 352.390456 -214.648521) (xy 352.382357 -214.699659)
			(xy 352.366358 -214.748899) (xy 352.342852 -214.795031) (xy 352.31242 -214.836918) (xy 352.27581 -214.873528)
			(xy 352.233923 -214.90396) (xy 352.187791 -214.927466) (xy 352.138551 -214.943465) (xy 352.087413 -214.951564)
			(xy 352.035639 -214.951564) (xy 351.984501 -214.943465) (xy 351.935261 -214.927466) (xy 351.889129 -214.90396)
			(xy 351.847242 -214.873528) (xy 351.810632 -214.836918) (xy 351.7802 -214.795031) (xy 351.756694 -214.748899)
			(xy 351.740695 -214.699659) (xy 351.732596 -214.648521) (xy 351.732088 -214.622634) (xy 351.732458 -214.599658)
			(xy 351.73877 -214.554143) (xy 351.751348 -214.509947) (xy 351.760282 -214.488776) (xy 351.770188 -214.466424)
			(xy 351.556574 -214.061294) (xy 351.532444 -214.056722) (xy 351.507513 -214.051663) (xy 351.459499 -214.034858)
			(xy 351.414639 -214.010874) (xy 351.373997 -213.980281) (xy 351.338539 -213.943805) (xy 351.309109 -213.902313)
			(xy 351.286405 -213.856791) (xy 351.270967 -213.80832) (xy 351.263162 -213.758053) (xy 351.262696 -213.732618)
			(xy 350.041972 -213.732618) (xy 350.041623 -213.755595) (xy 350.035302 -213.801111) (xy 350.022716 -213.845306)
			(xy 350.013778 -213.866476) (xy 350.003872 -213.888828) (xy 350.217486 -214.293958) (xy 350.241616 -214.29853)
			(xy 350.26653 -214.303664) (xy 350.31454 -214.320459) (xy 350.359399 -214.344434) (xy 350.400041 -214.375017)
			(xy 350.435499 -214.411484) (xy 350.464932 -214.452967) (xy 350.48764 -214.49848) (xy 350.503083 -214.546942)
			(xy 350.510895 -214.597202) (xy 350.511364 -214.622634) (xy 350.510856 -214.648521) (xy 350.502757 -214.699659)
			(xy 350.486758 -214.748899) (xy 350.463252 -214.795031) (xy 350.43282 -214.836918) (xy 350.39621 -214.873528)
			(xy 350.354323 -214.90396) (xy 350.308191 -214.927466) (xy 350.258951 -214.943465) (xy 350.207813 -214.951564)
			(xy 350.156039 -214.951564) (xy 350.104901 -214.943465) (xy 350.055661 -214.927466) (xy 350.009529 -214.90396)
			(xy 349.967642 -214.873528) (xy 349.931032 -214.836918) (xy 349.9006 -214.795031) (xy 349.877094 -214.748899)
			(xy 349.861095 -214.699659) (xy 349.852996 -214.648521) (xy 349.852488 -214.622634) (xy 349.852858 -214.599658)
			(xy 349.85917 -214.554143) (xy 349.871748 -214.509947) (xy 349.880682 -214.488776) (xy 349.890588 -214.466424)
			(xy 349.676974 -214.061294) (xy 349.652844 -214.056722) (xy 349.627913 -214.051663) (xy 349.579899 -214.034858)
			(xy 349.535039 -214.010874) (xy 349.494397 -213.980281) (xy 349.458939 -213.943805) (xy 349.429509 -213.902313)
			(xy 349.406805 -213.856791) (xy 349.391367 -213.80832) (xy 349.383562 -213.758053) (xy 349.383096 -213.732618)
			(xy 348.162372 -213.732618) (xy 348.162023 -213.755595) (xy 348.155702 -213.801111) (xy 348.143116 -213.845306)
			(xy 348.134178 -213.866476) (xy 348.124272 -213.888828) (xy 348.337886 -214.293958) (xy 348.362016 -214.29853)
			(xy 348.38693 -214.303664) (xy 348.43494 -214.320459) (xy 348.479799 -214.344434) (xy 348.520441 -214.375017)
			(xy 348.555899 -214.411484) (xy 348.585332 -214.452967) (xy 348.60804 -214.49848) (xy 348.623483 -214.546942)
			(xy 348.631295 -214.597202) (xy 348.631764 -214.622634) (xy 348.631256 -214.648521) (xy 348.623157 -214.699659)
			(xy 348.607158 -214.748899) (xy 348.583652 -214.795031) (xy 348.55322 -214.836918) (xy 348.51661 -214.873528)
			(xy 348.474723 -214.90396) (xy 348.428591 -214.927466) (xy 348.379351 -214.943465) (xy 348.328213 -214.951564)
			(xy 348.276439 -214.951564) (xy 348.225301 -214.943465) (xy 348.176061 -214.927466) (xy 348.129929 -214.90396)
			(xy 348.088042 -214.873528) (xy 348.051432 -214.836918) (xy 348.021 -214.795031) (xy 347.997494 -214.748899)
			(xy 347.981495 -214.699659) (xy 347.973396 -214.648521) (xy 347.972888 -214.622634) (xy 347.973258 -214.599658)
			(xy 347.97957 -214.554143) (xy 347.992148 -214.509947) (xy 348.001082 -214.488776) (xy 348.010988 -214.466424)
			(xy 347.797374 -214.061294) (xy 347.773244 -214.056722) (xy 347.748313 -214.051663) (xy 347.700299 -214.034858)
			(xy 347.655439 -214.010874) (xy 347.614797 -213.980281) (xy 347.579339 -213.943805) (xy 347.549909 -213.902313)
			(xy 347.527205 -213.856791) (xy 347.511767 -213.80832) (xy 347.503962 -213.758053) (xy 347.503496 -213.732618)
			(xy 346.282772 -213.732618) (xy 346.282423 -213.755595) (xy 346.276102 -213.801111) (xy 346.263516 -213.845306)
			(xy 346.254578 -213.866476) (xy 346.244672 -213.888828) (xy 346.458286 -214.293958) (xy 346.482416 -214.29853)
			(xy 346.50733 -214.303664) (xy 346.55534 -214.320459) (xy 346.600199 -214.344434) (xy 346.640841 -214.375017)
			(xy 346.676299 -214.411484) (xy 346.705732 -214.452967) (xy 346.72844 -214.49848) (xy 346.743883 -214.546942)
			(xy 346.751695 -214.597202) (xy 346.752164 -214.622634) (xy 346.751656 -214.648521) (xy 346.743557 -214.699659)
			(xy 346.727558 -214.748899) (xy 346.704052 -214.795031) (xy 346.67362 -214.836918) (xy 346.63701 -214.873528)
			(xy 346.595123 -214.90396) (xy 346.548991 -214.927466) (xy 346.499751 -214.943465) (xy 346.448613 -214.951564)
			(xy 346.396839 -214.951564) (xy 346.345701 -214.943465) (xy 346.296461 -214.927466) (xy 346.250329 -214.90396)
			(xy 346.208442 -214.873528) (xy 346.171832 -214.836918) (xy 346.1414 -214.795031) (xy 346.117894 -214.748899)
			(xy 346.101895 -214.699659) (xy 346.093796 -214.648521) (xy 346.093288 -214.622634) (xy 346.093658 -214.599658)
			(xy 346.09997 -214.554143) (xy 346.112548 -214.509947) (xy 346.121482 -214.488776) (xy 346.131388 -214.466424)
			(xy 345.917774 -214.061294) (xy 345.893644 -214.056722) (xy 345.868713 -214.051663) (xy 345.820699 -214.034858)
			(xy 345.775839 -214.010874) (xy 345.735197 -213.980281) (xy 345.699739 -213.943805) (xy 345.670309 -213.902313)
			(xy 345.647605 -213.856791) (xy 345.632167 -213.80832) (xy 345.624362 -213.758053) (xy 345.623896 -213.732618)
			(xy 344.403172 -213.732618) (xy 344.402823 -213.755595) (xy 344.396502 -213.801111) (xy 344.383916 -213.845306)
			(xy 344.374978 -213.866476) (xy 344.365072 -213.888828) (xy 344.578686 -214.293958) (xy 344.602816 -214.29853)
			(xy 344.62773 -214.303664) (xy 344.67574 -214.320459) (xy 344.720599 -214.344434) (xy 344.761241 -214.375017)
			(xy 344.796699 -214.411484) (xy 344.826132 -214.452967) (xy 344.84884 -214.49848) (xy 344.864283 -214.546942)
			(xy 344.872095 -214.597202) (xy 344.872564 -214.622634) (xy 344.872056 -214.648521) (xy 344.863957 -214.699659)
			(xy 344.847958 -214.748899) (xy 344.824452 -214.795031) (xy 344.79402 -214.836918) (xy 344.75741 -214.873528)
			(xy 344.715523 -214.90396) (xy 344.669391 -214.927466) (xy 344.620151 -214.943465) (xy 344.569013 -214.951564)
			(xy 344.517239 -214.951564) (xy 344.466101 -214.943465) (xy 344.416861 -214.927466) (xy 344.370729 -214.90396)
			(xy 344.328842 -214.873528) (xy 344.292232 -214.836918) (xy 344.2618 -214.795031) (xy 344.238294 -214.748899)
			(xy 344.222295 -214.699659) (xy 344.214196 -214.648521) (xy 344.213688 -214.622634) (xy 344.214058 -214.599658)
			(xy 344.22037 -214.554143) (xy 344.232948 -214.509947) (xy 344.241882 -214.488776) (xy 344.251788 -214.466424)
			(xy 344.038174 -214.061294) (xy 344.014044 -214.056722) (xy 343.989113 -214.051663) (xy 343.941099 -214.034858)
			(xy 343.896239 -214.010874) (xy 343.855597 -213.980281) (xy 343.820139 -213.943805) (xy 343.790709 -213.902313)
			(xy 343.768005 -213.856791) (xy 343.752567 -213.80832) (xy 343.744762 -213.758053) (xy 343.744296 -213.732618)
			(xy 342.523572 -213.732618) (xy 342.523223 -213.755595) (xy 342.516902 -213.801111) (xy 342.504316 -213.845306)
			(xy 342.495378 -213.866476) (xy 342.485472 -213.888828) (xy 342.699086 -214.293958) (xy 342.723216 -214.29853)
			(xy 342.74813 -214.303664) (xy 342.79614 -214.320459) (xy 342.840999 -214.344434) (xy 342.881641 -214.375017)
			(xy 342.917099 -214.411484) (xy 342.946532 -214.452967) (xy 342.96924 -214.49848) (xy 342.984683 -214.546942)
			(xy 342.992495 -214.597202) (xy 342.992964 -214.622634) (xy 342.992456 -214.648521) (xy 342.984357 -214.699659)
			(xy 342.968358 -214.748899) (xy 342.944852 -214.795031) (xy 342.91442 -214.836918) (xy 342.87781 -214.873528)
			(xy 342.835923 -214.90396) (xy 342.789791 -214.927466) (xy 342.740551 -214.943465) (xy 342.689413 -214.951564)
			(xy 342.637639 -214.951564) (xy 342.586501 -214.943465) (xy 342.537261 -214.927466) (xy 342.491129 -214.90396)
			(xy 342.449242 -214.873528) (xy 342.412632 -214.836918) (xy 342.3822 -214.795031) (xy 342.358694 -214.748899)
			(xy 342.342695 -214.699659) (xy 342.334596 -214.648521) (xy 342.334088 -214.622634) (xy 342.334458 -214.599658)
			(xy 342.34077 -214.554143) (xy 342.353348 -214.509947) (xy 342.362282 -214.488776) (xy 342.372188 -214.466424)
			(xy 342.158574 -214.061294) (xy 342.134444 -214.056722) (xy 342.109513 -214.051663) (xy 342.061499 -214.034858)
			(xy 342.016639 -214.010874) (xy 341.975997 -213.980281) (xy 341.940539 -213.943805) (xy 341.911109 -213.902313)
			(xy 341.888405 -213.856791) (xy 341.872967 -213.80832) (xy 341.865162 -213.758053) (xy 341.864696 -213.732618)
			(xy 340.643972 -213.732618) (xy 340.643623 -213.755595) (xy 340.637302 -213.801111) (xy 340.624716 -213.845306)
			(xy 340.615778 -213.866476) (xy 340.605872 -213.888828) (xy 340.819486 -214.293958) (xy 340.843616 -214.29853)
			(xy 340.86853 -214.303664) (xy 340.91654 -214.320459) (xy 340.961399 -214.344434) (xy 341.002041 -214.375017)
			(xy 341.037499 -214.411484) (xy 341.066932 -214.452967) (xy 341.08964 -214.49848) (xy 341.105083 -214.546942)
			(xy 341.112895 -214.597202) (xy 341.113364 -214.622634) (xy 341.112856 -214.648521) (xy 341.104757 -214.699659)
			(xy 341.088758 -214.748899) (xy 341.065252 -214.795031) (xy 341.03482 -214.836918) (xy 340.99821 -214.873528)
			(xy 340.956323 -214.90396) (xy 340.910191 -214.927466) (xy 340.860951 -214.943465) (xy 340.809813 -214.951564)
			(xy 340.758039 -214.951564) (xy 340.706901 -214.943465) (xy 340.657661 -214.927466) (xy 340.611529 -214.90396)
			(xy 340.569642 -214.873528) (xy 340.533032 -214.836918) (xy 340.5026 -214.795031) (xy 340.479094 -214.748899)
			(xy 340.463095 -214.699659) (xy 340.454996 -214.648521) (xy 340.454488 -214.622634) (xy 340.454858 -214.599658)
			(xy 340.46117 -214.554143) (xy 340.473748 -214.509947) (xy 340.482682 -214.488776) (xy 340.492588 -214.466424)
			(xy 340.278974 -214.061294) (xy 340.254844 -214.056722) (xy 340.229913 -214.051663) (xy 340.181899 -214.034858)
			(xy 340.137039 -214.010874) (xy 340.096397 -213.980281) (xy 340.060939 -213.943805) (xy 340.031509 -213.902313)
			(xy 340.008805 -213.856791) (xy 339.993367 -213.80832) (xy 339.985562 -213.758053) (xy 339.985096 -213.732618)
			(xy 338.764372 -213.732618) (xy 338.764023 -213.755595) (xy 338.757702 -213.801111) (xy 338.745116 -213.845306)
			(xy 338.736178 -213.866476) (xy 338.726272 -213.888828) (xy 338.939886 -214.293958) (xy 338.964016 -214.29853)
			(xy 338.98893 -214.303664) (xy 339.03694 -214.320459) (xy 339.081799 -214.344434) (xy 339.122441 -214.375017)
			(xy 339.157899 -214.411484) (xy 339.187332 -214.452967) (xy 339.21004 -214.49848) (xy 339.225483 -214.546942)
			(xy 339.233295 -214.597202) (xy 339.233764 -214.622634) (xy 339.233256 -214.648521) (xy 339.225157 -214.699659)
			(xy 339.209158 -214.748899) (xy 339.185652 -214.795031) (xy 339.15522 -214.836918) (xy 339.11861 -214.873528)
			(xy 339.076723 -214.90396) (xy 339.030591 -214.927466) (xy 338.981351 -214.943465) (xy 338.930213 -214.951564)
			(xy 338.878439 -214.951564) (xy 338.827301 -214.943465) (xy 338.778061 -214.927466) (xy 338.731929 -214.90396)
			(xy 338.690042 -214.873528) (xy 338.653432 -214.836918) (xy 338.623 -214.795031) (xy 338.599494 -214.748899)
			(xy 338.583495 -214.699659) (xy 338.575396 -214.648521) (xy 338.574888 -214.622634) (xy 338.575258 -214.599658)
			(xy 338.58157 -214.554143) (xy 338.594148 -214.509947) (xy 338.603082 -214.488776) (xy 338.612988 -214.466424)
			(xy 338.399374 -214.061294) (xy 338.375244 -214.056722) (xy 338.350313 -214.051663) (xy 338.302299 -214.034858)
			(xy 338.257439 -214.010874) (xy 338.216797 -213.980281) (xy 338.181339 -213.943805) (xy 338.151909 -213.902313)
			(xy 338.129205 -213.856791) (xy 338.113767 -213.80832) (xy 338.105962 -213.758053) (xy 338.105496 -213.732618)
			(xy 132.175504 -213.732618) (xy 132.175153 -213.755595) (xy 132.168832 -213.80111) (xy 132.156248 -213.845306)
			(xy 132.14731 -213.866476) (xy 132.137404 -213.888828) (xy 132.351018 -214.293958) (xy 132.375148 -214.29853)
			(xy 132.400067 -214.303641) (xy 132.448077 -214.320441) (xy 132.492936 -214.344419) (xy 132.533576 -214.375006)
			(xy 132.569034 -214.411476) (xy 132.598466 -214.452961) (xy 132.621173 -214.498476) (xy 132.636615 -214.54694)
			(xy 132.644427 -214.597201) (xy 132.644896 -214.622634) (xy 132.644388 -214.648521) (xy 132.636289 -214.699659)
			(xy 132.62029 -214.748899) (xy 132.596784 -214.795031) (xy 132.566352 -214.836918) (xy 132.529742 -214.873528)
			(xy 132.487855 -214.90396) (xy 132.441723 -214.927466) (xy 132.392483 -214.943465) (xy 132.341345 -214.951564)
			(xy 132.289571 -214.951564) (xy 132.238433 -214.943465) (xy 132.189193 -214.927466) (xy 132.143061 -214.90396)
			(xy 132.101174 -214.873528) (xy 132.064564 -214.836918) (xy 132.034132 -214.795031) (xy 132.010626 -214.748899)
			(xy 131.994627 -214.699659) (xy 131.986528 -214.648521) (xy 131.98602 -214.622634) (xy 131.986387 -214.599658)
			(xy 131.9927 -214.554143) (xy 132.005279 -214.509947) (xy 132.014214 -214.488776) (xy 132.02412 -214.466424)
			(xy 131.810506 -214.061294) (xy 131.786376 -214.056722) (xy 131.76145 -214.051639) (xy 131.713436 -214.034839)
			(xy 131.668575 -214.010859) (xy 131.627932 -213.980269) (xy 131.592474 -213.943796) (xy 131.563043 -213.902307)
			(xy 131.540338 -213.856787) (xy 131.5249 -213.808318) (xy 131.517094 -213.758052) (xy 131.516628 -213.732618)
			(xy 130.295904 -213.732618) (xy 130.295553 -213.755595) (xy 130.289232 -213.80111) (xy 130.276648 -213.845306)
			(xy 130.26771 -213.866476) (xy 130.257804 -213.888828) (xy 130.471418 -214.293958) (xy 130.495548 -214.29853)
			(xy 130.520467 -214.303641) (xy 130.568477 -214.320441) (xy 130.613336 -214.344419) (xy 130.653976 -214.375006)
			(xy 130.689434 -214.411476) (xy 130.718866 -214.452961) (xy 130.741573 -214.498476) (xy 130.757015 -214.54694)
			(xy 130.764827 -214.597201) (xy 130.765296 -214.622634) (xy 130.764788 -214.648521) (xy 130.756689 -214.699659)
			(xy 130.74069 -214.748899) (xy 130.717184 -214.795031) (xy 130.686752 -214.836918) (xy 130.650142 -214.873528)
			(xy 130.608255 -214.90396) (xy 130.562123 -214.927466) (xy 130.512883 -214.943465) (xy 130.461745 -214.951564)
			(xy 130.409971 -214.951564) (xy 130.358833 -214.943465) (xy 130.309593 -214.927466) (xy 130.263461 -214.90396)
			(xy 130.221574 -214.873528) (xy 130.184964 -214.836918) (xy 130.154532 -214.795031) (xy 130.131026 -214.748899)
			(xy 130.115027 -214.699659) (xy 130.106928 -214.648521) (xy 130.10642 -214.622634) (xy 130.106787 -214.599658)
			(xy 130.1131 -214.554143) (xy 130.125679 -214.509947) (xy 130.134614 -214.488776) (xy 130.14452 -214.466424)
			(xy 129.930906 -214.061294) (xy 129.906776 -214.056722) (xy 129.88185 -214.051639) (xy 129.833836 -214.034839)
			(xy 129.788975 -214.010859) (xy 129.748332 -213.980269) (xy 129.712874 -213.943796) (xy 129.683443 -213.902307)
			(xy 129.660738 -213.856787) (xy 129.6453 -213.808318) (xy 129.637494 -213.758052) (xy 129.637028 -213.732618)
			(xy 128.416304 -213.732618) (xy 128.415953 -213.755595) (xy 128.409632 -213.80111) (xy 128.397048 -213.845306)
			(xy 128.38811 -213.866476) (xy 128.378204 -213.888828) (xy 128.591818 -214.293958) (xy 128.615948 -214.29853)
			(xy 128.640867 -214.303641) (xy 128.688877 -214.320441) (xy 128.733736 -214.344419) (xy 128.774376 -214.375006)
			(xy 128.809834 -214.411476) (xy 128.839266 -214.452961) (xy 128.861973 -214.498476) (xy 128.877415 -214.54694)
			(xy 128.885227 -214.597201) (xy 128.885696 -214.622634) (xy 128.885188 -214.648521) (xy 128.877089 -214.699659)
			(xy 128.86109 -214.748899) (xy 128.837584 -214.795031) (xy 128.807152 -214.836918) (xy 128.770542 -214.873528)
			(xy 128.728655 -214.90396) (xy 128.682523 -214.927466) (xy 128.633283 -214.943465) (xy 128.582145 -214.951564)
			(xy 128.530371 -214.951564) (xy 128.479233 -214.943465) (xy 128.429993 -214.927466) (xy 128.383861 -214.90396)
			(xy 128.341974 -214.873528) (xy 128.305364 -214.836918) (xy 128.274932 -214.795031) (xy 128.251426 -214.748899)
			(xy 128.235427 -214.699659) (xy 128.227328 -214.648521) (xy 128.22682 -214.622634) (xy 128.227187 -214.599658)
			(xy 128.2335 -214.554143) (xy 128.246079 -214.509947) (xy 128.255014 -214.488776) (xy 128.26492 -214.466424)
			(xy 128.051306 -214.061294) (xy 128.027176 -214.056722) (xy 128.00225 -214.051639) (xy 127.954236 -214.034839)
			(xy 127.909375 -214.010859) (xy 127.868732 -213.980269) (xy 127.833274 -213.943796) (xy 127.803843 -213.902307)
			(xy 127.781138 -213.856787) (xy 127.7657 -213.808318) (xy 127.757894 -213.758052) (xy 127.757428 -213.732618)
			(xy 126.536704 -213.732618) (xy 126.536283 -213.755559) (xy 126.529855 -213.80099) (xy 126.517209 -213.845096)
			(xy 126.508256 -213.866222) (xy 126.49835 -213.888574) (xy 126.712218 -214.293958) (xy 126.736348 -214.29853)
			(xy 126.761267 -214.303641) (xy 126.809277 -214.320441) (xy 126.854136 -214.344419) (xy 126.894776 -214.375006)
			(xy 126.930234 -214.411476) (xy 126.959666 -214.452961) (xy 126.982373 -214.498476) (xy 126.997815 -214.54694)
			(xy 127.005627 -214.597201) (xy 127.006096 -214.622634) (xy 127.005588 -214.648521) (xy 126.997489 -214.699659)
			(xy 126.98149 -214.748899) (xy 126.957984 -214.795031) (xy 126.927552 -214.836918) (xy 126.890942 -214.873528)
			(xy 126.849055 -214.90396) (xy 126.802923 -214.927466) (xy 126.753683 -214.943465) (xy 126.702545 -214.951564)
			(xy 126.650771 -214.951564) (xy 126.599633 -214.943465) (xy 126.550393 -214.927466) (xy 126.504261 -214.90396)
			(xy 126.462374 -214.873528) (xy 126.425764 -214.836918) (xy 126.395332 -214.795031) (xy 126.371826 -214.748899)
			(xy 126.355827 -214.699659) (xy 126.347728 -214.648521) (xy 126.34722 -214.622634) (xy 126.347587 -214.599658)
			(xy 126.3539 -214.554143) (xy 126.366479 -214.509947) (xy 126.375414 -214.488776) (xy 126.38532 -214.466424)
			(xy 126.171706 -214.061294) (xy 126.147576 -214.056722) (xy 126.12262 -214.051672) (xy 126.074538 -214.034924)
			(xy 126.029605 -214.010979) (xy 125.98889 -213.980407) (xy 125.953363 -213.943936) (xy 125.92387 -213.902434)
			(xy 125.901111 -213.856888) (xy 125.88563 -213.808384) (xy 125.877795 -213.758075) (xy 125.87732 -213.732618)
			(xy 124.657104 -213.732618) (xy 124.656681 -213.756953) (xy 124.649527 -213.805095) (xy 124.635379 -213.851663)
			(xy 124.625354 -213.873842) (xy 124.614432 -213.896448) (xy 124.820172 -214.292942) (xy 124.845826 -214.296752)
			(xy 124.87151 -214.301109) (xy 124.921167 -214.316849) (xy 124.967731 -214.340204) (xy 125.010041 -214.370592)
			(xy 125.047044 -214.407258) (xy 125.077819 -214.449288) (xy 125.101599 -214.495635) (xy 125.117793 -214.545146)
			(xy 125.125998 -214.596588) (xy 125.126496 -214.622634) (xy 125.125988 -214.648521) (xy 125.117889 -214.699659)
			(xy 125.10189 -214.748899) (xy 125.078384 -214.795031) (xy 125.047952 -214.836918) (xy 125.011342 -214.873528)
			(xy 124.969455 -214.90396) (xy 124.923323 -214.927466) (xy 124.874083 -214.943465) (xy 124.822945 -214.951564)
			(xy 124.771171 -214.951564) (xy 124.720033 -214.943465) (xy 124.670793 -214.927466) (xy 124.624661 -214.90396)
			(xy 124.582774 -214.873528) (xy 124.546164 -214.836918) (xy 124.515732 -214.795031) (xy 124.492226 -214.748899)
			(xy 124.476227 -214.699659) (xy 124.468128 -214.648521) (xy 124.46762 -214.622634) (xy 124.468099 -214.597068)
			(xy 124.476002 -214.546552) (xy 124.491623 -214.497866) (xy 124.502672 -214.474806) (xy 124.514102 -214.451438)
			(xy 124.31268 -214.062818) (xy 124.28601 -214.059516) (xy 124.259814 -214.055663) (xy 124.20902 -214.04073)
			(xy 124.161267 -214.017866) (xy 124.117785 -213.987661) (xy 124.079693 -213.950891) (xy 124.047971 -213.908503)
			(xy 124.023436 -213.861587) (xy 124.006718 -213.811352) (xy 123.998249 -213.75909) (xy 123.99772 -213.732618)
			(xy 122.777504 -213.732618) (xy 122.777153 -213.755595) (xy 122.770832 -213.80111) (xy 122.758248 -213.845306)
			(xy 122.74931 -213.866476) (xy 122.739404 -213.888828) (xy 122.953018 -214.293958) (xy 122.977148 -214.29853)
			(xy 123.002067 -214.303641) (xy 123.050077 -214.320441) (xy 123.094936 -214.344419) (xy 123.135576 -214.375006)
			(xy 123.171034 -214.411476) (xy 123.200466 -214.452961) (xy 123.223173 -214.498476) (xy 123.238615 -214.54694)
			(xy 123.246427 -214.597201) (xy 123.246896 -214.622634) (xy 123.246388 -214.648521) (xy 123.238289 -214.699659)
			(xy 123.22229 -214.748899) (xy 123.198784 -214.795031) (xy 123.168352 -214.836918) (xy 123.131742 -214.873528)
			(xy 123.089855 -214.90396) (xy 123.043723 -214.927466) (xy 122.994483 -214.943465) (xy 122.943345 -214.951564)
			(xy 122.891571 -214.951564) (xy 122.840433 -214.943465) (xy 122.791193 -214.927466) (xy 122.745061 -214.90396)
			(xy 122.703174 -214.873528) (xy 122.666564 -214.836918) (xy 122.636132 -214.795031) (xy 122.612626 -214.748899)
			(xy 122.596627 -214.699659) (xy 122.588528 -214.648521) (xy 122.58802 -214.622634) (xy 122.588387 -214.599658)
			(xy 122.5947 -214.554143) (xy 122.607279 -214.509947) (xy 122.616214 -214.488776) (xy 122.62612 -214.466424)
			(xy 122.412506 -214.061294) (xy 122.388376 -214.056722) (xy 122.36345 -214.051639) (xy 122.315436 -214.034839)
			(xy 122.270575 -214.010859) (xy 122.229932 -213.980269) (xy 122.194474 -213.943796) (xy 122.165043 -213.902307)
			(xy 122.142338 -213.856787) (xy 122.1269 -213.808318) (xy 122.119094 -213.758052) (xy 122.118628 -213.732618)
			(xy 120.897904 -213.732618) (xy 120.897553 -213.755595) (xy 120.891232 -213.80111) (xy 120.878648 -213.845306)
			(xy 120.86971 -213.866476) (xy 120.859804 -213.888828) (xy 121.073418 -214.293958) (xy 121.097548 -214.29853)
			(xy 121.122467 -214.303641) (xy 121.170477 -214.320441) (xy 121.215336 -214.344419) (xy 121.255976 -214.375006)
			(xy 121.291434 -214.411476) (xy 121.320866 -214.452961) (xy 121.343573 -214.498476) (xy 121.359015 -214.54694)
			(xy 121.366827 -214.597201) (xy 121.367296 -214.622634) (xy 121.366788 -214.648521) (xy 121.358689 -214.699659)
			(xy 121.34269 -214.748899) (xy 121.319184 -214.795031) (xy 121.288752 -214.836918) (xy 121.252142 -214.873528)
			(xy 121.210255 -214.90396) (xy 121.164123 -214.927466) (xy 121.114883 -214.943465) (xy 121.063745 -214.951564)
			(xy 121.011971 -214.951564) (xy 120.960833 -214.943465) (xy 120.911593 -214.927466) (xy 120.865461 -214.90396)
			(xy 120.823574 -214.873528) (xy 120.786964 -214.836918) (xy 120.756532 -214.795031) (xy 120.733026 -214.748899)
			(xy 120.717027 -214.699659) (xy 120.708928 -214.648521) (xy 120.70842 -214.622634) (xy 120.708787 -214.599658)
			(xy 120.7151 -214.554143) (xy 120.727679 -214.509947) (xy 120.736614 -214.488776) (xy 120.74652 -214.466424)
			(xy 120.532906 -214.061294) (xy 120.508776 -214.056722) (xy 120.48385 -214.051639) (xy 120.435836 -214.034839)
			(xy 120.390975 -214.010859) (xy 120.350332 -213.980269) (xy 120.314874 -213.943796) (xy 120.285443 -213.902307)
			(xy 120.262738 -213.856787) (xy 120.2473 -213.808318) (xy 120.239494 -213.758052) (xy 120.239028 -213.732618)
			(xy 119.018304 -213.732618) (xy 119.017953 -213.755595) (xy 119.011632 -213.80111) (xy 118.999048 -213.845306)
			(xy 118.99011 -213.866476) (xy 118.980204 -213.888828) (xy 119.193818 -214.293958) (xy 119.217948 -214.29853)
			(xy 119.242867 -214.303641) (xy 119.290877 -214.320441) (xy 119.335736 -214.344419) (xy 119.376376 -214.375006)
			(xy 119.411834 -214.411476) (xy 119.441266 -214.452961) (xy 119.463973 -214.498476) (xy 119.479415 -214.54694)
			(xy 119.487227 -214.597201) (xy 119.487696 -214.622634) (xy 119.487188 -214.648521) (xy 119.479089 -214.699659)
			(xy 119.46309 -214.748899) (xy 119.439584 -214.795031) (xy 119.409152 -214.836918) (xy 119.372542 -214.873528)
			(xy 119.330655 -214.90396) (xy 119.284523 -214.927466) (xy 119.235283 -214.943465) (xy 119.184145 -214.951564)
			(xy 119.132371 -214.951564) (xy 119.081233 -214.943465) (xy 119.031993 -214.927466) (xy 118.985861 -214.90396)
			(xy 118.943974 -214.873528) (xy 118.907364 -214.836918) (xy 118.876932 -214.795031) (xy 118.853426 -214.748899)
			(xy 118.837427 -214.699659) (xy 118.829328 -214.648521) (xy 118.82882 -214.622634) (xy 118.829187 -214.599658)
			(xy 118.8355 -214.554143) (xy 118.848079 -214.509947) (xy 118.857014 -214.488776) (xy 118.86692 -214.466424)
			(xy 118.653306 -214.061294) (xy 118.629176 -214.056722) (xy 118.60425 -214.051639) (xy 118.556236 -214.034839)
			(xy 118.511375 -214.010859) (xy 118.470732 -213.980269) (xy 118.435274 -213.943796) (xy 118.405843 -213.902307)
			(xy 118.383138 -213.856787) (xy 118.3677 -213.808318) (xy 118.359894 -213.758052) (xy 118.359428 -213.732618)
			(xy 117.138704 -213.732618) (xy 117.138353 -213.755595) (xy 117.132032 -213.80111) (xy 117.119448 -213.845306)
			(xy 117.11051 -213.866476) (xy 117.100604 -213.888828) (xy 117.314218 -214.293958) (xy 117.338348 -214.29853)
			(xy 117.363267 -214.303641) (xy 117.411277 -214.320441) (xy 117.456136 -214.344419) (xy 117.496776 -214.375006)
			(xy 117.532234 -214.411476) (xy 117.561666 -214.452961) (xy 117.584373 -214.498476) (xy 117.599815 -214.54694)
			(xy 117.607627 -214.597201) (xy 117.608096 -214.622634) (xy 117.607588 -214.648521) (xy 117.599489 -214.699659)
			(xy 117.58349 -214.748899) (xy 117.559984 -214.795031) (xy 117.529552 -214.836918) (xy 117.492942 -214.873528)
			(xy 117.451055 -214.90396) (xy 117.404923 -214.927466) (xy 117.355683 -214.943465) (xy 117.304545 -214.951564)
			(xy 117.252771 -214.951564) (xy 117.201633 -214.943465) (xy 117.152393 -214.927466) (xy 117.106261 -214.90396)
			(xy 117.064374 -214.873528) (xy 117.027764 -214.836918) (xy 116.997332 -214.795031) (xy 116.973826 -214.748899)
			(xy 116.957827 -214.699659) (xy 116.949728 -214.648521) (xy 116.94922 -214.622634) (xy 116.949587 -214.599658)
			(xy 116.9559 -214.554143) (xy 116.968479 -214.509947) (xy 116.977414 -214.488776) (xy 116.98732 -214.466424)
			(xy 116.773706 -214.061294) (xy 116.749576 -214.056722) (xy 116.72465 -214.051639) (xy 116.676636 -214.034839)
			(xy 116.631775 -214.010859) (xy 116.591132 -213.980269) (xy 116.555674 -213.943796) (xy 116.526243 -213.902307)
			(xy 116.503538 -213.856787) (xy 116.4881 -213.808318) (xy 116.480294 -213.758052) (xy 116.479828 -213.732618)
			(xy 115.259104 -213.732618) (xy 115.258753 -213.755595) (xy 115.252432 -213.80111) (xy 115.239848 -213.845306)
			(xy 115.23091 -213.866476) (xy 115.221004 -213.888828) (xy 115.434618 -214.293958) (xy 115.458748 -214.29853)
			(xy 115.483667 -214.303641) (xy 115.531677 -214.320441) (xy 115.576536 -214.344419) (xy 115.617176 -214.375006)
			(xy 115.652634 -214.411476) (xy 115.682066 -214.452961) (xy 115.704773 -214.498476) (xy 115.720215 -214.54694)
			(xy 115.728027 -214.597201) (xy 115.728496 -214.622634) (xy 115.727988 -214.648521) (xy 115.719889 -214.699659)
			(xy 115.70389 -214.748899) (xy 115.680384 -214.795031) (xy 115.649952 -214.836918) (xy 115.613342 -214.873528)
			(xy 115.571455 -214.90396) (xy 115.525323 -214.927466) (xy 115.476083 -214.943465) (xy 115.424945 -214.951564)
			(xy 115.373171 -214.951564) (xy 115.322033 -214.943465) (xy 115.272793 -214.927466) (xy 115.226661 -214.90396)
			(xy 115.184774 -214.873528) (xy 115.148164 -214.836918) (xy 115.117732 -214.795031) (xy 115.094226 -214.748899)
			(xy 115.078227 -214.699659) (xy 115.070128 -214.648521) (xy 115.06962 -214.622634) (xy 115.069987 -214.599658)
			(xy 115.0763 -214.554143) (xy 115.088879 -214.509947) (xy 115.097814 -214.488776) (xy 115.10772 -214.466424)
			(xy 114.894106 -214.061294) (xy 114.869976 -214.056722) (xy 114.84505 -214.051639) (xy 114.797036 -214.034839)
			(xy 114.752175 -214.010859) (xy 114.711532 -213.980269) (xy 114.676074 -213.943796) (xy 114.646643 -213.902307)
			(xy 114.623938 -213.856787) (xy 114.6085 -213.808318) (xy 114.600694 -213.758052) (xy 114.600228 -213.732618)
			(xy 107.740704 -213.732618) (xy 107.740353 -213.755595) (xy 107.734032 -213.80111) (xy 107.721448 -213.845306)
			(xy 107.71251 -213.866476) (xy 107.702604 -213.888828) (xy 107.916218 -214.293958) (xy 107.940348 -214.29853)
			(xy 107.965267 -214.303641) (xy 108.013277 -214.320441) (xy 108.058136 -214.344419) (xy 108.098776 -214.375006)
			(xy 108.134234 -214.411476) (xy 108.163666 -214.452961) (xy 108.186373 -214.498476) (xy 108.201815 -214.54694)
			(xy 108.209627 -214.597201) (xy 108.210096 -214.622634) (xy 108.209588 -214.648521) (xy 108.201489 -214.699659)
			(xy 108.18549 -214.748899) (xy 108.161984 -214.795031) (xy 108.131552 -214.836918) (xy 108.094942 -214.873528)
			(xy 108.053055 -214.90396) (xy 108.006923 -214.927466) (xy 107.957683 -214.943465) (xy 107.906545 -214.951564)
			(xy 107.854771 -214.951564) (xy 107.803633 -214.943465) (xy 107.754393 -214.927466) (xy 107.708261 -214.90396)
			(xy 107.666374 -214.873528) (xy 107.629764 -214.836918) (xy 107.599332 -214.795031) (xy 107.575826 -214.748899)
			(xy 107.559827 -214.699659) (xy 107.551728 -214.648521) (xy 107.55122 -214.622634) (xy 107.551587 -214.599658)
			(xy 107.5579 -214.554143) (xy 107.570479 -214.509947) (xy 107.579414 -214.488776) (xy 107.58932 -214.466424)
			(xy 107.375706 -214.061294) (xy 107.351576 -214.056722) (xy 107.32665 -214.051639) (xy 107.278636 -214.034839)
			(xy 107.233775 -214.010859) (xy 107.193132 -213.980269) (xy 107.157674 -213.943796) (xy 107.128243 -213.902307)
			(xy 107.105538 -213.856787) (xy 107.0901 -213.808318) (xy 107.082294 -213.758052) (xy 107.081828 -213.732618)
			(xy 105.861104 -213.732618) (xy 105.860753 -213.755595) (xy 105.854432 -213.80111) (xy 105.841848 -213.845306)
			(xy 105.83291 -213.866476) (xy 105.823004 -213.888828) (xy 106.036618 -214.293958) (xy 106.060748 -214.29853)
			(xy 106.085667 -214.303641) (xy 106.133677 -214.320441) (xy 106.178536 -214.344419) (xy 106.219176 -214.375006)
			(xy 106.254634 -214.411476) (xy 106.284066 -214.452961) (xy 106.306773 -214.498476) (xy 106.322215 -214.54694)
			(xy 106.330027 -214.597201) (xy 106.330496 -214.622634) (xy 106.329988 -214.648521) (xy 106.321889 -214.699659)
			(xy 106.30589 -214.748899) (xy 106.282384 -214.795031) (xy 106.251952 -214.836918) (xy 106.215342 -214.873528)
			(xy 106.173455 -214.90396) (xy 106.127323 -214.927466) (xy 106.078083 -214.943465) (xy 106.026945 -214.951564)
			(xy 105.975171 -214.951564) (xy 105.924033 -214.943465) (xy 105.874793 -214.927466) (xy 105.828661 -214.90396)
			(xy 105.786774 -214.873528) (xy 105.750164 -214.836918) (xy 105.719732 -214.795031) (xy 105.696226 -214.748899)
			(xy 105.680227 -214.699659) (xy 105.672128 -214.648521) (xy 105.67162 -214.622634) (xy 105.671987 -214.599658)
			(xy 105.6783 -214.554143) (xy 105.690879 -214.509947) (xy 105.699814 -214.488776) (xy 105.70972 -214.466424)
			(xy 105.496106 -214.061294) (xy 105.471976 -214.056722) (xy 105.44705 -214.051639) (xy 105.399036 -214.034839)
			(xy 105.354175 -214.010859) (xy 105.313532 -213.980269) (xy 105.278074 -213.943796) (xy 105.248643 -213.902307)
			(xy 105.225938 -213.856787) (xy 105.2105 -213.808318) (xy 105.202694 -213.758052) (xy 105.202228 -213.732618)
			(xy 103.981504 -213.732618) (xy 103.981153 -213.755595) (xy 103.974832 -213.80111) (xy 103.962248 -213.845306)
			(xy 103.95331 -213.866476) (xy 103.943404 -213.888828) (xy 104.157018 -214.293958) (xy 104.181148 -214.29853)
			(xy 104.206067 -214.303641) (xy 104.254077 -214.320441) (xy 104.298936 -214.344419) (xy 104.339576 -214.375006)
			(xy 104.375034 -214.411476) (xy 104.404466 -214.452961) (xy 104.427173 -214.498476) (xy 104.442615 -214.54694)
			(xy 104.450427 -214.597201) (xy 104.450896 -214.622634) (xy 104.450388 -214.648521) (xy 104.442289 -214.699659)
			(xy 104.42629 -214.748899) (xy 104.402784 -214.795031) (xy 104.372352 -214.836918) (xy 104.335742 -214.873528)
			(xy 104.293855 -214.90396) (xy 104.247723 -214.927466) (xy 104.198483 -214.943465) (xy 104.147345 -214.951564)
			(xy 104.095571 -214.951564) (xy 104.044433 -214.943465) (xy 103.995193 -214.927466) (xy 103.949061 -214.90396)
			(xy 103.907174 -214.873528) (xy 103.870564 -214.836918) (xy 103.840132 -214.795031) (xy 103.816626 -214.748899)
			(xy 103.800627 -214.699659) (xy 103.792528 -214.648521) (xy 103.79202 -214.622634) (xy 103.792387 -214.599658)
			(xy 103.7987 -214.554143) (xy 103.811279 -214.509947) (xy 103.820214 -214.488776) (xy 103.83012 -214.466424)
			(xy 103.616506 -214.061294) (xy 103.592376 -214.056722) (xy 103.56745 -214.051639) (xy 103.519436 -214.034839)
			(xy 103.474575 -214.010859) (xy 103.433932 -213.980269) (xy 103.398474 -213.943796) (xy 103.369043 -213.902307)
			(xy 103.346338 -213.856787) (xy 103.3309 -213.808318) (xy 103.323094 -213.758052) (xy 103.322628 -213.732618)
			(xy 102.101904 -213.732618) (xy 102.101553 -213.755595) (xy 102.095232 -213.80111) (xy 102.082648 -213.845306)
			(xy 102.07371 -213.866476) (xy 102.063804 -213.888828) (xy 102.277418 -214.293958) (xy 102.301548 -214.29853)
			(xy 102.326467 -214.303641) (xy 102.374477 -214.320441) (xy 102.419336 -214.344419) (xy 102.459976 -214.375006)
			(xy 102.495434 -214.411476) (xy 102.524866 -214.452961) (xy 102.547573 -214.498476) (xy 102.563015 -214.54694)
			(xy 102.570827 -214.597201) (xy 102.571296 -214.622634) (xy 102.570788 -214.648521) (xy 102.562689 -214.699659)
			(xy 102.54669 -214.748899) (xy 102.523184 -214.795031) (xy 102.492752 -214.836918) (xy 102.456142 -214.873528)
			(xy 102.414255 -214.90396) (xy 102.368123 -214.927466) (xy 102.318883 -214.943465) (xy 102.267745 -214.951564)
			(xy 102.215971 -214.951564) (xy 102.164833 -214.943465) (xy 102.115593 -214.927466) (xy 102.069461 -214.90396)
			(xy 102.027574 -214.873528) (xy 101.990964 -214.836918) (xy 101.960532 -214.795031) (xy 101.937026 -214.748899)
			(xy 101.921027 -214.699659) (xy 101.912928 -214.648521) (xy 101.91242 -214.622634) (xy 101.912787 -214.599658)
			(xy 101.9191 -214.554143) (xy 101.931679 -214.509947) (xy 101.940614 -214.488776) (xy 101.95052 -214.466424)
			(xy 101.736906 -214.061294) (xy 101.712776 -214.056722) (xy 101.68785 -214.051639) (xy 101.639836 -214.034839)
			(xy 101.594975 -214.010859) (xy 101.554332 -213.980269) (xy 101.518874 -213.943796) (xy 101.489443 -213.902307)
			(xy 101.466738 -213.856787) (xy 101.4513 -213.808318) (xy 101.443494 -213.758052) (xy 101.443028 -213.732618)
			(xy 100.222304 -213.732618) (xy 100.221953 -213.755595) (xy 100.215632 -213.80111) (xy 100.203048 -213.845306)
			(xy 100.19411 -213.866476) (xy 100.184204 -213.888828) (xy 100.397818 -214.293958) (xy 100.421948 -214.29853)
			(xy 100.446867 -214.303641) (xy 100.494877 -214.320441) (xy 100.539736 -214.344419) (xy 100.580376 -214.375006)
			(xy 100.615834 -214.411476) (xy 100.645266 -214.452961) (xy 100.667973 -214.498476) (xy 100.683415 -214.54694)
			(xy 100.691227 -214.597201) (xy 100.691696 -214.622634) (xy 100.691188 -214.648521) (xy 100.683089 -214.699659)
			(xy 100.66709 -214.748899) (xy 100.643584 -214.795031) (xy 100.613152 -214.836918) (xy 100.576542 -214.873528)
			(xy 100.534655 -214.90396) (xy 100.488523 -214.927466) (xy 100.439283 -214.943465) (xy 100.388145 -214.951564)
			(xy 100.336371 -214.951564) (xy 100.285233 -214.943465) (xy 100.235993 -214.927466) (xy 100.189861 -214.90396)
			(xy 100.147974 -214.873528) (xy 100.111364 -214.836918) (xy 100.080932 -214.795031) (xy 100.057426 -214.748899)
			(xy 100.041427 -214.699659) (xy 100.033328 -214.648521) (xy 100.03282 -214.622634) (xy 100.033187 -214.599658)
			(xy 100.0395 -214.554143) (xy 100.052079 -214.509947) (xy 100.061014 -214.488776) (xy 100.07092 -214.466424)
			(xy 99.857306 -214.061294) (xy 99.833176 -214.056722) (xy 99.80825 -214.051639) (xy 99.760236 -214.034839)
			(xy 99.715375 -214.010859) (xy 99.674732 -213.980269) (xy 99.639274 -213.943796) (xy 99.609843 -213.902307)
			(xy 99.587138 -213.856787) (xy 99.5717 -213.808318) (xy 99.563894 -213.758052) (xy 99.563428 -213.732618)
			(xy 98.342704 -213.732618) (xy 98.342353 -213.755595) (xy 98.336032 -213.80111) (xy 98.323448 -213.845306)
			(xy 98.31451 -213.866476) (xy 98.304604 -213.888828) (xy 98.518218 -214.293958) (xy 98.542348 -214.29853)
			(xy 98.567267 -214.303641) (xy 98.615277 -214.320441) (xy 98.660136 -214.344419) (xy 98.700776 -214.375006)
			(xy 98.736234 -214.411476) (xy 98.765666 -214.452961) (xy 98.788373 -214.498476) (xy 98.803815 -214.54694)
			(xy 98.811627 -214.597201) (xy 98.812096 -214.622634) (xy 98.811588 -214.648521) (xy 98.803489 -214.699659)
			(xy 98.78749 -214.748899) (xy 98.763984 -214.795031) (xy 98.733552 -214.836918) (xy 98.696942 -214.873528)
			(xy 98.655055 -214.90396) (xy 98.608923 -214.927466) (xy 98.559683 -214.943465) (xy 98.508545 -214.951564)
			(xy 98.456771 -214.951564) (xy 98.405633 -214.943465) (xy 98.356393 -214.927466) (xy 98.310261 -214.90396)
			(xy 98.268374 -214.873528) (xy 98.231764 -214.836918) (xy 98.201332 -214.795031) (xy 98.177826 -214.748899)
			(xy 98.161827 -214.699659) (xy 98.153728 -214.648521) (xy 98.15322 -214.622634) (xy 98.153587 -214.599658)
			(xy 98.1599 -214.554143) (xy 98.172479 -214.509947) (xy 98.181414 -214.488776) (xy 98.19132 -214.466424)
			(xy 97.977706 -214.061294) (xy 97.953576 -214.056722) (xy 97.92865 -214.051639) (xy 97.880636 -214.034839)
			(xy 97.835775 -214.010859) (xy 97.795132 -213.980269) (xy 97.759674 -213.943796) (xy 97.730243 -213.902307)
			(xy 97.707538 -213.856787) (xy 97.6921 -213.808318) (xy 97.684294 -213.758052) (xy 97.683828 -213.732618)
			(xy 96.463104 -213.732618) (xy 96.462753 -213.755595) (xy 96.456432 -213.80111) (xy 96.443848 -213.845306)
			(xy 96.43491 -213.866476) (xy 96.425004 -213.888828) (xy 96.638618 -214.293958) (xy 96.662748 -214.29853)
			(xy 96.687667 -214.303641) (xy 96.735677 -214.320441) (xy 96.780536 -214.344419) (xy 96.821176 -214.375006)
			(xy 96.856634 -214.411476) (xy 96.886066 -214.452961) (xy 96.908773 -214.498476) (xy 96.924215 -214.54694)
			(xy 96.932027 -214.597201) (xy 96.932496 -214.622634) (xy 96.931988 -214.648521) (xy 96.923889 -214.699659)
			(xy 96.90789 -214.748899) (xy 96.884384 -214.795031) (xy 96.853952 -214.836918) (xy 96.817342 -214.873528)
			(xy 96.775455 -214.90396) (xy 96.729323 -214.927466) (xy 96.680083 -214.943465) (xy 96.628945 -214.951564)
			(xy 96.577171 -214.951564) (xy 96.526033 -214.943465) (xy 96.476793 -214.927466) (xy 96.430661 -214.90396)
			(xy 96.388774 -214.873528) (xy 96.352164 -214.836918) (xy 96.321732 -214.795031) (xy 96.298226 -214.748899)
			(xy 96.282227 -214.699659) (xy 96.274128 -214.648521) (xy 96.27362 -214.622634) (xy 96.273987 -214.599658)
			(xy 96.2803 -214.554143) (xy 96.292879 -214.509947) (xy 96.301814 -214.488776) (xy 96.31172 -214.466424)
			(xy 96.098106 -214.061294) (xy 96.073976 -214.056722) (xy 96.04905 -214.051639) (xy 96.001036 -214.034839)
			(xy 95.956175 -214.010859) (xy 95.915532 -213.980269) (xy 95.880074 -213.943796) (xy 95.850643 -213.902307)
			(xy 95.827938 -213.856787) (xy 95.8125 -213.808318) (xy 95.804694 -213.758052) (xy 95.804228 -213.732618)
			(xy 94.583504 -213.732618) (xy 94.583153 -213.755595) (xy 94.576832 -213.80111) (xy 94.564248 -213.845306)
			(xy 94.55531 -213.866476) (xy 94.545404 -213.888828) (xy 94.759018 -214.293958) (xy 94.783148 -214.29853)
			(xy 94.808067 -214.303641) (xy 94.856077 -214.320441) (xy 94.900936 -214.344419) (xy 94.941576 -214.375006)
			(xy 94.977034 -214.411476) (xy 95.006466 -214.452961) (xy 95.029173 -214.498476) (xy 95.044615 -214.54694)
			(xy 95.052427 -214.597201) (xy 95.052896 -214.622634) (xy 95.052388 -214.648521) (xy 95.044289 -214.699659)
			(xy 95.02829 -214.748899) (xy 95.004784 -214.795031) (xy 94.974352 -214.836918) (xy 94.937742 -214.873528)
			(xy 94.895855 -214.90396) (xy 94.849723 -214.927466) (xy 94.800483 -214.943465) (xy 94.749345 -214.951564)
			(xy 94.697571 -214.951564) (xy 94.646433 -214.943465) (xy 94.597193 -214.927466) (xy 94.551061 -214.90396)
			(xy 94.509174 -214.873528) (xy 94.472564 -214.836918) (xy 94.442132 -214.795031) (xy 94.418626 -214.748899)
			(xy 94.402627 -214.699659) (xy 94.394528 -214.648521) (xy 94.39402 -214.622634) (xy 94.394387 -214.599658)
			(xy 94.4007 -214.554143) (xy 94.413279 -214.509947) (xy 94.422214 -214.488776) (xy 94.43212 -214.466424)
			(xy 94.218506 -214.061294) (xy 94.194376 -214.056722) (xy 94.16945 -214.051639) (xy 94.121436 -214.034839)
			(xy 94.076575 -214.010859) (xy 94.035932 -213.980269) (xy 94.000474 -213.943796) (xy 93.971043 -213.902307)
			(xy 93.948338 -213.856787) (xy 93.9329 -213.808318) (xy 93.925094 -213.758052) (xy 93.924628 -213.732618)
			(xy 92.703904 -213.732618) (xy 92.703553 -213.755595) (xy 92.697232 -213.80111) (xy 92.684648 -213.845306)
			(xy 92.67571 -213.866476) (xy 92.665804 -213.888828) (xy 92.879418 -214.293958) (xy 92.903548 -214.29853)
			(xy 92.928467 -214.303641) (xy 92.976477 -214.320441) (xy 93.021336 -214.344419) (xy 93.061976 -214.375006)
			(xy 93.097434 -214.411476) (xy 93.126866 -214.452961) (xy 93.149573 -214.498476) (xy 93.165015 -214.54694)
			(xy 93.172827 -214.597201) (xy 93.173296 -214.622634) (xy 93.172788 -214.648521) (xy 93.164689 -214.699659)
			(xy 93.14869 -214.748899) (xy 93.125184 -214.795031) (xy 93.094752 -214.836918) (xy 93.058142 -214.873528)
			(xy 93.016255 -214.90396) (xy 92.970123 -214.927466) (xy 92.920883 -214.943465) (xy 92.869745 -214.951564)
			(xy 92.817971 -214.951564) (xy 92.766833 -214.943465) (xy 92.717593 -214.927466) (xy 92.671461 -214.90396)
			(xy 92.629574 -214.873528) (xy 92.592964 -214.836918) (xy 92.562532 -214.795031) (xy 92.539026 -214.748899)
			(xy 92.523027 -214.699659) (xy 92.514928 -214.648521) (xy 92.51442 -214.622634) (xy 92.514787 -214.599658)
			(xy 92.5211 -214.554143) (xy 92.533679 -214.509947) (xy 92.542614 -214.488776) (xy 92.55252 -214.466424)
			(xy 92.338906 -214.061294) (xy 92.314776 -214.056722) (xy 92.28985 -214.051639) (xy 92.241836 -214.034839)
			(xy 92.196975 -214.010859) (xy 92.156332 -213.980269) (xy 92.120874 -213.943796) (xy 92.091443 -213.902307)
			(xy 92.068738 -213.856787) (xy 92.0533 -213.808318) (xy 92.045494 -213.758052) (xy 92.045028 -213.732618)
			(xy 90.824304 -213.732618) (xy 90.823953 -213.755595) (xy 90.817632 -213.80111) (xy 90.805048 -213.845306)
			(xy 90.79611 -213.866476) (xy 90.786204 -213.888828) (xy 90.999818 -214.293958) (xy 91.023948 -214.29853)
			(xy 91.048867 -214.303641) (xy 91.096877 -214.320441) (xy 91.141736 -214.344419) (xy 91.182376 -214.375006)
			(xy 91.217834 -214.411476) (xy 91.247266 -214.452961) (xy 91.269973 -214.498476) (xy 91.285415 -214.54694)
			(xy 91.293227 -214.597201) (xy 91.293696 -214.622634) (xy 91.293188 -214.648521) (xy 91.285089 -214.699659)
			(xy 91.26909 -214.748899) (xy 91.245584 -214.795031) (xy 91.215152 -214.836918) (xy 91.178542 -214.873528)
			(xy 91.136655 -214.90396) (xy 91.090523 -214.927466) (xy 91.041283 -214.943465) (xy 90.990145 -214.951564)
			(xy 90.938371 -214.951564) (xy 90.887233 -214.943465) (xy 90.837993 -214.927466) (xy 90.791861 -214.90396)
			(xy 90.749974 -214.873528) (xy 90.713364 -214.836918) (xy 90.682932 -214.795031) (xy 90.659426 -214.748899)
			(xy 90.643427 -214.699659) (xy 90.635328 -214.648521) (xy 90.63482 -214.622634) (xy 90.635187 -214.599658)
			(xy 90.6415 -214.554143) (xy 90.654079 -214.509947) (xy 90.663014 -214.488776) (xy 90.67292 -214.466424)
			(xy 90.459306 -214.061294) (xy 90.435176 -214.056722) (xy 90.41025 -214.051639) (xy 90.362236 -214.034839)
			(xy 90.317375 -214.010859) (xy 90.276732 -213.980269) (xy 90.241274 -213.943796) (xy 90.211843 -213.902307)
			(xy 90.189138 -213.856787) (xy 90.1737 -213.808318) (xy 90.165894 -213.758052) (xy 90.165428 -213.732618)
			(xy 2.509012 -213.732618) (xy 2.509012 -215.436704) (xy 88.28532 -215.436704) (xy 88.285828 -215.410797)
			(xy 88.293934 -215.35962) (xy 88.309946 -215.310341) (xy 88.333469 -215.264174) (xy 88.363925 -215.222255)
			(xy 88.400563 -215.185617) (xy 88.442482 -215.155161) (xy 88.488649 -215.131638) (xy 88.537928 -215.115626)
			(xy 88.589105 -215.10752) (xy 88.640919 -215.10752) (xy 88.692096 -215.115626) (xy 88.741375 -215.131638)
			(xy 88.787542 -215.155161) (xy 88.829461 -215.185617) (xy 88.866099 -215.222255) (xy 88.896555 -215.264174)
			(xy 88.920078 -215.310341) (xy 88.93609 -215.35962) (xy 88.944196 -215.410797) (xy 88.944704 -215.436704)
			(xy 89.22512 -215.436704) (xy 89.225629 -215.41136) (xy 89.2334 -215.36127) (xy 89.248746 -215.31296)
			(xy 89.271303 -215.267567) (xy 89.300542 -215.226161) (xy 89.335773 -215.189717) (xy 89.376165 -215.159094)
			(xy 89.420769 -215.135013) (xy 89.468532 -215.118041) (xy 89.493344 -215.112854) (xy 89.516204 -215.108536)
			(xy 89.721182 -214.753444) (xy 89.713308 -214.7316) (xy 89.704729 -214.705181) (xy 89.695532 -214.650406)
			(xy 89.69502 -214.622634) (xy 89.695528 -214.596747) (xy 89.703627 -214.545609) (xy 89.719626 -214.496369)
			(xy 89.743132 -214.450237) (xy 89.773564 -214.40835) (xy 89.810174 -214.37174) (xy 89.852061 -214.341308)
			(xy 89.898193 -214.317802) (xy 89.947433 -214.301803) (xy 89.998571 -214.293704) (xy 90.050345 -214.293704)
			(xy 90.101483 -214.301803) (xy 90.150723 -214.317802) (xy 90.196855 -214.341308) (xy 90.238742 -214.37174)
			(xy 90.275352 -214.40835) (xy 90.305784 -214.450237) (xy 90.32929 -214.496369) (xy 90.345289 -214.545609)
			(xy 90.353388 -214.596747) (xy 90.353896 -214.622634) (xy 90.353447 -214.64797) (xy 90.34569 -214.698044)
			(xy 90.330363 -214.746341) (xy 90.307827 -214.791726) (xy 90.278612 -214.833128) (xy 90.243408 -214.869572)
			(xy 90.203042 -214.900202) (xy 90.158465 -214.924296) (xy 90.110727 -214.941286) (xy 90.085926 -214.946484)
			(xy 90.063066 -214.950802) (xy 89.858088 -215.305894) (xy 89.865962 -215.327738) (xy 89.87461 -215.354146)
			(xy 89.883929 -215.408922) (xy 89.884504 -215.436704) (xy 91.10472 -215.436704) (xy 91.105229 -215.41136)
			(xy 91.113 -215.36127) (xy 91.128346 -215.31296) (xy 91.150903 -215.267567) (xy 91.180142 -215.226161)
			(xy 91.215373 -215.189717) (xy 91.255765 -215.159094) (xy 91.300369 -215.135013) (xy 91.348132 -215.118041)
			(xy 91.372944 -215.112854) (xy 91.395804 -215.108536) (xy 91.600782 -214.753444) (xy 91.592908 -214.7316)
			(xy 91.584329 -214.705181) (xy 91.575132 -214.650406) (xy 91.57462 -214.622634) (xy 91.575128 -214.596747)
			(xy 91.583227 -214.545609) (xy 91.599226 -214.496369) (xy 91.622732 -214.450237) (xy 91.653164 -214.40835)
			(xy 91.689774 -214.37174) (xy 91.731661 -214.341308) (xy 91.777793 -214.317802) (xy 91.827033 -214.301803)
			(xy 91.878171 -214.293704) (xy 91.929945 -214.293704) (xy 91.981083 -214.301803) (xy 92.030323 -214.317802)
			(xy 92.076455 -214.341308) (xy 92.118342 -214.37174) (xy 92.154952 -214.40835) (xy 92.185384 -214.450237)
			(xy 92.20889 -214.496369) (xy 92.224889 -214.545609) (xy 92.232988 -214.596747) (xy 92.233496 -214.622634)
			(xy 92.233047 -214.64797) (xy 92.22529 -214.698044) (xy 92.209963 -214.746341) (xy 92.187427 -214.791726)
			(xy 92.158212 -214.833128) (xy 92.123008 -214.869572) (xy 92.082642 -214.900202) (xy 92.038065 -214.924296)
			(xy 91.990327 -214.941286) (xy 91.965526 -214.946484) (xy 91.942666 -214.950802) (xy 91.737688 -215.305894)
			(xy 91.745562 -215.327738) (xy 91.75421 -215.354146) (xy 91.763529 -215.408922) (xy 91.764104 -215.436704)
			(xy 92.98432 -215.436704) (xy 92.984829 -215.41136) (xy 92.9926 -215.36127) (xy 93.007946 -215.31296)
			(xy 93.030503 -215.267567) (xy 93.059742 -215.226161) (xy 93.094973 -215.189717) (xy 93.135365 -215.159094)
			(xy 93.179969 -215.135013) (xy 93.227732 -215.118041) (xy 93.252544 -215.112854) (xy 93.275404 -215.108536)
			(xy 93.480382 -214.753444) (xy 93.472508 -214.7316) (xy 93.463929 -214.705181) (xy 93.454732 -214.650406)
			(xy 93.45422 -214.622634) (xy 93.454728 -214.596747) (xy 93.462827 -214.545609) (xy 93.478826 -214.496369)
			(xy 93.502332 -214.450237) (xy 93.532764 -214.40835) (xy 93.569374 -214.37174) (xy 93.611261 -214.341308)
			(xy 93.657393 -214.317802) (xy 93.706633 -214.301803) (xy 93.757771 -214.293704) (xy 93.809545 -214.293704)
			(xy 93.860683 -214.301803) (xy 93.909923 -214.317802) (xy 93.956055 -214.341308) (xy 93.997942 -214.37174)
			(xy 94.034552 -214.40835) (xy 94.064984 -214.450237) (xy 94.08849 -214.496369) (xy 94.104489 -214.545609)
			(xy 94.112588 -214.596747) (xy 94.113096 -214.622634) (xy 94.112647 -214.64797) (xy 94.10489 -214.698044)
			(xy 94.089563 -214.746341) (xy 94.067027 -214.791726) (xy 94.037812 -214.833128) (xy 94.002608 -214.869572)
			(xy 93.962242 -214.900202) (xy 93.917665 -214.924296) (xy 93.869927 -214.941286) (xy 93.845126 -214.946484)
			(xy 93.822266 -214.950802) (xy 93.617288 -215.305894) (xy 93.625162 -215.327738) (xy 93.63381 -215.354146)
			(xy 93.643129 -215.408922) (xy 93.643704 -215.436704) (xy 94.86392 -215.436704) (xy 94.864429 -215.41136)
			(xy 94.8722 -215.36127) (xy 94.887546 -215.31296) (xy 94.910103 -215.267567) (xy 94.939342 -215.226161)
			(xy 94.974573 -215.189717) (xy 95.014965 -215.159094) (xy 95.059569 -215.135013) (xy 95.107332 -215.118041)
			(xy 95.132144 -215.112854) (xy 95.155004 -215.108536) (xy 95.359982 -214.753444) (xy 95.352108 -214.7316)
			(xy 95.343529 -214.705181) (xy 95.334332 -214.650406) (xy 95.33382 -214.622634) (xy 95.334328 -214.596747)
			(xy 95.342427 -214.545609) (xy 95.358426 -214.496369) (xy 95.381932 -214.450237) (xy 95.412364 -214.40835)
			(xy 95.448974 -214.37174) (xy 95.490861 -214.341308) (xy 95.536993 -214.317802) (xy 95.586233 -214.301803)
			(xy 95.637371 -214.293704) (xy 95.689145 -214.293704) (xy 95.740283 -214.301803) (xy 95.789523 -214.317802)
			(xy 95.835655 -214.341308) (xy 95.877542 -214.37174) (xy 95.914152 -214.40835) (xy 95.944584 -214.450237)
			(xy 95.96809 -214.496369) (xy 95.984089 -214.545609) (xy 95.992188 -214.596747) (xy 95.992696 -214.622634)
			(xy 95.992247 -214.64797) (xy 95.98449 -214.698044) (xy 95.969163 -214.746341) (xy 95.946627 -214.791726)
			(xy 95.917412 -214.833128) (xy 95.882208 -214.869572) (xy 95.841842 -214.900202) (xy 95.797265 -214.924296)
			(xy 95.749527 -214.941286) (xy 95.724726 -214.946484) (xy 95.701866 -214.950802) (xy 95.496888 -215.305894)
			(xy 95.504762 -215.327738) (xy 95.51341 -215.354146) (xy 95.522729 -215.408922) (xy 95.523304 -215.436704)
			(xy 96.74352 -215.436704) (xy 96.744029 -215.41136) (xy 96.7518 -215.36127) (xy 96.767146 -215.31296)
			(xy 96.789703 -215.267567) (xy 96.818942 -215.226161) (xy 96.854173 -215.189717) (xy 96.894565 -215.159094)
			(xy 96.939169 -215.135013) (xy 96.986932 -215.118041) (xy 97.011744 -215.112854) (xy 97.034604 -215.108536)
			(xy 97.239582 -214.753444) (xy 97.231708 -214.7316) (xy 97.223129 -214.705181) (xy 97.213932 -214.650406)
			(xy 97.21342 -214.622634) (xy 97.213928 -214.596747) (xy 97.222027 -214.545609) (xy 97.238026 -214.496369)
			(xy 97.261532 -214.450237) (xy 97.291964 -214.40835) (xy 97.328574 -214.37174) (xy 97.370461 -214.341308)
			(xy 97.416593 -214.317802) (xy 97.465833 -214.301803) (xy 97.516971 -214.293704) (xy 97.568745 -214.293704)
			(xy 97.619883 -214.301803) (xy 97.669123 -214.317802) (xy 97.715255 -214.341308) (xy 97.757142 -214.37174)
			(xy 97.793752 -214.40835) (xy 97.824184 -214.450237) (xy 97.84769 -214.496369) (xy 97.863689 -214.545609)
			(xy 97.871788 -214.596747) (xy 97.872296 -214.622634) (xy 97.871847 -214.64797) (xy 97.86409 -214.698044)
			(xy 97.848763 -214.746341) (xy 97.826227 -214.791726) (xy 97.797012 -214.833128) (xy 97.761808 -214.869572)
			(xy 97.721442 -214.900202) (xy 97.676865 -214.924296) (xy 97.629127 -214.941286) (xy 97.604326 -214.946484)
			(xy 97.581466 -214.950802) (xy 97.376488 -215.305894) (xy 97.384362 -215.327738) (xy 97.39301 -215.354146)
			(xy 97.402329 -215.408922) (xy 97.402904 -215.436704) (xy 98.62312 -215.436704) (xy 98.623629 -215.41136)
			(xy 98.6314 -215.36127) (xy 98.646746 -215.31296) (xy 98.669303 -215.267567) (xy 98.698542 -215.226161)
			(xy 98.733773 -215.189717) (xy 98.774165 -215.159094) (xy 98.818769 -215.135013) (xy 98.866532 -215.118041)
			(xy 98.891344 -215.112854) (xy 98.914204 -215.108536) (xy 99.119182 -214.753444) (xy 99.111308 -214.7316)
			(xy 99.102729 -214.705181) (xy 99.093532 -214.650406) (xy 99.09302 -214.622634) (xy 99.093528 -214.596747)
			(xy 99.101627 -214.545609) (xy 99.117626 -214.496369) (xy 99.141132 -214.450237) (xy 99.171564 -214.40835)
			(xy 99.208174 -214.37174) (xy 99.250061 -214.341308) (xy 99.296193 -214.317802) (xy 99.345433 -214.301803)
			(xy 99.396571 -214.293704) (xy 99.448345 -214.293704) (xy 99.499483 -214.301803) (xy 99.548723 -214.317802)
			(xy 99.594855 -214.341308) (xy 99.636742 -214.37174) (xy 99.673352 -214.40835) (xy 99.703784 -214.450237)
			(xy 99.72729 -214.496369) (xy 99.743289 -214.545609) (xy 99.751388 -214.596747) (xy 99.751896 -214.622634)
			(xy 99.751447 -214.64797) (xy 99.74369 -214.698044) (xy 99.728363 -214.746341) (xy 99.705827 -214.791726)
			(xy 99.676612 -214.833128) (xy 99.641408 -214.869572) (xy 99.601042 -214.900202) (xy 99.556465 -214.924296)
			(xy 99.508727 -214.941286) (xy 99.483926 -214.946484) (xy 99.461066 -214.950802) (xy 99.256088 -215.305894)
			(xy 99.263962 -215.327738) (xy 99.27261 -215.354146) (xy 99.281929 -215.408922) (xy 99.282504 -215.436704)
			(xy 100.50272 -215.436704) (xy 100.503229 -215.41136) (xy 100.511 -215.36127) (xy 100.526346 -215.31296)
			(xy 100.548903 -215.267567) (xy 100.578142 -215.226161) (xy 100.613373 -215.189717) (xy 100.653765 -215.159094)
			(xy 100.698369 -215.135013) (xy 100.746132 -215.118041) (xy 100.770944 -215.112854) (xy 100.793804 -215.108536)
			(xy 100.998782 -214.753444) (xy 100.990908 -214.7316) (xy 100.982329 -214.705181) (xy 100.973132 -214.650406)
			(xy 100.97262 -214.622634) (xy 100.973128 -214.596747) (xy 100.981227 -214.545609) (xy 100.997226 -214.496369)
			(xy 101.020732 -214.450237) (xy 101.051164 -214.40835) (xy 101.087774 -214.37174) (xy 101.129661 -214.341308)
			(xy 101.175793 -214.317802) (xy 101.225033 -214.301803) (xy 101.276171 -214.293704) (xy 101.327945 -214.293704)
			(xy 101.379083 -214.301803) (xy 101.428323 -214.317802) (xy 101.474455 -214.341308) (xy 101.516342 -214.37174)
			(xy 101.552952 -214.40835) (xy 101.583384 -214.450237) (xy 101.60689 -214.496369) (xy 101.622889 -214.545609)
			(xy 101.630988 -214.596747) (xy 101.631496 -214.622634) (xy 101.631047 -214.64797) (xy 101.62329 -214.698044)
			(xy 101.607963 -214.746341) (xy 101.585427 -214.791726) (xy 101.556212 -214.833128) (xy 101.521008 -214.869572)
			(xy 101.480642 -214.900202) (xy 101.436065 -214.924296) (xy 101.388327 -214.941286) (xy 101.363526 -214.946484)
			(xy 101.340666 -214.950802) (xy 101.135688 -215.305894) (xy 101.143562 -215.327738) (xy 101.15221 -215.354146)
			(xy 101.161529 -215.408922) (xy 101.162104 -215.436704) (xy 102.38232 -215.436704) (xy 102.382829 -215.41136)
			(xy 102.3906 -215.36127) (xy 102.405946 -215.31296) (xy 102.428503 -215.267567) (xy 102.457742 -215.226161)
			(xy 102.492973 -215.189717) (xy 102.533365 -215.159094) (xy 102.577969 -215.135013) (xy 102.625732 -215.118041)
			(xy 102.650544 -215.112854) (xy 102.673404 -215.108536) (xy 102.878382 -214.753444) (xy 102.870508 -214.7316)
			(xy 102.861929 -214.705181) (xy 102.852732 -214.650406) (xy 102.85222 -214.622634) (xy 102.852728 -214.596747)
			(xy 102.860827 -214.545609) (xy 102.876826 -214.496369) (xy 102.900332 -214.450237) (xy 102.930764 -214.40835)
			(xy 102.967374 -214.37174) (xy 103.009261 -214.341308) (xy 103.055393 -214.317802) (xy 103.104633 -214.301803)
			(xy 103.155771 -214.293704) (xy 103.207545 -214.293704) (xy 103.258683 -214.301803) (xy 103.307923 -214.317802)
			(xy 103.354055 -214.341308) (xy 103.395942 -214.37174) (xy 103.432552 -214.40835) (xy 103.462984 -214.450237)
			(xy 103.48649 -214.496369) (xy 103.502489 -214.545609) (xy 103.510588 -214.596747) (xy 103.511096 -214.622634)
			(xy 103.510647 -214.64797) (xy 103.50289 -214.698044) (xy 103.487563 -214.746341) (xy 103.465027 -214.791726)
			(xy 103.435812 -214.833128) (xy 103.400608 -214.869572) (xy 103.360242 -214.900202) (xy 103.315665 -214.924296)
			(xy 103.267927 -214.941286) (xy 103.243126 -214.946484) (xy 103.220266 -214.950802) (xy 103.015288 -215.305894)
			(xy 103.023162 -215.327738) (xy 103.03181 -215.354146) (xy 103.041129 -215.408922) (xy 103.041704 -215.436704)
			(xy 104.26192 -215.436704) (xy 104.262429 -215.41136) (xy 104.2702 -215.36127) (xy 104.285546 -215.31296)
			(xy 104.308103 -215.267567) (xy 104.337342 -215.226161) (xy 104.372573 -215.189717) (xy 104.412965 -215.159094)
			(xy 104.457569 -215.135013) (xy 104.505332 -215.118041) (xy 104.530144 -215.112854) (xy 104.553004 -215.108536)
			(xy 104.757982 -214.753444) (xy 104.750108 -214.7316) (xy 104.741529 -214.705181) (xy 104.732332 -214.650406)
			(xy 104.73182 -214.622634) (xy 104.732328 -214.596747) (xy 104.740427 -214.545609) (xy 104.756426 -214.496369)
			(xy 104.779932 -214.450237) (xy 104.810364 -214.40835) (xy 104.846974 -214.37174) (xy 104.888861 -214.341308)
			(xy 104.934993 -214.317802) (xy 104.984233 -214.301803) (xy 105.035371 -214.293704) (xy 105.087145 -214.293704)
			(xy 105.138283 -214.301803) (xy 105.187523 -214.317802) (xy 105.233655 -214.341308) (xy 105.275542 -214.37174)
			(xy 105.312152 -214.40835) (xy 105.342584 -214.450237) (xy 105.36609 -214.496369) (xy 105.382089 -214.545609)
			(xy 105.390188 -214.596747) (xy 105.390696 -214.622634) (xy 105.390247 -214.64797) (xy 105.38249 -214.698044)
			(xy 105.367163 -214.746341) (xy 105.344627 -214.791726) (xy 105.315412 -214.833128) (xy 105.280208 -214.869572)
			(xy 105.239842 -214.900202) (xy 105.195265 -214.924296) (xy 105.147527 -214.941286) (xy 105.122726 -214.946484)
			(xy 105.099866 -214.950802) (xy 104.894888 -215.305894) (xy 104.902762 -215.327738) (xy 104.91141 -215.354146)
			(xy 104.920729 -215.408922) (xy 104.921304 -215.436704) (xy 106.14152 -215.436704) (xy 106.142029 -215.41136)
			(xy 106.1498 -215.36127) (xy 106.165146 -215.31296) (xy 106.187703 -215.267567) (xy 106.216942 -215.226161)
			(xy 106.252173 -215.189717) (xy 106.292565 -215.159094) (xy 106.337169 -215.135013) (xy 106.384932 -215.118041)
			(xy 106.409744 -215.112854) (xy 106.432604 -215.108536) (xy 106.637582 -214.753444) (xy 106.629708 -214.7316)
			(xy 106.621129 -214.705181) (xy 106.611932 -214.650406) (xy 106.61142 -214.622634) (xy 106.611928 -214.596747)
			(xy 106.620027 -214.545609) (xy 106.636026 -214.496369) (xy 106.659532 -214.450237) (xy 106.689964 -214.40835)
			(xy 106.726574 -214.37174) (xy 106.768461 -214.341308) (xy 106.814593 -214.317802) (xy 106.863833 -214.301803)
			(xy 106.914971 -214.293704) (xy 106.966745 -214.293704) (xy 107.017883 -214.301803) (xy 107.067123 -214.317802)
			(xy 107.113255 -214.341308) (xy 107.155142 -214.37174) (xy 107.191752 -214.40835) (xy 107.222184 -214.450237)
			(xy 107.24569 -214.496369) (xy 107.261689 -214.545609) (xy 107.269788 -214.596747) (xy 107.270296 -214.622634)
			(xy 107.269847 -214.64797) (xy 107.26209 -214.698044) (xy 107.246763 -214.746341) (xy 107.224227 -214.791726)
			(xy 107.195012 -214.833128) (xy 107.159808 -214.869572) (xy 107.119442 -214.900202) (xy 107.074865 -214.924296)
			(xy 107.027127 -214.941286) (xy 107.002326 -214.946484) (xy 106.979466 -214.950802) (xy 106.774488 -215.305894)
			(xy 106.782362 -215.327738) (xy 106.79101 -215.354146) (xy 106.800329 -215.408922) (xy 106.800904 -215.436704)
			(xy 108.02112 -215.436704) (xy 108.021629 -215.41136) (xy 108.0294 -215.36127) (xy 108.044746 -215.31296)
			(xy 108.067303 -215.267567) (xy 108.096542 -215.226161) (xy 108.131773 -215.189717) (xy 108.172165 -215.159094)
			(xy 108.216769 -215.135013) (xy 108.264532 -215.118041) (xy 108.289344 -215.112854) (xy 108.312204 -215.108536)
			(xy 108.517182 -214.753444) (xy 108.509308 -214.7316) (xy 108.500729 -214.705181) (xy 108.491532 -214.650406)
			(xy 108.49102 -214.622634) (xy 108.491528 -214.596747) (xy 108.499627 -214.545609) (xy 108.515626 -214.496369)
			(xy 108.539132 -214.450237) (xy 108.569564 -214.40835) (xy 108.606174 -214.37174) (xy 108.648061 -214.341308)
			(xy 108.694193 -214.317802) (xy 108.743433 -214.301803) (xy 108.794571 -214.293704) (xy 108.846345 -214.293704)
			(xy 108.897483 -214.301803) (xy 108.946723 -214.317802) (xy 108.992855 -214.341308) (xy 109.034742 -214.37174)
			(xy 109.071352 -214.40835) (xy 109.101784 -214.450237) (xy 109.12529 -214.496369) (xy 109.141289 -214.545609)
			(xy 109.14142 -214.546434) (xy 110.371128 -214.546434) (xy 110.371636 -214.520547) (xy 110.379735 -214.469409)
			(xy 110.395734 -214.420169) (xy 110.41924 -214.374037) (xy 110.449672 -214.33215) (xy 110.486282 -214.29554)
			(xy 110.528169 -214.265108) (xy 110.574301 -214.241602) (xy 110.623541 -214.225603) (xy 110.674679 -214.217504)
			(xy 110.726453 -214.217504) (xy 110.777591 -214.225603) (xy 110.826831 -214.241602) (xy 110.872963 -214.265108)
			(xy 110.91485 -214.29554) (xy 110.95146 -214.33215) (xy 110.981892 -214.374037) (xy 111.005398 -214.420169)
			(xy 111.021397 -214.469409) (xy 111.029496 -214.520547) (xy 111.030004 -214.546434) (xy 111.030004 -214.546942)
			(xy 111.029596 -214.56979) (xy 111.029246 -214.572283) (xy 112.250803 -214.572283) (xy 112.250803 -214.520517)
			(xy 112.258901 -214.469389) (xy 112.274896 -214.420157) (xy 112.298395 -214.374033) (xy 112.32882 -214.332153)
			(xy 112.365421 -214.295547) (xy 112.407297 -214.265117) (xy 112.453418 -214.241612) (xy 112.502648 -214.22561)
			(xy 112.553775 -214.217507) (xy 112.579658 -214.216996) (xy 112.605169 -214.217509) (xy 112.655581 -214.225363)
			(xy 112.704182 -214.24089) (xy 112.749811 -214.263719) (xy 112.791377 -214.293306) (xy 112.827889 -214.328944)
			(xy 112.843564 -214.349076) (xy 113.255552 -214.349076) (xy 113.271247 -214.328958) (xy 113.307753 -214.293314)
			(xy 113.349314 -214.263719) (xy 113.394938 -214.24088) (xy 113.443536 -214.225342) (xy 113.493947 -214.217476)
			(xy 113.519458 -214.216996) (xy 113.545352 -214.217406) (xy 113.596504 -214.225502) (xy 113.645759 -214.2415)
			(xy 113.691905 -214.265008) (xy 113.733805 -214.295445) (xy 113.770428 -214.332063) (xy 113.80087 -214.373959)
			(xy 113.824384 -214.420102) (xy 113.840388 -214.469355) (xy 113.848491 -214.520506) (xy 113.848491 -214.572294)
			(xy 113.840388 -214.623445) (xy 113.824384 -214.672698) (xy 113.80087 -214.718841) (xy 113.770428 -214.760737)
			(xy 113.733805 -214.797355) (xy 113.691905 -214.827792) (xy 113.645759 -214.8513) (xy 113.596504 -214.867298)
			(xy 113.545352 -214.875394) (xy 113.519458 -214.875872) (xy 113.493944 -214.875433) (xy 113.443527 -214.867566)
			(xy 113.394925 -214.852025) (xy 113.349296 -214.829181) (xy 113.307732 -214.799581) (xy 113.271224 -214.763931)
			(xy 113.255552 -214.743792) (xy 112.843564 -214.743792) (xy 112.827909 -214.763943) (xy 112.791396 -214.799586)
			(xy 112.749827 -214.829178) (xy 112.704195 -214.852012) (xy 112.655589 -214.867542) (xy 112.605171 -214.875398)
			(xy 112.579658 -214.875872) (xy 112.553775 -214.875293) (xy 112.502648 -214.86719) (xy 112.453418 -214.851188)
			(xy 112.407297 -214.827683) (xy 112.365421 -214.797253) (xy 112.32882 -214.760647) (xy 112.298395 -214.718767)
			(xy 112.274896 -214.672643) (xy 112.258901 -214.623411) (xy 112.250803 -214.572283) (xy 111.029246 -214.572283)
			(xy 111.023246 -214.615045) (xy 111.010702 -214.658987) (xy 111.00181 -214.680038) (xy 110.991904 -214.702644)
			(xy 111.205772 -215.108028) (xy 111.229902 -215.1126) (xy 111.254835 -215.117694) (xy 111.302873 -215.134477)
			(xy 111.347761 -215.158443) (xy 111.388433 -215.189024) (xy 111.423922 -215.225492) (xy 111.453384 -215.266981)
			(xy 111.47612 -215.312505) (xy 111.491589 -215.360982) (xy 111.499424 -215.411261) (xy 111.499904 -215.436704)
			(xy 113.65992 -215.436704) (xy 113.660429 -215.41136) (xy 113.6682 -215.36127) (xy 113.683546 -215.31296)
			(xy 113.706103 -215.267567) (xy 113.735342 -215.226161) (xy 113.770573 -215.189717) (xy 113.810965 -215.159094)
			(xy 113.855569 -215.135013) (xy 113.903332 -215.118041) (xy 113.928144 -215.112854) (xy 113.951004 -215.108536)
			(xy 114.156236 -214.753444) (xy 114.148362 -214.731346) (xy 114.139733 -214.704999) (xy 114.130411 -214.650352)
			(xy 114.12982 -214.622634) (xy 114.130328 -214.596727) (xy 114.138434 -214.54555) (xy 114.154446 -214.496271)
			(xy 114.177969 -214.450104) (xy 114.208425 -214.408185) (xy 114.245063 -214.371547) (xy 114.286982 -214.341091)
			(xy 114.333149 -214.317568) (xy 114.382428 -214.301556) (xy 114.433605 -214.29345) (xy 114.485419 -214.29345)
			(xy 114.536596 -214.301556) (xy 114.585875 -214.317568) (xy 114.632042 -214.341091) (xy 114.673961 -214.371547)
			(xy 114.710599 -214.408185) (xy 114.741055 -214.450104) (xy 114.764578 -214.496271) (xy 114.78059 -214.54555)
			(xy 114.788696 -214.596727) (xy 114.789204 -214.622634) (xy 114.78871 -214.647978) (xy 114.780934 -214.698068)
			(xy 114.765584 -214.746377) (xy 114.743024 -214.791769) (xy 114.713783 -214.833174) (xy 114.678552 -214.869617)
			(xy 114.638158 -214.90024) (xy 114.593555 -214.924322) (xy 114.545792 -214.941296) (xy 114.52098 -214.946484)
			(xy 114.49812 -214.950802) (xy 114.292888 -215.305894) (xy 114.300762 -215.327992) (xy 114.309397 -215.354337)
			(xy 114.318716 -215.408986) (xy 114.319304 -215.436704) (xy 115.53952 -215.436704) (xy 115.540029 -215.41136)
			(xy 115.5478 -215.36127) (xy 115.563146 -215.31296) (xy 115.585703 -215.267567) (xy 115.614942 -215.226161)
			(xy 115.650173 -215.189717) (xy 115.690565 -215.159094) (xy 115.735169 -215.135013) (xy 115.782932 -215.118041)
			(xy 115.807744 -215.112854) (xy 115.830604 -215.108536) (xy 116.035582 -214.753444) (xy 116.027708 -214.7316)
			(xy 116.019129 -214.705181) (xy 116.009932 -214.650406) (xy 116.00942 -214.622634) (xy 116.009928 -214.596747)
			(xy 116.018027 -214.545609) (xy 116.034026 -214.496369) (xy 116.057532 -214.450237) (xy 116.087964 -214.40835)
			(xy 116.124574 -214.37174) (xy 116.166461 -214.341308) (xy 116.212593 -214.317802) (xy 116.261833 -214.301803)
			(xy 116.312971 -214.293704) (xy 116.364745 -214.293704) (xy 116.415883 -214.301803) (xy 116.465123 -214.317802)
			(xy 116.511255 -214.341308) (xy 116.553142 -214.37174) (xy 116.589752 -214.40835) (xy 116.620184 -214.450237)
			(xy 116.64369 -214.496369) (xy 116.659689 -214.545609) (xy 116.667788 -214.596747) (xy 116.668296 -214.622634)
			(xy 116.667847 -214.64797) (xy 116.66009 -214.698044) (xy 116.644763 -214.746341) (xy 116.622227 -214.791726)
			(xy 116.593012 -214.833128) (xy 116.557808 -214.869572) (xy 116.517442 -214.900202) (xy 116.472865 -214.924296)
			(xy 116.425127 -214.941286) (xy 116.400326 -214.946484) (xy 116.377466 -214.950802) (xy 116.172488 -215.305894)
			(xy 116.180362 -215.327738) (xy 116.18901 -215.354146) (xy 116.198329 -215.408922) (xy 116.198904 -215.436704)
			(xy 117.41912 -215.436704) (xy 117.419629 -215.41136) (xy 117.4274 -215.36127) (xy 117.442746 -215.31296)
			(xy 117.465303 -215.267567) (xy 117.494542 -215.226161) (xy 117.529773 -215.189717) (xy 117.570165 -215.159094)
			(xy 117.614769 -215.135013) (xy 117.662532 -215.118041) (xy 117.687344 -215.112854) (xy 117.710204 -215.108536)
			(xy 117.915182 -214.753444) (xy 117.907308 -214.7316) (xy 117.898729 -214.705181) (xy 117.889532 -214.650406)
			(xy 117.88902 -214.622634) (xy 117.889528 -214.596747) (xy 117.897627 -214.545609) (xy 117.913626 -214.496369)
			(xy 117.937132 -214.450237) (xy 117.967564 -214.40835) (xy 118.004174 -214.37174) (xy 118.046061 -214.341308)
			(xy 118.092193 -214.317802) (xy 118.141433 -214.301803) (xy 118.192571 -214.293704) (xy 118.244345 -214.293704)
			(xy 118.295483 -214.301803) (xy 118.344723 -214.317802) (xy 118.390855 -214.341308) (xy 118.432742 -214.37174)
			(xy 118.469352 -214.40835) (xy 118.499784 -214.450237) (xy 118.52329 -214.496369) (xy 118.539289 -214.545609)
			(xy 118.547388 -214.596747) (xy 118.547896 -214.622634) (xy 118.547447 -214.64797) (xy 118.53969 -214.698044)
			(xy 118.524363 -214.746341) (xy 118.501827 -214.791726) (xy 118.472612 -214.833128) (xy 118.437408 -214.869572)
			(xy 118.397042 -214.900202) (xy 118.352465 -214.924296) (xy 118.304727 -214.941286) (xy 118.279926 -214.946484)
			(xy 118.257066 -214.950802) (xy 118.052088 -215.305894) (xy 118.059962 -215.327738) (xy 118.06861 -215.354146)
			(xy 118.077929 -215.408922) (xy 118.078504 -215.436704) (xy 119.29872 -215.436704) (xy 119.299229 -215.41136)
			(xy 119.307 -215.36127) (xy 119.322346 -215.31296) (xy 119.344903 -215.267567) (xy 119.374142 -215.226161)
			(xy 119.409373 -215.189717) (xy 119.449765 -215.159094) (xy 119.494369 -215.135013) (xy 119.542132 -215.118041)
			(xy 119.566944 -215.112854) (xy 119.589804 -215.108536) (xy 119.794782 -214.753444) (xy 119.786908 -214.7316)
			(xy 119.778329 -214.705181) (xy 119.769132 -214.650406) (xy 119.76862 -214.622634) (xy 119.769128 -214.596747)
			(xy 119.777227 -214.545609) (xy 119.793226 -214.496369) (xy 119.816732 -214.450237) (xy 119.847164 -214.40835)
			(xy 119.883774 -214.37174) (xy 119.925661 -214.341308) (xy 119.971793 -214.317802) (xy 120.021033 -214.301803)
			(xy 120.072171 -214.293704) (xy 120.123945 -214.293704) (xy 120.175083 -214.301803) (xy 120.224323 -214.317802)
			(xy 120.270455 -214.341308) (xy 120.312342 -214.37174) (xy 120.348952 -214.40835) (xy 120.379384 -214.450237)
			(xy 120.40289 -214.496369) (xy 120.418889 -214.545609) (xy 120.426988 -214.596747) (xy 120.427496 -214.622634)
			(xy 120.427047 -214.64797) (xy 120.41929 -214.698044) (xy 120.403963 -214.746341) (xy 120.381427 -214.791726)
			(xy 120.352212 -214.833128) (xy 120.317008 -214.869572) (xy 120.276642 -214.900202) (xy 120.232065 -214.924296)
			(xy 120.184327 -214.941286) (xy 120.159526 -214.946484) (xy 120.136666 -214.950802) (xy 119.931688 -215.305894)
			(xy 119.939562 -215.327738) (xy 119.94821 -215.354146) (xy 119.957529 -215.408922) (xy 119.958104 -215.436704)
			(xy 121.17832 -215.436704) (xy 121.178829 -215.41136) (xy 121.1866 -215.36127) (xy 121.201946 -215.31296)
			(xy 121.224503 -215.267567) (xy 121.253742 -215.226161) (xy 121.288973 -215.189717) (xy 121.329365 -215.159094)
			(xy 121.373969 -215.135013) (xy 121.421732 -215.118041) (xy 121.446544 -215.112854) (xy 121.469404 -215.108536)
			(xy 121.674382 -214.753444) (xy 121.666508 -214.7316) (xy 121.657929 -214.705181) (xy 121.648732 -214.650406)
			(xy 121.64822 -214.622634) (xy 121.648728 -214.596747) (xy 121.656827 -214.545609) (xy 121.672826 -214.496369)
			(xy 121.696332 -214.450237) (xy 121.726764 -214.40835) (xy 121.763374 -214.37174) (xy 121.805261 -214.341308)
			(xy 121.851393 -214.317802) (xy 121.900633 -214.301803) (xy 121.951771 -214.293704) (xy 122.003545 -214.293704)
			(xy 122.054683 -214.301803) (xy 122.103923 -214.317802) (xy 122.150055 -214.341308) (xy 122.191942 -214.37174)
			(xy 122.228552 -214.40835) (xy 122.258984 -214.450237) (xy 122.28249 -214.496369) (xy 122.298489 -214.545609)
			(xy 122.306588 -214.596747) (xy 122.307096 -214.622634) (xy 122.306647 -214.64797) (xy 122.29889 -214.698044)
			(xy 122.283563 -214.746341) (xy 122.261027 -214.791726) (xy 122.231812 -214.833128) (xy 122.196608 -214.869572)
			(xy 122.156242 -214.900202) (xy 122.111665 -214.924296) (xy 122.063927 -214.941286) (xy 122.039126 -214.946484)
			(xy 122.016266 -214.950802) (xy 121.811288 -215.305894) (xy 121.819162 -215.327738) (xy 121.82781 -215.354146)
			(xy 121.837129 -215.408922) (xy 121.837704 -215.436704) (xy 123.05792 -215.436704) (xy 123.058429 -215.41136)
			(xy 123.0662 -215.36127) (xy 123.081546 -215.31296) (xy 123.104103 -215.267567) (xy 123.133342 -215.226161)
			(xy 123.168573 -215.189717) (xy 123.208965 -215.159094) (xy 123.253569 -215.135013) (xy 123.301332 -215.118041)
			(xy 123.326144 -215.112854) (xy 123.349004 -215.108536) (xy 123.553982 -214.753444) (xy 123.546108 -214.7316)
			(xy 123.537529 -214.705181) (xy 123.528332 -214.650406) (xy 123.52782 -214.622634) (xy 123.528328 -214.596747)
			(xy 123.536427 -214.545609) (xy 123.552426 -214.496369) (xy 123.575932 -214.450237) (xy 123.606364 -214.40835)
			(xy 123.642974 -214.37174) (xy 123.684861 -214.341308) (xy 123.730993 -214.317802) (xy 123.780233 -214.301803)
			(xy 123.831371 -214.293704) (xy 123.883145 -214.293704) (xy 123.934283 -214.301803) (xy 123.983523 -214.317802)
			(xy 124.029655 -214.341308) (xy 124.071542 -214.37174) (xy 124.108152 -214.40835) (xy 124.138584 -214.450237)
			(xy 124.16209 -214.496369) (xy 124.178089 -214.545609) (xy 124.186188 -214.596747) (xy 124.186696 -214.622634)
			(xy 124.186247 -214.64797) (xy 124.17849 -214.698044) (xy 124.163163 -214.746341) (xy 124.140627 -214.791726)
			(xy 124.111412 -214.833128) (xy 124.076208 -214.869572) (xy 124.035842 -214.900202) (xy 123.991265 -214.924296)
			(xy 123.943527 -214.941286) (xy 123.918726 -214.946484) (xy 123.895866 -214.950802) (xy 123.690888 -215.305894)
			(xy 123.698762 -215.327738) (xy 123.70741 -215.354146) (xy 123.716729 -215.408922) (xy 123.717304 -215.436704)
			(xy 124.93752 -215.436704) (xy 124.938029 -215.41136) (xy 124.9458 -215.36127) (xy 124.961146 -215.31296)
			(xy 124.983703 -215.267567) (xy 125.012942 -215.226161) (xy 125.048173 -215.189717) (xy 125.088565 -215.159094)
			(xy 125.133169 -215.135013) (xy 125.180932 -215.118041) (xy 125.205744 -215.112854) (xy 125.228604 -215.108536)
			(xy 125.433582 -214.753444) (xy 125.425708 -214.7316) (xy 125.417129 -214.705181) (xy 125.407932 -214.650406)
			(xy 125.40742 -214.622634) (xy 125.407928 -214.596747) (xy 125.416027 -214.545609) (xy 125.432026 -214.496369)
			(xy 125.455532 -214.450237) (xy 125.485964 -214.40835) (xy 125.522574 -214.37174) (xy 125.564461 -214.341308)
			(xy 125.610593 -214.317802) (xy 125.659833 -214.301803) (xy 125.710971 -214.293704) (xy 125.762745 -214.293704)
			(xy 125.813883 -214.301803) (xy 125.863123 -214.317802) (xy 125.909255 -214.341308) (xy 125.951142 -214.37174)
			(xy 125.987752 -214.40835) (xy 126.018184 -214.450237) (xy 126.04169 -214.496369) (xy 126.057689 -214.545609)
			(xy 126.065788 -214.596747) (xy 126.066296 -214.622634) (xy 126.065847 -214.64797) (xy 126.05809 -214.698044)
			(xy 126.042763 -214.746341) (xy 126.020227 -214.791726) (xy 125.991012 -214.833128) (xy 125.955808 -214.869572)
			(xy 125.915442 -214.900202) (xy 125.870865 -214.924296) (xy 125.823127 -214.941286) (xy 125.798326 -214.946484)
			(xy 125.775466 -214.950802) (xy 125.570488 -215.305894) (xy 125.578362 -215.327738) (xy 125.58701 -215.354146)
			(xy 125.596329 -215.408922) (xy 125.596904 -215.436704) (xy 126.81712 -215.436704) (xy 126.817629 -215.41136)
			(xy 126.8254 -215.36127) (xy 126.840746 -215.31296) (xy 126.863303 -215.267567) (xy 126.892542 -215.226161)
			(xy 126.927773 -215.189717) (xy 126.968165 -215.159094) (xy 127.012769 -215.135013) (xy 127.060532 -215.118041)
			(xy 127.085344 -215.112854) (xy 127.108204 -215.108536) (xy 127.313182 -214.753444) (xy 127.305308 -214.7316)
			(xy 127.296729 -214.705181) (xy 127.287532 -214.650406) (xy 127.28702 -214.622634) (xy 127.287528 -214.596747)
			(xy 127.295627 -214.545609) (xy 127.311626 -214.496369) (xy 127.335132 -214.450237) (xy 127.365564 -214.40835)
			(xy 127.402174 -214.37174) (xy 127.444061 -214.341308) (xy 127.490193 -214.317802) (xy 127.539433 -214.301803)
			(xy 127.590571 -214.293704) (xy 127.642345 -214.293704) (xy 127.693483 -214.301803) (xy 127.742723 -214.317802)
			(xy 127.788855 -214.341308) (xy 127.830742 -214.37174) (xy 127.867352 -214.40835) (xy 127.897784 -214.450237)
			(xy 127.92129 -214.496369) (xy 127.937289 -214.545609) (xy 127.945388 -214.596747) (xy 127.945896 -214.622634)
			(xy 127.945447 -214.64797) (xy 127.93769 -214.698044) (xy 127.922363 -214.746341) (xy 127.899827 -214.791726)
			(xy 127.870612 -214.833128) (xy 127.835408 -214.869572) (xy 127.795042 -214.900202) (xy 127.750465 -214.924296)
			(xy 127.702727 -214.941286) (xy 127.677926 -214.946484) (xy 127.655066 -214.950802) (xy 127.450088 -215.305894)
			(xy 127.457962 -215.327738) (xy 127.46661 -215.354146) (xy 127.475929 -215.408922) (xy 127.476504 -215.436704)
			(xy 128.69672 -215.436704) (xy 128.697229 -215.41136) (xy 128.705 -215.36127) (xy 128.720346 -215.31296)
			(xy 128.742903 -215.267567) (xy 128.772142 -215.226161) (xy 128.807373 -215.189717) (xy 128.847765 -215.159094)
			(xy 128.892369 -215.135013) (xy 128.940132 -215.118041) (xy 128.964944 -215.112854) (xy 128.987804 -215.108536)
			(xy 129.192782 -214.753444) (xy 129.184908 -214.7316) (xy 129.176329 -214.705181) (xy 129.167132 -214.650406)
			(xy 129.16662 -214.622634) (xy 129.167128 -214.596747) (xy 129.175227 -214.545609) (xy 129.191226 -214.496369)
			(xy 129.214732 -214.450237) (xy 129.245164 -214.40835) (xy 129.281774 -214.37174) (xy 129.323661 -214.341308)
			(xy 129.369793 -214.317802) (xy 129.419033 -214.301803) (xy 129.470171 -214.293704) (xy 129.521945 -214.293704)
			(xy 129.573083 -214.301803) (xy 129.622323 -214.317802) (xy 129.668455 -214.341308) (xy 129.710342 -214.37174)
			(xy 129.746952 -214.40835) (xy 129.777384 -214.450237) (xy 129.80089 -214.496369) (xy 129.816889 -214.545609)
			(xy 129.824988 -214.596747) (xy 129.825496 -214.622634) (xy 129.825047 -214.64797) (xy 129.81729 -214.698044)
			(xy 129.801963 -214.746341) (xy 129.779427 -214.791726) (xy 129.750212 -214.833128) (xy 129.715008 -214.869572)
			(xy 129.674642 -214.900202) (xy 129.630065 -214.924296) (xy 129.582327 -214.941286) (xy 129.557526 -214.946484)
			(xy 129.534666 -214.950802) (xy 129.329688 -215.305894) (xy 129.337562 -215.327738) (xy 129.34621 -215.354146)
			(xy 129.355529 -215.408922) (xy 129.356104 -215.436704) (xy 130.57632 -215.436704) (xy 130.576829 -215.41136)
			(xy 130.5846 -215.36127) (xy 130.599946 -215.31296) (xy 130.622503 -215.267567) (xy 130.651742 -215.226161)
			(xy 130.686973 -215.189717) (xy 130.727365 -215.159094) (xy 130.771969 -215.135013) (xy 130.819732 -215.118041)
			(xy 130.844544 -215.112854) (xy 130.867404 -215.108536) (xy 131.072382 -214.753444) (xy 131.064508 -214.7316)
			(xy 131.055929 -214.705181) (xy 131.046732 -214.650406) (xy 131.04622 -214.622634) (xy 131.046728 -214.596747)
			(xy 131.054827 -214.545609) (xy 131.070826 -214.496369) (xy 131.094332 -214.450237) (xy 131.124764 -214.40835)
			(xy 131.161374 -214.37174) (xy 131.203261 -214.341308) (xy 131.249393 -214.317802) (xy 131.298633 -214.301803)
			(xy 131.349771 -214.293704) (xy 131.401545 -214.293704) (xy 131.452683 -214.301803) (xy 131.501923 -214.317802)
			(xy 131.548055 -214.341308) (xy 131.589942 -214.37174) (xy 131.626552 -214.40835) (xy 131.656984 -214.450237)
			(xy 131.68049 -214.496369) (xy 131.696489 -214.545609) (xy 131.704588 -214.596747) (xy 131.705096 -214.622634)
			(xy 131.704647 -214.64797) (xy 131.69689 -214.698044) (xy 131.681563 -214.746341) (xy 131.659027 -214.791726)
			(xy 131.629812 -214.833128) (xy 131.594608 -214.869572) (xy 131.554242 -214.900202) (xy 131.509665 -214.924296)
			(xy 131.461927 -214.941286) (xy 131.437126 -214.946484) (xy 131.414266 -214.950802) (xy 131.209288 -215.305894)
			(xy 131.217162 -215.327738) (xy 131.22581 -215.354146) (xy 131.235129 -215.408922) (xy 131.235704 -215.436704)
			(xy 132.45592 -215.436704) (xy 132.456429 -215.41136) (xy 132.4642 -215.36127) (xy 132.479546 -215.31296)
			(xy 132.502103 -215.267567) (xy 132.531342 -215.226161) (xy 132.566573 -215.189717) (xy 132.606965 -215.159094)
			(xy 132.651569 -215.135013) (xy 132.699332 -215.118041) (xy 132.724144 -215.112854) (xy 132.747004 -215.108536)
			(xy 132.951982 -214.753444) (xy 132.944108 -214.7316) (xy 132.935529 -214.705181) (xy 132.926332 -214.650406)
			(xy 132.92582 -214.622634) (xy 132.926328 -214.596747) (xy 132.934427 -214.545609) (xy 132.950426 -214.496369)
			(xy 132.973932 -214.450237) (xy 133.004364 -214.40835) (xy 133.040974 -214.37174) (xy 133.082861 -214.341308)
			(xy 133.128993 -214.317802) (xy 133.178233 -214.301803) (xy 133.229371 -214.293704) (xy 133.281145 -214.293704)
			(xy 133.332283 -214.301803) (xy 133.381523 -214.317802) (xy 133.427655 -214.341308) (xy 133.469542 -214.37174)
			(xy 133.506152 -214.40835) (xy 133.536584 -214.450237) (xy 133.56009 -214.496369) (xy 133.576089 -214.545609)
			(xy 133.57622 -214.546434) (xy 134.80542 -214.546434) (xy 134.805928 -214.520527) (xy 134.814034 -214.46935)
			(xy 134.830046 -214.420071) (xy 134.853569 -214.373904) (xy 134.884025 -214.331985) (xy 134.920663 -214.295347)
			(xy 134.962582 -214.264891) (xy 135.008749 -214.241368) (xy 135.058028 -214.225356) (xy 135.109205 -214.21725)
			(xy 135.161019 -214.21725) (xy 135.212196 -214.225356) (xy 135.261475 -214.241368) (xy 135.307642 -214.264891)
			(xy 135.349561 -214.295347) (xy 135.386199 -214.331985) (xy 135.416655 -214.373904) (xy 135.440178 -214.420071)
			(xy 135.45619 -214.46935) (xy 135.464296 -214.520527) (xy 135.464804 -214.546434) (xy 135.464102 -214.577275)
			(xy 135.452589 -214.637875) (xy 135.441944 -214.66683) (xy 135.433308 -214.688674) (xy 135.656066 -215.110314)
			(xy 135.678672 -215.115394) (xy 135.702597 -215.121362) (xy 135.748484 -215.139404) (xy 135.791171 -215.164081)
			(xy 135.829706 -215.194841) (xy 135.863229 -215.230999) (xy 135.890992 -215.271747) (xy 135.912374 -215.316176)
			(xy 135.9269 -215.363294) (xy 135.934244 -215.412051) (xy 135.934704 -215.436704) (xy 336.225388 -215.436704)
			(xy 336.225896 -215.410797) (xy 336.234002 -215.35962) (xy 336.250014 -215.310341) (xy 336.273537 -215.264174)
			(xy 336.303993 -215.222255) (xy 336.340631 -215.185617) (xy 336.38255 -215.155161) (xy 336.428717 -215.131638)
			(xy 336.477996 -215.115626) (xy 336.529173 -215.10752) (xy 336.580987 -215.10752) (xy 336.632164 -215.115626)
			(xy 336.681443 -215.131638) (xy 336.72761 -215.155161) (xy 336.769529 -215.185617) (xy 336.806167 -215.222255)
			(xy 336.836623 -215.264174) (xy 336.860146 -215.310341) (xy 336.876158 -215.35962) (xy 336.884264 -215.410797)
			(xy 336.884772 -215.436704) (xy 337.165188 -215.436704) (xy 337.165723 -215.411361) (xy 337.173493 -215.361274)
			(xy 337.188837 -215.312966) (xy 337.211392 -215.267575) (xy 337.240627 -215.226169) (xy 337.275854 -215.189725)
			(xy 337.316243 -215.159101) (xy 337.360842 -215.135018) (xy 337.408601 -215.118043) (xy 337.433412 -215.112854)
			(xy 337.456272 -215.108536) (xy 337.66125 -214.753444) (xy 337.653376 -214.7316) (xy 337.644799 -214.705181)
			(xy 337.6356 -214.650406) (xy 337.635088 -214.622634) (xy 337.635596 -214.596747) (xy 337.643695 -214.545609)
			(xy 337.659694 -214.496369) (xy 337.6832 -214.450237) (xy 337.713632 -214.40835) (xy 337.750242 -214.37174)
			(xy 337.792129 -214.341308) (xy 337.838261 -214.317802) (xy 337.887501 -214.301803) (xy 337.938639 -214.293704)
			(xy 337.990413 -214.293704) (xy 338.041551 -214.301803) (xy 338.090791 -214.317802) (xy 338.136923 -214.341308)
			(xy 338.17881 -214.37174) (xy 338.21542 -214.40835) (xy 338.245852 -214.450237) (xy 338.269358 -214.496369)
			(xy 338.285357 -214.545609) (xy 338.293456 -214.596747) (xy 338.293964 -214.622634) (xy 338.293541 -214.647971)
			(xy 338.285783 -214.698047) (xy 338.270454 -214.746347) (xy 338.247915 -214.791733) (xy 338.218698 -214.833136)
			(xy 338.18349 -214.869581) (xy 338.14312 -214.90021) (xy 338.098539 -214.924301) (xy 338.050797 -214.941288)
			(xy 338.025994 -214.946484) (xy 338.003134 -214.950802) (xy 337.798156 -215.305894) (xy 337.80603 -215.327738)
			(xy 337.814677 -215.354146) (xy 337.823997 -215.408922) (xy 337.824572 -215.436704) (xy 339.044788 -215.436704)
			(xy 339.045323 -215.411361) (xy 339.053093 -215.361274) (xy 339.068437 -215.312966) (xy 339.090992 -215.267575)
			(xy 339.120227 -215.226169) (xy 339.155454 -215.189725) (xy 339.195843 -215.159101) (xy 339.240442 -215.135018)
			(xy 339.288201 -215.118043) (xy 339.313012 -215.112854) (xy 339.335872 -215.108536) (xy 339.54085 -214.753444)
			(xy 339.532976 -214.7316) (xy 339.524399 -214.705181) (xy 339.5152 -214.650406) (xy 339.514688 -214.622634)
			(xy 339.515196 -214.596747) (xy 339.523295 -214.545609) (xy 339.539294 -214.496369) (xy 339.5628 -214.450237)
			(xy 339.593232 -214.40835) (xy 339.629842 -214.37174) (xy 339.671729 -214.341308) (xy 339.717861 -214.317802)
			(xy 339.767101 -214.301803) (xy 339.818239 -214.293704) (xy 339.870013 -214.293704) (xy 339.921151 -214.301803)
			(xy 339.970391 -214.317802) (xy 340.016523 -214.341308) (xy 340.05841 -214.37174) (xy 340.09502 -214.40835)
			(xy 340.125452 -214.450237) (xy 340.148958 -214.496369) (xy 340.164957 -214.545609) (xy 340.173056 -214.596747)
			(xy 340.173564 -214.622634) (xy 340.173141 -214.647971) (xy 340.165383 -214.698047) (xy 340.150054 -214.746347)
			(xy 340.127515 -214.791733) (xy 340.098298 -214.833136) (xy 340.06309 -214.869581) (xy 340.02272 -214.90021)
			(xy 339.978139 -214.924301) (xy 339.930397 -214.941288) (xy 339.905594 -214.946484) (xy 339.882734 -214.950802)
			(xy 339.677756 -215.305894) (xy 339.68563 -215.327738) (xy 339.694277 -215.354146) (xy 339.703597 -215.408922)
			(xy 339.704172 -215.436704) (xy 340.924388 -215.436704) (xy 340.924923 -215.411361) (xy 340.932693 -215.361274)
			(xy 340.948037 -215.312966) (xy 340.970592 -215.267575) (xy 340.999827 -215.226169) (xy 341.035054 -215.189725)
			(xy 341.075443 -215.159101) (xy 341.120042 -215.135018) (xy 341.167801 -215.118043) (xy 341.192612 -215.112854)
			(xy 341.215472 -215.108536) (xy 341.42045 -214.753444) (xy 341.412576 -214.7316) (xy 341.403999 -214.705181)
			(xy 341.3948 -214.650406) (xy 341.394288 -214.622634) (xy 341.394796 -214.596747) (xy 341.402895 -214.545609)
			(xy 341.418894 -214.496369) (xy 341.4424 -214.450237) (xy 341.472832 -214.40835) (xy 341.509442 -214.37174)
			(xy 341.551329 -214.341308) (xy 341.597461 -214.317802) (xy 341.646701 -214.301803) (xy 341.697839 -214.293704)
			(xy 341.749613 -214.293704) (xy 341.800751 -214.301803) (xy 341.849991 -214.317802) (xy 341.896123 -214.341308)
			(xy 341.93801 -214.37174) (xy 341.97462 -214.40835) (xy 342.005052 -214.450237) (xy 342.028558 -214.496369)
			(xy 342.044557 -214.545609) (xy 342.052656 -214.596747) (xy 342.053164 -214.622634) (xy 342.052741 -214.647971)
			(xy 342.044983 -214.698047) (xy 342.029654 -214.746347) (xy 342.007115 -214.791733) (xy 341.977898 -214.833136)
			(xy 341.94269 -214.869581) (xy 341.90232 -214.90021) (xy 341.857739 -214.924301) (xy 341.809997 -214.941288)
			(xy 341.785194 -214.946484) (xy 341.762334 -214.950802) (xy 341.557356 -215.305894) (xy 341.56523 -215.327738)
			(xy 341.573877 -215.354146) (xy 341.583197 -215.408922) (xy 341.583772 -215.436704) (xy 342.803988 -215.436704)
			(xy 342.804523 -215.411361) (xy 342.812293 -215.361274) (xy 342.827637 -215.312966) (xy 342.850192 -215.267575)
			(xy 342.879427 -215.226169) (xy 342.914654 -215.189725) (xy 342.955043 -215.159101) (xy 342.999642 -215.135018)
			(xy 343.047401 -215.118043) (xy 343.072212 -215.112854) (xy 343.095072 -215.108536) (xy 343.30005 -214.753444)
			(xy 343.292176 -214.7316) (xy 343.283599 -214.705181) (xy 343.2744 -214.650406) (xy 343.273888 -214.622634)
			(xy 343.274396 -214.596747) (xy 343.282495 -214.545609) (xy 343.298494 -214.496369) (xy 343.322 -214.450237)
			(xy 343.352432 -214.40835) (xy 343.389042 -214.37174) (xy 343.430929 -214.341308) (xy 343.477061 -214.317802)
			(xy 343.526301 -214.301803) (xy 343.577439 -214.293704) (xy 343.629213 -214.293704) (xy 343.680351 -214.301803)
			(xy 343.729591 -214.317802) (xy 343.775723 -214.341308) (xy 343.81761 -214.37174) (xy 343.85422 -214.40835)
			(xy 343.884652 -214.450237) (xy 343.908158 -214.496369) (xy 343.924157 -214.545609) (xy 343.932256 -214.596747)
			(xy 343.932764 -214.622634) (xy 343.932341 -214.647971) (xy 343.924583 -214.698047) (xy 343.909254 -214.746347)
			(xy 343.886715 -214.791733) (xy 343.857498 -214.833136) (xy 343.82229 -214.869581) (xy 343.78192 -214.90021)
			(xy 343.737339 -214.924301) (xy 343.689597 -214.941288) (xy 343.664794 -214.946484) (xy 343.641934 -214.950802)
			(xy 343.436956 -215.305894) (xy 343.44483 -215.327738) (xy 343.453477 -215.354146) (xy 343.462797 -215.408922)
			(xy 343.463372 -215.436704) (xy 344.683588 -215.436704) (xy 344.684123 -215.411361) (xy 344.691893 -215.361274)
			(xy 344.707237 -215.312966) (xy 344.729792 -215.267575) (xy 344.759027 -215.226169) (xy 344.794254 -215.189725)
			(xy 344.834643 -215.159101) (xy 344.879242 -215.135018) (xy 344.927001 -215.118043) (xy 344.951812 -215.112854)
			(xy 344.974672 -215.108536) (xy 345.17965 -214.753444) (xy 345.171776 -214.7316) (xy 345.163199 -214.705181)
			(xy 345.154 -214.650406) (xy 345.153488 -214.622634) (xy 345.153996 -214.596747) (xy 345.162095 -214.545609)
			(xy 345.178094 -214.496369) (xy 345.2016 -214.450237) (xy 345.232032 -214.40835) (xy 345.268642 -214.37174)
			(xy 345.310529 -214.341308) (xy 345.356661 -214.317802) (xy 345.405901 -214.301803) (xy 345.457039 -214.293704)
			(xy 345.508813 -214.293704) (xy 345.559951 -214.301803) (xy 345.609191 -214.317802) (xy 345.655323 -214.341308)
			(xy 345.69721 -214.37174) (xy 345.73382 -214.40835) (xy 345.764252 -214.450237) (xy 345.787758 -214.496369)
			(xy 345.803757 -214.545609) (xy 345.811856 -214.596747) (xy 345.812364 -214.622634) (xy 345.811941 -214.647971)
			(xy 345.804183 -214.698047) (xy 345.788854 -214.746347) (xy 345.766315 -214.791733) (xy 345.737098 -214.833136)
			(xy 345.70189 -214.869581) (xy 345.66152 -214.90021) (xy 345.616939 -214.924301) (xy 345.569197 -214.941288)
			(xy 345.544394 -214.946484) (xy 345.521534 -214.950802) (xy 345.316556 -215.305894) (xy 345.32443 -215.327738)
			(xy 345.333077 -215.354146) (xy 345.342397 -215.408922) (xy 345.342972 -215.436704) (xy 346.563188 -215.436704)
			(xy 346.563723 -215.411361) (xy 346.571493 -215.361274) (xy 346.586837 -215.312966) (xy 346.609392 -215.267575)
			(xy 346.638627 -215.226169) (xy 346.673854 -215.189725) (xy 346.714243 -215.159101) (xy 346.758842 -215.135018)
			(xy 346.806601 -215.118043) (xy 346.831412 -215.112854) (xy 346.854272 -215.108536) (xy 347.05925 -214.753444)
			(xy 347.051376 -214.7316) (xy 347.042799 -214.705181) (xy 347.0336 -214.650406) (xy 347.033088 -214.622634)
			(xy 347.033596 -214.596747) (xy 347.041695 -214.545609) (xy 347.057694 -214.496369) (xy 347.0812 -214.450237)
			(xy 347.111632 -214.40835) (xy 347.148242 -214.37174) (xy 347.190129 -214.341308) (xy 347.236261 -214.317802)
			(xy 347.285501 -214.301803) (xy 347.336639 -214.293704) (xy 347.388413 -214.293704) (xy 347.439551 -214.301803)
			(xy 347.488791 -214.317802) (xy 347.534923 -214.341308) (xy 347.57681 -214.37174) (xy 347.61342 -214.40835)
			(xy 347.643852 -214.450237) (xy 347.667358 -214.496369) (xy 347.683357 -214.545609) (xy 347.691456 -214.596747)
			(xy 347.691964 -214.622634) (xy 347.691541 -214.647971) (xy 347.683783 -214.698047) (xy 347.668454 -214.746347)
			(xy 347.645915 -214.791733) (xy 347.616698 -214.833136) (xy 347.58149 -214.869581) (xy 347.54112 -214.90021)
			(xy 347.496539 -214.924301) (xy 347.448797 -214.941288) (xy 347.423994 -214.946484) (xy 347.401134 -214.950802)
			(xy 347.196156 -215.305894) (xy 347.20403 -215.327738) (xy 347.212677 -215.354146) (xy 347.221997 -215.408922)
			(xy 347.222572 -215.436704) (xy 348.442788 -215.436704) (xy 348.443323 -215.411361) (xy 348.451093 -215.361274)
			(xy 348.466437 -215.312966) (xy 348.488992 -215.267575) (xy 348.518227 -215.226169) (xy 348.553454 -215.189725)
			(xy 348.593843 -215.159101) (xy 348.638442 -215.135018) (xy 348.686201 -215.118043) (xy 348.711012 -215.112854)
			(xy 348.733872 -215.108536) (xy 348.93885 -214.753444) (xy 348.930976 -214.7316) (xy 348.922399 -214.705181)
			(xy 348.9132 -214.650406) (xy 348.912688 -214.622634) (xy 348.913196 -214.596747) (xy 348.921295 -214.545609)
			(xy 348.937294 -214.496369) (xy 348.9608 -214.450237) (xy 348.991232 -214.40835) (xy 349.027842 -214.37174)
			(xy 349.069729 -214.341308) (xy 349.115861 -214.317802) (xy 349.165101 -214.301803) (xy 349.216239 -214.293704)
			(xy 349.268013 -214.293704) (xy 349.319151 -214.301803) (xy 349.368391 -214.317802) (xy 349.414523 -214.341308)
			(xy 349.45641 -214.37174) (xy 349.49302 -214.40835) (xy 349.523452 -214.450237) (xy 349.546958 -214.496369)
			(xy 349.562957 -214.545609) (xy 349.571056 -214.596747) (xy 349.571564 -214.622634) (xy 349.571141 -214.647971)
			(xy 349.563383 -214.698047) (xy 349.548054 -214.746347) (xy 349.525515 -214.791733) (xy 349.496298 -214.833136)
			(xy 349.46109 -214.869581) (xy 349.42072 -214.90021) (xy 349.376139 -214.924301) (xy 349.328397 -214.941288)
			(xy 349.303594 -214.946484) (xy 349.280734 -214.950802) (xy 349.075756 -215.305894) (xy 349.08363 -215.327738)
			(xy 349.092277 -215.354146) (xy 349.101597 -215.408922) (xy 349.102172 -215.436704) (xy 350.322388 -215.436704)
			(xy 350.322923 -215.411361) (xy 350.330693 -215.361274) (xy 350.346037 -215.312966) (xy 350.368592 -215.267575)
			(xy 350.397827 -215.226169) (xy 350.433054 -215.189725) (xy 350.473443 -215.159101) (xy 350.518042 -215.135018)
			(xy 350.565801 -215.118043) (xy 350.590612 -215.112854) (xy 350.613472 -215.108536) (xy 350.81845 -214.753444)
			(xy 350.810576 -214.7316) (xy 350.801999 -214.705181) (xy 350.7928 -214.650406) (xy 350.792288 -214.622634)
			(xy 350.792796 -214.596747) (xy 350.800895 -214.545609) (xy 350.816894 -214.496369) (xy 350.8404 -214.450237)
			(xy 350.870832 -214.40835) (xy 350.907442 -214.37174) (xy 350.949329 -214.341308) (xy 350.995461 -214.317802)
			(xy 351.044701 -214.301803) (xy 351.095839 -214.293704) (xy 351.147613 -214.293704) (xy 351.198751 -214.301803)
			(xy 351.247991 -214.317802) (xy 351.294123 -214.341308) (xy 351.33601 -214.37174) (xy 351.37262 -214.40835)
			(xy 351.403052 -214.450237) (xy 351.426558 -214.496369) (xy 351.442557 -214.545609) (xy 351.450656 -214.596747)
			(xy 351.451164 -214.622634) (xy 351.450741 -214.647971) (xy 351.442983 -214.698047) (xy 351.427654 -214.746347)
			(xy 351.405115 -214.791733) (xy 351.375898 -214.833136) (xy 351.34069 -214.869581) (xy 351.30032 -214.90021)
			(xy 351.255739 -214.924301) (xy 351.207997 -214.941288) (xy 351.183194 -214.946484) (xy 351.160334 -214.950802)
			(xy 350.955356 -215.305894) (xy 350.96323 -215.327738) (xy 350.971877 -215.354146) (xy 350.981197 -215.408922)
			(xy 350.981772 -215.436704) (xy 352.201988 -215.436704) (xy 352.202523 -215.411361) (xy 352.210293 -215.361274)
			(xy 352.225637 -215.312966) (xy 352.248192 -215.267575) (xy 352.277427 -215.226169) (xy 352.312654 -215.189725)
			(xy 352.353043 -215.159101) (xy 352.397642 -215.135018) (xy 352.445401 -215.118043) (xy 352.470212 -215.112854)
			(xy 352.493072 -215.108536) (xy 352.69805 -214.753444) (xy 352.690176 -214.7316) (xy 352.681599 -214.705181)
			(xy 352.6724 -214.650406) (xy 352.671888 -214.622634) (xy 352.672396 -214.596747) (xy 352.680495 -214.545609)
			(xy 352.696494 -214.496369) (xy 352.72 -214.450237) (xy 352.750432 -214.40835) (xy 352.787042 -214.37174)
			(xy 352.828929 -214.341308) (xy 352.875061 -214.317802) (xy 352.924301 -214.301803) (xy 352.975439 -214.293704)
			(xy 353.027213 -214.293704) (xy 353.078351 -214.301803) (xy 353.127591 -214.317802) (xy 353.173723 -214.341308)
			(xy 353.21561 -214.37174) (xy 353.25222 -214.40835) (xy 353.282652 -214.450237) (xy 353.306158 -214.496369)
			(xy 353.322157 -214.545609) (xy 353.330256 -214.596747) (xy 353.330764 -214.622634) (xy 353.330341 -214.647971)
			(xy 353.322583 -214.698047) (xy 353.307254 -214.746347) (xy 353.284715 -214.791733) (xy 353.255498 -214.833136)
			(xy 353.22029 -214.869581) (xy 353.17992 -214.90021) (xy 353.135339 -214.924301) (xy 353.087597 -214.941288)
			(xy 353.062794 -214.946484) (xy 353.039934 -214.950802) (xy 352.834956 -215.305894) (xy 352.84283 -215.327738)
			(xy 352.851477 -215.354146) (xy 352.860797 -215.408922) (xy 352.861372 -215.436704) (xy 354.081588 -215.436704)
			(xy 354.082123 -215.411361) (xy 354.089893 -215.361274) (xy 354.105237 -215.312966) (xy 354.127792 -215.267575)
			(xy 354.157027 -215.226169) (xy 354.192254 -215.189725) (xy 354.232643 -215.159101) (xy 354.277242 -215.135018)
			(xy 354.325001 -215.118043) (xy 354.349812 -215.112854) (xy 354.372672 -215.108536) (xy 354.57765 -214.753444)
			(xy 354.569776 -214.7316) (xy 354.561199 -214.705181) (xy 354.552 -214.650406) (xy 354.551488 -214.622634)
			(xy 354.551996 -214.596747) (xy 354.560095 -214.545609) (xy 354.576094 -214.496369) (xy 354.5996 -214.450237)
			(xy 354.630032 -214.40835) (xy 354.666642 -214.37174) (xy 354.708529 -214.341308) (xy 354.754661 -214.317802)
			(xy 354.803901 -214.301803) (xy 354.855039 -214.293704) (xy 354.906813 -214.293704) (xy 354.957951 -214.301803)
			(xy 355.007191 -214.317802) (xy 355.053323 -214.341308) (xy 355.09521 -214.37174) (xy 355.13182 -214.40835)
			(xy 355.162252 -214.450237) (xy 355.185758 -214.496369) (xy 355.201757 -214.545609) (xy 355.209856 -214.596747)
			(xy 355.210364 -214.622634) (xy 355.209941 -214.647971) (xy 355.202183 -214.698047) (xy 355.186854 -214.746347)
			(xy 355.164315 -214.791733) (xy 355.135098 -214.833136) (xy 355.09989 -214.869581) (xy 355.05952 -214.90021)
			(xy 355.014939 -214.924301) (xy 354.967197 -214.941288) (xy 354.942394 -214.946484) (xy 354.919534 -214.950802)
			(xy 354.714556 -215.305894) (xy 354.72243 -215.327738) (xy 354.731077 -215.354146) (xy 354.740397 -215.408922)
			(xy 354.740972 -215.436704) (xy 355.961188 -215.436704) (xy 355.961723 -215.411361) (xy 355.969493 -215.361274)
			(xy 355.984837 -215.312966) (xy 356.007392 -215.267575) (xy 356.036627 -215.226169) (xy 356.071854 -215.189725)
			(xy 356.112243 -215.159101) (xy 356.156842 -215.135018) (xy 356.204601 -215.118043) (xy 356.229412 -215.112854)
			(xy 356.252272 -215.108536) (xy 356.45725 -214.753444) (xy 356.449376 -214.7316) (xy 356.440799 -214.705181)
			(xy 356.4316 -214.650406) (xy 356.431088 -214.622634) (xy 356.431596 -214.596747) (xy 356.439695 -214.545609)
			(xy 356.455694 -214.496369) (xy 356.4792 -214.450237) (xy 356.509632 -214.40835) (xy 356.546242 -214.37174)
			(xy 356.588129 -214.341308) (xy 356.634261 -214.317802) (xy 356.683501 -214.301803) (xy 356.734639 -214.293704)
			(xy 356.786413 -214.293704) (xy 356.837551 -214.301803) (xy 356.886791 -214.317802) (xy 356.932923 -214.341308)
			(xy 356.97481 -214.37174) (xy 357.01142 -214.40835) (xy 357.041852 -214.450237) (xy 357.065358 -214.496369)
			(xy 357.081357 -214.545609) (xy 357.089456 -214.596747) (xy 357.089964 -214.622634) (xy 358.310688 -214.622634)
			(xy 358.311196 -214.596747) (xy 358.319295 -214.545609) (xy 358.335294 -214.496369) (xy 358.3588 -214.450237)
			(xy 358.389232 -214.40835) (xy 358.425842 -214.37174) (xy 358.467729 -214.341308) (xy 358.513861 -214.317802)
			(xy 358.563101 -214.301803) (xy 358.614239 -214.293704) (xy 358.666013 -214.293704) (xy 358.717151 -214.301803)
			(xy 358.766391 -214.317802) (xy 358.812523 -214.341308) (xy 358.85441 -214.37174) (xy 358.89102 -214.40835)
			(xy 358.921452 -214.450237) (xy 358.944958 -214.496369) (xy 358.960957 -214.545609) (xy 358.969056 -214.596747)
			(xy 358.969564 -214.622634) (xy 358.969564 -214.623142) (xy 358.968984 -214.650659) (xy 358.959791 -214.70492)
			(xy 358.951276 -214.731092) (xy 358.943656 -214.75319) (xy 359.148888 -215.108536) (xy 359.171748 -215.112854)
			(xy 359.196559 -215.118062) (xy 359.244336 -215.135013) (xy 359.288953 -215.15908) (xy 359.329358 -215.189696)
			(xy 359.364599 -215.226137) (xy 359.393844 -215.267545) (xy 359.416403 -215.312943) (xy 359.431745 -215.36126)
			(xy 359.439507 -215.411357) (xy 359.439972 -215.436704) (xy 359.439464 -215.462611) (xy 359.431358 -215.513788)
			(xy 359.415346 -215.563067) (xy 359.391823 -215.609234) (xy 359.361367 -215.651153) (xy 359.324729 -215.687791)
			(xy 359.28281 -215.718247) (xy 359.236643 -215.74177) (xy 359.187364 -215.757782) (xy 359.136187 -215.765888)
			(xy 359.084373 -215.765888) (xy 359.033196 -215.757782) (xy 358.983917 -215.74177) (xy 358.93775 -215.718247)
			(xy 358.895831 -215.687791) (xy 358.859193 -215.651153) (xy 358.828737 -215.609234) (xy 358.805214 -215.563067)
			(xy 358.789202 -215.513788) (xy 358.781096 -215.462611) (xy 358.780588 -215.436704) (xy 358.781184 -215.408987)
			(xy 358.790506 -215.35434) (xy 358.79913 -215.327992) (xy 358.80675 -215.306148) (xy 358.601772 -214.950802)
			(xy 358.578912 -214.946484) (xy 358.554096 -214.941291) (xy 358.506315 -214.924344) (xy 358.461694 -214.900279)
			(xy 358.421285 -214.869663) (xy 358.386043 -214.833219) (xy 358.356798 -214.791807) (xy 358.33424 -214.746405)
			(xy 358.318903 -214.698083) (xy 358.311148 -214.647983) (xy 358.310688 -214.622634) (xy 357.089964 -214.622634)
			(xy 357.089541 -214.647971) (xy 357.081783 -214.698047) (xy 357.066454 -214.746347) (xy 357.043915 -214.791733)
			(xy 357.014698 -214.833136) (xy 356.97949 -214.869581) (xy 356.93912 -214.90021) (xy 356.894539 -214.924301)
			(xy 356.846797 -214.941288) (xy 356.821994 -214.946484) (xy 356.799134 -214.950802) (xy 356.594156 -215.305894)
			(xy 356.60203 -215.327738) (xy 356.610677 -215.354146) (xy 356.619997 -215.408922) (xy 356.620572 -215.436704)
			(xy 356.620064 -215.462606) (xy 356.90152 -215.462606) (xy 356.90152 -215.410794) (xy 356.909625 -215.35962)
			(xy 356.925635 -215.310344) (xy 356.949157 -215.264178) (xy 356.97961 -215.222261) (xy 357.016246 -215.185623)
			(xy 357.058161 -215.155167) (xy 357.104325 -215.131643) (xy 357.1536 -215.11563) (xy 357.204774 -215.107522)
			(xy 357.23068 -215.107012) (xy 357.256191 -215.107502) (xy 357.306606 -215.11536) (xy 357.355207 -215.130891)
			(xy 357.400836 -215.153725) (xy 357.442402 -215.183316) (xy 357.478912 -215.218958) (xy 357.494586 -215.239092)
			(xy 357.906574 -215.239092) (xy 357.92226 -215.218967) (xy 357.958768 -215.183323) (xy 358.000331 -215.153729)
			(xy 358.045956 -215.130891) (xy 358.094556 -215.115355) (xy 358.144969 -215.107491) (xy 358.17048 -215.107012)
			(xy 358.196391 -215.107484) (xy 358.247575 -215.115588) (xy 358.296861 -215.131599) (xy 358.343035 -215.155124)
			(xy 358.38496 -215.185582) (xy 358.421605 -215.222224) (xy 358.452066 -215.264148) (xy 358.475593 -215.310321)
			(xy 358.491607 -215.359606) (xy 358.499714 -215.410789) (xy 358.499714 -215.462611) (xy 358.491607 -215.513794)
			(xy 358.475593 -215.563079) (xy 358.452066 -215.609252) (xy 358.421605 -215.651176) (xy 358.38496 -215.687818)
			(xy 358.343035 -215.718276) (xy 358.296861 -215.741801) (xy 358.247575 -215.757812) (xy 358.196391 -215.765916)
			(xy 358.17048 -215.766396) (xy 358.144968 -215.765932) (xy 358.094552 -215.758068) (xy 358.04595 -215.742532)
			(xy 358.000322 -215.719693) (xy 357.958757 -215.690098) (xy 357.922247 -215.654452) (xy 357.906574 -215.634316)
			(xy 357.494586 -215.634316) (xy 357.478925 -215.654461) (xy 357.442412 -215.690104) (xy 357.400844 -215.719696)
			(xy 357.355213 -215.74253) (xy 357.306609 -215.758062) (xy 357.256193 -215.76592) (xy 357.23068 -215.766396)
			(xy 357.204774 -215.765878) (xy 357.1536 -215.75777) (xy 357.104325 -215.741757) (xy 357.058161 -215.718233)
			(xy 357.016246 -215.687777) (xy 356.97961 -215.651139) (xy 356.949157 -215.609222) (xy 356.925635 -215.563056)
			(xy 356.909625 -215.51378) (xy 356.90152 -215.462606) (xy 356.620064 -215.462606) (xy 356.620064 -215.462611)
			(xy 356.611958 -215.513788) (xy 356.595946 -215.563067) (xy 356.572423 -215.609234) (xy 356.541967 -215.651153)
			(xy 356.505329 -215.687791) (xy 356.46341 -215.718247) (xy 356.417243 -215.74177) (xy 356.367964 -215.757782)
			(xy 356.316787 -215.765888) (xy 356.264973 -215.765888) (xy 356.213796 -215.757782) (xy 356.164517 -215.74177)
			(xy 356.11835 -215.718247) (xy 356.076431 -215.687791) (xy 356.039793 -215.651153) (xy 356.009337 -215.609234)
			(xy 355.985814 -215.563067) (xy 355.969802 -215.513788) (xy 355.961696 -215.462611) (xy 355.961188 -215.436704)
			(xy 354.740972 -215.436704) (xy 354.740464 -215.462611) (xy 354.732358 -215.513788) (xy 354.716346 -215.563067)
			(xy 354.692823 -215.609234) (xy 354.662367 -215.651153) (xy 354.625729 -215.687791) (xy 354.58381 -215.718247)
			(xy 354.537643 -215.74177) (xy 354.488364 -215.757782) (xy 354.437187 -215.765888) (xy 354.385373 -215.765888)
			(xy 354.334196 -215.757782) (xy 354.284917 -215.74177) (xy 354.23875 -215.718247) (xy 354.196831 -215.687791)
			(xy 354.160193 -215.651153) (xy 354.129737 -215.609234) (xy 354.106214 -215.563067) (xy 354.090202 -215.513788)
			(xy 354.082096 -215.462611) (xy 354.081588 -215.436704) (xy 352.861372 -215.436704) (xy 352.860864 -215.462611)
			(xy 352.852758 -215.513788) (xy 352.836746 -215.563067) (xy 352.813223 -215.609234) (xy 352.782767 -215.651153)
			(xy 352.746129 -215.687791) (xy 352.70421 -215.718247) (xy 352.658043 -215.74177) (xy 352.608764 -215.757782)
			(xy 352.557587 -215.765888) (xy 352.505773 -215.765888) (xy 352.454596 -215.757782) (xy 352.405317 -215.74177)
			(xy 352.35915 -215.718247) (xy 352.317231 -215.687791) (xy 352.280593 -215.651153) (xy 352.250137 -215.609234)
			(xy 352.226614 -215.563067) (xy 352.210602 -215.513788) (xy 352.202496 -215.462611) (xy 352.201988 -215.436704)
			(xy 350.981772 -215.436704) (xy 350.981264 -215.462611) (xy 350.973158 -215.513788) (xy 350.957146 -215.563067)
			(xy 350.933623 -215.609234) (xy 350.903167 -215.651153) (xy 350.866529 -215.687791) (xy 350.82461 -215.718247)
			(xy 350.778443 -215.74177) (xy 350.729164 -215.757782) (xy 350.677987 -215.765888) (xy 350.626173 -215.765888)
			(xy 350.574996 -215.757782) (xy 350.525717 -215.74177) (xy 350.47955 -215.718247) (xy 350.437631 -215.687791)
			(xy 350.400993 -215.651153) (xy 350.370537 -215.609234) (xy 350.347014 -215.563067) (xy 350.331002 -215.513788)
			(xy 350.322896 -215.462611) (xy 350.322388 -215.436704) (xy 349.102172 -215.436704) (xy 349.101664 -215.462611)
			(xy 349.093558 -215.513788) (xy 349.077546 -215.563067) (xy 349.054023 -215.609234) (xy 349.023567 -215.651153)
			(xy 348.986929 -215.687791) (xy 348.94501 -215.718247) (xy 348.898843 -215.74177) (xy 348.849564 -215.757782)
			(xy 348.798387 -215.765888) (xy 348.746573 -215.765888) (xy 348.695396 -215.757782) (xy 348.646117 -215.74177)
			(xy 348.59995 -215.718247) (xy 348.558031 -215.687791) (xy 348.521393 -215.651153) (xy 348.490937 -215.609234)
			(xy 348.467414 -215.563067) (xy 348.451402 -215.513788) (xy 348.443296 -215.462611) (xy 348.442788 -215.436704)
			(xy 347.222572 -215.436704) (xy 347.222064 -215.462611) (xy 347.213958 -215.513788) (xy 347.197946 -215.563067)
			(xy 347.174423 -215.609234) (xy 347.143967 -215.651153) (xy 347.107329 -215.687791) (xy 347.06541 -215.718247)
			(xy 347.019243 -215.74177) (xy 346.969964 -215.757782) (xy 346.918787 -215.765888) (xy 346.866973 -215.765888)
			(xy 346.815796 -215.757782) (xy 346.766517 -215.74177) (xy 346.72035 -215.718247) (xy 346.678431 -215.687791)
			(xy 346.641793 -215.651153) (xy 346.611337 -215.609234) (xy 346.587814 -215.563067) (xy 346.571802 -215.513788)
			(xy 346.563696 -215.462611) (xy 346.563188 -215.436704) (xy 345.342972 -215.436704) (xy 345.342464 -215.462611)
			(xy 345.334358 -215.513788) (xy 345.318346 -215.563067) (xy 345.294823 -215.609234) (xy 345.264367 -215.651153)
			(xy 345.227729 -215.687791) (xy 345.18581 -215.718247) (xy 345.139643 -215.74177) (xy 345.090364 -215.757782)
			(xy 345.039187 -215.765888) (xy 344.987373 -215.765888) (xy 344.936196 -215.757782) (xy 344.886917 -215.74177)
			(xy 344.84075 -215.718247) (xy 344.798831 -215.687791) (xy 344.762193 -215.651153) (xy 344.731737 -215.609234)
			(xy 344.708214 -215.563067) (xy 344.692202 -215.513788) (xy 344.684096 -215.462611) (xy 344.683588 -215.436704)
			(xy 343.463372 -215.436704) (xy 343.462864 -215.462611) (xy 343.454758 -215.513788) (xy 343.438746 -215.563067)
			(xy 343.415223 -215.609234) (xy 343.384767 -215.651153) (xy 343.348129 -215.687791) (xy 343.30621 -215.718247)
			(xy 343.260043 -215.74177) (xy 343.210764 -215.757782) (xy 343.159587 -215.765888) (xy 343.107773 -215.765888)
			(xy 343.056596 -215.757782) (xy 343.007317 -215.74177) (xy 342.96115 -215.718247) (xy 342.919231 -215.687791)
			(xy 342.882593 -215.651153) (xy 342.852137 -215.609234) (xy 342.828614 -215.563067) (xy 342.812602 -215.513788)
			(xy 342.804496 -215.462611) (xy 342.803988 -215.436704) (xy 341.583772 -215.436704) (xy 341.583264 -215.462611)
			(xy 341.575158 -215.513788) (xy 341.559146 -215.563067) (xy 341.535623 -215.609234) (xy 341.505167 -215.651153)
			(xy 341.468529 -215.687791) (xy 341.42661 -215.718247) (xy 341.380443 -215.74177) (xy 341.331164 -215.757782)
			(xy 341.279987 -215.765888) (xy 341.228173 -215.765888) (xy 341.176996 -215.757782) (xy 341.127717 -215.74177)
			(xy 341.08155 -215.718247) (xy 341.039631 -215.687791) (xy 341.002993 -215.651153) (xy 340.972537 -215.609234)
			(xy 340.949014 -215.563067) (xy 340.933002 -215.513788) (xy 340.924896 -215.462611) (xy 340.924388 -215.436704)
			(xy 339.704172 -215.436704) (xy 339.703664 -215.462611) (xy 339.695558 -215.513788) (xy 339.679546 -215.563067)
			(xy 339.656023 -215.609234) (xy 339.625567 -215.651153) (xy 339.588929 -215.687791) (xy 339.54701 -215.718247)
			(xy 339.500843 -215.74177) (xy 339.451564 -215.757782) (xy 339.400387 -215.765888) (xy 339.348573 -215.765888)
			(xy 339.297396 -215.757782) (xy 339.248117 -215.74177) (xy 339.20195 -215.718247) (xy 339.160031 -215.687791)
			(xy 339.123393 -215.651153) (xy 339.092937 -215.609234) (xy 339.069414 -215.563067) (xy 339.053402 -215.513788)
			(xy 339.045296 -215.462611) (xy 339.044788 -215.436704) (xy 337.824572 -215.436704) (xy 337.824064 -215.462611)
			(xy 337.815958 -215.513788) (xy 337.799946 -215.563067) (xy 337.776423 -215.609234) (xy 337.745967 -215.651153)
			(xy 337.709329 -215.687791) (xy 337.66741 -215.718247) (xy 337.621243 -215.74177) (xy 337.571964 -215.757782)
			(xy 337.520787 -215.765888) (xy 337.468973 -215.765888) (xy 337.417796 -215.757782) (xy 337.368517 -215.74177)
			(xy 337.32235 -215.718247) (xy 337.280431 -215.687791) (xy 337.243793 -215.651153) (xy 337.213337 -215.609234)
			(xy 337.189814 -215.563067) (xy 337.173802 -215.513788) (xy 337.165696 -215.462611) (xy 337.165188 -215.436704)
			(xy 336.884772 -215.436704) (xy 336.884181 -215.464421) (xy 336.874856 -215.519068) (xy 336.86623 -215.545416)
			(xy 336.858356 -215.567514) (xy 337.063334 -215.922352) (xy 337.086194 -215.92667) (xy 337.110997 -215.931858)
			(xy 337.158737 -215.948846) (xy 337.203315 -215.972939) (xy 337.243681 -216.00357) (xy 337.278884 -216.040017)
			(xy 337.308096 -216.081421) (xy 337.330629 -216.126808) (xy 337.345951 -216.175108) (xy 337.353702 -216.225184)
			(xy 337.354164 -216.25052) (xy 337.353656 -216.276407) (xy 337.345557 -216.327545) (xy 337.329558 -216.376785)
			(xy 337.306052 -216.422917) (xy 337.27562 -216.464804) (xy 337.23901 -216.501414) (xy 337.197123 -216.531846)
			(xy 337.150991 -216.555352) (xy 337.101751 -216.571351) (xy 337.050613 -216.57945) (xy 336.998839 -216.57945)
			(xy 336.947701 -216.571351) (xy 336.898461 -216.555352) (xy 336.852329 -216.531846) (xy 336.810442 -216.501414)
			(xy 336.773832 -216.464804) (xy 336.7434 -216.422917) (xy 336.719894 -216.376785) (xy 336.703895 -216.327545)
			(xy 336.695796 -216.276407) (xy 336.695288 -216.25052) (xy 336.695823 -216.222812) (xy 336.705015 -216.168165)
			(xy 336.713576 -216.141808) (xy 336.72145 -216.11971) (xy 336.516472 -215.764872) (xy 336.493612 -215.760554)
			(xy 336.46879 -215.755389) (xy 336.421007 -215.73844) (xy 336.376384 -215.714372) (xy 336.335974 -215.683753)
			(xy 336.300731 -215.647305) (xy 336.271487 -215.60589) (xy 336.248932 -215.560483) (xy 336.233597 -215.512158)
			(xy 336.225846 -215.462054) (xy 336.225388 -215.436704) (xy 135.934704 -215.436704) (xy 135.934196 -215.462611)
			(xy 135.92609 -215.513788) (xy 135.910078 -215.563067) (xy 135.886555 -215.609234) (xy 135.856099 -215.651153)
			(xy 135.819461 -215.687791) (xy 135.777542 -215.718247) (xy 135.731375 -215.74177) (xy 135.682096 -215.757782)
			(xy 135.630919 -215.765888) (xy 135.579105 -215.765888) (xy 135.527928 -215.757782) (xy 135.478649 -215.74177)
			(xy 135.432482 -215.718247) (xy 135.390563 -215.687791) (xy 135.353925 -215.651153) (xy 135.323469 -215.609234)
			(xy 135.299946 -215.563067) (xy 135.283934 -215.513788) (xy 135.275828 -215.462611) (xy 135.27532 -215.436704)
			(xy 135.27603 -215.405863) (xy 135.287538 -215.345263) (xy 135.29818 -215.316308) (xy 135.306816 -215.294464)
			(xy 135.084058 -214.872824) (xy 135.061452 -214.867744) (xy 135.037516 -214.861817) (xy 134.991624 -214.843773)
			(xy 134.948934 -214.819093) (xy 134.910397 -214.788329) (xy 134.876873 -214.752166) (xy 134.849112 -214.711412)
			(xy 134.827733 -214.666976) (xy 134.813212 -214.619852) (xy 134.805875 -214.57109) (xy 134.80542 -214.546434)
			(xy 133.57622 -214.546434) (xy 133.584188 -214.596747) (xy 133.584696 -214.622634) (xy 133.584247 -214.64797)
			(xy 133.57649 -214.698044) (xy 133.561163 -214.746341) (xy 133.538627 -214.791726) (xy 133.509412 -214.833128)
			(xy 133.474208 -214.869572) (xy 133.433842 -214.900202) (xy 133.389265 -214.924296) (xy 133.341527 -214.941286)
			(xy 133.316726 -214.946484) (xy 133.293866 -214.950802) (xy 133.088888 -215.305894) (xy 133.096762 -215.327738)
			(xy 133.10541 -215.354146) (xy 133.114729 -215.408922) (xy 133.115304 -215.436704) (xy 133.114796 -215.46261)
			(xy 133.396194 -215.46261) (xy 133.396194 -215.41079) (xy 133.4043 -215.359609) (xy 133.420313 -215.310326)
			(xy 133.44384 -215.264155) (xy 133.474299 -215.222232) (xy 133.510941 -215.185591) (xy 133.552865 -215.155133)
			(xy 133.599037 -215.131609) (xy 133.648321 -215.115597) (xy 133.699502 -215.107493) (xy 133.725412 -215.107012)
			(xy 133.750924 -215.107479) (xy 133.80134 -215.115342) (xy 133.849942 -215.130878) (xy 133.89557 -215.153716)
			(xy 133.937135 -215.183311) (xy 133.973645 -215.218956) (xy 133.989318 -215.239092) (xy 134.401306 -215.239092)
			(xy 134.416974 -215.218952) (xy 134.453485 -215.183309) (xy 134.495052 -215.153716) (xy 134.540681 -215.130881)
			(xy 134.589284 -215.115348) (xy 134.6397 -215.107489) (xy 134.665212 -215.107012) (xy 134.691119 -215.107513)
			(xy 134.742295 -215.11562) (xy 134.791573 -215.131633) (xy 134.837739 -215.155158) (xy 134.879656 -215.185614)
			(xy 134.916294 -215.222253) (xy 134.946749 -215.264172) (xy 134.970271 -215.310339) (xy 134.986282 -215.359617)
			(xy 134.994388 -215.410793) (xy 134.994388 -215.462607) (xy 134.986282 -215.513783) (xy 134.970271 -215.563061)
			(xy 134.946749 -215.609228) (xy 134.916294 -215.651147) (xy 134.879656 -215.687786) (xy 134.837739 -215.718242)
			(xy 134.791573 -215.741767) (xy 134.742295 -215.75778) (xy 134.691119 -215.765887) (xy 134.665212 -215.766396)
			(xy 134.6397 -215.765908) (xy 134.589286 -215.758049) (xy 134.540685 -215.742517) (xy 134.495056 -215.719683)
			(xy 134.453491 -215.690092) (xy 134.41698 -215.65445) (xy 134.401306 -215.634316) (xy 133.989318 -215.634316)
			(xy 133.973638 -215.654446) (xy 133.937129 -215.69009) (xy 133.895565 -215.719683) (xy 133.849938 -215.74252)
			(xy 133.801337 -215.758055) (xy 133.750924 -215.765918) (xy 133.725412 -215.766396) (xy 133.699502 -215.765907)
			(xy 133.648321 -215.757803) (xy 133.599037 -215.741791) (xy 133.552865 -215.718267) (xy 133.510941 -215.687809)
			(xy 133.474299 -215.651168) (xy 133.44384 -215.609245) (xy 133.420313 -215.563074) (xy 133.4043 -215.513791)
			(xy 133.396194 -215.46261) (xy 133.114796 -215.46261) (xy 133.114796 -215.462611) (xy 133.10669 -215.513788)
			(xy 133.090678 -215.563067) (xy 133.067155 -215.609234) (xy 133.036699 -215.651153) (xy 133.000061 -215.687791)
			(xy 132.958142 -215.718247) (xy 132.911975 -215.74177) (xy 132.862696 -215.757782) (xy 132.811519 -215.765888)
			(xy 132.759705 -215.765888) (xy 132.708528 -215.757782) (xy 132.659249 -215.74177) (xy 132.613082 -215.718247)
			(xy 132.571163 -215.687791) (xy 132.534525 -215.651153) (xy 132.504069 -215.609234) (xy 132.480546 -215.563067)
			(xy 132.464534 -215.513788) (xy 132.456428 -215.462611) (xy 132.45592 -215.436704) (xy 131.235704 -215.436704)
			(xy 131.235196 -215.462611) (xy 131.22709 -215.513788) (xy 131.211078 -215.563067) (xy 131.187555 -215.609234)
			(xy 131.157099 -215.651153) (xy 131.120461 -215.687791) (xy 131.078542 -215.718247) (xy 131.032375 -215.74177)
			(xy 130.983096 -215.757782) (xy 130.931919 -215.765888) (xy 130.880105 -215.765888) (xy 130.828928 -215.757782)
			(xy 130.779649 -215.74177) (xy 130.733482 -215.718247) (xy 130.691563 -215.687791) (xy 130.654925 -215.651153)
			(xy 130.624469 -215.609234) (xy 130.600946 -215.563067) (xy 130.584934 -215.513788) (xy 130.576828 -215.462611)
			(xy 130.57632 -215.436704) (xy 129.356104 -215.436704) (xy 129.355596 -215.462611) (xy 129.34749 -215.513788)
			(xy 129.331478 -215.563067) (xy 129.307955 -215.609234) (xy 129.277499 -215.651153) (xy 129.240861 -215.687791)
			(xy 129.198942 -215.718247) (xy 129.152775 -215.74177) (xy 129.103496 -215.757782) (xy 129.052319 -215.765888)
			(xy 129.000505 -215.765888) (xy 128.949328 -215.757782) (xy 128.900049 -215.74177) (xy 128.853882 -215.718247)
			(xy 128.811963 -215.687791) (xy 128.775325 -215.651153) (xy 128.744869 -215.609234) (xy 128.721346 -215.563067)
			(xy 128.705334 -215.513788) (xy 128.697228 -215.462611) (xy 128.69672 -215.436704) (xy 127.476504 -215.436704)
			(xy 127.475996 -215.462611) (xy 127.46789 -215.513788) (xy 127.451878 -215.563067) (xy 127.428355 -215.609234)
			(xy 127.397899 -215.651153) (xy 127.361261 -215.687791) (xy 127.319342 -215.718247) (xy 127.273175 -215.74177)
			(xy 127.223896 -215.757782) (xy 127.172719 -215.765888) (xy 127.120905 -215.765888) (xy 127.069728 -215.757782)
			(xy 127.020449 -215.74177) (xy 126.974282 -215.718247) (xy 126.932363 -215.687791) (xy 126.895725 -215.651153)
			(xy 126.865269 -215.609234) (xy 126.841746 -215.563067) (xy 126.825734 -215.513788) (xy 126.817628 -215.462611)
			(xy 126.81712 -215.436704) (xy 125.596904 -215.436704) (xy 125.596396 -215.462611) (xy 125.58829 -215.513788)
			(xy 125.572278 -215.563067) (xy 125.548755 -215.609234) (xy 125.518299 -215.651153) (xy 125.481661 -215.687791)
			(xy 125.439742 -215.718247) (xy 125.393575 -215.74177) (xy 125.344296 -215.757782) (xy 125.293119 -215.765888)
			(xy 125.241305 -215.765888) (xy 125.190128 -215.757782) (xy 125.140849 -215.74177) (xy 125.094682 -215.718247)
			(xy 125.052763 -215.687791) (xy 125.016125 -215.651153) (xy 124.985669 -215.609234) (xy 124.962146 -215.563067)
			(xy 124.946134 -215.513788) (xy 124.938028 -215.462611) (xy 124.93752 -215.436704) (xy 123.717304 -215.436704)
			(xy 123.716796 -215.462611) (xy 123.70869 -215.513788) (xy 123.692678 -215.563067) (xy 123.669155 -215.609234)
			(xy 123.638699 -215.651153) (xy 123.602061 -215.687791) (xy 123.560142 -215.718247) (xy 123.513975 -215.74177)
			(xy 123.464696 -215.757782) (xy 123.413519 -215.765888) (xy 123.361705 -215.765888) (xy 123.310528 -215.757782)
			(xy 123.261249 -215.74177) (xy 123.215082 -215.718247) (xy 123.173163 -215.687791) (xy 123.136525 -215.651153)
			(xy 123.106069 -215.609234) (xy 123.082546 -215.563067) (xy 123.066534 -215.513788) (xy 123.058428 -215.462611)
			(xy 123.05792 -215.436704) (xy 121.837704 -215.436704) (xy 121.837196 -215.462611) (xy 121.82909 -215.513788)
			(xy 121.813078 -215.563067) (xy 121.789555 -215.609234) (xy 121.759099 -215.651153) (xy 121.722461 -215.687791)
			(xy 121.680542 -215.718247) (xy 121.634375 -215.74177) (xy 121.585096 -215.757782) (xy 121.533919 -215.765888)
			(xy 121.482105 -215.765888) (xy 121.430928 -215.757782) (xy 121.381649 -215.74177) (xy 121.335482 -215.718247)
			(xy 121.293563 -215.687791) (xy 121.256925 -215.651153) (xy 121.226469 -215.609234) (xy 121.202946 -215.563067)
			(xy 121.186934 -215.513788) (xy 121.178828 -215.462611) (xy 121.17832 -215.436704) (xy 119.958104 -215.436704)
			(xy 119.957596 -215.462611) (xy 119.94949 -215.513788) (xy 119.933478 -215.563067) (xy 119.909955 -215.609234)
			(xy 119.879499 -215.651153) (xy 119.842861 -215.687791) (xy 119.800942 -215.718247) (xy 119.754775 -215.74177)
			(xy 119.705496 -215.757782) (xy 119.654319 -215.765888) (xy 119.602505 -215.765888) (xy 119.551328 -215.757782)
			(xy 119.502049 -215.74177) (xy 119.455882 -215.718247) (xy 119.413963 -215.687791) (xy 119.377325 -215.651153)
			(xy 119.346869 -215.609234) (xy 119.323346 -215.563067) (xy 119.307334 -215.513788) (xy 119.299228 -215.462611)
			(xy 119.29872 -215.436704) (xy 118.078504 -215.436704) (xy 118.077996 -215.462611) (xy 118.06989 -215.513788)
			(xy 118.053878 -215.563067) (xy 118.030355 -215.609234) (xy 117.999899 -215.651153) (xy 117.963261 -215.687791)
			(xy 117.921342 -215.718247) (xy 117.875175 -215.74177) (xy 117.825896 -215.757782) (xy 117.774719 -215.765888)
			(xy 117.722905 -215.765888) (xy 117.671728 -215.757782) (xy 117.622449 -215.74177) (xy 117.576282 -215.718247)
			(xy 117.534363 -215.687791) (xy 117.497725 -215.651153) (xy 117.467269 -215.609234) (xy 117.443746 -215.563067)
			(xy 117.427734 -215.513788) (xy 117.419628 -215.462611) (xy 117.41912 -215.436704) (xy 116.198904 -215.436704)
			(xy 116.198396 -215.462611) (xy 116.19029 -215.513788) (xy 116.174278 -215.563067) (xy 116.150755 -215.609234)
			(xy 116.120299 -215.651153) (xy 116.083661 -215.687791) (xy 116.041742 -215.718247) (xy 115.995575 -215.74177)
			(xy 115.946296 -215.757782) (xy 115.895119 -215.765888) (xy 115.843305 -215.765888) (xy 115.792128 -215.757782)
			(xy 115.742849 -215.74177) (xy 115.696682 -215.718247) (xy 115.654763 -215.687791) (xy 115.618125 -215.651153)
			(xy 115.587669 -215.609234) (xy 115.564146 -215.563067) (xy 115.548134 -215.513788) (xy 115.540028 -215.462611)
			(xy 115.53952 -215.436704) (xy 114.319304 -215.436704) (xy 114.318796 -215.462611) (xy 114.31069 -215.513788)
			(xy 114.294678 -215.563067) (xy 114.271155 -215.609234) (xy 114.240699 -215.651153) (xy 114.204061 -215.687791)
			(xy 114.162142 -215.718247) (xy 114.115975 -215.74177) (xy 114.066696 -215.757782) (xy 114.015519 -215.765888)
			(xy 113.963705 -215.765888) (xy 113.912528 -215.757782) (xy 113.863249 -215.74177) (xy 113.817082 -215.718247)
			(xy 113.775163 -215.687791) (xy 113.738525 -215.651153) (xy 113.708069 -215.609234) (xy 113.684546 -215.563067)
			(xy 113.668534 -215.513788) (xy 113.660428 -215.462611) (xy 113.65992 -215.436704) (xy 111.499904 -215.436704)
			(xy 111.499396 -215.462611) (xy 111.49129 -215.513788) (xy 111.475278 -215.563067) (xy 111.451755 -215.609234)
			(xy 111.421299 -215.651153) (xy 111.384661 -215.687791) (xy 111.342742 -215.718247) (xy 111.296575 -215.74177)
			(xy 111.247296 -215.757782) (xy 111.196119 -215.765888) (xy 111.144305 -215.765888) (xy 111.093128 -215.757782)
			(xy 111.043849 -215.74177) (xy 110.997682 -215.718247) (xy 110.955763 -215.687791) (xy 110.919125 -215.651153)
			(xy 110.888669 -215.609234) (xy 110.865146 -215.563067) (xy 110.849134 -215.513788) (xy 110.841028 -215.462611)
			(xy 110.84052 -215.436704) (xy 110.840955 -215.413764) (xy 110.847378 -215.368334) (xy 110.860018 -215.324227)
			(xy 110.868968 -215.3031) (xy 110.878874 -215.280494) (xy 110.665006 -214.87511) (xy 110.640876 -214.870538)
			(xy 110.615954 -214.86544) (xy 110.567941 -214.848641) (xy 110.523081 -214.824663) (xy 110.482438 -214.794075)
			(xy 110.44698 -214.757604) (xy 110.417549 -214.716116) (xy 110.394843 -214.670598) (xy 110.379403 -214.622131)
			(xy 110.371595 -214.571867) (xy 110.371128 -214.546434) (xy 109.14142 -214.546434) (xy 109.149388 -214.596747)
			(xy 109.149896 -214.622634) (xy 109.149447 -214.64797) (xy 109.14169 -214.698044) (xy 109.126363 -214.746341)
			(xy 109.103827 -214.791726) (xy 109.074612 -214.833128) (xy 109.039408 -214.869572) (xy 108.999042 -214.900202)
			(xy 108.954465 -214.924296) (xy 108.906727 -214.941286) (xy 108.881926 -214.946484) (xy 108.859066 -214.950802)
			(xy 108.654088 -215.305894) (xy 108.661962 -215.327738) (xy 108.67061 -215.354146) (xy 108.679929 -215.408922)
			(xy 108.680504 -215.436704) (xy 108.679996 -215.46261) (xy 108.961394 -215.46261) (xy 108.961394 -215.41079)
			(xy 108.9695 -215.359609) (xy 108.985513 -215.310326) (xy 109.00904 -215.264155) (xy 109.039499 -215.222232)
			(xy 109.076141 -215.185591) (xy 109.118065 -215.155133) (xy 109.164237 -215.131609) (xy 109.213521 -215.115597)
			(xy 109.264702 -215.107493) (xy 109.290612 -215.107012) (xy 109.316124 -215.107479) (xy 109.36654 -215.115342)
			(xy 109.415142 -215.130878) (xy 109.46077 -215.153716) (xy 109.502335 -215.183311) (xy 109.538845 -215.218956)
			(xy 109.554518 -215.239092) (xy 109.966506 -215.239092) (xy 109.982174 -215.218952) (xy 110.018685 -215.183309)
			(xy 110.060252 -215.153716) (xy 110.105881 -215.130881) (xy 110.154484 -215.115348) (xy 110.2049 -215.107489)
			(xy 110.230412 -215.107012) (xy 110.256319 -215.107513) (xy 110.307495 -215.11562) (xy 110.356773 -215.131633)
			(xy 110.402939 -215.155158) (xy 110.444856 -215.185614) (xy 110.481494 -215.222253) (xy 110.511949 -215.264172)
			(xy 110.535471 -215.310339) (xy 110.551482 -215.359617) (xy 110.559588 -215.410793) (xy 110.559588 -215.462607)
			(xy 110.551482 -215.513783) (xy 110.535471 -215.563061) (xy 110.511949 -215.609228) (xy 110.481494 -215.651147)
			(xy 110.444856 -215.687786) (xy 110.402939 -215.718242) (xy 110.356773 -215.741767) (xy 110.307495 -215.75778)
			(xy 110.256319 -215.765887) (xy 110.230412 -215.766396) (xy 110.2049 -215.765908) (xy 110.154486 -215.758049)
			(xy 110.105885 -215.742517) (xy 110.060256 -215.719683) (xy 110.018691 -215.690092) (xy 109.98218 -215.65445)
			(xy 109.966506 -215.634316) (xy 109.554518 -215.634316) (xy 109.538838 -215.654446) (xy 109.502329 -215.69009)
			(xy 109.460765 -215.719683) (xy 109.415138 -215.74252) (xy 109.366537 -215.758055) (xy 109.316124 -215.765918)
			(xy 109.290612 -215.766396) (xy 109.264702 -215.765907) (xy 109.213521 -215.757803) (xy 109.164237 -215.741791)
			(xy 109.118065 -215.718267) (xy 109.076141 -215.687809) (xy 109.039499 -215.651168) (xy 109.00904 -215.609245)
			(xy 108.985513 -215.563074) (xy 108.9695 -215.513791) (xy 108.961394 -215.46261) (xy 108.679996 -215.46261)
			(xy 108.679996 -215.462611) (xy 108.67189 -215.513788) (xy 108.655878 -215.563067) (xy 108.632355 -215.609234)
			(xy 108.601899 -215.651153) (xy 108.565261 -215.687791) (xy 108.523342 -215.718247) (xy 108.477175 -215.74177)
			(xy 108.427896 -215.757782) (xy 108.376719 -215.765888) (xy 108.324905 -215.765888) (xy 108.273728 -215.757782)
			(xy 108.224449 -215.74177) (xy 108.178282 -215.718247) (xy 108.136363 -215.687791) (xy 108.099725 -215.651153)
			(xy 108.069269 -215.609234) (xy 108.045746 -215.563067) (xy 108.029734 -215.513788) (xy 108.021628 -215.462611)
			(xy 108.02112 -215.436704) (xy 106.800904 -215.436704) (xy 106.800396 -215.462611) (xy 106.79229 -215.513788)
			(xy 106.776278 -215.563067) (xy 106.752755 -215.609234) (xy 106.722299 -215.651153) (xy 106.685661 -215.687791)
			(xy 106.643742 -215.718247) (xy 106.597575 -215.74177) (xy 106.548296 -215.757782) (xy 106.497119 -215.765888)
			(xy 106.445305 -215.765888) (xy 106.394128 -215.757782) (xy 106.344849 -215.74177) (xy 106.298682 -215.718247)
			(xy 106.256763 -215.687791) (xy 106.220125 -215.651153) (xy 106.189669 -215.609234) (xy 106.166146 -215.563067)
			(xy 106.150134 -215.513788) (xy 106.142028 -215.462611) (xy 106.14152 -215.436704) (xy 104.921304 -215.436704)
			(xy 104.920796 -215.462611) (xy 104.91269 -215.513788) (xy 104.896678 -215.563067) (xy 104.873155 -215.609234)
			(xy 104.842699 -215.651153) (xy 104.806061 -215.687791) (xy 104.764142 -215.718247) (xy 104.717975 -215.74177)
			(xy 104.668696 -215.757782) (xy 104.617519 -215.765888) (xy 104.565705 -215.765888) (xy 104.514528 -215.757782)
			(xy 104.465249 -215.74177) (xy 104.419082 -215.718247) (xy 104.377163 -215.687791) (xy 104.340525 -215.651153)
			(xy 104.310069 -215.609234) (xy 104.286546 -215.563067) (xy 104.270534 -215.513788) (xy 104.262428 -215.462611)
			(xy 104.26192 -215.436704) (xy 103.041704 -215.436704) (xy 103.041196 -215.462611) (xy 103.03309 -215.513788)
			(xy 103.017078 -215.563067) (xy 102.993555 -215.609234) (xy 102.963099 -215.651153) (xy 102.926461 -215.687791)
			(xy 102.884542 -215.718247) (xy 102.838375 -215.74177) (xy 102.789096 -215.757782) (xy 102.737919 -215.765888)
			(xy 102.686105 -215.765888) (xy 102.634928 -215.757782) (xy 102.585649 -215.74177) (xy 102.539482 -215.718247)
			(xy 102.497563 -215.687791) (xy 102.460925 -215.651153) (xy 102.430469 -215.609234) (xy 102.406946 -215.563067)
			(xy 102.390934 -215.513788) (xy 102.382828 -215.462611) (xy 102.38232 -215.436704) (xy 101.162104 -215.436704)
			(xy 101.161596 -215.462611) (xy 101.15349 -215.513788) (xy 101.137478 -215.563067) (xy 101.113955 -215.609234)
			(xy 101.083499 -215.651153) (xy 101.046861 -215.687791) (xy 101.004942 -215.718247) (xy 100.958775 -215.74177)
			(xy 100.909496 -215.757782) (xy 100.858319 -215.765888) (xy 100.806505 -215.765888) (xy 100.755328 -215.757782)
			(xy 100.706049 -215.74177) (xy 100.659882 -215.718247) (xy 100.617963 -215.687791) (xy 100.581325 -215.651153)
			(xy 100.550869 -215.609234) (xy 100.527346 -215.563067) (xy 100.511334 -215.513788) (xy 100.503228 -215.462611)
			(xy 100.50272 -215.436704) (xy 99.282504 -215.436704) (xy 99.281996 -215.462611) (xy 99.27389 -215.513788)
			(xy 99.257878 -215.563067) (xy 99.234355 -215.609234) (xy 99.203899 -215.651153) (xy 99.167261 -215.687791)
			(xy 99.125342 -215.718247) (xy 99.079175 -215.74177) (xy 99.029896 -215.757782) (xy 98.978719 -215.765888)
			(xy 98.926905 -215.765888) (xy 98.875728 -215.757782) (xy 98.826449 -215.74177) (xy 98.780282 -215.718247)
			(xy 98.738363 -215.687791) (xy 98.701725 -215.651153) (xy 98.671269 -215.609234) (xy 98.647746 -215.563067)
			(xy 98.631734 -215.513788) (xy 98.623628 -215.462611) (xy 98.62312 -215.436704) (xy 97.402904 -215.436704)
			(xy 97.402396 -215.462611) (xy 97.39429 -215.513788) (xy 97.378278 -215.563067) (xy 97.354755 -215.609234)
			(xy 97.324299 -215.651153) (xy 97.287661 -215.687791) (xy 97.245742 -215.718247) (xy 97.199575 -215.74177)
			(xy 97.150296 -215.757782) (xy 97.099119 -215.765888) (xy 97.047305 -215.765888) (xy 96.996128 -215.757782)
			(xy 96.946849 -215.74177) (xy 96.900682 -215.718247) (xy 96.858763 -215.687791) (xy 96.822125 -215.651153)
			(xy 96.791669 -215.609234) (xy 96.768146 -215.563067) (xy 96.752134 -215.513788) (xy 96.744028 -215.462611)
			(xy 96.74352 -215.436704) (xy 95.523304 -215.436704) (xy 95.522796 -215.462611) (xy 95.51469 -215.513788)
			(xy 95.498678 -215.563067) (xy 95.475155 -215.609234) (xy 95.444699 -215.651153) (xy 95.408061 -215.687791)
			(xy 95.366142 -215.718247) (xy 95.319975 -215.74177) (xy 95.270696 -215.757782) (xy 95.219519 -215.765888)
			(xy 95.167705 -215.765888) (xy 95.116528 -215.757782) (xy 95.067249 -215.74177) (xy 95.021082 -215.718247)
			(xy 94.979163 -215.687791) (xy 94.942525 -215.651153) (xy 94.912069 -215.609234) (xy 94.888546 -215.563067)
			(xy 94.872534 -215.513788) (xy 94.864428 -215.462611) (xy 94.86392 -215.436704) (xy 93.643704 -215.436704)
			(xy 93.643196 -215.462611) (xy 93.63509 -215.513788) (xy 93.619078 -215.563067) (xy 93.595555 -215.609234)
			(xy 93.565099 -215.651153) (xy 93.528461 -215.687791) (xy 93.486542 -215.718247) (xy 93.440375 -215.74177)
			(xy 93.391096 -215.757782) (xy 93.339919 -215.765888) (xy 93.288105 -215.765888) (xy 93.236928 -215.757782)
			(xy 93.187649 -215.74177) (xy 93.141482 -215.718247) (xy 93.099563 -215.687791) (xy 93.062925 -215.651153)
			(xy 93.032469 -215.609234) (xy 93.008946 -215.563067) (xy 92.992934 -215.513788) (xy 92.984828 -215.462611)
			(xy 92.98432 -215.436704) (xy 91.764104 -215.436704) (xy 91.763596 -215.462611) (xy 91.75549 -215.513788)
			(xy 91.739478 -215.563067) (xy 91.715955 -215.609234) (xy 91.685499 -215.651153) (xy 91.648861 -215.687791)
			(xy 91.606942 -215.718247) (xy 91.560775 -215.74177) (xy 91.511496 -215.757782) (xy 91.460319 -215.765888)
			(xy 91.408505 -215.765888) (xy 91.357328 -215.757782) (xy 91.308049 -215.74177) (xy 91.261882 -215.718247)
			(xy 91.219963 -215.687791) (xy 91.183325 -215.651153) (xy 91.152869 -215.609234) (xy 91.129346 -215.563067)
			(xy 91.113334 -215.513788) (xy 91.105228 -215.462611) (xy 91.10472 -215.436704) (xy 89.884504 -215.436704)
			(xy 89.883996 -215.462611) (xy 89.87589 -215.513788) (xy 89.859878 -215.563067) (xy 89.836355 -215.609234)
			(xy 89.805899 -215.651153) (xy 89.769261 -215.687791) (xy 89.727342 -215.718247) (xy 89.681175 -215.74177)
			(xy 89.631896 -215.757782) (xy 89.580719 -215.765888) (xy 89.528905 -215.765888) (xy 89.477728 -215.757782)
			(xy 89.428449 -215.74177) (xy 89.382282 -215.718247) (xy 89.340363 -215.687791) (xy 89.303725 -215.651153)
			(xy 89.273269 -215.609234) (xy 89.249746 -215.563067) (xy 89.233734 -215.513788) (xy 89.225628 -215.462611)
			(xy 89.22512 -215.436704) (xy 88.944704 -215.436704) (xy 88.944111 -215.464421) (xy 88.934787 -215.519068)
			(xy 88.926162 -215.545416) (xy 88.918288 -215.567514) (xy 89.123266 -215.922352) (xy 89.146126 -215.92667)
			(xy 89.170934 -215.931835) (xy 89.218674 -215.948828) (xy 89.263251 -215.972925) (xy 89.303616 -216.003559)
			(xy 89.338819 -216.040009) (xy 89.36803 -216.081415) (xy 89.390562 -216.126804) (xy 89.405883 -216.175106)
			(xy 89.413634 -216.225183) (xy 89.414096 -216.25052) (xy 89.413588 -216.276407) (xy 89.405489 -216.327545)
			(xy 89.38949 -216.376785) (xy 89.365984 -216.422917) (xy 89.335552 -216.464804) (xy 89.298942 -216.501414)
			(xy 89.257055 -216.531846) (xy 89.210923 -216.555352) (xy 89.161683 -216.571351) (xy 89.110545 -216.57945)
			(xy 89.058771 -216.57945) (xy 89.007633 -216.571351) (xy 88.958393 -216.555352) (xy 88.912261 -216.531846)
			(xy 88.870374 -216.501414) (xy 88.833764 -216.464804) (xy 88.803332 -216.422917) (xy 88.779826 -216.376785)
			(xy 88.763827 -216.327545) (xy 88.755728 -216.276407) (xy 88.75522 -216.25052) (xy 88.755754 -216.222812)
			(xy 88.764946 -216.168165) (xy 88.773508 -216.141808) (xy 88.781382 -216.11971) (xy 88.576404 -215.764872)
			(xy 88.553544 -215.760554) (xy 88.528711 -215.755439) (xy 88.480928 -215.73848) (xy 88.436306 -215.714403)
			(xy 88.395898 -215.683776) (xy 88.360658 -215.647323) (xy 88.331415 -215.605902) (xy 88.308862 -215.560492)
			(xy 88.293529 -215.512163) (xy 88.285778 -215.462056) (xy 88.28532 -215.436704) (xy 2.509012 -215.436704)
			(xy 2.509012 -217.878406) (xy 88.755728 -217.878406) (xy 88.756236 -217.852519) (xy 88.764335 -217.801381)
			(xy 88.780334 -217.752141) (xy 88.80384 -217.706009) (xy 88.834272 -217.664122) (xy 88.870882 -217.627512)
			(xy 88.912769 -217.59708) (xy 88.958901 -217.573574) (xy 89.008141 -217.557575) (xy 89.059279 -217.549476)
			(xy 89.111053 -217.549476) (xy 89.162191 -217.557575) (xy 89.211431 -217.573574) (xy 89.257563 -217.59708)
			(xy 89.29945 -217.627512) (xy 89.33606 -217.664122) (xy 89.366492 -217.706009) (xy 89.389998 -217.752141)
			(xy 89.405997 -217.801381) (xy 89.414096 -217.852519) (xy 89.414604 -217.878406) (xy 89.695528 -217.878406)
			(xy 89.695994 -217.853071) (xy 89.703746 -217.802996) (xy 89.719069 -217.754698) (xy 89.741602 -217.709313)
			(xy 89.770814 -217.66791) (xy 89.806017 -217.631464) (xy 89.846382 -217.600835) (xy 89.890959 -217.576742)
			(xy 89.938697 -217.559754) (xy 89.963498 -217.554556) (xy 89.986358 -217.550238) (xy 90.191336 -217.195146)
			(xy 90.183462 -217.173302) (xy 90.174824 -217.146891) (xy 90.165499 -217.092117) (xy 90.16492 -217.064336)
			(xy 90.165428 -217.038429) (xy 90.173534 -216.987252) (xy 90.189546 -216.937973) (xy 90.213069 -216.891806)
			(xy 90.243525 -216.849887) (xy 90.280163 -216.813249) (xy 90.322082 -216.782793) (xy 90.368249 -216.75927)
			(xy 90.417528 -216.743258) (xy 90.468705 -216.735152) (xy 90.520519 -216.735152) (xy 90.571696 -216.743258)
			(xy 90.620975 -216.75927) (xy 90.667142 -216.782793) (xy 90.709061 -216.813249) (xy 90.745699 -216.849887)
			(xy 90.776155 -216.891806) (xy 90.799678 -216.937973) (xy 90.81569 -216.987252) (xy 90.823796 -217.038429)
			(xy 90.824304 -217.064336) (xy 90.823812 -217.08968) (xy 90.816035 -217.13977) (xy 90.800686 -217.188079)
			(xy 90.778125 -217.233471) (xy 90.748884 -217.274876) (xy 90.713652 -217.311319) (xy 90.673259 -217.341943)
			(xy 90.628655 -217.366024) (xy 90.580892 -217.382998) (xy 90.55608 -217.388186) (xy 90.53322 -217.392504)
			(xy 90.328242 -217.747596) (xy 90.336116 -217.76944) (xy 90.344706 -217.795856) (xy 90.353895 -217.850633)
			(xy 90.354404 -217.878406) (xy 90.635328 -217.878406) (xy 90.635836 -217.852519) (xy 90.643935 -217.801381)
			(xy 90.659934 -217.752141) (xy 90.68344 -217.706009) (xy 90.713872 -217.664122) (xy 90.750482 -217.627512)
			(xy 90.792369 -217.59708) (xy 90.838501 -217.573574) (xy 90.887741 -217.557575) (xy 90.938879 -217.549476)
			(xy 90.990653 -217.549476) (xy 91.041791 -217.557575) (xy 91.091031 -217.573574) (xy 91.137163 -217.59708)
			(xy 91.17905 -217.627512) (xy 91.21566 -217.664122) (xy 91.246092 -217.706009) (xy 91.269598 -217.752141)
			(xy 91.285597 -217.801381) (xy 91.293696 -217.852519) (xy 91.294204 -217.878406) (xy 91.575128 -217.878406)
			(xy 91.575594 -217.853071) (xy 91.583346 -217.802996) (xy 91.598669 -217.754698) (xy 91.621202 -217.709313)
			(xy 91.650414 -217.66791) (xy 91.685617 -217.631464) (xy 91.725982 -217.600835) (xy 91.770559 -217.576742)
			(xy 91.818297 -217.559754) (xy 91.843098 -217.554556) (xy 91.865958 -217.550238) (xy 92.070936 -217.195146)
			(xy 92.063062 -217.173302) (xy 92.054424 -217.146891) (xy 92.045099 -217.092117) (xy 92.04452 -217.064336)
			(xy 92.045028 -217.038429) (xy 92.053134 -216.987252) (xy 92.069146 -216.937973) (xy 92.092669 -216.891806)
			(xy 92.123125 -216.849887) (xy 92.159763 -216.813249) (xy 92.201682 -216.782793) (xy 92.247849 -216.75927)
			(xy 92.297128 -216.743258) (xy 92.348305 -216.735152) (xy 92.400119 -216.735152) (xy 92.451296 -216.743258)
			(xy 92.500575 -216.75927) (xy 92.546742 -216.782793) (xy 92.588661 -216.813249) (xy 92.625299 -216.849887)
			(xy 92.655755 -216.891806) (xy 92.679278 -216.937973) (xy 92.69529 -216.987252) (xy 92.703396 -217.038429)
			(xy 92.703904 -217.064336) (xy 92.703412 -217.08968) (xy 92.695635 -217.13977) (xy 92.680286 -217.188079)
			(xy 92.657725 -217.233471) (xy 92.628484 -217.274876) (xy 92.593252 -217.311319) (xy 92.552859 -217.341943)
			(xy 92.508255 -217.366024) (xy 92.460492 -217.382998) (xy 92.43568 -217.388186) (xy 92.41282 -217.392504)
			(xy 92.207842 -217.747596) (xy 92.215716 -217.76944) (xy 92.224306 -217.795856) (xy 92.233495 -217.850633)
			(xy 92.234004 -217.878406) (xy 92.514928 -217.878406) (xy 92.515436 -217.852519) (xy 92.523535 -217.801381)
			(xy 92.539534 -217.752141) (xy 92.56304 -217.706009) (xy 92.593472 -217.664122) (xy 92.630082 -217.627512)
			(xy 92.671969 -217.59708) (xy 92.718101 -217.573574) (xy 92.767341 -217.557575) (xy 92.818479 -217.549476)
			(xy 92.870253 -217.549476) (xy 92.921391 -217.557575) (xy 92.970631 -217.573574) (xy 93.016763 -217.59708)
			(xy 93.05865 -217.627512) (xy 93.09526 -217.664122) (xy 93.125692 -217.706009) (xy 93.149198 -217.752141)
			(xy 93.165197 -217.801381) (xy 93.173296 -217.852519) (xy 93.173804 -217.878406) (xy 93.454728 -217.878406)
			(xy 93.455194 -217.853071) (xy 93.462946 -217.802996) (xy 93.478269 -217.754698) (xy 93.500802 -217.709313)
			(xy 93.530014 -217.66791) (xy 93.565217 -217.631464) (xy 93.605582 -217.600835) (xy 93.650159 -217.576742)
			(xy 93.697897 -217.559754) (xy 93.722698 -217.554556) (xy 93.745558 -217.550238) (xy 93.950536 -217.195146)
			(xy 93.942662 -217.173302) (xy 93.934024 -217.146891) (xy 93.924699 -217.092117) (xy 93.92412 -217.064336)
			(xy 93.924628 -217.038429) (xy 93.932734 -216.987252) (xy 93.948746 -216.937973) (xy 93.972269 -216.891806)
			(xy 94.002725 -216.849887) (xy 94.039363 -216.813249) (xy 94.081282 -216.782793) (xy 94.127449 -216.75927)
			(xy 94.176728 -216.743258) (xy 94.227905 -216.735152) (xy 94.279719 -216.735152) (xy 94.330896 -216.743258)
			(xy 94.380175 -216.75927) (xy 94.426342 -216.782793) (xy 94.468261 -216.813249) (xy 94.504899 -216.849887)
			(xy 94.535355 -216.891806) (xy 94.558878 -216.937973) (xy 94.57489 -216.987252) (xy 94.582996 -217.038429)
			(xy 94.583504 -217.064336) (xy 94.583012 -217.08968) (xy 94.575235 -217.13977) (xy 94.559886 -217.188079)
			(xy 94.537325 -217.233471) (xy 94.508084 -217.274876) (xy 94.472852 -217.311319) (xy 94.432459 -217.341943)
			(xy 94.387855 -217.366024) (xy 94.340092 -217.382998) (xy 94.31528 -217.388186) (xy 94.29242 -217.392504)
			(xy 94.087442 -217.747596) (xy 94.095316 -217.76944) (xy 94.103906 -217.795856) (xy 94.113095 -217.850633)
			(xy 94.113604 -217.878406) (xy 94.394528 -217.878406) (xy 94.395036 -217.852519) (xy 94.403135 -217.801381)
			(xy 94.419134 -217.752141) (xy 94.44264 -217.706009) (xy 94.473072 -217.664122) (xy 94.509682 -217.627512)
			(xy 94.551569 -217.59708) (xy 94.597701 -217.573574) (xy 94.646941 -217.557575) (xy 94.698079 -217.549476)
			(xy 94.749853 -217.549476) (xy 94.800991 -217.557575) (xy 94.850231 -217.573574) (xy 94.896363 -217.59708)
			(xy 94.93825 -217.627512) (xy 94.97486 -217.664122) (xy 95.005292 -217.706009) (xy 95.028798 -217.752141)
			(xy 95.044797 -217.801381) (xy 95.052896 -217.852519) (xy 95.053404 -217.878406) (xy 95.334328 -217.878406)
			(xy 95.334794 -217.853071) (xy 95.342546 -217.802996) (xy 95.357869 -217.754698) (xy 95.380402 -217.709313)
			(xy 95.409614 -217.66791) (xy 95.444817 -217.631464) (xy 95.485182 -217.600835) (xy 95.529759 -217.576742)
			(xy 95.577497 -217.559754) (xy 95.602298 -217.554556) (xy 95.625158 -217.550238) (xy 95.830136 -217.195146)
			(xy 95.822262 -217.173302) (xy 95.813624 -217.146891) (xy 95.804299 -217.092117) (xy 95.80372 -217.064336)
			(xy 95.804228 -217.038429) (xy 95.812334 -216.987252) (xy 95.828346 -216.937973) (xy 95.851869 -216.891806)
			(xy 95.882325 -216.849887) (xy 95.918963 -216.813249) (xy 95.960882 -216.782793) (xy 96.007049 -216.75927)
			(xy 96.056328 -216.743258) (xy 96.107505 -216.735152) (xy 96.159319 -216.735152) (xy 96.210496 -216.743258)
			(xy 96.259775 -216.75927) (xy 96.305942 -216.782793) (xy 96.347861 -216.813249) (xy 96.384499 -216.849887)
			(xy 96.414955 -216.891806) (xy 96.438478 -216.937973) (xy 96.45449 -216.987252) (xy 96.462596 -217.038429)
			(xy 96.463104 -217.064336) (xy 96.462612 -217.08968) (xy 96.454835 -217.13977) (xy 96.439486 -217.188079)
			(xy 96.416925 -217.233471) (xy 96.387684 -217.274876) (xy 96.352452 -217.311319) (xy 96.312059 -217.341943)
			(xy 96.267455 -217.366024) (xy 96.219692 -217.382998) (xy 96.19488 -217.388186) (xy 96.17202 -217.392504)
			(xy 95.967042 -217.747596) (xy 95.974916 -217.76944) (xy 95.983506 -217.795856) (xy 95.992695 -217.850633)
			(xy 95.993204 -217.878406) (xy 96.274128 -217.878406) (xy 96.274636 -217.852519) (xy 96.282735 -217.801381)
			(xy 96.298734 -217.752141) (xy 96.32224 -217.706009) (xy 96.352672 -217.664122) (xy 96.389282 -217.627512)
			(xy 96.431169 -217.59708) (xy 96.477301 -217.573574) (xy 96.526541 -217.557575) (xy 96.577679 -217.549476)
			(xy 96.629453 -217.549476) (xy 96.680591 -217.557575) (xy 96.729831 -217.573574) (xy 96.775963 -217.59708)
			(xy 96.81785 -217.627512) (xy 96.85446 -217.664122) (xy 96.884892 -217.706009) (xy 96.908398 -217.752141)
			(xy 96.924397 -217.801381) (xy 96.932496 -217.852519) (xy 96.933004 -217.878406) (xy 97.213928 -217.878406)
			(xy 97.214394 -217.853071) (xy 97.222146 -217.802996) (xy 97.237469 -217.754698) (xy 97.260002 -217.709313)
			(xy 97.289214 -217.66791) (xy 97.324417 -217.631464) (xy 97.364782 -217.600835) (xy 97.409359 -217.576742)
			(xy 97.457097 -217.559754) (xy 97.481898 -217.554556) (xy 97.504758 -217.550238) (xy 97.709736 -217.195146)
			(xy 97.701862 -217.173302) (xy 97.693224 -217.146891) (xy 97.683899 -217.092117) (xy 97.68332 -217.064336)
			(xy 97.683828 -217.038429) (xy 97.691934 -216.987252) (xy 97.707946 -216.937973) (xy 97.731469 -216.891806)
			(xy 97.761925 -216.849887) (xy 97.798563 -216.813249) (xy 97.840482 -216.782793) (xy 97.886649 -216.75927)
			(xy 97.935928 -216.743258) (xy 97.987105 -216.735152) (xy 98.038919 -216.735152) (xy 98.090096 -216.743258)
			(xy 98.139375 -216.75927) (xy 98.185542 -216.782793) (xy 98.227461 -216.813249) (xy 98.264099 -216.849887)
			(xy 98.294555 -216.891806) (xy 98.318078 -216.937973) (xy 98.33409 -216.987252) (xy 98.342196 -217.038429)
			(xy 98.342704 -217.064336) (xy 98.342212 -217.08968) (xy 98.334435 -217.13977) (xy 98.319086 -217.188079)
			(xy 98.296525 -217.233471) (xy 98.267284 -217.274876) (xy 98.232052 -217.311319) (xy 98.191659 -217.341943)
			(xy 98.147055 -217.366024) (xy 98.099292 -217.382998) (xy 98.07448 -217.388186) (xy 98.05162 -217.392504)
			(xy 97.846642 -217.747596) (xy 97.854516 -217.76944) (xy 97.863106 -217.795856) (xy 97.872295 -217.850633)
			(xy 97.872804 -217.878406) (xy 98.153728 -217.878406) (xy 98.154236 -217.852519) (xy 98.162335 -217.801381)
			(xy 98.178334 -217.752141) (xy 98.20184 -217.706009) (xy 98.232272 -217.664122) (xy 98.268882 -217.627512)
			(xy 98.310769 -217.59708) (xy 98.356901 -217.573574) (xy 98.406141 -217.557575) (xy 98.457279 -217.549476)
			(xy 98.509053 -217.549476) (xy 98.560191 -217.557575) (xy 98.609431 -217.573574) (xy 98.655563 -217.59708)
			(xy 98.69745 -217.627512) (xy 98.73406 -217.664122) (xy 98.764492 -217.706009) (xy 98.787998 -217.752141)
			(xy 98.803997 -217.801381) (xy 98.812096 -217.852519) (xy 98.812604 -217.878406) (xy 99.093528 -217.878406)
			(xy 99.093994 -217.853071) (xy 99.101746 -217.802996) (xy 99.117069 -217.754698) (xy 99.139602 -217.709313)
			(xy 99.168814 -217.66791) (xy 99.204017 -217.631464) (xy 99.244382 -217.600835) (xy 99.288959 -217.576742)
			(xy 99.336697 -217.559754) (xy 99.361498 -217.554556) (xy 99.384358 -217.550238) (xy 99.589336 -217.195146)
			(xy 99.581462 -217.173302) (xy 99.572824 -217.146891) (xy 99.563499 -217.092117) (xy 99.56292 -217.064336)
			(xy 99.563428 -217.038429) (xy 99.571534 -216.987252) (xy 99.587546 -216.937973) (xy 99.611069 -216.891806)
			(xy 99.641525 -216.849887) (xy 99.678163 -216.813249) (xy 99.720082 -216.782793) (xy 99.766249 -216.75927)
			(xy 99.815528 -216.743258) (xy 99.866705 -216.735152) (xy 99.918519 -216.735152) (xy 99.969696 -216.743258)
			(xy 100.018975 -216.75927) (xy 100.065142 -216.782793) (xy 100.107061 -216.813249) (xy 100.143699 -216.849887)
			(xy 100.174155 -216.891806) (xy 100.197678 -216.937973) (xy 100.21369 -216.987252) (xy 100.221796 -217.038429)
			(xy 100.222304 -217.064336) (xy 100.221812 -217.08968) (xy 100.214035 -217.13977) (xy 100.198686 -217.188079)
			(xy 100.176125 -217.233471) (xy 100.146884 -217.274876) (xy 100.111652 -217.311319) (xy 100.071259 -217.341943)
			(xy 100.026655 -217.366024) (xy 99.978892 -217.382998) (xy 99.95408 -217.388186) (xy 99.93122 -217.392504)
			(xy 99.726242 -217.747596) (xy 99.734116 -217.76944) (xy 99.742706 -217.795856) (xy 99.751895 -217.850633)
			(xy 99.752404 -217.878406) (xy 100.033328 -217.878406) (xy 100.033836 -217.852519) (xy 100.041935 -217.801381)
			(xy 100.057934 -217.752141) (xy 100.08144 -217.706009) (xy 100.111872 -217.664122) (xy 100.148482 -217.627512)
			(xy 100.190369 -217.59708) (xy 100.236501 -217.573574) (xy 100.285741 -217.557575) (xy 100.336879 -217.549476)
			(xy 100.388653 -217.549476) (xy 100.439791 -217.557575) (xy 100.489031 -217.573574) (xy 100.535163 -217.59708)
			(xy 100.57705 -217.627512) (xy 100.61366 -217.664122) (xy 100.644092 -217.706009) (xy 100.667598 -217.752141)
			(xy 100.683597 -217.801381) (xy 100.691696 -217.852519) (xy 100.692204 -217.878406) (xy 100.973128 -217.878406)
			(xy 100.973594 -217.853071) (xy 100.981346 -217.802996) (xy 100.996669 -217.754698) (xy 101.019202 -217.709313)
			(xy 101.048414 -217.66791) (xy 101.083617 -217.631464) (xy 101.123982 -217.600835) (xy 101.168559 -217.576742)
			(xy 101.216297 -217.559754) (xy 101.241098 -217.554556) (xy 101.263958 -217.550238) (xy 101.468936 -217.195146)
			(xy 101.461062 -217.173302) (xy 101.452424 -217.146891) (xy 101.443099 -217.092117) (xy 101.44252 -217.064336)
			(xy 101.443028 -217.038429) (xy 101.451134 -216.987252) (xy 101.467146 -216.937973) (xy 101.490669 -216.891806)
			(xy 101.521125 -216.849887) (xy 101.557763 -216.813249) (xy 101.599682 -216.782793) (xy 101.645849 -216.75927)
			(xy 101.695128 -216.743258) (xy 101.746305 -216.735152) (xy 101.798119 -216.735152) (xy 101.849296 -216.743258)
			(xy 101.898575 -216.75927) (xy 101.944742 -216.782793) (xy 101.986661 -216.813249) (xy 102.023299 -216.849887)
			(xy 102.053755 -216.891806) (xy 102.077278 -216.937973) (xy 102.09329 -216.987252) (xy 102.101396 -217.038429)
			(xy 102.101904 -217.064336) (xy 102.101412 -217.08968) (xy 102.093635 -217.13977) (xy 102.078286 -217.188079)
			(xy 102.055725 -217.233471) (xy 102.026484 -217.274876) (xy 101.991252 -217.311319) (xy 101.950859 -217.341943)
			(xy 101.906255 -217.366024) (xy 101.858492 -217.382998) (xy 101.83368 -217.388186) (xy 101.81082 -217.392504)
			(xy 101.605842 -217.747596) (xy 101.613716 -217.76944) (xy 101.622306 -217.795856) (xy 101.631495 -217.850633)
			(xy 101.632004 -217.878406) (xy 101.912928 -217.878406) (xy 101.913436 -217.852519) (xy 101.921535 -217.801381)
			(xy 101.937534 -217.752141) (xy 101.96104 -217.706009) (xy 101.991472 -217.664122) (xy 102.028082 -217.627512)
			(xy 102.069969 -217.59708) (xy 102.116101 -217.573574) (xy 102.165341 -217.557575) (xy 102.216479 -217.549476)
			(xy 102.268253 -217.549476) (xy 102.319391 -217.557575) (xy 102.368631 -217.573574) (xy 102.414763 -217.59708)
			(xy 102.45665 -217.627512) (xy 102.49326 -217.664122) (xy 102.523692 -217.706009) (xy 102.547198 -217.752141)
			(xy 102.563197 -217.801381) (xy 102.571296 -217.852519) (xy 102.571804 -217.878406) (xy 102.852728 -217.878406)
			(xy 102.853194 -217.853071) (xy 102.860946 -217.802996) (xy 102.876269 -217.754698) (xy 102.898802 -217.709313)
			(xy 102.928014 -217.66791) (xy 102.963217 -217.631464) (xy 103.003582 -217.600835) (xy 103.048159 -217.576742)
			(xy 103.095897 -217.559754) (xy 103.120698 -217.554556) (xy 103.143558 -217.550238) (xy 103.348536 -217.195146)
			(xy 103.340662 -217.173302) (xy 103.332024 -217.146891) (xy 103.322699 -217.092117) (xy 103.32212 -217.064336)
			(xy 103.322628 -217.038429) (xy 103.330734 -216.987252) (xy 103.346746 -216.937973) (xy 103.370269 -216.891806)
			(xy 103.400725 -216.849887) (xy 103.437363 -216.813249) (xy 103.479282 -216.782793) (xy 103.525449 -216.75927)
			(xy 103.574728 -216.743258) (xy 103.625905 -216.735152) (xy 103.677719 -216.735152) (xy 103.728896 -216.743258)
			(xy 103.778175 -216.75927) (xy 103.824342 -216.782793) (xy 103.866261 -216.813249) (xy 103.902899 -216.849887)
			(xy 103.933355 -216.891806) (xy 103.956878 -216.937973) (xy 103.97289 -216.987252) (xy 103.980996 -217.038429)
			(xy 103.981504 -217.064336) (xy 103.981012 -217.08968) (xy 103.973235 -217.13977) (xy 103.957886 -217.188079)
			(xy 103.935325 -217.233471) (xy 103.906084 -217.274876) (xy 103.870852 -217.311319) (xy 103.830459 -217.341943)
			(xy 103.785855 -217.366024) (xy 103.738092 -217.382998) (xy 103.71328 -217.388186) (xy 103.69042 -217.392504)
			(xy 103.485442 -217.747596) (xy 103.493316 -217.76944) (xy 103.501906 -217.795856) (xy 103.511095 -217.850633)
			(xy 103.511604 -217.878406) (xy 103.792528 -217.878406) (xy 103.793036 -217.852519) (xy 103.801135 -217.801381)
			(xy 103.817134 -217.752141) (xy 103.84064 -217.706009) (xy 103.871072 -217.664122) (xy 103.907682 -217.627512)
			(xy 103.949569 -217.59708) (xy 103.995701 -217.573574) (xy 104.044941 -217.557575) (xy 104.096079 -217.549476)
			(xy 104.147853 -217.549476) (xy 104.198991 -217.557575) (xy 104.248231 -217.573574) (xy 104.294363 -217.59708)
			(xy 104.33625 -217.627512) (xy 104.37286 -217.664122) (xy 104.403292 -217.706009) (xy 104.426798 -217.752141)
			(xy 104.442797 -217.801381) (xy 104.450896 -217.852519) (xy 104.451404 -217.878406) (xy 104.732328 -217.878406)
			(xy 104.732794 -217.853071) (xy 104.740546 -217.802996) (xy 104.755869 -217.754698) (xy 104.778402 -217.709313)
			(xy 104.807614 -217.66791) (xy 104.842817 -217.631464) (xy 104.883182 -217.600835) (xy 104.927759 -217.576742)
			(xy 104.975497 -217.559754) (xy 105.000298 -217.554556) (xy 105.023158 -217.550238) (xy 105.228136 -217.195146)
			(xy 105.220262 -217.173302) (xy 105.211624 -217.146891) (xy 105.202299 -217.092117) (xy 105.20172 -217.064336)
			(xy 105.202228 -217.038429) (xy 105.210334 -216.987252) (xy 105.226346 -216.937973) (xy 105.249869 -216.891806)
			(xy 105.280325 -216.849887) (xy 105.316963 -216.813249) (xy 105.358882 -216.782793) (xy 105.405049 -216.75927)
			(xy 105.454328 -216.743258) (xy 105.505505 -216.735152) (xy 105.557319 -216.735152) (xy 105.608496 -216.743258)
			(xy 105.657775 -216.75927) (xy 105.703942 -216.782793) (xy 105.745861 -216.813249) (xy 105.782499 -216.849887)
			(xy 105.812955 -216.891806) (xy 105.836478 -216.937973) (xy 105.85249 -216.987252) (xy 105.860596 -217.038429)
			(xy 105.861104 -217.064336) (xy 105.860612 -217.08968) (xy 105.852835 -217.13977) (xy 105.837486 -217.188079)
			(xy 105.814925 -217.233471) (xy 105.785684 -217.274876) (xy 105.750452 -217.311319) (xy 105.710059 -217.341943)
			(xy 105.665455 -217.366024) (xy 105.617692 -217.382998) (xy 105.59288 -217.388186) (xy 105.57002 -217.392504)
			(xy 105.365042 -217.747596) (xy 105.372916 -217.76944) (xy 105.381506 -217.795856) (xy 105.390695 -217.850633)
			(xy 105.391204 -217.878406) (xy 105.672128 -217.878406) (xy 105.672636 -217.852519) (xy 105.680735 -217.801381)
			(xy 105.696734 -217.752141) (xy 105.72024 -217.706009) (xy 105.750672 -217.664122) (xy 105.787282 -217.627512)
			(xy 105.829169 -217.59708) (xy 105.875301 -217.573574) (xy 105.924541 -217.557575) (xy 105.975679 -217.549476)
			(xy 106.027453 -217.549476) (xy 106.078591 -217.557575) (xy 106.127831 -217.573574) (xy 106.173963 -217.59708)
			(xy 106.21585 -217.627512) (xy 106.25246 -217.664122) (xy 106.282892 -217.706009) (xy 106.306398 -217.752141)
			(xy 106.322397 -217.801381) (xy 106.330496 -217.852519) (xy 106.331004 -217.878406) (xy 106.611928 -217.878406)
			(xy 106.612394 -217.853071) (xy 106.620146 -217.802996) (xy 106.635469 -217.754698) (xy 106.658002 -217.709313)
			(xy 106.687214 -217.66791) (xy 106.722417 -217.631464) (xy 106.762782 -217.600835) (xy 106.807359 -217.576742)
			(xy 106.855097 -217.559754) (xy 106.879898 -217.554556) (xy 106.902758 -217.550238) (xy 107.107736 -217.195146)
			(xy 107.099862 -217.173302) (xy 107.091224 -217.146891) (xy 107.081899 -217.092117) (xy 107.08132 -217.064336)
			(xy 107.081828 -217.038429) (xy 107.089934 -216.987252) (xy 107.105946 -216.937973) (xy 107.129469 -216.891806)
			(xy 107.159925 -216.849887) (xy 107.196563 -216.813249) (xy 107.238482 -216.782793) (xy 107.284649 -216.75927)
			(xy 107.333928 -216.743258) (xy 107.385105 -216.735152) (xy 107.436919 -216.735152) (xy 107.488096 -216.743258)
			(xy 107.537375 -216.75927) (xy 107.583542 -216.782793) (xy 107.625461 -216.813249) (xy 107.662099 -216.849887)
			(xy 107.692555 -216.891806) (xy 107.716078 -216.937973) (xy 107.73209 -216.987252) (xy 107.740196 -217.038429)
			(xy 107.740704 -217.064336) (xy 107.740212 -217.08968) (xy 107.732435 -217.13977) (xy 107.717086 -217.188079)
			(xy 107.694525 -217.233471) (xy 107.665284 -217.274876) (xy 107.630052 -217.311319) (xy 107.589659 -217.341943)
			(xy 107.545055 -217.366024) (xy 107.497292 -217.382998) (xy 107.47248 -217.388186) (xy 107.44962 -217.392504)
			(xy 107.244642 -217.747596) (xy 107.252516 -217.76944) (xy 107.261106 -217.795856) (xy 107.270295 -217.850633)
			(xy 107.270804 -217.878406) (xy 107.551728 -217.878406) (xy 107.552236 -217.852519) (xy 107.560335 -217.801381)
			(xy 107.576334 -217.752141) (xy 107.59984 -217.706009) (xy 107.630272 -217.664122) (xy 107.666882 -217.627512)
			(xy 107.708769 -217.59708) (xy 107.754901 -217.573574) (xy 107.804141 -217.557575) (xy 107.855279 -217.549476)
			(xy 107.907053 -217.549476) (xy 107.958191 -217.557575) (xy 108.007431 -217.573574) (xy 108.053563 -217.59708)
			(xy 108.09545 -217.627512) (xy 108.13206 -217.664122) (xy 108.162492 -217.706009) (xy 108.185998 -217.752141)
			(xy 108.201997 -217.801381) (xy 108.210096 -217.852519) (xy 108.210604 -217.878406) (xy 108.491528 -217.878406)
			(xy 108.491994 -217.853071) (xy 108.499746 -217.802996) (xy 108.515069 -217.754698) (xy 108.537602 -217.709313)
			(xy 108.566814 -217.66791) (xy 108.602017 -217.631464) (xy 108.642382 -217.600835) (xy 108.686959 -217.576742)
			(xy 108.734697 -217.559754) (xy 108.759498 -217.554556) (xy 108.782358 -217.550238) (xy 108.987336 -217.195146)
			(xy 108.979462 -217.173302) (xy 108.970824 -217.146891) (xy 108.961499 -217.092117) (xy 108.96092 -217.064336)
			(xy 108.961428 -217.038429) (xy 108.969534 -216.987252) (xy 108.985546 -216.937973) (xy 109.009069 -216.891806)
			(xy 109.039525 -216.849887) (xy 109.076163 -216.813249) (xy 109.118082 -216.782793) (xy 109.164249 -216.75927)
			(xy 109.213528 -216.743258) (xy 109.264705 -216.735152) (xy 109.316519 -216.735152) (xy 109.367696 -216.743258)
			(xy 109.416975 -216.75927) (xy 109.463142 -216.782793) (xy 109.505061 -216.813249) (xy 109.541699 -216.849887)
			(xy 109.572155 -216.891806) (xy 109.595678 -216.937973) (xy 109.61169 -216.987252) (xy 109.619796 -217.038429)
			(xy 109.620304 -217.064336) (xy 109.619812 -217.08968) (xy 109.612035 -217.13977) (xy 109.596686 -217.188079)
			(xy 109.574125 -217.233471) (xy 109.544884 -217.274876) (xy 109.509652 -217.311319) (xy 109.469259 -217.341943)
			(xy 109.424655 -217.366024) (xy 109.376892 -217.382998) (xy 109.35208 -217.388186) (xy 109.32922 -217.392504)
			(xy 109.124242 -217.747596) (xy 109.132116 -217.76944) (xy 109.140706 -217.795856) (xy 109.149895 -217.850633)
			(xy 109.150404 -217.878406) (xy 109.431328 -217.878406) (xy 109.431836 -217.852519) (xy 109.439935 -217.801381)
			(xy 109.455934 -217.752141) (xy 109.47944 -217.706009) (xy 109.509872 -217.664122) (xy 109.546482 -217.627512)
			(xy 109.588369 -217.59708) (xy 109.634501 -217.573574) (xy 109.683741 -217.557575) (xy 109.734879 -217.549476)
			(xy 109.786653 -217.549476) (xy 109.837791 -217.557575) (xy 109.887031 -217.573574) (xy 109.933163 -217.59708)
			(xy 109.97505 -217.627512) (xy 110.01166 -217.664122) (xy 110.042092 -217.706009) (xy 110.065598 -217.752141)
			(xy 110.081597 -217.801381) (xy 110.089696 -217.852519) (xy 110.090204 -217.878406) (xy 110.371128 -217.878406)
			(xy 110.371594 -217.853071) (xy 110.379346 -217.802996) (xy 110.394669 -217.754698) (xy 110.417202 -217.709313)
			(xy 110.446414 -217.66791) (xy 110.481617 -217.631464) (xy 110.521982 -217.600835) (xy 110.566559 -217.576742)
			(xy 110.614297 -217.559754) (xy 110.639098 -217.554556) (xy 110.661958 -217.550238) (xy 110.866936 -217.194892)
			(xy 110.859316 -217.173048) (xy 110.850741 -217.146694) (xy 110.841552 -217.092045) (xy 110.841028 -217.064336)
			(xy 110.841536 -217.038449) (xy 110.849635 -216.987311) (xy 110.865634 -216.938071) (xy 110.88914 -216.891939)
			(xy 110.919572 -216.850052) (xy 110.956182 -216.813442) (xy 110.998069 -216.78301) (xy 111.044201 -216.759504)
			(xy 111.093441 -216.743505) (xy 111.144579 -216.735406) (xy 111.196353 -216.735406) (xy 111.247491 -216.743505)
			(xy 111.296731 -216.759504) (xy 111.342863 -216.78301) (xy 111.38475 -216.813442) (xy 111.42136 -216.850052)
			(xy 111.451792 -216.891939) (xy 111.475298 -216.938071) (xy 111.491297 -216.987311) (xy 111.499396 -217.038449)
			(xy 111.499904 -217.064336) (xy 112.72012 -217.064336) (xy 112.720628 -217.038429) (xy 112.728734 -216.987252)
			(xy 112.744746 -216.937973) (xy 112.768269 -216.891806) (xy 112.798725 -216.849887) (xy 112.835363 -216.813249)
			(xy 112.877282 -216.782793) (xy 112.923449 -216.75927) (xy 112.972728 -216.743258) (xy 113.023905 -216.735152)
			(xy 113.075719 -216.735152) (xy 113.126896 -216.743258) (xy 113.176175 -216.75927) (xy 113.222342 -216.782793)
			(xy 113.264261 -216.813249) (xy 113.300899 -216.849887) (xy 113.331355 -216.891806) (xy 113.354878 -216.937973)
			(xy 113.37089 -216.987252) (xy 113.378996 -217.038429) (xy 113.379504 -217.064336) (xy 114.59972 -217.064336)
			(xy 114.600228 -217.038429) (xy 114.608334 -216.987252) (xy 114.624346 -216.937973) (xy 114.647869 -216.891806)
			(xy 114.678325 -216.849887) (xy 114.714963 -216.813249) (xy 114.756882 -216.782793) (xy 114.803049 -216.75927)
			(xy 114.852328 -216.743258) (xy 114.903505 -216.735152) (xy 114.955319 -216.735152) (xy 115.006496 -216.743258)
			(xy 115.055775 -216.75927) (xy 115.101942 -216.782793) (xy 115.143861 -216.813249) (xy 115.180499 -216.849887)
			(xy 115.210955 -216.891806) (xy 115.234478 -216.937973) (xy 115.25049 -216.987252) (xy 115.258596 -217.038429)
			(xy 115.259104 -217.064336) (xy 116.47932 -217.064336) (xy 116.479828 -217.038429) (xy 116.487934 -216.987252)
			(xy 116.503946 -216.937973) (xy 116.527469 -216.891806) (xy 116.557925 -216.849887) (xy 116.594563 -216.813249)
			(xy 116.636482 -216.782793) (xy 116.682649 -216.75927) (xy 116.731928 -216.743258) (xy 116.783105 -216.735152)
			(xy 116.834919 -216.735152) (xy 116.886096 -216.743258) (xy 116.935375 -216.75927) (xy 116.981542 -216.782793)
			(xy 117.023461 -216.813249) (xy 117.060099 -216.849887) (xy 117.090555 -216.891806) (xy 117.114078 -216.937973)
			(xy 117.13009 -216.987252) (xy 117.138196 -217.038429) (xy 117.138704 -217.064336) (xy 118.35892 -217.064336)
			(xy 118.359428 -217.038429) (xy 118.367534 -216.987252) (xy 118.383546 -216.937973) (xy 118.407069 -216.891806)
			(xy 118.437525 -216.849887) (xy 118.474163 -216.813249) (xy 118.516082 -216.782793) (xy 118.562249 -216.75927)
			(xy 118.611528 -216.743258) (xy 118.662705 -216.735152) (xy 118.714519 -216.735152) (xy 118.765696 -216.743258)
			(xy 118.814975 -216.75927) (xy 118.861142 -216.782793) (xy 118.903061 -216.813249) (xy 118.939699 -216.849887)
			(xy 118.970155 -216.891806) (xy 118.993678 -216.937973) (xy 119.00969 -216.987252) (xy 119.017796 -217.038429)
			(xy 119.018304 -217.064336) (xy 120.23852 -217.064336) (xy 120.239028 -217.038429) (xy 120.247134 -216.987252)
			(xy 120.263146 -216.937973) (xy 120.286669 -216.891806) (xy 120.317125 -216.849887) (xy 120.353763 -216.813249)
			(xy 120.395682 -216.782793) (xy 120.441849 -216.75927) (xy 120.491128 -216.743258) (xy 120.542305 -216.735152)
			(xy 120.594119 -216.735152) (xy 120.645296 -216.743258) (xy 120.694575 -216.75927) (xy 120.740742 -216.782793)
			(xy 120.782661 -216.813249) (xy 120.819299 -216.849887) (xy 120.849755 -216.891806) (xy 120.873278 -216.937973)
			(xy 120.88929 -216.987252) (xy 120.897396 -217.038429) (xy 120.897904 -217.064336) (xy 122.11812 -217.064336)
			(xy 122.118628 -217.038429) (xy 122.126734 -216.987252) (xy 122.142746 -216.937973) (xy 122.166269 -216.891806)
			(xy 122.196725 -216.849887) (xy 122.233363 -216.813249) (xy 122.275282 -216.782793) (xy 122.321449 -216.75927)
			(xy 122.370728 -216.743258) (xy 122.421905 -216.735152) (xy 122.473719 -216.735152) (xy 122.524896 -216.743258)
			(xy 122.574175 -216.75927) (xy 122.620342 -216.782793) (xy 122.662261 -216.813249) (xy 122.698899 -216.849887)
			(xy 122.729355 -216.891806) (xy 122.752878 -216.937973) (xy 122.76889 -216.987252) (xy 122.776996 -217.038429)
			(xy 122.777504 -217.064336) (xy 123.99772 -217.064336) (xy 123.998228 -217.038429) (xy 124.006334 -216.987252)
			(xy 124.022346 -216.937973) (xy 124.045869 -216.891806) (xy 124.076325 -216.849887) (xy 124.112963 -216.813249)
			(xy 124.154882 -216.782793) (xy 124.201049 -216.75927) (xy 124.250328 -216.743258) (xy 124.301505 -216.735152)
			(xy 124.353319 -216.735152) (xy 124.404496 -216.743258) (xy 124.453775 -216.75927) (xy 124.499942 -216.782793)
			(xy 124.541861 -216.813249) (xy 124.578499 -216.849887) (xy 124.608955 -216.891806) (xy 124.632478 -216.937973)
			(xy 124.64849 -216.987252) (xy 124.656596 -217.038429) (xy 124.657104 -217.064336) (xy 125.87732 -217.064336)
			(xy 125.877828 -217.038429) (xy 125.885934 -216.987252) (xy 125.901946 -216.937973) (xy 125.925469 -216.891806)
			(xy 125.955925 -216.849887) (xy 125.992563 -216.813249) (xy 126.034482 -216.782793) (xy 126.080649 -216.75927)
			(xy 126.129928 -216.743258) (xy 126.181105 -216.735152) (xy 126.232919 -216.735152) (xy 126.284096 -216.743258)
			(xy 126.333375 -216.75927) (xy 126.379542 -216.782793) (xy 126.421461 -216.813249) (xy 126.458099 -216.849887)
			(xy 126.488555 -216.891806) (xy 126.512078 -216.937973) (xy 126.52809 -216.987252) (xy 126.536196 -217.038429)
			(xy 126.536704 -217.064336) (xy 127.75692 -217.064336) (xy 127.757428 -217.038429) (xy 127.765534 -216.987252)
			(xy 127.781546 -216.937973) (xy 127.805069 -216.891806) (xy 127.835525 -216.849887) (xy 127.872163 -216.813249)
			(xy 127.914082 -216.782793) (xy 127.960249 -216.75927) (xy 128.009528 -216.743258) (xy 128.060705 -216.735152)
			(xy 128.112519 -216.735152) (xy 128.163696 -216.743258) (xy 128.212975 -216.75927) (xy 128.259142 -216.782793)
			(xy 128.301061 -216.813249) (xy 128.337699 -216.849887) (xy 128.368155 -216.891806) (xy 128.391678 -216.937973)
			(xy 128.40769 -216.987252) (xy 128.415796 -217.038429) (xy 128.416304 -217.064336) (xy 129.63652 -217.064336)
			(xy 129.637028 -217.038429) (xy 129.645134 -216.987252) (xy 129.661146 -216.937973) (xy 129.684669 -216.891806)
			(xy 129.715125 -216.849887) (xy 129.751763 -216.813249) (xy 129.793682 -216.782793) (xy 129.839849 -216.75927)
			(xy 129.889128 -216.743258) (xy 129.940305 -216.735152) (xy 129.992119 -216.735152) (xy 130.043296 -216.743258)
			(xy 130.092575 -216.75927) (xy 130.138742 -216.782793) (xy 130.180661 -216.813249) (xy 130.217299 -216.849887)
			(xy 130.247755 -216.891806) (xy 130.271278 -216.937973) (xy 130.28729 -216.987252) (xy 130.295396 -217.038429)
			(xy 130.295904 -217.064336) (xy 131.51612 -217.064336) (xy 131.516628 -217.038429) (xy 131.524734 -216.987252)
			(xy 131.540746 -216.937973) (xy 131.564269 -216.891806) (xy 131.594725 -216.849887) (xy 131.631363 -216.813249)
			(xy 131.673282 -216.782793) (xy 131.719449 -216.75927) (xy 131.768728 -216.743258) (xy 131.819905 -216.735152)
			(xy 131.871719 -216.735152) (xy 131.922896 -216.743258) (xy 131.972175 -216.75927) (xy 132.018342 -216.782793)
			(xy 132.060261 -216.813249) (xy 132.096899 -216.849887) (xy 132.127355 -216.891806) (xy 132.150878 -216.937973)
			(xy 132.16689 -216.987252) (xy 132.174996 -217.038429) (xy 132.175504 -217.064336) (xy 133.39572 -217.064336)
			(xy 133.396228 -217.038429) (xy 133.404334 -216.987252) (xy 133.420346 -216.937973) (xy 133.443869 -216.891806)
			(xy 133.474325 -216.849887) (xy 133.510963 -216.813249) (xy 133.552882 -216.782793) (xy 133.599049 -216.75927)
			(xy 133.648328 -216.743258) (xy 133.699505 -216.735152) (xy 133.751319 -216.735152) (xy 133.802496 -216.743258)
			(xy 133.851775 -216.75927) (xy 133.897942 -216.782793) (xy 133.939861 -216.813249) (xy 133.976499 -216.849887)
			(xy 134.006955 -216.891806) (xy 134.030478 -216.937973) (xy 134.04649 -216.987252) (xy 134.054596 -217.038429)
			(xy 134.055104 -217.064336) (xy 134.054489 -217.091989) (xy 134.045169 -217.146507) (xy 134.036562 -217.172794)
			(xy 134.028942 -217.194892) (xy 134.234174 -217.550238) (xy 134.257034 -217.554556) (xy 134.281841 -217.559728)
			(xy 134.329579 -217.576721) (xy 134.374156 -217.600818) (xy 134.41452 -217.631451) (xy 134.449723 -217.6679)
			(xy 134.478934 -217.709305) (xy 134.501466 -217.754693) (xy 134.516789 -217.802993) (xy 134.524541 -217.85307)
			(xy 134.525004 -217.878406) (xy 336.695796 -217.878406) (xy 336.696304 -217.852519) (xy 336.704403 -217.801381)
			(xy 336.720402 -217.752141) (xy 336.743908 -217.706009) (xy 336.77434 -217.664122) (xy 336.81095 -217.627512)
			(xy 336.852837 -217.59708) (xy 336.898969 -217.573574) (xy 336.948209 -217.557575) (xy 336.999347 -217.549476)
			(xy 337.051121 -217.549476) (xy 337.102259 -217.557575) (xy 337.151499 -217.573574) (xy 337.197631 -217.59708)
			(xy 337.239518 -217.627512) (xy 337.276128 -217.664122) (xy 337.30656 -217.706009) (xy 337.330066 -217.752141)
			(xy 337.346065 -217.801381) (xy 337.354164 -217.852519) (xy 337.354672 -217.878406) (xy 337.635596 -217.878406)
			(xy 337.636088 -217.853072) (xy 337.643839 -217.803) (xy 337.65916 -217.754704) (xy 337.681691 -217.70932)
			(xy 337.710899 -217.667918) (xy 337.746099 -217.631473) (xy 337.78646 -217.600842) (xy 337.831033 -217.576747)
			(xy 337.878767 -217.559756) (xy 337.903566 -217.554556) (xy 337.926426 -217.550238) (xy 338.131404 -217.195146)
			(xy 338.12353 -217.173302) (xy 338.114891 -217.146892) (xy 338.105567 -217.092117) (xy 338.104988 -217.064336)
			(xy 338.105496 -217.038429) (xy 338.113602 -216.987252) (xy 338.129614 -216.937973) (xy 338.153137 -216.891806)
			(xy 338.183593 -216.849887) (xy 338.220231 -216.813249) (xy 338.26215 -216.782793) (xy 338.308317 -216.75927)
			(xy 338.357596 -216.743258) (xy 338.408773 -216.735152) (xy 338.460587 -216.735152) (xy 338.511764 -216.743258)
			(xy 338.561043 -216.75927) (xy 338.60721 -216.782793) (xy 338.649129 -216.813249) (xy 338.685767 -216.849887)
			(xy 338.716223 -216.891806) (xy 338.739746 -216.937973) (xy 338.755758 -216.987252) (xy 338.763864 -217.038429)
			(xy 338.764372 -217.064336) (xy 338.763906 -217.089682) (xy 338.756128 -217.139773) (xy 338.740777 -217.188085)
			(xy 338.718213 -217.233478) (xy 338.688969 -217.274884) (xy 338.653734 -217.311328) (xy 338.613336 -217.34195)
			(xy 338.568729 -217.36603) (xy 338.520962 -217.383) (xy 338.496148 -217.388186) (xy 338.473288 -217.392504)
			(xy 338.26831 -217.747596) (xy 338.276184 -217.76944) (xy 338.284773 -217.795856) (xy 338.293963 -217.850633)
			(xy 338.294472 -217.878406) (xy 338.575396 -217.878406) (xy 338.575904 -217.852519) (xy 338.584003 -217.801381)
			(xy 338.600002 -217.752141) (xy 338.623508 -217.706009) (xy 338.65394 -217.664122) (xy 338.69055 -217.627512)
			(xy 338.732437 -217.59708) (xy 338.778569 -217.573574) (xy 338.827809 -217.557575) (xy 338.878947 -217.549476)
			(xy 338.930721 -217.549476) (xy 338.981859 -217.557575) (xy 339.031099 -217.573574) (xy 339.077231 -217.59708)
			(xy 339.119118 -217.627512) (xy 339.155728 -217.664122) (xy 339.18616 -217.706009) (xy 339.209666 -217.752141)
			(xy 339.225665 -217.801381) (xy 339.233764 -217.852519) (xy 339.234272 -217.878406) (xy 339.515196 -217.878406)
			(xy 339.515688 -217.853072) (xy 339.523439 -217.803) (xy 339.53876 -217.754704) (xy 339.561291 -217.70932)
			(xy 339.590499 -217.667918) (xy 339.625699 -217.631473) (xy 339.66606 -217.600842) (xy 339.710633 -217.576747)
			(xy 339.758367 -217.559756) (xy 339.783166 -217.554556) (xy 339.806026 -217.550238) (xy 340.011004 -217.195146)
			(xy 340.00313 -217.173302) (xy 339.994491 -217.146892) (xy 339.985167 -217.092117) (xy 339.984588 -217.064336)
			(xy 339.985096 -217.038429) (xy 339.993202 -216.987252) (xy 340.009214 -216.937973) (xy 340.032737 -216.891806)
			(xy 340.063193 -216.849887) (xy 340.099831 -216.813249) (xy 340.14175 -216.782793) (xy 340.187917 -216.75927)
			(xy 340.237196 -216.743258) (xy 340.288373 -216.735152) (xy 340.340187 -216.735152) (xy 340.391364 -216.743258)
			(xy 340.440643 -216.75927) (xy 340.48681 -216.782793) (xy 340.528729 -216.813249) (xy 340.565367 -216.849887)
			(xy 340.595823 -216.891806) (xy 340.619346 -216.937973) (xy 340.635358 -216.987252) (xy 340.643464 -217.038429)
			(xy 340.643972 -217.064336) (xy 340.643506 -217.089682) (xy 340.635728 -217.139773) (xy 340.620377 -217.188085)
			(xy 340.597813 -217.233478) (xy 340.568569 -217.274884) (xy 340.533334 -217.311328) (xy 340.492936 -217.34195)
			(xy 340.448329 -217.36603) (xy 340.400562 -217.383) (xy 340.375748 -217.388186) (xy 340.352888 -217.392504)
			(xy 340.14791 -217.747596) (xy 340.155784 -217.76944) (xy 340.164373 -217.795856) (xy 340.173563 -217.850633)
			(xy 340.174072 -217.878406) (xy 340.454996 -217.878406) (xy 340.455504 -217.852519) (xy 340.463603 -217.801381)
			(xy 340.479602 -217.752141) (xy 340.503108 -217.706009) (xy 340.53354 -217.664122) (xy 340.57015 -217.627512)
			(xy 340.612037 -217.59708) (xy 340.658169 -217.573574) (xy 340.707409 -217.557575) (xy 340.758547 -217.549476)
			(xy 340.810321 -217.549476) (xy 340.861459 -217.557575) (xy 340.910699 -217.573574) (xy 340.956831 -217.59708)
			(xy 340.998718 -217.627512) (xy 341.035328 -217.664122) (xy 341.06576 -217.706009) (xy 341.089266 -217.752141)
			(xy 341.105265 -217.801381) (xy 341.113364 -217.852519) (xy 341.113872 -217.878406) (xy 341.394796 -217.878406)
			(xy 341.395288 -217.853072) (xy 341.403039 -217.803) (xy 341.41836 -217.754704) (xy 341.440891 -217.70932)
			(xy 341.470099 -217.667918) (xy 341.505299 -217.631473) (xy 341.54566 -217.600842) (xy 341.590233 -217.576747)
			(xy 341.637967 -217.559756) (xy 341.662766 -217.554556) (xy 341.685626 -217.550238) (xy 341.890604 -217.195146)
			(xy 341.88273 -217.173302) (xy 341.874091 -217.146892) (xy 341.864767 -217.092117) (xy 341.864188 -217.064336)
			(xy 341.864696 -217.038429) (xy 341.872802 -216.987252) (xy 341.888814 -216.937973) (xy 341.912337 -216.891806)
			(xy 341.942793 -216.849887) (xy 341.979431 -216.813249) (xy 342.02135 -216.782793) (xy 342.067517 -216.75927)
			(xy 342.116796 -216.743258) (xy 342.167973 -216.735152) (xy 342.219787 -216.735152) (xy 342.270964 -216.743258)
			(xy 342.320243 -216.75927) (xy 342.36641 -216.782793) (xy 342.408329 -216.813249) (xy 342.444967 -216.849887)
			(xy 342.475423 -216.891806) (xy 342.498946 -216.937973) (xy 342.514958 -216.987252) (xy 342.523064 -217.038429)
			(xy 342.523572 -217.064336) (xy 342.523106 -217.089682) (xy 342.515328 -217.139773) (xy 342.499977 -217.188085)
			(xy 342.477413 -217.233478) (xy 342.448169 -217.274884) (xy 342.412934 -217.311328) (xy 342.372536 -217.34195)
			(xy 342.327929 -217.36603) (xy 342.280162 -217.383) (xy 342.255348 -217.388186) (xy 342.232488 -217.392504)
			(xy 342.02751 -217.747596) (xy 342.035384 -217.76944) (xy 342.043973 -217.795856) (xy 342.053163 -217.850633)
			(xy 342.053672 -217.878406) (xy 342.334596 -217.878406) (xy 342.335104 -217.852519) (xy 342.343203 -217.801381)
			(xy 342.359202 -217.752141) (xy 342.382708 -217.706009) (xy 342.41314 -217.664122) (xy 342.44975 -217.627512)
			(xy 342.491637 -217.59708) (xy 342.537769 -217.573574) (xy 342.587009 -217.557575) (xy 342.638147 -217.549476)
			(xy 342.689921 -217.549476) (xy 342.741059 -217.557575) (xy 342.790299 -217.573574) (xy 342.836431 -217.59708)
			(xy 342.878318 -217.627512) (xy 342.914928 -217.664122) (xy 342.94536 -217.706009) (xy 342.968866 -217.752141)
			(xy 342.984865 -217.801381) (xy 342.992964 -217.852519) (xy 342.993472 -217.878406) (xy 343.274396 -217.878406)
			(xy 343.274888 -217.853072) (xy 343.282639 -217.803) (xy 343.29796 -217.754704) (xy 343.320491 -217.70932)
			(xy 343.349699 -217.667918) (xy 343.384899 -217.631473) (xy 343.42526 -217.600842) (xy 343.469833 -217.576747)
			(xy 343.517567 -217.559756) (xy 343.542366 -217.554556) (xy 343.565226 -217.550238) (xy 343.770204 -217.195146)
			(xy 343.76233 -217.173302) (xy 343.753691 -217.146892) (xy 343.744367 -217.092117) (xy 343.743788 -217.064336)
			(xy 343.744296 -217.038429) (xy 343.752402 -216.987252) (xy 343.768414 -216.937973) (xy 343.791937 -216.891806)
			(xy 343.822393 -216.849887) (xy 343.859031 -216.813249) (xy 343.90095 -216.782793) (xy 343.947117 -216.75927)
			(xy 343.996396 -216.743258) (xy 344.047573 -216.735152) (xy 344.099387 -216.735152) (xy 344.150564 -216.743258)
			(xy 344.199843 -216.75927) (xy 344.24601 -216.782793) (xy 344.287929 -216.813249) (xy 344.324567 -216.849887)
			(xy 344.355023 -216.891806) (xy 344.378546 -216.937973) (xy 344.394558 -216.987252) (xy 344.402664 -217.038429)
			(xy 344.403172 -217.064336) (xy 344.402706 -217.089682) (xy 344.394928 -217.139773) (xy 344.379577 -217.188085)
			(xy 344.357013 -217.233478) (xy 344.327769 -217.274884) (xy 344.292534 -217.311328) (xy 344.252136 -217.34195)
			(xy 344.207529 -217.36603) (xy 344.159762 -217.383) (xy 344.134948 -217.388186) (xy 344.112088 -217.392504)
			(xy 343.90711 -217.747596) (xy 343.914984 -217.76944) (xy 343.923573 -217.795856) (xy 343.932763 -217.850633)
			(xy 343.933272 -217.878406) (xy 344.214196 -217.878406) (xy 344.214704 -217.852519) (xy 344.222803 -217.801381)
			(xy 344.238802 -217.752141) (xy 344.262308 -217.706009) (xy 344.29274 -217.664122) (xy 344.32935 -217.627512)
			(xy 344.371237 -217.59708) (xy 344.417369 -217.573574) (xy 344.466609 -217.557575) (xy 344.517747 -217.549476)
			(xy 344.569521 -217.549476) (xy 344.620659 -217.557575) (xy 344.669899 -217.573574) (xy 344.716031 -217.59708)
			(xy 344.757918 -217.627512) (xy 344.794528 -217.664122) (xy 344.82496 -217.706009) (xy 344.848466 -217.752141)
			(xy 344.864465 -217.801381) (xy 344.872564 -217.852519) (xy 344.873072 -217.878406) (xy 345.153996 -217.878406)
			(xy 345.154488 -217.853072) (xy 345.162239 -217.803) (xy 345.17756 -217.754704) (xy 345.200091 -217.70932)
			(xy 345.229299 -217.667918) (xy 345.264499 -217.631473) (xy 345.30486 -217.600842) (xy 345.349433 -217.576747)
			(xy 345.397167 -217.559756) (xy 345.421966 -217.554556) (xy 345.444826 -217.550238) (xy 345.649804 -217.195146)
			(xy 345.64193 -217.173302) (xy 345.633291 -217.146892) (xy 345.623967 -217.092117) (xy 345.623388 -217.064336)
			(xy 345.623896 -217.038429) (xy 345.632002 -216.987252) (xy 345.648014 -216.937973) (xy 345.671537 -216.891806)
			(xy 345.701993 -216.849887) (xy 345.738631 -216.813249) (xy 345.78055 -216.782793) (xy 345.826717 -216.75927)
			(xy 345.875996 -216.743258) (xy 345.927173 -216.735152) (xy 345.978987 -216.735152) (xy 346.030164 -216.743258)
			(xy 346.079443 -216.75927) (xy 346.12561 -216.782793) (xy 346.167529 -216.813249) (xy 346.204167 -216.849887)
			(xy 346.234623 -216.891806) (xy 346.258146 -216.937973) (xy 346.274158 -216.987252) (xy 346.282264 -217.038429)
			(xy 346.282772 -217.064336) (xy 346.282306 -217.089682) (xy 346.274528 -217.139773) (xy 346.259177 -217.188085)
			(xy 346.236613 -217.233478) (xy 346.207369 -217.274884) (xy 346.172134 -217.311328) (xy 346.131736 -217.34195)
			(xy 346.087129 -217.36603) (xy 346.039362 -217.383) (xy 346.014548 -217.388186) (xy 345.991688 -217.392504)
			(xy 345.78671 -217.747596) (xy 345.794584 -217.76944) (xy 345.803173 -217.795856) (xy 345.812363 -217.850633)
			(xy 345.812872 -217.878406) (xy 346.093796 -217.878406) (xy 346.094304 -217.852519) (xy 346.102403 -217.801381)
			(xy 346.118402 -217.752141) (xy 346.141908 -217.706009) (xy 346.17234 -217.664122) (xy 346.20895 -217.627512)
			(xy 346.250837 -217.59708) (xy 346.296969 -217.573574) (xy 346.346209 -217.557575) (xy 346.397347 -217.549476)
			(xy 346.449121 -217.549476) (xy 346.500259 -217.557575) (xy 346.549499 -217.573574) (xy 346.595631 -217.59708)
			(xy 346.637518 -217.627512) (xy 346.674128 -217.664122) (xy 346.70456 -217.706009) (xy 346.728066 -217.752141)
			(xy 346.744065 -217.801381) (xy 346.752164 -217.852519) (xy 346.752672 -217.878406) (xy 347.033596 -217.878406)
			(xy 347.034088 -217.853072) (xy 347.041839 -217.803) (xy 347.05716 -217.754704) (xy 347.079691 -217.70932)
			(xy 347.108899 -217.667918) (xy 347.144099 -217.631473) (xy 347.18446 -217.600842) (xy 347.229033 -217.576747)
			(xy 347.276767 -217.559756) (xy 347.301566 -217.554556) (xy 347.324426 -217.550238) (xy 347.529404 -217.195146)
			(xy 347.52153 -217.173302) (xy 347.512891 -217.146892) (xy 347.503567 -217.092117) (xy 347.502988 -217.064336)
			(xy 347.503496 -217.038429) (xy 347.511602 -216.987252) (xy 347.527614 -216.937973) (xy 347.551137 -216.891806)
			(xy 347.581593 -216.849887) (xy 347.618231 -216.813249) (xy 347.66015 -216.782793) (xy 347.706317 -216.75927)
			(xy 347.755596 -216.743258) (xy 347.806773 -216.735152) (xy 347.858587 -216.735152) (xy 347.909764 -216.743258)
			(xy 347.959043 -216.75927) (xy 348.00521 -216.782793) (xy 348.047129 -216.813249) (xy 348.083767 -216.849887)
			(xy 348.114223 -216.891806) (xy 348.137746 -216.937973) (xy 348.153758 -216.987252) (xy 348.161864 -217.038429)
			(xy 348.162372 -217.064336) (xy 348.161906 -217.089682) (xy 348.154128 -217.139773) (xy 348.138777 -217.188085)
			(xy 348.116213 -217.233478) (xy 348.086969 -217.274884) (xy 348.051734 -217.311328) (xy 348.011336 -217.34195)
			(xy 347.966729 -217.36603) (xy 347.918962 -217.383) (xy 347.894148 -217.388186) (xy 347.871288 -217.392504)
			(xy 347.66631 -217.747596) (xy 347.674184 -217.76944) (xy 347.682773 -217.795856) (xy 347.691963 -217.850633)
			(xy 347.692472 -217.878406) (xy 347.973396 -217.878406) (xy 347.973904 -217.852519) (xy 347.982003 -217.801381)
			(xy 347.998002 -217.752141) (xy 348.021508 -217.706009) (xy 348.05194 -217.664122) (xy 348.08855 -217.627512)
			(xy 348.130437 -217.59708) (xy 348.176569 -217.573574) (xy 348.225809 -217.557575) (xy 348.276947 -217.549476)
			(xy 348.328721 -217.549476) (xy 348.379859 -217.557575) (xy 348.429099 -217.573574) (xy 348.475231 -217.59708)
			(xy 348.517118 -217.627512) (xy 348.553728 -217.664122) (xy 348.58416 -217.706009) (xy 348.607666 -217.752141)
			(xy 348.623665 -217.801381) (xy 348.631764 -217.852519) (xy 348.632272 -217.878406) (xy 348.913196 -217.878406)
			(xy 348.913688 -217.853072) (xy 348.921439 -217.803) (xy 348.93676 -217.754704) (xy 348.959291 -217.70932)
			(xy 348.988499 -217.667918) (xy 349.023699 -217.631473) (xy 349.06406 -217.600842) (xy 349.108633 -217.576747)
			(xy 349.156367 -217.559756) (xy 349.181166 -217.554556) (xy 349.204026 -217.550238) (xy 349.409004 -217.195146)
			(xy 349.40113 -217.173302) (xy 349.392491 -217.146892) (xy 349.383167 -217.092117) (xy 349.382588 -217.064336)
			(xy 349.383096 -217.038429) (xy 349.391202 -216.987252) (xy 349.407214 -216.937973) (xy 349.430737 -216.891806)
			(xy 349.461193 -216.849887) (xy 349.497831 -216.813249) (xy 349.53975 -216.782793) (xy 349.585917 -216.75927)
			(xy 349.635196 -216.743258) (xy 349.686373 -216.735152) (xy 349.738187 -216.735152) (xy 349.789364 -216.743258)
			(xy 349.838643 -216.75927) (xy 349.88481 -216.782793) (xy 349.926729 -216.813249) (xy 349.963367 -216.849887)
			(xy 349.993823 -216.891806) (xy 350.017346 -216.937973) (xy 350.033358 -216.987252) (xy 350.041464 -217.038429)
			(xy 350.041972 -217.064336) (xy 350.041506 -217.089682) (xy 350.033728 -217.139773) (xy 350.018377 -217.188085)
			(xy 349.995813 -217.233478) (xy 349.966569 -217.274884) (xy 349.931334 -217.311328) (xy 349.890936 -217.34195)
			(xy 349.846329 -217.36603) (xy 349.798562 -217.383) (xy 349.773748 -217.388186) (xy 349.750888 -217.392504)
			(xy 349.54591 -217.747596) (xy 349.553784 -217.76944) (xy 349.562373 -217.795856) (xy 349.571563 -217.850633)
			(xy 349.572072 -217.878406) (xy 349.852996 -217.878406) (xy 349.853504 -217.852519) (xy 349.861603 -217.801381)
			(xy 349.877602 -217.752141) (xy 349.901108 -217.706009) (xy 349.93154 -217.664122) (xy 349.96815 -217.627512)
			(xy 350.010037 -217.59708) (xy 350.056169 -217.573574) (xy 350.105409 -217.557575) (xy 350.156547 -217.549476)
			(xy 350.208321 -217.549476) (xy 350.259459 -217.557575) (xy 350.308699 -217.573574) (xy 350.354831 -217.59708)
			(xy 350.396718 -217.627512) (xy 350.433328 -217.664122) (xy 350.46376 -217.706009) (xy 350.487266 -217.752141)
			(xy 350.503265 -217.801381) (xy 350.511364 -217.852519) (xy 350.511872 -217.878406) (xy 350.792796 -217.878406)
			(xy 350.793288 -217.853072) (xy 350.801039 -217.803) (xy 350.81636 -217.754704) (xy 350.838891 -217.70932)
			(xy 350.868099 -217.667918) (xy 350.903299 -217.631473) (xy 350.94366 -217.600842) (xy 350.988233 -217.576747)
			(xy 351.035967 -217.559756) (xy 351.060766 -217.554556) (xy 351.083626 -217.550238) (xy 351.288604 -217.195146)
			(xy 351.28073 -217.173302) (xy 351.272091 -217.146892) (xy 351.262767 -217.092117) (xy 351.262188 -217.064336)
			(xy 351.262696 -217.038429) (xy 351.270802 -216.987252) (xy 351.286814 -216.937973) (xy 351.310337 -216.891806)
			(xy 351.340793 -216.849887) (xy 351.377431 -216.813249) (xy 351.41935 -216.782793) (xy 351.465517 -216.75927)
			(xy 351.514796 -216.743258) (xy 351.565973 -216.735152) (xy 351.617787 -216.735152) (xy 351.668964 -216.743258)
			(xy 351.718243 -216.75927) (xy 351.76441 -216.782793) (xy 351.806329 -216.813249) (xy 351.842967 -216.849887)
			(xy 351.873423 -216.891806) (xy 351.896946 -216.937973) (xy 351.912958 -216.987252) (xy 351.921064 -217.038429)
			(xy 351.921572 -217.064336) (xy 351.921106 -217.089682) (xy 351.913328 -217.139773) (xy 351.897977 -217.188085)
			(xy 351.875413 -217.233478) (xy 351.846169 -217.274884) (xy 351.810934 -217.311328) (xy 351.770536 -217.34195)
			(xy 351.725929 -217.36603) (xy 351.678162 -217.383) (xy 351.653348 -217.388186) (xy 351.630488 -217.392504)
			(xy 351.42551 -217.747596) (xy 351.433384 -217.76944) (xy 351.441973 -217.795856) (xy 351.451163 -217.850633)
			(xy 351.451672 -217.878406) (xy 351.732596 -217.878406) (xy 351.733104 -217.852519) (xy 351.741203 -217.801381)
			(xy 351.757202 -217.752141) (xy 351.780708 -217.706009) (xy 351.81114 -217.664122) (xy 351.84775 -217.627512)
			(xy 351.889637 -217.59708) (xy 351.935769 -217.573574) (xy 351.985009 -217.557575) (xy 352.036147 -217.549476)
			(xy 352.087921 -217.549476) (xy 352.139059 -217.557575) (xy 352.188299 -217.573574) (xy 352.234431 -217.59708)
			(xy 352.276318 -217.627512) (xy 352.312928 -217.664122) (xy 352.34336 -217.706009) (xy 352.366866 -217.752141)
			(xy 352.382865 -217.801381) (xy 352.390964 -217.852519) (xy 352.391472 -217.878406) (xy 352.672396 -217.878406)
			(xy 352.672888 -217.853072) (xy 352.680639 -217.803) (xy 352.69596 -217.754704) (xy 352.718491 -217.70932)
			(xy 352.747699 -217.667918) (xy 352.782899 -217.631473) (xy 352.82326 -217.600842) (xy 352.867833 -217.576747)
			(xy 352.915567 -217.559756) (xy 352.940366 -217.554556) (xy 352.963226 -217.550238) (xy 353.168204 -217.195146)
			(xy 353.16033 -217.173302) (xy 353.151691 -217.146892) (xy 353.142367 -217.092117) (xy 353.141788 -217.064336)
			(xy 353.142296 -217.038429) (xy 353.150402 -216.987252) (xy 353.166414 -216.937973) (xy 353.189937 -216.891806)
			(xy 353.220393 -216.849887) (xy 353.257031 -216.813249) (xy 353.29895 -216.782793) (xy 353.345117 -216.75927)
			(xy 353.394396 -216.743258) (xy 353.445573 -216.735152) (xy 353.497387 -216.735152) (xy 353.548564 -216.743258)
			(xy 353.597843 -216.75927) (xy 353.64401 -216.782793) (xy 353.685929 -216.813249) (xy 353.722567 -216.849887)
			(xy 353.753023 -216.891806) (xy 353.776546 -216.937973) (xy 353.792558 -216.987252) (xy 353.800664 -217.038429)
			(xy 353.801172 -217.064336) (xy 353.800706 -217.089682) (xy 353.792928 -217.139773) (xy 353.777577 -217.188085)
			(xy 353.755013 -217.233478) (xy 353.725769 -217.274884) (xy 353.690534 -217.311328) (xy 353.650136 -217.34195)
			(xy 353.605529 -217.36603) (xy 353.557762 -217.383) (xy 353.532948 -217.388186) (xy 353.510088 -217.392504)
			(xy 353.30511 -217.747596) (xy 353.312984 -217.76944) (xy 353.321573 -217.795856) (xy 353.330763 -217.850633)
			(xy 353.331272 -217.878406) (xy 353.612196 -217.878406) (xy 353.612704 -217.852519) (xy 353.620803 -217.801381)
			(xy 353.636802 -217.752141) (xy 353.660308 -217.706009) (xy 353.69074 -217.664122) (xy 353.72735 -217.627512)
			(xy 353.769237 -217.59708) (xy 353.815369 -217.573574) (xy 353.864609 -217.557575) (xy 353.915747 -217.549476)
			(xy 353.967521 -217.549476) (xy 354.018659 -217.557575) (xy 354.067899 -217.573574) (xy 354.114031 -217.59708)
			(xy 354.155918 -217.627512) (xy 354.192528 -217.664122) (xy 354.22296 -217.706009) (xy 354.246466 -217.752141)
			(xy 354.262465 -217.801381) (xy 354.270564 -217.852519) (xy 354.271072 -217.878406) (xy 354.551996 -217.878406)
			(xy 354.552488 -217.853072) (xy 354.560239 -217.803) (xy 354.57556 -217.754704) (xy 354.598091 -217.70932)
			(xy 354.627299 -217.667918) (xy 354.662499 -217.631473) (xy 354.70286 -217.600842) (xy 354.747433 -217.576747)
			(xy 354.795167 -217.559756) (xy 354.819966 -217.554556) (xy 354.842826 -217.550238) (xy 355.047804 -217.195146)
			(xy 355.03993 -217.173302) (xy 355.031291 -217.146892) (xy 355.021967 -217.092117) (xy 355.021388 -217.064336)
			(xy 355.021896 -217.038429) (xy 355.030002 -216.987252) (xy 355.046014 -216.937973) (xy 355.069537 -216.891806)
			(xy 355.099993 -216.849887) (xy 355.136631 -216.813249) (xy 355.17855 -216.782793) (xy 355.224717 -216.75927)
			(xy 355.273996 -216.743258) (xy 355.325173 -216.735152) (xy 355.376987 -216.735152) (xy 355.428164 -216.743258)
			(xy 355.477443 -216.75927) (xy 355.52361 -216.782793) (xy 355.565529 -216.813249) (xy 355.602167 -216.849887)
			(xy 355.632623 -216.891806) (xy 355.656146 -216.937973) (xy 355.672158 -216.987252) (xy 355.680264 -217.038429)
			(xy 355.680772 -217.064336) (xy 355.680306 -217.089682) (xy 355.672528 -217.139773) (xy 355.657177 -217.188085)
			(xy 355.634613 -217.233478) (xy 355.605369 -217.274884) (xy 355.570134 -217.311328) (xy 355.529736 -217.34195)
			(xy 355.485129 -217.36603) (xy 355.437362 -217.383) (xy 355.412548 -217.388186) (xy 355.389688 -217.392504)
			(xy 355.18471 -217.747596) (xy 355.192584 -217.76944) (xy 355.201173 -217.795856) (xy 355.210363 -217.850633)
			(xy 355.210872 -217.878406) (xy 355.491796 -217.878406) (xy 355.492304 -217.852519) (xy 355.500403 -217.801381)
			(xy 355.516402 -217.752141) (xy 355.539908 -217.706009) (xy 355.57034 -217.664122) (xy 355.60695 -217.627512)
			(xy 355.648837 -217.59708) (xy 355.694969 -217.573574) (xy 355.744209 -217.557575) (xy 355.795347 -217.549476)
			(xy 355.847121 -217.549476) (xy 355.898259 -217.557575) (xy 355.947499 -217.573574) (xy 355.993631 -217.59708)
			(xy 356.035518 -217.627512) (xy 356.072128 -217.664122) (xy 356.10256 -217.706009) (xy 356.126066 -217.752141)
			(xy 356.142065 -217.801381) (xy 356.150164 -217.852519) (xy 356.150672 -217.878406) (xy 356.431596 -217.878406)
			(xy 356.432088 -217.853072) (xy 356.439839 -217.803) (xy 356.45516 -217.754704) (xy 356.477691 -217.70932)
			(xy 356.506899 -217.667918) (xy 356.542099 -217.631473) (xy 356.58246 -217.600842) (xy 356.627033 -217.576747)
			(xy 356.674767 -217.559756) (xy 356.699566 -217.554556) (xy 356.722426 -217.550238) (xy 356.927404 -217.195146)
			(xy 356.91953 -217.173302) (xy 356.910891 -217.146892) (xy 356.901567 -217.092117) (xy 356.900988 -217.064336)
			(xy 356.901496 -217.038429) (xy 356.909602 -216.987252) (xy 356.925614 -216.937973) (xy 356.949137 -216.891806)
			(xy 356.979593 -216.849887) (xy 357.016231 -216.813249) (xy 357.05815 -216.782793) (xy 357.104317 -216.75927)
			(xy 357.153596 -216.743258) (xy 357.204773 -216.735152) (xy 357.256587 -216.735152) (xy 357.307764 -216.743258)
			(xy 357.357043 -216.75927) (xy 357.40321 -216.782793) (xy 357.445129 -216.813249) (xy 357.481767 -216.849887)
			(xy 357.512223 -216.891806) (xy 357.535746 -216.937973) (xy 357.551758 -216.987252) (xy 357.559864 -217.038429)
			(xy 357.560372 -217.064336) (xy 357.559906 -217.089682) (xy 357.552128 -217.139773) (xy 357.536777 -217.188085)
			(xy 357.514213 -217.233478) (xy 357.484969 -217.274884) (xy 357.449734 -217.311328) (xy 357.409336 -217.34195)
			(xy 357.364729 -217.36603) (xy 357.316962 -217.383) (xy 357.292148 -217.388186) (xy 357.269288 -217.392504)
			(xy 357.06431 -217.747596) (xy 357.072184 -217.76944) (xy 357.080773 -217.795856) (xy 357.089963 -217.850633)
			(xy 357.090472 -217.878406) (xy 357.371396 -217.878406) (xy 357.371904 -217.852519) (xy 357.380003 -217.801381)
			(xy 357.396002 -217.752141) (xy 357.419508 -217.706009) (xy 357.44994 -217.664122) (xy 357.48655 -217.627512)
			(xy 357.528437 -217.59708) (xy 357.574569 -217.573574) (xy 357.623809 -217.557575) (xy 357.674947 -217.549476)
			(xy 357.726721 -217.549476) (xy 357.777859 -217.557575) (xy 357.827099 -217.573574) (xy 357.873231 -217.59708)
			(xy 357.915118 -217.627512) (xy 357.951728 -217.664122) (xy 357.98216 -217.706009) (xy 358.005666 -217.752141)
			(xy 358.021665 -217.801381) (xy 358.029764 -217.852519) (xy 358.030272 -217.878406) (xy 358.311196 -217.878406)
			(xy 358.311688 -217.853072) (xy 358.319439 -217.803) (xy 358.33476 -217.754704) (xy 358.357291 -217.70932)
			(xy 358.386499 -217.667918) (xy 358.421699 -217.631473) (xy 358.46206 -217.600842) (xy 358.506633 -217.576747)
			(xy 358.554367 -217.559756) (xy 358.579166 -217.554556) (xy 358.602026 -217.550238) (xy 358.807004 -217.194892)
			(xy 358.799384 -217.173048) (xy 358.790811 -217.146694) (xy 358.78162 -217.092045) (xy 358.781096 -217.064336)
			(xy 358.781604 -217.038449) (xy 358.789703 -216.987311) (xy 358.805702 -216.938071) (xy 358.829208 -216.891939)
			(xy 358.85964 -216.850052) (xy 358.89625 -216.813442) (xy 358.938137 -216.78301) (xy 358.984269 -216.759504)
			(xy 359.033509 -216.743505) (xy 359.084647 -216.735406) (xy 359.136421 -216.735406) (xy 359.187559 -216.743505)
			(xy 359.236799 -216.759504) (xy 359.282931 -216.78301) (xy 359.324818 -216.813442) (xy 359.361428 -216.850052)
			(xy 359.39186 -216.891939) (xy 359.415366 -216.938071) (xy 359.431365 -216.987311) (xy 359.439464 -217.038449)
			(xy 359.439972 -217.064336) (xy 360.660188 -217.064336) (xy 360.660696 -217.038429) (xy 360.668802 -216.987252)
			(xy 360.684814 -216.937973) (xy 360.708337 -216.891806) (xy 360.738793 -216.849887) (xy 360.775431 -216.813249)
			(xy 360.81735 -216.782793) (xy 360.863517 -216.75927) (xy 360.912796 -216.743258) (xy 360.963973 -216.735152)
			(xy 361.015787 -216.735152) (xy 361.066964 -216.743258) (xy 361.116243 -216.75927) (xy 361.16241 -216.782793)
			(xy 361.204329 -216.813249) (xy 361.240967 -216.849887) (xy 361.271423 -216.891806) (xy 361.294946 -216.937973)
			(xy 361.310958 -216.987252) (xy 361.319064 -217.038429) (xy 361.319572 -217.064336) (xy 362.539788 -217.064336)
			(xy 362.540296 -217.038429) (xy 362.548402 -216.987252) (xy 362.564414 -216.937973) (xy 362.587937 -216.891806)
			(xy 362.618393 -216.849887) (xy 362.655031 -216.813249) (xy 362.69695 -216.782793) (xy 362.743117 -216.75927)
			(xy 362.792396 -216.743258) (xy 362.843573 -216.735152) (xy 362.895387 -216.735152) (xy 362.946564 -216.743258)
			(xy 362.995843 -216.75927) (xy 363.04201 -216.782793) (xy 363.083929 -216.813249) (xy 363.120567 -216.849887)
			(xy 363.151023 -216.891806) (xy 363.174546 -216.937973) (xy 363.190558 -216.987252) (xy 363.198664 -217.038429)
			(xy 363.199172 -217.064336) (xy 364.419388 -217.064336) (xy 364.419896 -217.038429) (xy 364.428002 -216.987252)
			(xy 364.444014 -216.937973) (xy 364.467537 -216.891806) (xy 364.497993 -216.849887) (xy 364.534631 -216.813249)
			(xy 364.57655 -216.782793) (xy 364.622717 -216.75927) (xy 364.671996 -216.743258) (xy 364.723173 -216.735152)
			(xy 364.774987 -216.735152) (xy 364.826164 -216.743258) (xy 364.875443 -216.75927) (xy 364.92161 -216.782793)
			(xy 364.963529 -216.813249) (xy 365.000167 -216.849887) (xy 365.030623 -216.891806) (xy 365.054146 -216.937973)
			(xy 365.070158 -216.987252) (xy 365.078264 -217.038429) (xy 365.078772 -217.064336) (xy 366.298988 -217.064336)
			(xy 366.299496 -217.038429) (xy 366.307602 -216.987252) (xy 366.323614 -216.937973) (xy 366.347137 -216.891806)
			(xy 366.377593 -216.849887) (xy 366.414231 -216.813249) (xy 366.45615 -216.782793) (xy 366.502317 -216.75927)
			(xy 366.551596 -216.743258) (xy 366.602773 -216.735152) (xy 366.654587 -216.735152) (xy 366.705764 -216.743258)
			(xy 366.755043 -216.75927) (xy 366.80121 -216.782793) (xy 366.843129 -216.813249) (xy 366.879767 -216.849887)
			(xy 366.910223 -216.891806) (xy 366.933746 -216.937973) (xy 366.949758 -216.987252) (xy 366.957864 -217.038429)
			(xy 366.958372 -217.064336) (xy 368.178588 -217.064336) (xy 368.179096 -217.038429) (xy 368.187202 -216.987252)
			(xy 368.203214 -216.937973) (xy 368.226737 -216.891806) (xy 368.257193 -216.849887) (xy 368.293831 -216.813249)
			(xy 368.33575 -216.782793) (xy 368.381917 -216.75927) (xy 368.431196 -216.743258) (xy 368.482373 -216.735152)
			(xy 368.534187 -216.735152) (xy 368.585364 -216.743258) (xy 368.634643 -216.75927) (xy 368.68081 -216.782793)
			(xy 368.722729 -216.813249) (xy 368.759367 -216.849887) (xy 368.789823 -216.891806) (xy 368.813346 -216.937973)
			(xy 368.829358 -216.987252) (xy 368.837464 -217.038429) (xy 368.837972 -217.064336) (xy 370.058188 -217.064336)
			(xy 370.058696 -217.038429) (xy 370.066802 -216.987252) (xy 370.082814 -216.937973) (xy 370.106337 -216.891806)
			(xy 370.136793 -216.849887) (xy 370.173431 -216.813249) (xy 370.21535 -216.782793) (xy 370.261517 -216.75927)
			(xy 370.310796 -216.743258) (xy 370.361973 -216.735152) (xy 370.413787 -216.735152) (xy 370.464964 -216.743258)
			(xy 370.514243 -216.75927) (xy 370.56041 -216.782793) (xy 370.602329 -216.813249) (xy 370.638967 -216.849887)
			(xy 370.669423 -216.891806) (xy 370.692946 -216.937973) (xy 370.708958 -216.987252) (xy 370.717064 -217.038429)
			(xy 370.717572 -217.064336) (xy 371.937788 -217.064336) (xy 371.938296 -217.038429) (xy 371.946402 -216.987252)
			(xy 371.962414 -216.937973) (xy 371.985937 -216.891806) (xy 372.016393 -216.849887) (xy 372.053031 -216.813249)
			(xy 372.09495 -216.782793) (xy 372.141117 -216.75927) (xy 372.190396 -216.743258) (xy 372.241573 -216.735152)
			(xy 372.293387 -216.735152) (xy 372.344564 -216.743258) (xy 372.393843 -216.75927) (xy 372.44001 -216.782793)
			(xy 372.481929 -216.813249) (xy 372.518567 -216.849887) (xy 372.549023 -216.891806) (xy 372.572546 -216.937973)
			(xy 372.588558 -216.987252) (xy 372.596664 -217.038429) (xy 372.597172 -217.064336) (xy 373.817388 -217.064336)
			(xy 373.817896 -217.038429) (xy 373.826002 -216.987252) (xy 373.842014 -216.937973) (xy 373.865537 -216.891806)
			(xy 373.895993 -216.849887) (xy 373.932631 -216.813249) (xy 373.97455 -216.782793) (xy 374.020717 -216.75927)
			(xy 374.069996 -216.743258) (xy 374.121173 -216.735152) (xy 374.172987 -216.735152) (xy 374.224164 -216.743258)
			(xy 374.273443 -216.75927) (xy 374.31961 -216.782793) (xy 374.361529 -216.813249) (xy 374.398167 -216.849887)
			(xy 374.428623 -216.891806) (xy 374.452146 -216.937973) (xy 374.468158 -216.987252) (xy 374.476264 -217.038429)
			(xy 374.476772 -217.064336) (xy 375.696988 -217.064336) (xy 375.697496 -217.038429) (xy 375.705602 -216.987252)
			(xy 375.721614 -216.937973) (xy 375.745137 -216.891806) (xy 375.775593 -216.849887) (xy 375.812231 -216.813249)
			(xy 375.85415 -216.782793) (xy 375.900317 -216.75927) (xy 375.949596 -216.743258) (xy 376.000773 -216.735152)
			(xy 376.052587 -216.735152) (xy 376.103764 -216.743258) (xy 376.153043 -216.75927) (xy 376.19921 -216.782793)
			(xy 376.241129 -216.813249) (xy 376.277767 -216.849887) (xy 376.308223 -216.891806) (xy 376.331746 -216.937973)
			(xy 376.347758 -216.987252) (xy 376.355864 -217.038429) (xy 376.356372 -217.064336) (xy 377.576588 -217.064336)
			(xy 377.577096 -217.038429) (xy 377.585202 -216.987252) (xy 377.601214 -216.937973) (xy 377.624737 -216.891806)
			(xy 377.655193 -216.849887) (xy 377.691831 -216.813249) (xy 377.73375 -216.782793) (xy 377.779917 -216.75927)
			(xy 377.829196 -216.743258) (xy 377.880373 -216.735152) (xy 377.932187 -216.735152) (xy 377.983364 -216.743258)
			(xy 378.032643 -216.75927) (xy 378.07881 -216.782793) (xy 378.120729 -216.813249) (xy 378.157367 -216.849887)
			(xy 378.187823 -216.891806) (xy 378.211346 -216.937973) (xy 378.227358 -216.987252) (xy 378.235464 -217.038429)
			(xy 378.235972 -217.064336) (xy 379.456188 -217.064336) (xy 379.456696 -217.038429) (xy 379.464802 -216.987252)
			(xy 379.480814 -216.937973) (xy 379.504337 -216.891806) (xy 379.534793 -216.849887) (xy 379.571431 -216.813249)
			(xy 379.61335 -216.782793) (xy 379.659517 -216.75927) (xy 379.708796 -216.743258) (xy 379.759973 -216.735152)
			(xy 379.811787 -216.735152) (xy 379.862964 -216.743258) (xy 379.912243 -216.75927) (xy 379.95841 -216.782793)
			(xy 380.000329 -216.813249) (xy 380.036967 -216.849887) (xy 380.067423 -216.891806) (xy 380.090946 -216.937973)
			(xy 380.106958 -216.987252) (xy 380.115064 -217.038429) (xy 380.115572 -217.064336) (xy 381.335788 -217.064336)
			(xy 381.336296 -217.038429) (xy 381.344402 -216.987252) (xy 381.360414 -216.937973) (xy 381.383937 -216.891806)
			(xy 381.414393 -216.849887) (xy 381.451031 -216.813249) (xy 381.49295 -216.782793) (xy 381.539117 -216.75927)
			(xy 381.588396 -216.743258) (xy 381.639573 -216.735152) (xy 381.691387 -216.735152) (xy 381.742564 -216.743258)
			(xy 381.791843 -216.75927) (xy 381.83801 -216.782793) (xy 381.879929 -216.813249) (xy 381.916567 -216.849887)
			(xy 381.947023 -216.891806) (xy 381.970546 -216.937973) (xy 381.986558 -216.987252) (xy 381.994664 -217.038429)
			(xy 381.995172 -217.064336) (xy 381.994559 -217.091989) (xy 381.985238 -217.146507) (xy 381.97663 -217.172794)
			(xy 381.96901 -217.194892) (xy 382.174242 -217.550238) (xy 382.197102 -217.554556) (xy 382.221903 -217.559751)
			(xy 382.269642 -217.57674) (xy 382.314219 -217.600833) (xy 382.354584 -217.631463) (xy 382.389788 -217.667908)
			(xy 382.419 -217.709312) (xy 382.441533 -217.754697) (xy 382.456856 -217.802996) (xy 382.464608 -217.85307)
			(xy 382.465072 -217.878406) (xy 382.464564 -217.904293) (xy 382.456465 -217.955431) (xy 382.440466 -218.004671)
			(xy 382.41696 -218.050803) (xy 382.386528 -218.09269) (xy 382.349918 -218.1293) (xy 382.308031 -218.159732)
			(xy 382.261899 -218.183238) (xy 382.212659 -218.199237) (xy 382.161521 -218.207336) (xy 382.109747 -218.207336)
			(xy 382.058609 -218.199237) (xy 382.009369 -218.183238) (xy 381.963237 -218.159732) (xy 381.92135 -218.1293)
			(xy 381.88474 -218.09269) (xy 381.854308 -218.050803) (xy 381.830802 -218.004671) (xy 381.814803 -217.955431)
			(xy 381.806704 -217.904293) (xy 381.806196 -217.878406) (xy 381.806727 -217.850698) (xy 381.815921 -217.796051)
			(xy 381.824484 -217.769694) (xy 381.832358 -217.747596) (xy 381.62738 -217.392504) (xy 381.60452 -217.388186)
			(xy 381.579675 -217.38302) (xy 381.531826 -217.366126) (xy 381.487133 -217.342096) (xy 381.446653 -217.311499)
			(xy 381.411341 -217.275058) (xy 381.382033 -217.233634) (xy 381.359422 -217.188207) (xy 381.344043 -217.13985)
			(xy 381.336258 -217.089708) (xy 381.335788 -217.064336) (xy 380.115572 -217.064336) (xy 380.114959 -217.091989)
			(xy 380.105638 -217.146507) (xy 380.09703 -217.172794) (xy 380.08941 -217.194892) (xy 380.294642 -217.550238)
			(xy 380.317502 -217.554556) (xy 380.342303 -217.559751) (xy 380.390042 -217.57674) (xy 380.434619 -217.600833)
			(xy 380.474984 -217.631463) (xy 380.510188 -217.667908) (xy 380.5394 -217.709312) (xy 380.561933 -217.754697)
			(xy 380.577256 -217.802996) (xy 380.585008 -217.85307) (xy 380.585472 -217.878406) (xy 380.584964 -217.904293)
			(xy 380.576865 -217.955431) (xy 380.560866 -218.004671) (xy 380.53736 -218.050803) (xy 380.506928 -218.09269)
			(xy 380.470318 -218.1293) (xy 380.428431 -218.159732) (xy 380.382299 -218.183238) (xy 380.333059 -218.199237)
			(xy 380.281921 -218.207336) (xy 380.230147 -218.207336) (xy 380.179009 -218.199237) (xy 380.129769 -218.183238)
			(xy 380.083637 -218.159732) (xy 380.04175 -218.1293) (xy 380.00514 -218.09269) (xy 379.974708 -218.050803)
			(xy 379.951202 -218.004671) (xy 379.935203 -217.955431) (xy 379.927104 -217.904293) (xy 379.926596 -217.878406)
			(xy 379.927127 -217.850698) (xy 379.936321 -217.796051) (xy 379.944884 -217.769694) (xy 379.952758 -217.747596)
			(xy 379.74778 -217.392504) (xy 379.72492 -217.388186) (xy 379.700075 -217.38302) (xy 379.652226 -217.366126)
			(xy 379.607533 -217.342096) (xy 379.567053 -217.311499) (xy 379.531741 -217.275058) (xy 379.502433 -217.233634)
			(xy 379.479822 -217.188207) (xy 379.464443 -217.13985) (xy 379.456658 -217.089708) (xy 379.456188 -217.064336)
			(xy 378.235972 -217.064336) (xy 378.235359 -217.091989) (xy 378.226038 -217.146507) (xy 378.21743 -217.172794)
			(xy 378.20981 -217.194892) (xy 378.415042 -217.550238) (xy 378.437902 -217.554556) (xy 378.462703 -217.559751)
			(xy 378.510442 -217.57674) (xy 378.555019 -217.600833) (xy 378.595384 -217.631463) (xy 378.630588 -217.667908)
			(xy 378.6598 -217.709312) (xy 378.682333 -217.754697) (xy 378.697656 -217.802996) (xy 378.705408 -217.85307)
			(xy 378.705872 -217.878406) (xy 378.705364 -217.904293) (xy 378.697265 -217.955431) (xy 378.681266 -218.004671)
			(xy 378.65776 -218.050803) (xy 378.627328 -218.09269) (xy 378.590718 -218.1293) (xy 378.548831 -218.159732)
			(xy 378.502699 -218.183238) (xy 378.453459 -218.199237) (xy 378.402321 -218.207336) (xy 378.350547 -218.207336)
			(xy 378.299409 -218.199237) (xy 378.250169 -218.183238) (xy 378.204037 -218.159732) (xy 378.16215 -218.1293)
			(xy 378.12554 -218.09269) (xy 378.095108 -218.050803) (xy 378.071602 -218.004671) (xy 378.055603 -217.955431)
			(xy 378.047504 -217.904293) (xy 378.046996 -217.878406) (xy 378.047527 -217.850698) (xy 378.056721 -217.796051)
			(xy 378.065284 -217.769694) (xy 378.073158 -217.747596) (xy 377.86818 -217.392504) (xy 377.84532 -217.388186)
			(xy 377.820475 -217.38302) (xy 377.772626 -217.366126) (xy 377.727933 -217.342096) (xy 377.687453 -217.311499)
			(xy 377.652141 -217.275058) (xy 377.622833 -217.233634) (xy 377.600222 -217.188207) (xy 377.584843 -217.13985)
			(xy 377.577058 -217.089708) (xy 377.576588 -217.064336) (xy 376.356372 -217.064336) (xy 376.355759 -217.091989)
			(xy 376.346438 -217.146507) (xy 376.33783 -217.172794) (xy 376.33021 -217.194892) (xy 376.535442 -217.550238)
			(xy 376.558302 -217.554556) (xy 376.583103 -217.559751) (xy 376.630842 -217.57674) (xy 376.675419 -217.600833)
			(xy 376.715784 -217.631463) (xy 376.750988 -217.667908) (xy 376.7802 -217.709312) (xy 376.802733 -217.754697)
			(xy 376.818056 -217.802996) (xy 376.825808 -217.85307) (xy 376.826272 -217.878406) (xy 376.825764 -217.904293)
			(xy 376.817665 -217.955431) (xy 376.801666 -218.004671) (xy 376.77816 -218.050803) (xy 376.747728 -218.09269)
			(xy 376.711118 -218.1293) (xy 376.669231 -218.159732) (xy 376.623099 -218.183238) (xy 376.573859 -218.199237)
			(xy 376.522721 -218.207336) (xy 376.470947 -218.207336) (xy 376.419809 -218.199237) (xy 376.370569 -218.183238)
			(xy 376.324437 -218.159732) (xy 376.28255 -218.1293) (xy 376.24594 -218.09269) (xy 376.215508 -218.050803)
			(xy 376.192002 -218.004671) (xy 376.176003 -217.955431) (xy 376.167904 -217.904293) (xy 376.167396 -217.878406)
			(xy 376.167927 -217.850698) (xy 376.177121 -217.796051) (xy 376.185684 -217.769694) (xy 376.193558 -217.747596)
			(xy 375.98858 -217.392504) (xy 375.96572 -217.388186) (xy 375.940875 -217.38302) (xy 375.893026 -217.366126)
			(xy 375.848333 -217.342096) (xy 375.807853 -217.311499) (xy 375.772541 -217.275058) (xy 375.743233 -217.233634)
			(xy 375.720622 -217.188207) (xy 375.705243 -217.13985) (xy 375.697458 -217.089708) (xy 375.696988 -217.064336)
			(xy 374.476772 -217.064336) (xy 374.476159 -217.091989) (xy 374.466838 -217.146507) (xy 374.45823 -217.172794)
			(xy 374.45061 -217.194892) (xy 374.655842 -217.550238) (xy 374.678702 -217.554556) (xy 374.703503 -217.559751)
			(xy 374.751242 -217.57674) (xy 374.795819 -217.600833) (xy 374.836184 -217.631463) (xy 374.871388 -217.667908)
			(xy 374.9006 -217.709312) (xy 374.923133 -217.754697) (xy 374.938456 -217.802996) (xy 374.946208 -217.85307)
			(xy 374.946672 -217.878406) (xy 374.946164 -217.904293) (xy 374.938065 -217.955431) (xy 374.922066 -218.004671)
			(xy 374.89856 -218.050803) (xy 374.868128 -218.09269) (xy 374.831518 -218.1293) (xy 374.789631 -218.159732)
			(xy 374.743499 -218.183238) (xy 374.694259 -218.199237) (xy 374.643121 -218.207336) (xy 374.591347 -218.207336)
			(xy 374.540209 -218.199237) (xy 374.490969 -218.183238) (xy 374.444837 -218.159732) (xy 374.40295 -218.1293)
			(xy 374.36634 -218.09269) (xy 374.335908 -218.050803) (xy 374.312402 -218.004671) (xy 374.296403 -217.955431)
			(xy 374.288304 -217.904293) (xy 374.287796 -217.878406) (xy 374.288327 -217.850698) (xy 374.297521 -217.796051)
			(xy 374.306084 -217.769694) (xy 374.313958 -217.747596) (xy 374.10898 -217.392504) (xy 374.08612 -217.388186)
			(xy 374.061275 -217.38302) (xy 374.013426 -217.366126) (xy 373.968733 -217.342096) (xy 373.928253 -217.311499)
			(xy 373.892941 -217.275058) (xy 373.863633 -217.233634) (xy 373.841022 -217.188207) (xy 373.825643 -217.13985)
			(xy 373.817858 -217.089708) (xy 373.817388 -217.064336) (xy 372.597172 -217.064336) (xy 372.596559 -217.091989)
			(xy 372.587238 -217.146507) (xy 372.57863 -217.172794) (xy 372.57101 -217.194892) (xy 372.776242 -217.550238)
			(xy 372.799102 -217.554556) (xy 372.823903 -217.559751) (xy 372.871642 -217.57674) (xy 372.916219 -217.600833)
			(xy 372.956584 -217.631463) (xy 372.991788 -217.667908) (xy 373.021 -217.709312) (xy 373.043533 -217.754697)
			(xy 373.058856 -217.802996) (xy 373.066608 -217.85307) (xy 373.067072 -217.878406) (xy 373.066564 -217.904293)
			(xy 373.058465 -217.955431) (xy 373.042466 -218.004671) (xy 373.01896 -218.050803) (xy 372.988528 -218.09269)
			(xy 372.951918 -218.1293) (xy 372.910031 -218.159732) (xy 372.863899 -218.183238) (xy 372.814659 -218.199237)
			(xy 372.763521 -218.207336) (xy 372.711747 -218.207336) (xy 372.660609 -218.199237) (xy 372.611369 -218.183238)
			(xy 372.565237 -218.159732) (xy 372.52335 -218.1293) (xy 372.48674 -218.09269) (xy 372.456308 -218.050803)
			(xy 372.432802 -218.004671) (xy 372.416803 -217.955431) (xy 372.408704 -217.904293) (xy 372.408196 -217.878406)
			(xy 372.408727 -217.850698) (xy 372.417921 -217.796051) (xy 372.426484 -217.769694) (xy 372.434358 -217.747596)
			(xy 372.22938 -217.392504) (xy 372.20652 -217.388186) (xy 372.181675 -217.38302) (xy 372.133826 -217.366126)
			(xy 372.089133 -217.342096) (xy 372.048653 -217.311499) (xy 372.013341 -217.275058) (xy 371.984033 -217.233634)
			(xy 371.961422 -217.188207) (xy 371.946043 -217.13985) (xy 371.938258 -217.089708) (xy 371.937788 -217.064336)
			(xy 370.717572 -217.064336) (xy 370.716959 -217.091989) (xy 370.707638 -217.146507) (xy 370.69903 -217.172794)
			(xy 370.69141 -217.194892) (xy 370.896642 -217.550238) (xy 370.919502 -217.554556) (xy 370.944303 -217.559751)
			(xy 370.992042 -217.57674) (xy 371.036619 -217.600833) (xy 371.076984 -217.631463) (xy 371.112188 -217.667908)
			(xy 371.1414 -217.709312) (xy 371.163933 -217.754697) (xy 371.179256 -217.802996) (xy 371.187008 -217.85307)
			(xy 371.187472 -217.878406) (xy 371.186964 -217.904293) (xy 371.178865 -217.955431) (xy 371.162866 -218.004671)
			(xy 371.13936 -218.050803) (xy 371.108928 -218.09269) (xy 371.072318 -218.1293) (xy 371.030431 -218.159732)
			(xy 370.984299 -218.183238) (xy 370.935059 -218.199237) (xy 370.883921 -218.207336) (xy 370.832147 -218.207336)
			(xy 370.781009 -218.199237) (xy 370.731769 -218.183238) (xy 370.685637 -218.159732) (xy 370.64375 -218.1293)
			(xy 370.60714 -218.09269) (xy 370.576708 -218.050803) (xy 370.553202 -218.004671) (xy 370.537203 -217.955431)
			(xy 370.529104 -217.904293) (xy 370.528596 -217.878406) (xy 370.529127 -217.850698) (xy 370.538321 -217.796051)
			(xy 370.546884 -217.769694) (xy 370.554758 -217.747596) (xy 370.34978 -217.392504) (xy 370.32692 -217.388186)
			(xy 370.302075 -217.38302) (xy 370.254226 -217.366126) (xy 370.209533 -217.342096) (xy 370.169053 -217.311499)
			(xy 370.133741 -217.275058) (xy 370.104433 -217.233634) (xy 370.081822 -217.188207) (xy 370.066443 -217.13985)
			(xy 370.058658 -217.089708) (xy 370.058188 -217.064336) (xy 368.837972 -217.064336) (xy 368.837359 -217.091989)
			(xy 368.828038 -217.146507) (xy 368.81943 -217.172794) (xy 368.81181 -217.194892) (xy 369.017042 -217.550238)
			(xy 369.039902 -217.554556) (xy 369.064703 -217.559751) (xy 369.112442 -217.57674) (xy 369.157019 -217.600833)
			(xy 369.197384 -217.631463) (xy 369.232588 -217.667908) (xy 369.2618 -217.709312) (xy 369.284333 -217.754697)
			(xy 369.299656 -217.802996) (xy 369.307408 -217.85307) (xy 369.307872 -217.878406) (xy 369.307364 -217.904293)
			(xy 369.299265 -217.955431) (xy 369.283266 -218.004671) (xy 369.25976 -218.050803) (xy 369.229328 -218.09269)
			(xy 369.192718 -218.1293) (xy 369.150831 -218.159732) (xy 369.104699 -218.183238) (xy 369.055459 -218.199237)
			(xy 369.004321 -218.207336) (xy 368.952547 -218.207336) (xy 368.901409 -218.199237) (xy 368.852169 -218.183238)
			(xy 368.806037 -218.159732) (xy 368.76415 -218.1293) (xy 368.72754 -218.09269) (xy 368.697108 -218.050803)
			(xy 368.673602 -218.004671) (xy 368.657603 -217.955431) (xy 368.649504 -217.904293) (xy 368.648996 -217.878406)
			(xy 368.649527 -217.850698) (xy 368.658721 -217.796051) (xy 368.667284 -217.769694) (xy 368.675158 -217.747596)
			(xy 368.47018 -217.392504) (xy 368.44732 -217.388186) (xy 368.422475 -217.38302) (xy 368.374626 -217.366126)
			(xy 368.329933 -217.342096) (xy 368.289453 -217.311499) (xy 368.254141 -217.275058) (xy 368.224833 -217.233634)
			(xy 368.202222 -217.188207) (xy 368.186843 -217.13985) (xy 368.179058 -217.089708) (xy 368.178588 -217.064336)
			(xy 366.958372 -217.064336) (xy 366.957759 -217.091989) (xy 366.948438 -217.146507) (xy 366.93983 -217.172794)
			(xy 366.93221 -217.194892) (xy 367.137442 -217.550238) (xy 367.160302 -217.554556) (xy 367.185103 -217.559751)
			(xy 367.232842 -217.57674) (xy 367.277419 -217.600833) (xy 367.317784 -217.631463) (xy 367.352988 -217.667908)
			(xy 367.3822 -217.709312) (xy 367.404733 -217.754697) (xy 367.420056 -217.802996) (xy 367.427808 -217.85307)
			(xy 367.428272 -217.878406) (xy 367.427764 -217.904293) (xy 367.419665 -217.955431) (xy 367.403666 -218.004671)
			(xy 367.38016 -218.050803) (xy 367.349728 -218.09269) (xy 367.313118 -218.1293) (xy 367.271231 -218.159732)
			(xy 367.225099 -218.183238) (xy 367.175859 -218.199237) (xy 367.124721 -218.207336) (xy 367.072947 -218.207336)
			(xy 367.021809 -218.199237) (xy 366.972569 -218.183238) (xy 366.926437 -218.159732) (xy 366.88455 -218.1293)
			(xy 366.84794 -218.09269) (xy 366.817508 -218.050803) (xy 366.794002 -218.004671) (xy 366.778003 -217.955431)
			(xy 366.769904 -217.904293) (xy 366.769396 -217.878406) (xy 366.769927 -217.850698) (xy 366.779121 -217.796051)
			(xy 366.787684 -217.769694) (xy 366.795558 -217.747596) (xy 366.59058 -217.392504) (xy 366.56772 -217.388186)
			(xy 366.542875 -217.38302) (xy 366.495026 -217.366126) (xy 366.450333 -217.342096) (xy 366.409853 -217.311499)
			(xy 366.374541 -217.275058) (xy 366.345233 -217.233634) (xy 366.322622 -217.188207) (xy 366.307243 -217.13985)
			(xy 366.299458 -217.089708) (xy 366.298988 -217.064336) (xy 365.078772 -217.064336) (xy 365.078159 -217.091989)
			(xy 365.068838 -217.146507) (xy 365.06023 -217.172794) (xy 365.05261 -217.194892) (xy 365.257842 -217.550238)
			(xy 365.280702 -217.554556) (xy 365.305503 -217.559751) (xy 365.353242 -217.57674) (xy 365.397819 -217.600833)
			(xy 365.438184 -217.631463) (xy 365.473388 -217.667908) (xy 365.5026 -217.709312) (xy 365.525133 -217.754697)
			(xy 365.540456 -217.802996) (xy 365.548208 -217.85307) (xy 365.548672 -217.878406) (xy 365.548164 -217.904293)
			(xy 365.540065 -217.955431) (xy 365.524066 -218.004671) (xy 365.50056 -218.050803) (xy 365.470128 -218.09269)
			(xy 365.433518 -218.1293) (xy 365.391631 -218.159732) (xy 365.345499 -218.183238) (xy 365.296259 -218.199237)
			(xy 365.245121 -218.207336) (xy 365.193347 -218.207336) (xy 365.142209 -218.199237) (xy 365.092969 -218.183238)
			(xy 365.046837 -218.159732) (xy 365.00495 -218.1293) (xy 364.96834 -218.09269) (xy 364.937908 -218.050803)
			(xy 364.914402 -218.004671) (xy 364.898403 -217.955431) (xy 364.890304 -217.904293) (xy 364.889796 -217.878406)
			(xy 364.890327 -217.850698) (xy 364.899521 -217.796051) (xy 364.908084 -217.769694) (xy 364.915958 -217.747596)
			(xy 364.71098 -217.392504) (xy 364.68812 -217.388186) (xy 364.663275 -217.38302) (xy 364.615426 -217.366126)
			(xy 364.570733 -217.342096) (xy 364.530253 -217.311499) (xy 364.494941 -217.275058) (xy 364.465633 -217.233634)
			(xy 364.443022 -217.188207) (xy 364.427643 -217.13985) (xy 364.419858 -217.089708) (xy 364.419388 -217.064336)
			(xy 363.199172 -217.064336) (xy 363.198559 -217.091989) (xy 363.189238 -217.146507) (xy 363.18063 -217.172794)
			(xy 363.17301 -217.194892) (xy 363.378242 -217.550238) (xy 363.401102 -217.554556) (xy 363.425903 -217.559751)
			(xy 363.473642 -217.57674) (xy 363.518219 -217.600833) (xy 363.558584 -217.631463) (xy 363.593788 -217.667908)
			(xy 363.623 -217.709312) (xy 363.645533 -217.754697) (xy 363.660856 -217.802996) (xy 363.668608 -217.85307)
			(xy 363.669072 -217.878406) (xy 363.668564 -217.904293) (xy 363.660465 -217.955431) (xy 363.644466 -218.004671)
			(xy 363.62096 -218.050803) (xy 363.590528 -218.09269) (xy 363.553918 -218.1293) (xy 363.512031 -218.159732)
			(xy 363.465899 -218.183238) (xy 363.416659 -218.199237) (xy 363.365521 -218.207336) (xy 363.313747 -218.207336)
			(xy 363.262609 -218.199237) (xy 363.213369 -218.183238) (xy 363.167237 -218.159732) (xy 363.12535 -218.1293)
			(xy 363.08874 -218.09269) (xy 363.058308 -218.050803) (xy 363.034802 -218.004671) (xy 363.018803 -217.955431)
			(xy 363.010704 -217.904293) (xy 363.010196 -217.878406) (xy 363.010727 -217.850698) (xy 363.019921 -217.796051)
			(xy 363.028484 -217.769694) (xy 363.036358 -217.747596) (xy 362.83138 -217.392504) (xy 362.80852 -217.388186)
			(xy 362.783675 -217.38302) (xy 362.735826 -217.366126) (xy 362.691133 -217.342096) (xy 362.650653 -217.311499)
			(xy 362.615341 -217.275058) (xy 362.586033 -217.233634) (xy 362.563422 -217.188207) (xy 362.548043 -217.13985)
			(xy 362.540258 -217.089708) (xy 362.539788 -217.064336) (xy 361.319572 -217.064336) (xy 361.318959 -217.091989)
			(xy 361.309638 -217.146507) (xy 361.30103 -217.172794) (xy 361.29341 -217.194892) (xy 361.498642 -217.550238)
			(xy 361.521502 -217.554556) (xy 361.546303 -217.559751) (xy 361.594042 -217.57674) (xy 361.638619 -217.600833)
			(xy 361.678984 -217.631463) (xy 361.714188 -217.667908) (xy 361.7434 -217.709312) (xy 361.765933 -217.754697)
			(xy 361.781256 -217.802996) (xy 361.789008 -217.85307) (xy 361.789472 -217.878406) (xy 361.788964 -217.904293)
			(xy 361.780865 -217.955431) (xy 361.764866 -218.004671) (xy 361.74136 -218.050803) (xy 361.710928 -218.09269)
			(xy 361.674318 -218.1293) (xy 361.632431 -218.159732) (xy 361.586299 -218.183238) (xy 361.537059 -218.199237)
			(xy 361.485921 -218.207336) (xy 361.434147 -218.207336) (xy 361.383009 -218.199237) (xy 361.333769 -218.183238)
			(xy 361.287637 -218.159732) (xy 361.24575 -218.1293) (xy 361.20914 -218.09269) (xy 361.178708 -218.050803)
			(xy 361.155202 -218.004671) (xy 361.139203 -217.955431) (xy 361.131104 -217.904293) (xy 361.130596 -217.878406)
			(xy 361.131127 -217.850698) (xy 361.140321 -217.796051) (xy 361.148884 -217.769694) (xy 361.156758 -217.747596)
			(xy 360.95178 -217.392504) (xy 360.92892 -217.388186) (xy 360.904075 -217.38302) (xy 360.856226 -217.366126)
			(xy 360.811533 -217.342096) (xy 360.771053 -217.311499) (xy 360.735741 -217.275058) (xy 360.706433 -217.233634)
			(xy 360.683822 -217.188207) (xy 360.668443 -217.13985) (xy 360.660658 -217.089708) (xy 360.660188 -217.064336)
			(xy 359.439972 -217.064336) (xy 359.439506 -217.089682) (xy 359.431728 -217.139773) (xy 359.416377 -217.188085)
			(xy 359.393813 -217.233478) (xy 359.364569 -217.274884) (xy 359.329334 -217.311328) (xy 359.288936 -217.34195)
			(xy 359.244329 -217.36603) (xy 359.196562 -217.383) (xy 359.171748 -217.388186) (xy 359.148888 -217.392504)
			(xy 358.94391 -217.747596) (xy 358.951784 -217.76944) (xy 358.960373 -217.795856) (xy 358.969563 -217.850633)
			(xy 358.970072 -217.878406) (xy 358.969564 -217.904293) (xy 358.961465 -217.955431) (xy 358.945466 -218.004671)
			(xy 358.92196 -218.050803) (xy 358.891528 -218.09269) (xy 358.854918 -218.1293) (xy 358.813031 -218.159732)
			(xy 358.766899 -218.183238) (xy 358.717659 -218.199237) (xy 358.666521 -218.207336) (xy 358.614747 -218.207336)
			(xy 358.563609 -218.199237) (xy 358.514369 -218.183238) (xy 358.468237 -218.159732) (xy 358.42635 -218.1293)
			(xy 358.38974 -218.09269) (xy 358.359308 -218.050803) (xy 358.335802 -218.004671) (xy 358.319803 -217.955431)
			(xy 358.311704 -217.904293) (xy 358.311196 -217.878406) (xy 358.030272 -217.878406) (xy 358.029741 -217.906114)
			(xy 358.020546 -217.960761) (xy 358.011984 -217.987118) (xy 358.004364 -218.008962) (xy 358.209342 -218.364054)
			(xy 358.232202 -218.368372) (xy 358.257007 -218.373552) (xy 358.304747 -218.390542) (xy 358.349324 -218.414636)
			(xy 358.38969 -218.445268) (xy 358.424894 -218.481716) (xy 358.454106 -218.523121) (xy 358.476638 -218.568508)
			(xy 358.491959 -218.616809) (xy 358.49971 -218.666886) (xy 358.500172 -218.692222) (xy 359.720388 -218.692222)
			(xy 359.720939 -218.66688) (xy 359.728707 -218.616793) (xy 359.744048 -218.568485) (xy 359.766601 -218.523094)
			(xy 359.795834 -218.481689) (xy 359.831059 -218.445245) (xy 359.871446 -218.41462) (xy 359.916044 -218.390537)
			(xy 359.963802 -218.373561) (xy 359.988612 -218.368372) (xy 360.011472 -218.364054) (xy 360.216704 -218.008708)
			(xy 360.20883 -217.98661) (xy 360.200361 -217.960367) (xy 360.191292 -217.905977) (xy 360.190796 -217.878406)
			(xy 360.191304 -217.852519) (xy 360.199403 -217.801381) (xy 360.215402 -217.752141) (xy 360.238908 -217.706009)
			(xy 360.26934 -217.664122) (xy 360.30595 -217.627512) (xy 360.347837 -217.59708) (xy 360.393969 -217.573574)
			(xy 360.443209 -217.557575) (xy 360.494347 -217.549476) (xy 360.546121 -217.549476) (xy 360.597259 -217.557575)
			(xy 360.646499 -217.573574) (xy 360.692631 -217.59708) (xy 360.734518 -217.627512) (xy 360.771128 -217.664122)
			(xy 360.80156 -217.706009) (xy 360.825066 -217.752141) (xy 360.841065 -217.801381) (xy 360.849164 -217.852519)
			(xy 360.849672 -217.878406) (xy 360.849225 -217.903782) (xy 360.841455 -217.953934) (xy 360.826085 -218.002302)
			(xy 360.803477 -218.047739) (xy 360.774167 -218.089171) (xy 360.73885 -218.125617) (xy 360.69836 -218.156215)
			(xy 360.653656 -218.18024) (xy 360.605796 -218.197124) (xy 360.58094 -218.202256) (xy 360.55808 -218.206574)
			(xy 360.353356 -218.561412) (xy 360.36123 -218.583256) (xy 360.369881 -218.609663) (xy 360.379198 -218.66444)
			(xy 360.379772 -218.692222) (xy 361.600496 -218.692222) (xy 361.601002 -218.666888) (xy 361.608751 -218.616817)
			(xy 361.62407 -218.568521) (xy 361.646599 -218.523138) (xy 361.675805 -218.481736) (xy 361.711003 -218.44529)
			(xy 361.751363 -218.414659) (xy 361.795934 -218.390564) (xy 361.843667 -218.373572) (xy 361.868466 -218.368372)
			(xy 361.891326 -218.364054) (xy 362.096304 -218.008962) (xy 362.088684 -217.986864) (xy 362.080159 -217.960694)
			(xy 362.070969 -217.906431) (xy 362.070396 -217.878914) (xy 362.070396 -217.878406) (xy 362.070904 -217.852519)
			(xy 362.079003 -217.801381) (xy 362.095002 -217.752141) (xy 362.118508 -217.706009) (xy 362.14894 -217.664122)
			(xy 362.18555 -217.627512) (xy 362.227437 -217.59708) (xy 362.273569 -217.573574) (xy 362.322809 -217.557575)
			(xy 362.373947 -217.549476) (xy 362.425721 -217.549476) (xy 362.476859 -217.557575) (xy 362.526099 -217.573574)
			(xy 362.572231 -217.59708) (xy 362.614118 -217.627512) (xy 362.650728 -217.664122) (xy 362.68116 -217.706009)
			(xy 362.704666 -217.752141) (xy 362.720665 -217.801381) (xy 362.728764 -217.852519) (xy 362.729272 -217.878406)
			(xy 362.728863 -217.903772) (xy 362.721112 -217.953909) (xy 362.705764 -218.002264) (xy 362.683182 -218.047694)
			(xy 362.6539 -218.089122) (xy 362.61861 -218.12557) (xy 362.578149 -218.156175) (xy 362.533472 -218.180212)
			(xy 362.485638 -218.197113) (xy 362.460794 -218.202256) (xy 362.437934 -218.206574) (xy 362.23321 -218.561412)
			(xy 362.241084 -218.583256) (xy 362.249677 -218.609671) (xy 362.258865 -218.664449) (xy 362.259372 -218.692222)
			(xy 363.479588 -218.692222) (xy 363.480139 -218.66688) (xy 363.487907 -218.616793) (xy 363.503248 -218.568485)
			(xy 363.525801 -218.523094) (xy 363.555034 -218.481689) (xy 363.590259 -218.445245) (xy 363.630646 -218.41462)
			(xy 363.675244 -218.390537) (xy 363.723002 -218.373561) (xy 363.747812 -218.368372) (xy 363.770672 -218.364054)
			(xy 363.975904 -218.008708) (xy 363.96803 -217.98661) (xy 363.959561 -217.960367) (xy 363.950492 -217.905977)
			(xy 363.949996 -217.878406) (xy 363.950504 -217.852519) (xy 363.958603 -217.801381) (xy 363.974602 -217.752141)
			(xy 363.998108 -217.706009) (xy 364.02854 -217.664122) (xy 364.06515 -217.627512) (xy 364.107037 -217.59708)
			(xy 364.153169 -217.573574) (xy 364.202409 -217.557575) (xy 364.253547 -217.549476) (xy 364.305321 -217.549476)
			(xy 364.356459 -217.557575) (xy 364.405699 -217.573574) (xy 364.451831 -217.59708) (xy 364.493718 -217.627512)
			(xy 364.530328 -217.664122) (xy 364.56076 -217.706009) (xy 364.584266 -217.752141) (xy 364.600265 -217.801381)
			(xy 364.608364 -217.852519) (xy 364.608872 -217.878406) (xy 364.608425 -217.903782) (xy 364.600655 -217.953934)
			(xy 364.585285 -218.002302) (xy 364.562677 -218.047739) (xy 364.533367 -218.089171) (xy 364.49805 -218.125617)
			(xy 364.45756 -218.156215) (xy 364.412856 -218.18024) (xy 364.364996 -218.197124) (xy 364.34014 -218.202256)
			(xy 364.31728 -218.206574) (xy 364.112556 -218.561412) (xy 364.12043 -218.583256) (xy 364.129081 -218.609663)
			(xy 364.138398 -218.66444) (xy 364.138972 -218.692222) (xy 365.359188 -218.692222) (xy 365.359739 -218.66688)
			(xy 365.367507 -218.616793) (xy 365.382848 -218.568485) (xy 365.405401 -218.523094) (xy 365.434634 -218.481689)
			(xy 365.469859 -218.445245) (xy 365.510246 -218.41462) (xy 365.554844 -218.390537) (xy 365.602602 -218.373561)
			(xy 365.627412 -218.368372) (xy 365.650272 -218.364054) (xy 365.855504 -218.008708) (xy 365.84763 -217.98661)
			(xy 365.839161 -217.960367) (xy 365.830092 -217.905977) (xy 365.829596 -217.878406) (xy 365.830104 -217.852519)
			(xy 365.838203 -217.801381) (xy 365.854202 -217.752141) (xy 365.877708 -217.706009) (xy 365.90814 -217.664122)
			(xy 365.94475 -217.627512) (xy 365.986637 -217.59708) (xy 366.032769 -217.573574) (xy 366.082009 -217.557575)
			(xy 366.133147 -217.549476) (xy 366.184921 -217.549476) (xy 366.236059 -217.557575) (xy 366.285299 -217.573574)
			(xy 366.331431 -217.59708) (xy 366.373318 -217.627512) (xy 366.409928 -217.664122) (xy 366.44036 -217.706009)
			(xy 366.463866 -217.752141) (xy 366.479865 -217.801381) (xy 366.487964 -217.852519) (xy 366.488472 -217.878406)
			(xy 366.488025 -217.903782) (xy 366.480255 -217.953934) (xy 366.464885 -218.002302) (xy 366.442277 -218.047739)
			(xy 366.412967 -218.089171) (xy 366.37765 -218.125617) (xy 366.33716 -218.156215) (xy 366.292456 -218.18024)
			(xy 366.244596 -218.197124) (xy 366.21974 -218.202256) (xy 366.19688 -218.206574) (xy 365.992156 -218.561412)
			(xy 366.00003 -218.583256) (xy 366.008681 -218.609663) (xy 366.017998 -218.66444) (xy 366.018572 -218.692222)
			(xy 367.238788 -218.692222) (xy 367.239339 -218.66688) (xy 367.247107 -218.616793) (xy 367.262448 -218.568485)
			(xy 367.285001 -218.523094) (xy 367.314234 -218.481689) (xy 367.349459 -218.445245) (xy 367.389846 -218.41462)
			(xy 367.434444 -218.390537) (xy 367.482202 -218.373561) (xy 367.507012 -218.368372) (xy 367.529872 -218.364054)
			(xy 367.735104 -218.008708) (xy 367.72723 -217.98661) (xy 367.718761 -217.960367) (xy 367.709692 -217.905977)
			(xy 367.709196 -217.878406) (xy 367.709704 -217.852519) (xy 367.717803 -217.801381) (xy 367.733802 -217.752141)
			(xy 367.757308 -217.706009) (xy 367.78774 -217.664122) (xy 367.82435 -217.627512) (xy 367.866237 -217.59708)
			(xy 367.912369 -217.573574) (xy 367.961609 -217.557575) (xy 368.012747 -217.549476) (xy 368.064521 -217.549476)
			(xy 368.115659 -217.557575) (xy 368.164899 -217.573574) (xy 368.211031 -217.59708) (xy 368.252918 -217.627512)
			(xy 368.289528 -217.664122) (xy 368.31996 -217.706009) (xy 368.343466 -217.752141) (xy 368.359465 -217.801381)
			(xy 368.367564 -217.852519) (xy 368.368072 -217.878406) (xy 368.367625 -217.903782) (xy 368.359855 -217.953934)
			(xy 368.344485 -218.002302) (xy 368.321877 -218.047739) (xy 368.292567 -218.089171) (xy 368.25725 -218.125617)
			(xy 368.21676 -218.156215) (xy 368.172056 -218.18024) (xy 368.124196 -218.197124) (xy 368.09934 -218.202256)
			(xy 368.07648 -218.206574) (xy 367.871756 -218.561412) (xy 367.87963 -218.583256) (xy 367.888281 -218.609663)
			(xy 367.897598 -218.66444) (xy 367.898172 -218.692222) (xy 369.118388 -218.692222) (xy 369.118939 -218.66688)
			(xy 369.126707 -218.616793) (xy 369.142048 -218.568485) (xy 369.164601 -218.523094) (xy 369.193834 -218.481689)
			(xy 369.229059 -218.445245) (xy 369.269446 -218.41462) (xy 369.314044 -218.390537) (xy 369.361802 -218.373561)
			(xy 369.386612 -218.368372) (xy 369.409472 -218.364054) (xy 369.614704 -218.008708) (xy 369.60683 -217.98661)
			(xy 369.598361 -217.960367) (xy 369.589292 -217.905977) (xy 369.588796 -217.878406) (xy 369.589304 -217.852519)
			(xy 369.597403 -217.801381) (xy 369.613402 -217.752141) (xy 369.636908 -217.706009) (xy 369.66734 -217.664122)
			(xy 369.70395 -217.627512) (xy 369.745837 -217.59708) (xy 369.791969 -217.573574) (xy 369.841209 -217.557575)
			(xy 369.892347 -217.549476) (xy 369.944121 -217.549476) (xy 369.995259 -217.557575) (xy 370.044499 -217.573574)
			(xy 370.090631 -217.59708) (xy 370.132518 -217.627512) (xy 370.169128 -217.664122) (xy 370.19956 -217.706009)
			(xy 370.223066 -217.752141) (xy 370.239065 -217.801381) (xy 370.247164 -217.852519) (xy 370.247672 -217.878406)
			(xy 370.247225 -217.903782) (xy 370.239455 -217.953934) (xy 370.224085 -218.002302) (xy 370.201477 -218.047739)
			(xy 370.172167 -218.089171) (xy 370.13685 -218.125617) (xy 370.09636 -218.156215) (xy 370.051656 -218.18024)
			(xy 370.003796 -218.197124) (xy 369.97894 -218.202256) (xy 369.95608 -218.206574) (xy 369.751356 -218.561412)
			(xy 369.75923 -218.583256) (xy 369.767881 -218.609663) (xy 369.777198 -218.66444) (xy 369.777772 -218.692222)
			(xy 370.997988 -218.692222) (xy 370.998539 -218.66688) (xy 371.006307 -218.616793) (xy 371.021648 -218.568485)
			(xy 371.044201 -218.523094) (xy 371.073434 -218.481689) (xy 371.108659 -218.445245) (xy 371.149046 -218.41462)
			(xy 371.193644 -218.390537) (xy 371.241402 -218.373561) (xy 371.266212 -218.368372) (xy 371.289072 -218.364054)
			(xy 371.494304 -218.008708) (xy 371.48643 -217.98661) (xy 371.477961 -217.960367) (xy 371.468892 -217.905977)
			(xy 371.468396 -217.878406) (xy 371.468904 -217.852519) (xy 371.477003 -217.801381) (xy 371.493002 -217.752141)
			(xy 371.516508 -217.706009) (xy 371.54694 -217.664122) (xy 371.58355 -217.627512) (xy 371.625437 -217.59708)
			(xy 371.671569 -217.573574) (xy 371.720809 -217.557575) (xy 371.771947 -217.549476) (xy 371.823721 -217.549476)
			(xy 371.874859 -217.557575) (xy 371.924099 -217.573574) (xy 371.970231 -217.59708) (xy 372.012118 -217.627512)
			(xy 372.048728 -217.664122) (xy 372.07916 -217.706009) (xy 372.102666 -217.752141) (xy 372.118665 -217.801381)
			(xy 372.126764 -217.852519) (xy 372.127272 -217.878406) (xy 372.126825 -217.903782) (xy 372.119055 -217.953934)
			(xy 372.103685 -218.002302) (xy 372.081077 -218.047739) (xy 372.051767 -218.089171) (xy 372.01645 -218.125617)
			(xy 371.97596 -218.156215) (xy 371.931256 -218.18024) (xy 371.883396 -218.197124) (xy 371.85854 -218.202256)
			(xy 371.83568 -218.206574) (xy 371.630956 -218.561412) (xy 371.63883 -218.583256) (xy 371.647481 -218.609663)
			(xy 371.656798 -218.66444) (xy 371.657372 -218.692222) (xy 372.877588 -218.692222) (xy 372.878139 -218.66688)
			(xy 372.885907 -218.616793) (xy 372.901248 -218.568485) (xy 372.923801 -218.523094) (xy 372.953034 -218.481689)
			(xy 372.988259 -218.445245) (xy 373.028646 -218.41462) (xy 373.073244 -218.390537) (xy 373.121002 -218.373561)
			(xy 373.145812 -218.368372) (xy 373.168672 -218.364054) (xy 373.373904 -218.008708) (xy 373.36603 -217.98661)
			(xy 373.357561 -217.960367) (xy 373.348492 -217.905977) (xy 373.347996 -217.878406) (xy 373.348504 -217.852519)
			(xy 373.356603 -217.801381) (xy 373.372602 -217.752141) (xy 373.396108 -217.706009) (xy 373.42654 -217.664122)
			(xy 373.46315 -217.627512) (xy 373.505037 -217.59708) (xy 373.551169 -217.573574) (xy 373.600409 -217.557575)
			(xy 373.651547 -217.549476) (xy 373.703321 -217.549476) (xy 373.754459 -217.557575) (xy 373.803699 -217.573574)
			(xy 373.849831 -217.59708) (xy 373.891718 -217.627512) (xy 373.928328 -217.664122) (xy 373.95876 -217.706009)
			(xy 373.982266 -217.752141) (xy 373.998265 -217.801381) (xy 374.006364 -217.852519) (xy 374.006872 -217.878406)
			(xy 374.006425 -217.903782) (xy 373.998655 -217.953934) (xy 373.983285 -218.002302) (xy 373.960677 -218.047739)
			(xy 373.931367 -218.089171) (xy 373.89605 -218.125617) (xy 373.85556 -218.156215) (xy 373.810856 -218.18024)
			(xy 373.762996 -218.197124) (xy 373.73814 -218.202256) (xy 373.71528 -218.206574) (xy 373.510556 -218.561412)
			(xy 373.51843 -218.583256) (xy 373.527081 -218.609663) (xy 373.536398 -218.66444) (xy 373.536972 -218.692222)
			(xy 374.757188 -218.692222) (xy 374.757739 -218.66688) (xy 374.765507 -218.616793) (xy 374.780848 -218.568485)
			(xy 374.803401 -218.523094) (xy 374.832634 -218.481689) (xy 374.867859 -218.445245) (xy 374.908246 -218.41462)
			(xy 374.952844 -218.390537) (xy 375.000602 -218.373561) (xy 375.025412 -218.368372) (xy 375.048272 -218.364054)
			(xy 375.253504 -218.008708) (xy 375.24563 -217.98661) (xy 375.237161 -217.960367) (xy 375.228092 -217.905977)
			(xy 375.227596 -217.878406) (xy 375.228104 -217.852519) (xy 375.236203 -217.801381) (xy 375.252202 -217.752141)
			(xy 375.275708 -217.706009) (xy 375.30614 -217.664122) (xy 375.34275 -217.627512) (xy 375.384637 -217.59708)
			(xy 375.430769 -217.573574) (xy 375.480009 -217.557575) (xy 375.531147 -217.549476) (xy 375.582921 -217.549476)
			(xy 375.634059 -217.557575) (xy 375.683299 -217.573574) (xy 375.729431 -217.59708) (xy 375.771318 -217.627512)
			(xy 375.807928 -217.664122) (xy 375.83836 -217.706009) (xy 375.861866 -217.752141) (xy 375.877865 -217.801381)
			(xy 375.885964 -217.852519) (xy 375.886472 -217.878406) (xy 375.886025 -217.903782) (xy 375.878255 -217.953934)
			(xy 375.862885 -218.002302) (xy 375.840277 -218.047739) (xy 375.810967 -218.089171) (xy 375.77565 -218.125617)
			(xy 375.73516 -218.156215) (xy 375.690456 -218.18024) (xy 375.642596 -218.197124) (xy 375.61774 -218.202256)
			(xy 375.59488 -218.206574) (xy 375.390156 -218.561412) (xy 375.39803 -218.583256) (xy 375.406681 -218.609663)
			(xy 375.415998 -218.66444) (xy 375.416572 -218.692222) (xy 376.636788 -218.692222) (xy 376.637339 -218.66688)
			(xy 376.645107 -218.616793) (xy 376.660448 -218.568485) (xy 376.683001 -218.523094) (xy 376.712234 -218.481689)
			(xy 376.747459 -218.445245) (xy 376.787846 -218.41462) (xy 376.832444 -218.390537) (xy 376.880202 -218.373561)
			(xy 376.905012 -218.368372) (xy 376.927872 -218.364054) (xy 377.133104 -218.008708) (xy 377.12523 -217.98661)
			(xy 377.116761 -217.960367) (xy 377.107692 -217.905977) (xy 377.107196 -217.878406) (xy 377.107704 -217.852519)
			(xy 377.115803 -217.801381) (xy 377.131802 -217.752141) (xy 377.155308 -217.706009) (xy 377.18574 -217.664122)
			(xy 377.22235 -217.627512) (xy 377.264237 -217.59708) (xy 377.310369 -217.573574) (xy 377.359609 -217.557575)
			(xy 377.410747 -217.549476) (xy 377.462521 -217.549476) (xy 377.513659 -217.557575) (xy 377.562899 -217.573574)
			(xy 377.609031 -217.59708) (xy 377.650918 -217.627512) (xy 377.687528 -217.664122) (xy 377.71796 -217.706009)
			(xy 377.741466 -217.752141) (xy 377.757465 -217.801381) (xy 377.765564 -217.852519) (xy 377.766072 -217.878406)
			(xy 377.765625 -217.903782) (xy 377.757855 -217.953934) (xy 377.742485 -218.002302) (xy 377.719877 -218.047739)
			(xy 377.690567 -218.089171) (xy 377.65525 -218.125617) (xy 377.61476 -218.156215) (xy 377.570056 -218.18024)
			(xy 377.522196 -218.197124) (xy 377.49734 -218.202256) (xy 377.47448 -218.206574) (xy 377.269756 -218.561412)
			(xy 377.27763 -218.583256) (xy 377.286281 -218.609663) (xy 377.295598 -218.66444) (xy 377.296172 -218.692222)
			(xy 378.516388 -218.692222) (xy 378.516939 -218.66688) (xy 378.524707 -218.616793) (xy 378.540048 -218.568485)
			(xy 378.562601 -218.523094) (xy 378.591834 -218.481689) (xy 378.627059 -218.445245) (xy 378.667446 -218.41462)
			(xy 378.712044 -218.390537) (xy 378.759802 -218.373561) (xy 378.784612 -218.368372) (xy 378.807472 -218.364054)
			(xy 379.012704 -218.008708) (xy 379.00483 -217.98661) (xy 378.996361 -217.960367) (xy 378.987292 -217.905977)
			(xy 378.986796 -217.878406) (xy 378.987304 -217.852519) (xy 378.995403 -217.801381) (xy 379.011402 -217.752141)
			(xy 379.034908 -217.706009) (xy 379.06534 -217.664122) (xy 379.10195 -217.627512) (xy 379.143837 -217.59708)
			(xy 379.189969 -217.573574) (xy 379.239209 -217.557575) (xy 379.290347 -217.549476) (xy 379.342121 -217.549476)
			(xy 379.393259 -217.557575) (xy 379.442499 -217.573574) (xy 379.488631 -217.59708) (xy 379.530518 -217.627512)
			(xy 379.567128 -217.664122) (xy 379.59756 -217.706009) (xy 379.621066 -217.752141) (xy 379.637065 -217.801381)
			(xy 379.645164 -217.852519) (xy 379.645672 -217.878406) (xy 379.645225 -217.903782) (xy 379.637455 -217.953934)
			(xy 379.622085 -218.002302) (xy 379.599477 -218.047739) (xy 379.570167 -218.089171) (xy 379.53485 -218.125617)
			(xy 379.49436 -218.156215) (xy 379.449656 -218.18024) (xy 379.401796 -218.197124) (xy 379.37694 -218.202256)
			(xy 379.35408 -218.206574) (xy 379.149356 -218.561412) (xy 379.15723 -218.583256) (xy 379.165881 -218.609663)
			(xy 379.175198 -218.66444) (xy 379.175772 -218.692222) (xy 380.395988 -218.692222) (xy 380.396539 -218.66688)
			(xy 380.404307 -218.616793) (xy 380.419648 -218.568485) (xy 380.442201 -218.523094) (xy 380.471434 -218.481689)
			(xy 380.506659 -218.445245) (xy 380.547046 -218.41462) (xy 380.591644 -218.390537) (xy 380.639402 -218.373561)
			(xy 380.664212 -218.368372) (xy 380.687072 -218.364054) (xy 380.892304 -218.008708) (xy 380.88443 -217.98661)
			(xy 380.875961 -217.960367) (xy 380.866892 -217.905977) (xy 380.866396 -217.878406) (xy 380.866904 -217.852519)
			(xy 380.875003 -217.801381) (xy 380.891002 -217.752141) (xy 380.914508 -217.706009) (xy 380.94494 -217.664122)
			(xy 380.98155 -217.627512) (xy 381.023437 -217.59708) (xy 381.069569 -217.573574) (xy 381.118809 -217.557575)
			(xy 381.169947 -217.549476) (xy 381.221721 -217.549476) (xy 381.272859 -217.557575) (xy 381.322099 -217.573574)
			(xy 381.368231 -217.59708) (xy 381.410118 -217.627512) (xy 381.446728 -217.664122) (xy 381.47716 -217.706009)
			(xy 381.500666 -217.752141) (xy 381.516665 -217.801381) (xy 381.524764 -217.852519) (xy 381.525272 -217.878406)
			(xy 381.524825 -217.903782) (xy 381.517055 -217.953934) (xy 381.501685 -218.002302) (xy 381.479077 -218.047739)
			(xy 381.449767 -218.089171) (xy 381.41445 -218.125617) (xy 381.37396 -218.156215) (xy 381.329256 -218.18024)
			(xy 381.281396 -218.197124) (xy 381.25654 -218.202256) (xy 381.23368 -218.206574) (xy 381.028956 -218.561412)
			(xy 381.03683 -218.583256) (xy 381.045481 -218.609663) (xy 381.054798 -218.66444) (xy 381.055372 -218.692222)
			(xy 381.054864 -218.718129) (xy 381.046758 -218.769306) (xy 381.030746 -218.818585) (xy 381.007223 -218.864752)
			(xy 380.976767 -218.906671) (xy 380.940129 -218.943309) (xy 380.89821 -218.973765) (xy 380.852043 -218.997288)
			(xy 380.802764 -219.0133) (xy 380.751587 -219.021406) (xy 380.699773 -219.021406) (xy 380.648596 -219.0133)
			(xy 380.599317 -218.997288) (xy 380.55315 -218.973765) (xy 380.511231 -218.943309) (xy 380.474593 -218.906671)
			(xy 380.444137 -218.864752) (xy 380.420614 -218.818585) (xy 380.404602 -218.769306) (xy 380.396496 -218.718129)
			(xy 380.395988 -218.692222) (xy 379.175772 -218.692222) (xy 379.175264 -218.718129) (xy 379.167158 -218.769306)
			(xy 379.151146 -218.818585) (xy 379.127623 -218.864752) (xy 379.097167 -218.906671) (xy 379.060529 -218.943309)
			(xy 379.01861 -218.973765) (xy 378.972443 -218.997288) (xy 378.923164 -219.0133) (xy 378.871987 -219.021406)
			(xy 378.820173 -219.021406) (xy 378.768996 -219.0133) (xy 378.719717 -218.997288) (xy 378.67355 -218.973765)
			(xy 378.631631 -218.943309) (xy 378.594993 -218.906671) (xy 378.564537 -218.864752) (xy 378.541014 -218.818585)
			(xy 378.525002 -218.769306) (xy 378.516896 -218.718129) (xy 378.516388 -218.692222) (xy 377.296172 -218.692222)
			(xy 377.295664 -218.718129) (xy 377.287558 -218.769306) (xy 377.271546 -218.818585) (xy 377.248023 -218.864752)
			(xy 377.217567 -218.906671) (xy 377.180929 -218.943309) (xy 377.13901 -218.973765) (xy 377.092843 -218.997288)
			(xy 377.043564 -219.0133) (xy 376.992387 -219.021406) (xy 376.940573 -219.021406) (xy 376.889396 -219.0133)
			(xy 376.840117 -218.997288) (xy 376.79395 -218.973765) (xy 376.752031 -218.943309) (xy 376.715393 -218.906671)
			(xy 376.684937 -218.864752) (xy 376.661414 -218.818585) (xy 376.645402 -218.769306) (xy 376.637296 -218.718129)
			(xy 376.636788 -218.692222) (xy 375.416572 -218.692222) (xy 375.416064 -218.718129) (xy 375.407958 -218.769306)
			(xy 375.391946 -218.818585) (xy 375.368423 -218.864752) (xy 375.337967 -218.906671) (xy 375.301329 -218.943309)
			(xy 375.25941 -218.973765) (xy 375.213243 -218.997288) (xy 375.163964 -219.0133) (xy 375.112787 -219.021406)
			(xy 375.060973 -219.021406) (xy 375.009796 -219.0133) (xy 374.960517 -218.997288) (xy 374.91435 -218.973765)
			(xy 374.872431 -218.943309) (xy 374.835793 -218.906671) (xy 374.805337 -218.864752) (xy 374.781814 -218.818585)
			(xy 374.765802 -218.769306) (xy 374.757696 -218.718129) (xy 374.757188 -218.692222) (xy 373.536972 -218.692222)
			(xy 373.536464 -218.718129) (xy 373.528358 -218.769306) (xy 373.512346 -218.818585) (xy 373.488823 -218.864752)
			(xy 373.458367 -218.906671) (xy 373.421729 -218.943309) (xy 373.37981 -218.973765) (xy 373.333643 -218.997288)
			(xy 373.284364 -219.0133) (xy 373.233187 -219.021406) (xy 373.181373 -219.021406) (xy 373.130196 -219.0133)
			(xy 373.080917 -218.997288) (xy 373.03475 -218.973765) (xy 372.992831 -218.943309) (xy 372.956193 -218.906671)
			(xy 372.925737 -218.864752) (xy 372.902214 -218.818585) (xy 372.886202 -218.769306) (xy 372.878096 -218.718129)
			(xy 372.877588 -218.692222) (xy 371.657372 -218.692222) (xy 371.656864 -218.718129) (xy 371.648758 -218.769306)
			(xy 371.632746 -218.818585) (xy 371.609223 -218.864752) (xy 371.578767 -218.906671) (xy 371.542129 -218.943309)
			(xy 371.50021 -218.973765) (xy 371.454043 -218.997288) (xy 371.404764 -219.0133) (xy 371.353587 -219.021406)
			(xy 371.301773 -219.021406) (xy 371.250596 -219.0133) (xy 371.201317 -218.997288) (xy 371.15515 -218.973765)
			(xy 371.113231 -218.943309) (xy 371.076593 -218.906671) (xy 371.046137 -218.864752) (xy 371.022614 -218.818585)
			(xy 371.006602 -218.769306) (xy 370.998496 -218.718129) (xy 370.997988 -218.692222) (xy 369.777772 -218.692222)
			(xy 369.777264 -218.718129) (xy 369.769158 -218.769306) (xy 369.753146 -218.818585) (xy 369.729623 -218.864752)
			(xy 369.699167 -218.906671) (xy 369.662529 -218.943309) (xy 369.62061 -218.973765) (xy 369.574443 -218.997288)
			(xy 369.525164 -219.0133) (xy 369.473987 -219.021406) (xy 369.422173 -219.021406) (xy 369.370996 -219.0133)
			(xy 369.321717 -218.997288) (xy 369.27555 -218.973765) (xy 369.233631 -218.943309) (xy 369.196993 -218.906671)
			(xy 369.166537 -218.864752) (xy 369.143014 -218.818585) (xy 369.127002 -218.769306) (xy 369.118896 -218.718129)
			(xy 369.118388 -218.692222) (xy 367.898172 -218.692222) (xy 367.897664 -218.718129) (xy 367.889558 -218.769306)
			(xy 367.873546 -218.818585) (xy 367.850023 -218.864752) (xy 367.819567 -218.906671) (xy 367.782929 -218.943309)
			(xy 367.74101 -218.973765) (xy 367.694843 -218.997288) (xy 367.645564 -219.0133) (xy 367.594387 -219.021406)
			(xy 367.542573 -219.021406) (xy 367.491396 -219.0133) (xy 367.442117 -218.997288) (xy 367.39595 -218.973765)
			(xy 367.354031 -218.943309) (xy 367.317393 -218.906671) (xy 367.286937 -218.864752) (xy 367.263414 -218.818585)
			(xy 367.247402 -218.769306) (xy 367.239296 -218.718129) (xy 367.238788 -218.692222) (xy 366.018572 -218.692222)
			(xy 366.018064 -218.718129) (xy 366.009958 -218.769306) (xy 365.993946 -218.818585) (xy 365.970423 -218.864752)
			(xy 365.939967 -218.906671) (xy 365.903329 -218.943309) (xy 365.86141 -218.973765) (xy 365.815243 -218.997288)
			(xy 365.765964 -219.0133) (xy 365.714787 -219.021406) (xy 365.662973 -219.021406) (xy 365.611796 -219.0133)
			(xy 365.562517 -218.997288) (xy 365.51635 -218.973765) (xy 365.474431 -218.943309) (xy 365.437793 -218.906671)
			(xy 365.407337 -218.864752) (xy 365.383814 -218.818585) (xy 365.367802 -218.769306) (xy 365.359696 -218.718129)
			(xy 365.359188 -218.692222) (xy 364.138972 -218.692222) (xy 364.138464 -218.718129) (xy 364.130358 -218.769306)
			(xy 364.114346 -218.818585) (xy 364.090823 -218.864752) (xy 364.060367 -218.906671) (xy 364.023729 -218.943309)
			(xy 363.98181 -218.973765) (xy 363.935643 -218.997288) (xy 363.886364 -219.0133) (xy 363.835187 -219.021406)
			(xy 363.783373 -219.021406) (xy 363.732196 -219.0133) (xy 363.682917 -218.997288) (xy 363.63675 -218.973765)
			(xy 363.594831 -218.943309) (xy 363.558193 -218.906671) (xy 363.527737 -218.864752) (xy 363.504214 -218.818585)
			(xy 363.488202 -218.769306) (xy 363.480096 -218.718129) (xy 363.479588 -218.692222) (xy 362.259372 -218.692222)
			(xy 362.258864 -218.718109) (xy 362.250765 -218.769247) (xy 362.234766 -218.818487) (xy 362.21126 -218.864619)
			(xy 362.180828 -218.906506) (xy 362.144218 -218.943116) (xy 362.102331 -218.973548) (xy 362.056199 -218.997054)
			(xy 362.006959 -219.013053) (xy 361.955821 -219.021152) (xy 361.904047 -219.021152) (xy 361.852909 -219.013053)
			(xy 361.803669 -218.997054) (xy 361.757537 -218.973548) (xy 361.71565 -218.943116) (xy 361.67904 -218.906506)
			(xy 361.648608 -218.864619) (xy 361.625102 -218.818487) (xy 361.609103 -218.769247) (xy 361.601004 -218.718109)
			(xy 361.600496 -218.692222) (xy 360.379772 -218.692222) (xy 360.379264 -218.718129) (xy 360.371158 -218.769306)
			(xy 360.355146 -218.818585) (xy 360.331623 -218.864752) (xy 360.301167 -218.906671) (xy 360.264529 -218.943309)
			(xy 360.22261 -218.973765) (xy 360.176443 -218.997288) (xy 360.127164 -219.0133) (xy 360.075987 -219.021406)
			(xy 360.024173 -219.021406) (xy 359.972996 -219.0133) (xy 359.923717 -218.997288) (xy 359.87755 -218.973765)
			(xy 359.835631 -218.943309) (xy 359.798993 -218.906671) (xy 359.768537 -218.864752) (xy 359.745014 -218.818585)
			(xy 359.729002 -218.769306) (xy 359.720896 -218.718129) (xy 359.720388 -218.692222) (xy 358.500172 -218.692222)
			(xy 358.499664 -218.718109) (xy 358.491565 -218.769247) (xy 358.475566 -218.818487) (xy 358.45206 -218.864619)
			(xy 358.421628 -218.906506) (xy 358.385018 -218.943116) (xy 358.343131 -218.973548) (xy 358.296999 -218.997054)
			(xy 358.247759 -219.013053) (xy 358.196621 -219.021152) (xy 358.144847 -219.021152) (xy 358.093709 -219.013053)
			(xy 358.044469 -218.997054) (xy 357.998337 -218.973548) (xy 357.95645 -218.943116) (xy 357.91984 -218.906506)
			(xy 357.889408 -218.864619) (xy 357.865902 -218.818487) (xy 357.849903 -218.769247) (xy 357.841804 -218.718109)
			(xy 357.841296 -218.692222) (xy 357.841831 -218.664514) (xy 357.851023 -218.609867) (xy 357.859584 -218.58351)
			(xy 357.867458 -218.561412) (xy 357.66248 -218.206574) (xy 357.63962 -218.202256) (xy 357.614783 -218.197156)
			(xy 357.567001 -218.180194) (xy 357.52238 -218.156114) (xy 357.481972 -218.125486) (xy 357.446732 -218.08903)
			(xy 357.417491 -218.047608) (xy 357.394937 -218.002196) (xy 357.379605 -217.953866) (xy 357.371854 -217.903758)
			(xy 357.371396 -217.878406) (xy 357.090472 -217.878406) (xy 357.089964 -217.904293) (xy 357.081865 -217.955431)
			(xy 357.065866 -218.004671) (xy 357.04236 -218.050803) (xy 357.011928 -218.09269) (xy 356.975318 -218.1293)
			(xy 356.933431 -218.159732) (xy 356.887299 -218.183238) (xy 356.838059 -218.199237) (xy 356.786921 -218.207336)
			(xy 356.735147 -218.207336) (xy 356.684009 -218.199237) (xy 356.634769 -218.183238) (xy 356.588637 -218.159732)
			(xy 356.54675 -218.1293) (xy 356.51014 -218.09269) (xy 356.479708 -218.050803) (xy 356.456202 -218.004671)
			(xy 356.440203 -217.955431) (xy 356.432104 -217.904293) (xy 356.431596 -217.878406) (xy 356.150672 -217.878406)
			(xy 356.150141 -217.906114) (xy 356.140946 -217.960761) (xy 356.132384 -217.987118) (xy 356.12451 -218.009216)
			(xy 356.329488 -218.364054) (xy 356.352348 -218.368372) (xy 356.377163 -218.373563) (xy 356.424941 -218.390515)
			(xy 356.469559 -218.414584) (xy 356.509965 -218.445202) (xy 356.545206 -218.481645) (xy 356.57445 -218.523056)
			(xy 356.597009 -218.568456) (xy 356.612349 -218.616776) (xy 356.620108 -218.666874) (xy 356.620572 -218.692222)
			(xy 356.620064 -218.718129) (xy 356.611958 -218.769306) (xy 356.595946 -218.818585) (xy 356.572423 -218.864752)
			(xy 356.541967 -218.906671) (xy 356.505329 -218.943309) (xy 356.46341 -218.973765) (xy 356.417243 -218.997288)
			(xy 356.367964 -219.0133) (xy 356.316787 -219.021406) (xy 356.264973 -219.021406) (xy 356.213796 -219.0133)
			(xy 356.164517 -218.997288) (xy 356.11835 -218.973765) (xy 356.076431 -218.943309) (xy 356.039793 -218.906671)
			(xy 356.009337 -218.864752) (xy 355.985814 -218.818585) (xy 355.969802 -218.769306) (xy 355.961696 -218.718129)
			(xy 355.961188 -218.692222) (xy 355.961788 -218.664505) (xy 355.971107 -218.609859) (xy 355.97973 -218.58351)
			(xy 355.987604 -218.561412) (xy 355.782626 -218.206574) (xy 355.759766 -218.202256) (xy 355.734962 -218.197073)
			(xy 355.687224 -218.180081) (xy 355.642649 -218.155985) (xy 355.602284 -218.125353) (xy 355.567082 -218.088906)
			(xy 355.53787 -218.047502) (xy 355.515337 -218.002116) (xy 355.500013 -217.953817) (xy 355.49226 -217.903742)
			(xy 355.491796 -217.878406) (xy 355.210872 -217.878406) (xy 355.210364 -217.904293) (xy 355.202265 -217.955431)
			(xy 355.186266 -218.004671) (xy 355.16276 -218.050803) (xy 355.132328 -218.09269) (xy 355.095718 -218.1293)
			(xy 355.053831 -218.159732) (xy 355.007699 -218.183238) (xy 354.958459 -218.199237) (xy 354.907321 -218.207336)
			(xy 354.855547 -218.207336) (xy 354.804409 -218.199237) (xy 354.755169 -218.183238) (xy 354.709037 -218.159732)
			(xy 354.66715 -218.1293) (xy 354.63054 -218.09269) (xy 354.600108 -218.050803) (xy 354.576602 -218.004671)
			(xy 354.560603 -217.955431) (xy 354.552504 -217.904293) (xy 354.551996 -217.878406) (xy 354.271072 -217.878406)
			(xy 354.270541 -217.906114) (xy 354.261346 -217.960761) (xy 354.252784 -217.987118) (xy 354.24491 -218.009216)
			(xy 354.449888 -218.364054) (xy 354.472748 -218.368372) (xy 354.497563 -218.373563) (xy 354.545341 -218.390515)
			(xy 354.589959 -218.414584) (xy 354.630365 -218.445202) (xy 354.665606 -218.481645) (xy 354.69485 -218.523056)
			(xy 354.717409 -218.568456) (xy 354.732749 -218.616776) (xy 354.740508 -218.666874) (xy 354.740972 -218.692222)
			(xy 354.740464 -218.718129) (xy 354.732358 -218.769306) (xy 354.716346 -218.818585) (xy 354.692823 -218.864752)
			(xy 354.662367 -218.906671) (xy 354.625729 -218.943309) (xy 354.58381 -218.973765) (xy 354.537643 -218.997288)
			(xy 354.488364 -219.0133) (xy 354.437187 -219.021406) (xy 354.385373 -219.021406) (xy 354.334196 -219.0133)
			(xy 354.284917 -218.997288) (xy 354.23875 -218.973765) (xy 354.196831 -218.943309) (xy 354.160193 -218.906671)
			(xy 354.129737 -218.864752) (xy 354.106214 -218.818585) (xy 354.090202 -218.769306) (xy 354.082096 -218.718129)
			(xy 354.081588 -218.692222) (xy 354.082188 -218.664505) (xy 354.091507 -218.609859) (xy 354.10013 -218.58351)
			(xy 354.108004 -218.561412) (xy 353.903026 -218.206574) (xy 353.880166 -218.202256) (xy 353.855362 -218.197073)
			(xy 353.807624 -218.180081) (xy 353.763049 -218.155985) (xy 353.722684 -218.125353) (xy 353.687482 -218.088906)
			(xy 353.65827 -218.047502) (xy 353.635737 -218.002116) (xy 353.620413 -217.953817) (xy 353.61266 -217.903742)
			(xy 353.612196 -217.878406) (xy 353.331272 -217.878406) (xy 353.330764 -217.904293) (xy 353.322665 -217.955431)
			(xy 353.306666 -218.004671) (xy 353.28316 -218.050803) (xy 353.252728 -218.09269) (xy 353.216118 -218.1293)
			(xy 353.174231 -218.159732) (xy 353.128099 -218.183238) (xy 353.078859 -218.199237) (xy 353.027721 -218.207336)
			(xy 352.975947 -218.207336) (xy 352.924809 -218.199237) (xy 352.875569 -218.183238) (xy 352.829437 -218.159732)
			(xy 352.78755 -218.1293) (xy 352.75094 -218.09269) (xy 352.720508 -218.050803) (xy 352.697002 -218.004671)
			(xy 352.681003 -217.955431) (xy 352.672904 -217.904293) (xy 352.672396 -217.878406) (xy 352.391472 -217.878406)
			(xy 352.390941 -217.906114) (xy 352.381746 -217.960761) (xy 352.373184 -217.987118) (xy 352.36531 -218.009216)
			(xy 352.570288 -218.364054) (xy 352.593148 -218.368372) (xy 352.617963 -218.373563) (xy 352.665741 -218.390515)
			(xy 352.710359 -218.414584) (xy 352.750765 -218.445202) (xy 352.786006 -218.481645) (xy 352.81525 -218.523056)
			(xy 352.837809 -218.568456) (xy 352.853149 -218.616776) (xy 352.860908 -218.666874) (xy 352.861372 -218.692222)
			(xy 352.860864 -218.718129) (xy 352.852758 -218.769306) (xy 352.836746 -218.818585) (xy 352.813223 -218.864752)
			(xy 352.782767 -218.906671) (xy 352.746129 -218.943309) (xy 352.70421 -218.973765) (xy 352.658043 -218.997288)
			(xy 352.608764 -219.0133) (xy 352.557587 -219.021406) (xy 352.505773 -219.021406) (xy 352.454596 -219.0133)
			(xy 352.405317 -218.997288) (xy 352.35915 -218.973765) (xy 352.317231 -218.943309) (xy 352.280593 -218.906671)
			(xy 352.250137 -218.864752) (xy 352.226614 -218.818585) (xy 352.210602 -218.769306) (xy 352.202496 -218.718129)
			(xy 352.201988 -218.692222) (xy 352.202588 -218.664505) (xy 352.211907 -218.609859) (xy 352.22053 -218.58351)
			(xy 352.228404 -218.561412) (xy 352.023426 -218.206574) (xy 352.000566 -218.202256) (xy 351.975762 -218.197073)
			(xy 351.928024 -218.180081) (xy 351.883449 -218.155985) (xy 351.843084 -218.125353) (xy 351.807882 -218.088906)
			(xy 351.77867 -218.047502) (xy 351.756137 -218.002116) (xy 351.740813 -217.953817) (xy 351.73306 -217.903742)
			(xy 351.732596 -217.878406) (xy 351.451672 -217.878406) (xy 351.451164 -217.904293) (xy 351.443065 -217.955431)
			(xy 351.427066 -218.004671) (xy 351.40356 -218.050803) (xy 351.373128 -218.09269) (xy 351.336518 -218.1293)
			(xy 351.294631 -218.159732) (xy 351.248499 -218.183238) (xy 351.199259 -218.199237) (xy 351.148121 -218.207336)
			(xy 351.096347 -218.207336) (xy 351.045209 -218.199237) (xy 350.995969 -218.183238) (xy 350.949837 -218.159732)
			(xy 350.90795 -218.1293) (xy 350.87134 -218.09269) (xy 350.840908 -218.050803) (xy 350.817402 -218.004671)
			(xy 350.801403 -217.955431) (xy 350.793304 -217.904293) (xy 350.792796 -217.878406) (xy 350.511872 -217.878406)
			(xy 350.511341 -217.906114) (xy 350.502146 -217.960761) (xy 350.493584 -217.987118) (xy 350.48571 -218.009216)
			(xy 350.690688 -218.364054) (xy 350.713548 -218.368372) (xy 350.738363 -218.373563) (xy 350.786141 -218.390515)
			(xy 350.830759 -218.414584) (xy 350.871165 -218.445202) (xy 350.906406 -218.481645) (xy 350.93565 -218.523056)
			(xy 350.958209 -218.568456) (xy 350.973549 -218.616776) (xy 350.981308 -218.666874) (xy 350.981772 -218.692222)
			(xy 350.981264 -218.718129) (xy 350.973158 -218.769306) (xy 350.957146 -218.818585) (xy 350.933623 -218.864752)
			(xy 350.903167 -218.906671) (xy 350.866529 -218.943309) (xy 350.82461 -218.973765) (xy 350.778443 -218.997288)
			(xy 350.729164 -219.0133) (xy 350.677987 -219.021406) (xy 350.626173 -219.021406) (xy 350.574996 -219.0133)
			(xy 350.525717 -218.997288) (xy 350.47955 -218.973765) (xy 350.437631 -218.943309) (xy 350.400993 -218.906671)
			(xy 350.370537 -218.864752) (xy 350.347014 -218.818585) (xy 350.331002 -218.769306) (xy 350.322896 -218.718129)
			(xy 350.322388 -218.692222) (xy 350.322988 -218.664505) (xy 350.332307 -218.609859) (xy 350.34093 -218.58351)
			(xy 350.348804 -218.561412) (xy 350.143826 -218.206574) (xy 350.120966 -218.202256) (xy 350.096162 -218.197073)
			(xy 350.048424 -218.180081) (xy 350.003849 -218.155985) (xy 349.963484 -218.125353) (xy 349.928282 -218.088906)
			(xy 349.89907 -218.047502) (xy 349.876537 -218.002116) (xy 349.861213 -217.953817) (xy 349.85346 -217.903742)
			(xy 349.852996 -217.878406) (xy 349.572072 -217.878406) (xy 349.571564 -217.904293) (xy 349.563465 -217.955431)
			(xy 349.547466 -218.004671) (xy 349.52396 -218.050803) (xy 349.493528 -218.09269) (xy 349.456918 -218.1293)
			(xy 349.415031 -218.159732) (xy 349.368899 -218.183238) (xy 349.319659 -218.199237) (xy 349.268521 -218.207336)
			(xy 349.216747 -218.207336) (xy 349.165609 -218.199237) (xy 349.116369 -218.183238) (xy 349.070237 -218.159732)
			(xy 349.02835 -218.1293) (xy 348.99174 -218.09269) (xy 348.961308 -218.050803) (xy 348.937802 -218.004671)
			(xy 348.921803 -217.955431) (xy 348.913704 -217.904293) (xy 348.913196 -217.878406) (xy 348.632272 -217.878406)
			(xy 348.631741 -217.906114) (xy 348.622546 -217.960761) (xy 348.613984 -217.987118) (xy 348.60611 -218.009216)
			(xy 348.811088 -218.364054) (xy 348.833948 -218.368372) (xy 348.858763 -218.373563) (xy 348.906541 -218.390515)
			(xy 348.951159 -218.414584) (xy 348.991565 -218.445202) (xy 349.026806 -218.481645) (xy 349.05605 -218.523056)
			(xy 349.078609 -218.568456) (xy 349.093949 -218.616776) (xy 349.101708 -218.666874) (xy 349.102172 -218.692222)
			(xy 349.101664 -218.718129) (xy 349.093558 -218.769306) (xy 349.077546 -218.818585) (xy 349.054023 -218.864752)
			(xy 349.023567 -218.906671) (xy 348.986929 -218.943309) (xy 348.94501 -218.973765) (xy 348.898843 -218.997288)
			(xy 348.849564 -219.0133) (xy 348.798387 -219.021406) (xy 348.746573 -219.021406) (xy 348.695396 -219.0133)
			(xy 348.646117 -218.997288) (xy 348.59995 -218.973765) (xy 348.558031 -218.943309) (xy 348.521393 -218.906671)
			(xy 348.490937 -218.864752) (xy 348.467414 -218.818585) (xy 348.451402 -218.769306) (xy 348.443296 -218.718129)
			(xy 348.442788 -218.692222) (xy 348.443388 -218.664505) (xy 348.452707 -218.609859) (xy 348.46133 -218.58351)
			(xy 348.469204 -218.561412) (xy 348.264226 -218.206574) (xy 348.241366 -218.202256) (xy 348.216562 -218.197073)
			(xy 348.168824 -218.180081) (xy 348.124249 -218.155985) (xy 348.083884 -218.125353) (xy 348.048682 -218.088906)
			(xy 348.01947 -218.047502) (xy 347.996937 -218.002116) (xy 347.981613 -217.953817) (xy 347.97386 -217.903742)
			(xy 347.973396 -217.878406) (xy 347.692472 -217.878406) (xy 347.691964 -217.904293) (xy 347.683865 -217.955431)
			(xy 347.667866 -218.004671) (xy 347.64436 -218.050803) (xy 347.613928 -218.09269) (xy 347.577318 -218.1293)
			(xy 347.535431 -218.159732) (xy 347.489299 -218.183238) (xy 347.440059 -218.199237) (xy 347.388921 -218.207336)
			(xy 347.337147 -218.207336) (xy 347.286009 -218.199237) (xy 347.236769 -218.183238) (xy 347.190637 -218.159732)
			(xy 347.14875 -218.1293) (xy 347.11214 -218.09269) (xy 347.081708 -218.050803) (xy 347.058202 -218.004671)
			(xy 347.042203 -217.955431) (xy 347.034104 -217.904293) (xy 347.033596 -217.878406) (xy 346.752672 -217.878406)
			(xy 346.752141 -217.906114) (xy 346.742946 -217.960761) (xy 346.734384 -217.987118) (xy 346.72651 -218.009216)
			(xy 346.931488 -218.364054) (xy 346.954348 -218.368372) (xy 346.979163 -218.373563) (xy 347.026941 -218.390515)
			(xy 347.071559 -218.414584) (xy 347.111965 -218.445202) (xy 347.147206 -218.481645) (xy 347.17645 -218.523056)
			(xy 347.199009 -218.568456) (xy 347.214349 -218.616776) (xy 347.222108 -218.666874) (xy 347.222572 -218.692222)
			(xy 347.222064 -218.718129) (xy 347.213958 -218.769306) (xy 347.197946 -218.818585) (xy 347.174423 -218.864752)
			(xy 347.143967 -218.906671) (xy 347.107329 -218.943309) (xy 347.06541 -218.973765) (xy 347.019243 -218.997288)
			(xy 346.969964 -219.0133) (xy 346.918787 -219.021406) (xy 346.866973 -219.021406) (xy 346.815796 -219.0133)
			(xy 346.766517 -218.997288) (xy 346.72035 -218.973765) (xy 346.678431 -218.943309) (xy 346.641793 -218.906671)
			(xy 346.611337 -218.864752) (xy 346.587814 -218.818585) (xy 346.571802 -218.769306) (xy 346.563696 -218.718129)
			(xy 346.563188 -218.692222) (xy 346.563788 -218.664505) (xy 346.573107 -218.609859) (xy 346.58173 -218.58351)
			(xy 346.589604 -218.561412) (xy 346.384626 -218.206574) (xy 346.361766 -218.202256) (xy 346.336962 -218.197073)
			(xy 346.289224 -218.180081) (xy 346.244649 -218.155985) (xy 346.204284 -218.125353) (xy 346.169082 -218.088906)
			(xy 346.13987 -218.047502) (xy 346.117337 -218.002116) (xy 346.102013 -217.953817) (xy 346.09426 -217.903742)
			(xy 346.093796 -217.878406) (xy 345.812872 -217.878406) (xy 345.812364 -217.904293) (xy 345.804265 -217.955431)
			(xy 345.788266 -218.004671) (xy 345.76476 -218.050803) (xy 345.734328 -218.09269) (xy 345.697718 -218.1293)
			(xy 345.655831 -218.159732) (xy 345.609699 -218.183238) (xy 345.560459 -218.199237) (xy 345.509321 -218.207336)
			(xy 345.457547 -218.207336) (xy 345.406409 -218.199237) (xy 345.357169 -218.183238) (xy 345.311037 -218.159732)
			(xy 345.26915 -218.1293) (xy 345.23254 -218.09269) (xy 345.202108 -218.050803) (xy 345.178602 -218.004671)
			(xy 345.162603 -217.955431) (xy 345.154504 -217.904293) (xy 345.153996 -217.878406) (xy 344.873072 -217.878406)
			(xy 344.872541 -217.906114) (xy 344.863346 -217.960761) (xy 344.854784 -217.987118) (xy 344.84691 -218.009216)
			(xy 345.051888 -218.364054) (xy 345.074748 -218.368372) (xy 345.099563 -218.373563) (xy 345.147341 -218.390515)
			(xy 345.191959 -218.414584) (xy 345.232365 -218.445202) (xy 345.267606 -218.481645) (xy 345.29685 -218.523056)
			(xy 345.319409 -218.568456) (xy 345.334749 -218.616776) (xy 345.342508 -218.666874) (xy 345.342972 -218.692222)
			(xy 345.342464 -218.718129) (xy 345.334358 -218.769306) (xy 345.318346 -218.818585) (xy 345.294823 -218.864752)
			(xy 345.264367 -218.906671) (xy 345.227729 -218.943309) (xy 345.18581 -218.973765) (xy 345.139643 -218.997288)
			(xy 345.090364 -219.0133) (xy 345.039187 -219.021406) (xy 344.987373 -219.021406) (xy 344.936196 -219.0133)
			(xy 344.886917 -218.997288) (xy 344.84075 -218.973765) (xy 344.798831 -218.943309) (xy 344.762193 -218.906671)
			(xy 344.731737 -218.864752) (xy 344.708214 -218.818585) (xy 344.692202 -218.769306) (xy 344.684096 -218.718129)
			(xy 344.683588 -218.692222) (xy 344.684188 -218.664505) (xy 344.693507 -218.609859) (xy 344.70213 -218.58351)
			(xy 344.710004 -218.561412) (xy 344.505026 -218.206574) (xy 344.482166 -218.202256) (xy 344.457362 -218.197073)
			(xy 344.409624 -218.180081) (xy 344.365049 -218.155985) (xy 344.324684 -218.125353) (xy 344.289482 -218.088906)
			(xy 344.26027 -218.047502) (xy 344.237737 -218.002116) (xy 344.222413 -217.953817) (xy 344.21466 -217.903742)
			(xy 344.214196 -217.878406) (xy 343.933272 -217.878406) (xy 343.932764 -217.904293) (xy 343.924665 -217.955431)
			(xy 343.908666 -218.004671) (xy 343.88516 -218.050803) (xy 343.854728 -218.09269) (xy 343.818118 -218.1293)
			(xy 343.776231 -218.159732) (xy 343.730099 -218.183238) (xy 343.680859 -218.199237) (xy 343.629721 -218.207336)
			(xy 343.577947 -218.207336) (xy 343.526809 -218.199237) (xy 343.477569 -218.183238) (xy 343.431437 -218.159732)
			(xy 343.38955 -218.1293) (xy 343.35294 -218.09269) (xy 343.322508 -218.050803) (xy 343.299002 -218.004671)
			(xy 343.283003 -217.955431) (xy 343.274904 -217.904293) (xy 343.274396 -217.878406) (xy 342.993472 -217.878406)
			(xy 342.992941 -217.906114) (xy 342.983746 -217.960761) (xy 342.975184 -217.987118) (xy 342.96731 -218.009216)
			(xy 343.172288 -218.364054) (xy 343.195148 -218.368372) (xy 343.219963 -218.373563) (xy 343.267741 -218.390515)
			(xy 343.312359 -218.414584) (xy 343.352765 -218.445202) (xy 343.388006 -218.481645) (xy 343.41725 -218.523056)
			(xy 343.439809 -218.568456) (xy 343.455149 -218.616776) (xy 343.462908 -218.666874) (xy 343.463372 -218.692222)
			(xy 343.462864 -218.718129) (xy 343.454758 -218.769306) (xy 343.438746 -218.818585) (xy 343.415223 -218.864752)
			(xy 343.384767 -218.906671) (xy 343.348129 -218.943309) (xy 343.30621 -218.973765) (xy 343.260043 -218.997288)
			(xy 343.210764 -219.0133) (xy 343.159587 -219.021406) (xy 343.107773 -219.021406) (xy 343.056596 -219.0133)
			(xy 343.007317 -218.997288) (xy 342.96115 -218.973765) (xy 342.919231 -218.943309) (xy 342.882593 -218.906671)
			(xy 342.852137 -218.864752) (xy 342.828614 -218.818585) (xy 342.812602 -218.769306) (xy 342.804496 -218.718129)
			(xy 342.803988 -218.692222) (xy 342.804588 -218.664505) (xy 342.813907 -218.609859) (xy 342.82253 -218.58351)
			(xy 342.830404 -218.561412) (xy 342.625426 -218.206574) (xy 342.602566 -218.202256) (xy 342.577762 -218.197073)
			(xy 342.530024 -218.180081) (xy 342.485449 -218.155985) (xy 342.445084 -218.125353) (xy 342.409882 -218.088906)
			(xy 342.38067 -218.047502) (xy 342.358137 -218.002116) (xy 342.342813 -217.953817) (xy 342.33506 -217.903742)
			(xy 342.334596 -217.878406) (xy 342.053672 -217.878406) (xy 342.053164 -217.904293) (xy 342.045065 -217.955431)
			(xy 342.029066 -218.004671) (xy 342.00556 -218.050803) (xy 341.975128 -218.09269) (xy 341.938518 -218.1293)
			(xy 341.896631 -218.159732) (xy 341.850499 -218.183238) (xy 341.801259 -218.199237) (xy 341.750121 -218.207336)
			(xy 341.698347 -218.207336) (xy 341.647209 -218.199237) (xy 341.597969 -218.183238) (xy 341.551837 -218.159732)
			(xy 341.50995 -218.1293) (xy 341.47334 -218.09269) (xy 341.442908 -218.050803) (xy 341.419402 -218.004671)
			(xy 341.403403 -217.955431) (xy 341.395304 -217.904293) (xy 341.394796 -217.878406) (xy 341.113872 -217.878406)
			(xy 341.113341 -217.906114) (xy 341.104146 -217.960761) (xy 341.095584 -217.987118) (xy 341.08771 -218.009216)
			(xy 341.292688 -218.364054) (xy 341.315548 -218.368372) (xy 341.340363 -218.373563) (xy 341.388141 -218.390515)
			(xy 341.432759 -218.414584) (xy 341.473165 -218.445202) (xy 341.508406 -218.481645) (xy 341.53765 -218.523056)
			(xy 341.560209 -218.568456) (xy 341.575549 -218.616776) (xy 341.583308 -218.666874) (xy 341.583772 -218.692222)
			(xy 341.583264 -218.718129) (xy 341.575158 -218.769306) (xy 341.559146 -218.818585) (xy 341.535623 -218.864752)
			(xy 341.505167 -218.906671) (xy 341.468529 -218.943309) (xy 341.42661 -218.973765) (xy 341.380443 -218.997288)
			(xy 341.331164 -219.0133) (xy 341.279987 -219.021406) (xy 341.228173 -219.021406) (xy 341.176996 -219.0133)
			(xy 341.127717 -218.997288) (xy 341.08155 -218.973765) (xy 341.039631 -218.943309) (xy 341.002993 -218.906671)
			(xy 340.972537 -218.864752) (xy 340.949014 -218.818585) (xy 340.933002 -218.769306) (xy 340.924896 -218.718129)
			(xy 340.924388 -218.692222) (xy 340.924988 -218.664505) (xy 340.934307 -218.609859) (xy 340.94293 -218.58351)
			(xy 340.950804 -218.561412) (xy 340.745826 -218.206574) (xy 340.722966 -218.202256) (xy 340.698162 -218.197073)
			(xy 340.650424 -218.180081) (xy 340.605849 -218.155985) (xy 340.565484 -218.125353) (xy 340.530282 -218.088906)
			(xy 340.50107 -218.047502) (xy 340.478537 -218.002116) (xy 340.463213 -217.953817) (xy 340.45546 -217.903742)
			(xy 340.454996 -217.878406) (xy 340.174072 -217.878406) (xy 340.173564 -217.904293) (xy 340.165465 -217.955431)
			(xy 340.149466 -218.004671) (xy 340.12596 -218.050803) (xy 340.095528 -218.09269) (xy 340.058918 -218.1293)
			(xy 340.017031 -218.159732) (xy 339.970899 -218.183238) (xy 339.921659 -218.199237) (xy 339.870521 -218.207336)
			(xy 339.818747 -218.207336) (xy 339.767609 -218.199237) (xy 339.718369 -218.183238) (xy 339.672237 -218.159732)
			(xy 339.63035 -218.1293) (xy 339.59374 -218.09269) (xy 339.563308 -218.050803) (xy 339.539802 -218.004671)
			(xy 339.523803 -217.955431) (xy 339.515704 -217.904293) (xy 339.515196 -217.878406) (xy 339.234272 -217.878406)
			(xy 339.233741 -217.906114) (xy 339.224546 -217.960761) (xy 339.215984 -217.987118) (xy 339.20811 -218.009216)
			(xy 339.413088 -218.364054) (xy 339.435948 -218.368372) (xy 339.460763 -218.373563) (xy 339.508541 -218.390515)
			(xy 339.553159 -218.414584) (xy 339.593565 -218.445202) (xy 339.628806 -218.481645) (xy 339.65805 -218.523056)
			(xy 339.680609 -218.568456) (xy 339.695949 -218.616776) (xy 339.703708 -218.666874) (xy 339.704172 -218.692222)
			(xy 339.703664 -218.718129) (xy 339.695558 -218.769306) (xy 339.679546 -218.818585) (xy 339.656023 -218.864752)
			(xy 339.625567 -218.906671) (xy 339.588929 -218.943309) (xy 339.54701 -218.973765) (xy 339.500843 -218.997288)
			(xy 339.451564 -219.0133) (xy 339.400387 -219.021406) (xy 339.348573 -219.021406) (xy 339.297396 -219.0133)
			(xy 339.248117 -218.997288) (xy 339.20195 -218.973765) (xy 339.160031 -218.943309) (xy 339.123393 -218.906671)
			(xy 339.092937 -218.864752) (xy 339.069414 -218.818585) (xy 339.053402 -218.769306) (xy 339.045296 -218.718129)
			(xy 339.044788 -218.692222) (xy 339.045388 -218.664505) (xy 339.054707 -218.609859) (xy 339.06333 -218.58351)
			(xy 339.071204 -218.561412) (xy 338.866226 -218.206574) (xy 338.843366 -218.202256) (xy 338.818562 -218.197073)
			(xy 338.770824 -218.180081) (xy 338.726249 -218.155985) (xy 338.685884 -218.125353) (xy 338.650682 -218.088906)
			(xy 338.62147 -218.047502) (xy 338.598937 -218.002116) (xy 338.583613 -217.953817) (xy 338.57586 -217.903742)
			(xy 338.575396 -217.878406) (xy 338.294472 -217.878406) (xy 338.293964 -217.904293) (xy 338.285865 -217.955431)
			(xy 338.269866 -218.004671) (xy 338.24636 -218.050803) (xy 338.215928 -218.09269) (xy 338.179318 -218.1293)
			(xy 338.137431 -218.159732) (xy 338.091299 -218.183238) (xy 338.042059 -218.199237) (xy 337.990921 -218.207336)
			(xy 337.939147 -218.207336) (xy 337.888009 -218.199237) (xy 337.838769 -218.183238) (xy 337.792637 -218.159732)
			(xy 337.75075 -218.1293) (xy 337.71414 -218.09269) (xy 337.683708 -218.050803) (xy 337.660202 -218.004671)
			(xy 337.644203 -217.955431) (xy 337.636104 -217.904293) (xy 337.635596 -217.878406) (xy 337.354672 -217.878406)
			(xy 337.354141 -217.906114) (xy 337.344946 -217.960761) (xy 337.336384 -217.987118) (xy 337.32851 -218.009216)
			(xy 337.533488 -218.364054) (xy 337.556348 -218.368372) (xy 337.581163 -218.373563) (xy 337.628941 -218.390515)
			(xy 337.673559 -218.414584) (xy 337.713965 -218.445202) (xy 337.749206 -218.481645) (xy 337.77845 -218.523056)
			(xy 337.801009 -218.568456) (xy 337.816349 -218.616776) (xy 337.824108 -218.666874) (xy 337.824572 -218.692222)
			(xy 337.824064 -218.718129) (xy 337.815958 -218.769306) (xy 337.799946 -218.818585) (xy 337.776423 -218.864752)
			(xy 337.745967 -218.906671) (xy 337.709329 -218.943309) (xy 337.66741 -218.973765) (xy 337.621243 -218.997288)
			(xy 337.571964 -219.0133) (xy 337.520787 -219.021406) (xy 337.468973 -219.021406) (xy 337.417796 -219.0133)
			(xy 337.368517 -218.997288) (xy 337.32235 -218.973765) (xy 337.280431 -218.943309) (xy 337.243793 -218.906671)
			(xy 337.213337 -218.864752) (xy 337.189814 -218.818585) (xy 337.173802 -218.769306) (xy 337.165696 -218.718129)
			(xy 337.165188 -218.692222) (xy 337.165788 -218.664505) (xy 337.175107 -218.609859) (xy 337.18373 -218.58351)
			(xy 337.191604 -218.561412) (xy 336.986626 -218.206574) (xy 336.963766 -218.202256) (xy 336.938962 -218.197073)
			(xy 336.891224 -218.180081) (xy 336.846649 -218.155985) (xy 336.806284 -218.125353) (xy 336.771082 -218.088906)
			(xy 336.74187 -218.047502) (xy 336.719337 -218.002116) (xy 336.704013 -217.953817) (xy 336.69626 -217.903742)
			(xy 336.695796 -217.878406) (xy 134.525004 -217.878406) (xy 134.524496 -217.904293) (xy 134.516397 -217.955431)
			(xy 134.500398 -218.004671) (xy 134.476892 -218.050803) (xy 134.44646 -218.09269) (xy 134.40985 -218.1293)
			(xy 134.367963 -218.159732) (xy 134.321831 -218.183238) (xy 134.272591 -218.199237) (xy 134.221453 -218.207336)
			(xy 134.169679 -218.207336) (xy 134.118541 -218.199237) (xy 134.069301 -218.183238) (xy 134.023169 -218.159732)
			(xy 133.981282 -218.1293) (xy 133.944672 -218.09269) (xy 133.91424 -218.050803) (xy 133.890734 -218.004671)
			(xy 133.874735 -217.955431) (xy 133.866636 -217.904293) (xy 133.866128 -217.878406) (xy 133.866662 -217.850698)
			(xy 133.875855 -217.796051) (xy 133.884416 -217.769694) (xy 133.89229 -217.747596) (xy 133.687312 -217.392504)
			(xy 133.664452 -217.388186) (xy 133.639596 -217.383069) (xy 133.591748 -217.366166) (xy 133.547056 -217.342128)
			(xy 133.506577 -217.311523) (xy 133.471267 -217.275076) (xy 133.441961 -217.233647) (xy 133.419352 -217.188215)
			(xy 133.403974 -217.139855) (xy 133.39619 -217.089709) (xy 133.39572 -217.064336) (xy 132.175504 -217.064336)
			(xy 132.174889 -217.091989) (xy 132.165569 -217.146507) (xy 132.156962 -217.172794) (xy 132.149342 -217.194892)
			(xy 132.354574 -217.550238) (xy 132.377434 -217.554556) (xy 132.402241 -217.559728) (xy 132.449979 -217.576721)
			(xy 132.494556 -217.600818) (xy 132.53492 -217.631451) (xy 132.570123 -217.6679) (xy 132.599334 -217.709305)
			(xy 132.621866 -217.754693) (xy 132.637189 -217.802993) (xy 132.644941 -217.85307) (xy 132.645404 -217.878406)
			(xy 132.644896 -217.904293) (xy 132.636797 -217.955431) (xy 132.620798 -218.004671) (xy 132.597292 -218.050803)
			(xy 132.56686 -218.09269) (xy 132.53025 -218.1293) (xy 132.488363 -218.159732) (xy 132.442231 -218.183238)
			(xy 132.392991 -218.199237) (xy 132.341853 -218.207336) (xy 132.290079 -218.207336) (xy 132.238941 -218.199237)
			(xy 132.189701 -218.183238) (xy 132.143569 -218.159732) (xy 132.101682 -218.1293) (xy 132.065072 -218.09269)
			(xy 132.03464 -218.050803) (xy 132.011134 -218.004671) (xy 131.995135 -217.955431) (xy 131.987036 -217.904293)
			(xy 131.986528 -217.878406) (xy 131.987062 -217.850698) (xy 131.996255 -217.796051) (xy 132.004816 -217.769694)
			(xy 132.01269 -217.747596) (xy 131.807712 -217.392504) (xy 131.784852 -217.388186) (xy 131.759996 -217.383069)
			(xy 131.712148 -217.366166) (xy 131.667456 -217.342128) (xy 131.626977 -217.311523) (xy 131.591667 -217.275076)
			(xy 131.562361 -217.233647) (xy 131.539752 -217.188215) (xy 131.524374 -217.139855) (xy 131.51659 -217.089709)
			(xy 131.51612 -217.064336) (xy 130.295904 -217.064336) (xy 130.295289 -217.091989) (xy 130.285969 -217.146507)
			(xy 130.277362 -217.172794) (xy 130.269742 -217.194892) (xy 130.474974 -217.550238) (xy 130.497834 -217.554556)
			(xy 130.522641 -217.559728) (xy 130.570379 -217.576721) (xy 130.614956 -217.600818) (xy 130.65532 -217.631451)
			(xy 130.690523 -217.6679) (xy 130.719734 -217.709305) (xy 130.742266 -217.754693) (xy 130.757589 -217.802993)
			(xy 130.765341 -217.85307) (xy 130.765804 -217.878406) (xy 130.765296 -217.904293) (xy 130.757197 -217.955431)
			(xy 130.741198 -218.004671) (xy 130.717692 -218.050803) (xy 130.68726 -218.09269) (xy 130.65065 -218.1293)
			(xy 130.608763 -218.159732) (xy 130.562631 -218.183238) (xy 130.513391 -218.199237) (xy 130.462253 -218.207336)
			(xy 130.410479 -218.207336) (xy 130.359341 -218.199237) (xy 130.310101 -218.183238) (xy 130.263969 -218.159732)
			(xy 130.222082 -218.1293) (xy 130.185472 -218.09269) (xy 130.15504 -218.050803) (xy 130.131534 -218.004671)
			(xy 130.115535 -217.955431) (xy 130.107436 -217.904293) (xy 130.106928 -217.878406) (xy 130.107462 -217.850698)
			(xy 130.116655 -217.796051) (xy 130.125216 -217.769694) (xy 130.13309 -217.747596) (xy 129.928112 -217.392504)
			(xy 129.905252 -217.388186) (xy 129.880396 -217.383069) (xy 129.832548 -217.366166) (xy 129.787856 -217.342128)
			(xy 129.747377 -217.311523) (xy 129.712067 -217.275076) (xy 129.682761 -217.233647) (xy 129.660152 -217.188215)
			(xy 129.644774 -217.139855) (xy 129.63699 -217.089709) (xy 129.63652 -217.064336) (xy 128.416304 -217.064336)
			(xy 128.415689 -217.091989) (xy 128.406369 -217.146507) (xy 128.397762 -217.172794) (xy 128.390142 -217.194892)
			(xy 128.595374 -217.550238) (xy 128.618234 -217.554556) (xy 128.643041 -217.559728) (xy 128.690779 -217.576721)
			(xy 128.735356 -217.600818) (xy 128.77572 -217.631451) (xy 128.810923 -217.6679) (xy 128.840134 -217.709305)
			(xy 128.862666 -217.754693) (xy 128.877989 -217.802993) (xy 128.885741 -217.85307) (xy 128.886204 -217.878406)
			(xy 128.885696 -217.904293) (xy 128.877597 -217.955431) (xy 128.861598 -218.004671) (xy 128.838092 -218.050803)
			(xy 128.80766 -218.09269) (xy 128.77105 -218.1293) (xy 128.729163 -218.159732) (xy 128.683031 -218.183238)
			(xy 128.633791 -218.199237) (xy 128.582653 -218.207336) (xy 128.530879 -218.207336) (xy 128.479741 -218.199237)
			(xy 128.430501 -218.183238) (xy 128.384369 -218.159732) (xy 128.342482 -218.1293) (xy 128.305872 -218.09269)
			(xy 128.27544 -218.050803) (xy 128.251934 -218.004671) (xy 128.235935 -217.955431) (xy 128.227836 -217.904293)
			(xy 128.227328 -217.878406) (xy 128.227862 -217.850698) (xy 128.237055 -217.796051) (xy 128.245616 -217.769694)
			(xy 128.25349 -217.747596) (xy 128.048512 -217.392504) (xy 128.025652 -217.388186) (xy 128.000796 -217.383069)
			(xy 127.952948 -217.366166) (xy 127.908256 -217.342128) (xy 127.867777 -217.311523) (xy 127.832467 -217.275076)
			(xy 127.803161 -217.233647) (xy 127.780552 -217.188215) (xy 127.765174 -217.139855) (xy 127.75739 -217.089709)
			(xy 127.75692 -217.064336) (xy 126.536704 -217.064336) (xy 126.536089 -217.091989) (xy 126.526769 -217.146507)
			(xy 126.518162 -217.172794) (xy 126.510542 -217.194892) (xy 126.715774 -217.550238) (xy 126.738634 -217.554556)
			(xy 126.763441 -217.559728) (xy 126.811179 -217.576721) (xy 126.855756 -217.600818) (xy 126.89612 -217.631451)
			(xy 126.931323 -217.6679) (xy 126.960534 -217.709305) (xy 126.983066 -217.754693) (xy 126.998389 -217.802993)
			(xy 127.006141 -217.85307) (xy 127.006604 -217.878406) (xy 127.006096 -217.904293) (xy 126.997997 -217.955431)
			(xy 126.981998 -218.004671) (xy 126.958492 -218.050803) (xy 126.92806 -218.09269) (xy 126.89145 -218.1293)
			(xy 126.849563 -218.159732) (xy 126.803431 -218.183238) (xy 126.754191 -218.199237) (xy 126.703053 -218.207336)
			(xy 126.651279 -218.207336) (xy 126.600141 -218.199237) (xy 126.550901 -218.183238) (xy 126.504769 -218.159732)
			(xy 126.462882 -218.1293) (xy 126.426272 -218.09269) (xy 126.39584 -218.050803) (xy 126.372334 -218.004671)
			(xy 126.356335 -217.955431) (xy 126.348236 -217.904293) (xy 126.347728 -217.878406) (xy 126.348262 -217.850698)
			(xy 126.357455 -217.796051) (xy 126.366016 -217.769694) (xy 126.37389 -217.747596) (xy 126.168912 -217.392504)
			(xy 126.146052 -217.388186) (xy 126.121196 -217.383069) (xy 126.073348 -217.366166) (xy 126.028656 -217.342128)
			(xy 125.988177 -217.311523) (xy 125.952867 -217.275076) (xy 125.923561 -217.233647) (xy 125.900952 -217.188215)
			(xy 125.885574 -217.139855) (xy 125.87779 -217.089709) (xy 125.87732 -217.064336) (xy 124.657104 -217.064336)
			(xy 124.656489 -217.091989) (xy 124.647169 -217.146507) (xy 124.638562 -217.172794) (xy 124.630942 -217.194892)
			(xy 124.836174 -217.550238) (xy 124.859034 -217.554556) (xy 124.883841 -217.559728) (xy 124.931579 -217.576721)
			(xy 124.976156 -217.600818) (xy 125.01652 -217.631451) (xy 125.051723 -217.6679) (xy 125.080934 -217.709305)
			(xy 125.103466 -217.754693) (xy 125.118789 -217.802993) (xy 125.126541 -217.85307) (xy 125.127004 -217.878406)
			(xy 125.126496 -217.904293) (xy 125.118397 -217.955431) (xy 125.102398 -218.004671) (xy 125.078892 -218.050803)
			(xy 125.04846 -218.09269) (xy 125.01185 -218.1293) (xy 124.969963 -218.159732) (xy 124.923831 -218.183238)
			(xy 124.874591 -218.199237) (xy 124.823453 -218.207336) (xy 124.771679 -218.207336) (xy 124.720541 -218.199237)
			(xy 124.671301 -218.183238) (xy 124.625169 -218.159732) (xy 124.583282 -218.1293) (xy 124.546672 -218.09269)
			(xy 124.51624 -218.050803) (xy 124.492734 -218.004671) (xy 124.476735 -217.955431) (xy 124.468636 -217.904293)
			(xy 124.468128 -217.878406) (xy 124.468662 -217.850698) (xy 124.477855 -217.796051) (xy 124.486416 -217.769694)
			(xy 124.49429 -217.747596) (xy 124.289312 -217.392504) (xy 124.266452 -217.388186) (xy 124.241596 -217.383069)
			(xy 124.193748 -217.366166) (xy 124.149056 -217.342128) (xy 124.108577 -217.311523) (xy 124.073267 -217.275076)
			(xy 124.043961 -217.233647) (xy 124.021352 -217.188215) (xy 124.005974 -217.139855) (xy 123.99819 -217.089709)
			(xy 123.99772 -217.064336) (xy 122.777504 -217.064336) (xy 122.776889 -217.091989) (xy 122.767569 -217.146507)
			(xy 122.758962 -217.172794) (xy 122.751342 -217.194892) (xy 122.956574 -217.550238) (xy 122.979434 -217.554556)
			(xy 123.004241 -217.559728) (xy 123.051979 -217.576721) (xy 123.096556 -217.600818) (xy 123.13692 -217.631451)
			(xy 123.172123 -217.6679) (xy 123.201334 -217.709305) (xy 123.223866 -217.754693) (xy 123.239189 -217.802993)
			(xy 123.246941 -217.85307) (xy 123.247404 -217.878406) (xy 123.246896 -217.904293) (xy 123.238797 -217.955431)
			(xy 123.222798 -218.004671) (xy 123.199292 -218.050803) (xy 123.16886 -218.09269) (xy 123.13225 -218.1293)
			(xy 123.090363 -218.159732) (xy 123.044231 -218.183238) (xy 122.994991 -218.199237) (xy 122.943853 -218.207336)
			(xy 122.892079 -218.207336) (xy 122.840941 -218.199237) (xy 122.791701 -218.183238) (xy 122.745569 -218.159732)
			(xy 122.703682 -218.1293) (xy 122.667072 -218.09269) (xy 122.63664 -218.050803) (xy 122.613134 -218.004671)
			(xy 122.597135 -217.955431) (xy 122.589036 -217.904293) (xy 122.588528 -217.878406) (xy 122.589062 -217.850698)
			(xy 122.598255 -217.796051) (xy 122.606816 -217.769694) (xy 122.61469 -217.747596) (xy 122.409712 -217.392504)
			(xy 122.386852 -217.388186) (xy 122.361996 -217.383069) (xy 122.314148 -217.366166) (xy 122.269456 -217.342128)
			(xy 122.228977 -217.311523) (xy 122.193667 -217.275076) (xy 122.164361 -217.233647) (xy 122.141752 -217.188215)
			(xy 122.126374 -217.139855) (xy 122.11859 -217.089709) (xy 122.11812 -217.064336) (xy 120.897904 -217.064336)
			(xy 120.897289 -217.091989) (xy 120.887969 -217.146507) (xy 120.879362 -217.172794) (xy 120.871742 -217.194892)
			(xy 121.076974 -217.550238) (xy 121.099834 -217.554556) (xy 121.124641 -217.559728) (xy 121.172379 -217.576721)
			(xy 121.216956 -217.600818) (xy 121.25732 -217.631451) (xy 121.292523 -217.6679) (xy 121.321734 -217.709305)
			(xy 121.344266 -217.754693) (xy 121.359589 -217.802993) (xy 121.367341 -217.85307) (xy 121.367804 -217.878406)
			(xy 121.367296 -217.904293) (xy 121.359197 -217.955431) (xy 121.343198 -218.004671) (xy 121.319692 -218.050803)
			(xy 121.28926 -218.09269) (xy 121.25265 -218.1293) (xy 121.210763 -218.159732) (xy 121.164631 -218.183238)
			(xy 121.115391 -218.199237) (xy 121.064253 -218.207336) (xy 121.012479 -218.207336) (xy 120.961341 -218.199237)
			(xy 120.912101 -218.183238) (xy 120.865969 -218.159732) (xy 120.824082 -218.1293) (xy 120.787472 -218.09269)
			(xy 120.75704 -218.050803) (xy 120.733534 -218.004671) (xy 120.717535 -217.955431) (xy 120.709436 -217.904293)
			(xy 120.708928 -217.878406) (xy 120.709462 -217.850698) (xy 120.718655 -217.796051) (xy 120.727216 -217.769694)
			(xy 120.73509 -217.747596) (xy 120.530112 -217.392504) (xy 120.507252 -217.388186) (xy 120.482396 -217.383069)
			(xy 120.434548 -217.366166) (xy 120.389856 -217.342128) (xy 120.349377 -217.311523) (xy 120.314067 -217.275076)
			(xy 120.284761 -217.233647) (xy 120.262152 -217.188215) (xy 120.246774 -217.139855) (xy 120.23899 -217.089709)
			(xy 120.23852 -217.064336) (xy 119.018304 -217.064336) (xy 119.017689 -217.091989) (xy 119.008369 -217.146507)
			(xy 118.999762 -217.172794) (xy 118.992142 -217.194892) (xy 119.197374 -217.550238) (xy 119.220234 -217.554556)
			(xy 119.245041 -217.559728) (xy 119.292779 -217.576721) (xy 119.337356 -217.600818) (xy 119.37772 -217.631451)
			(xy 119.412923 -217.6679) (xy 119.442134 -217.709305) (xy 119.464666 -217.754693) (xy 119.479989 -217.802993)
			(xy 119.487741 -217.85307) (xy 119.488204 -217.878406) (xy 119.487696 -217.904293) (xy 119.479597 -217.955431)
			(xy 119.463598 -218.004671) (xy 119.440092 -218.050803) (xy 119.40966 -218.09269) (xy 119.37305 -218.1293)
			(xy 119.331163 -218.159732) (xy 119.285031 -218.183238) (xy 119.235791 -218.199237) (xy 119.184653 -218.207336)
			(xy 119.132879 -218.207336) (xy 119.081741 -218.199237) (xy 119.032501 -218.183238) (xy 118.986369 -218.159732)
			(xy 118.944482 -218.1293) (xy 118.907872 -218.09269) (xy 118.87744 -218.050803) (xy 118.853934 -218.004671)
			(xy 118.837935 -217.955431) (xy 118.829836 -217.904293) (xy 118.829328 -217.878406) (xy 118.829862 -217.850698)
			(xy 118.839055 -217.796051) (xy 118.847616 -217.769694) (xy 118.85549 -217.747596) (xy 118.650512 -217.392504)
			(xy 118.627652 -217.388186) (xy 118.602796 -217.383069) (xy 118.554948 -217.366166) (xy 118.510256 -217.342128)
			(xy 118.469777 -217.311523) (xy 118.434467 -217.275076) (xy 118.405161 -217.233647) (xy 118.382552 -217.188215)
			(xy 118.367174 -217.139855) (xy 118.35939 -217.089709) (xy 118.35892 -217.064336) (xy 117.138704 -217.064336)
			(xy 117.138089 -217.091989) (xy 117.128769 -217.146507) (xy 117.120162 -217.172794) (xy 117.112542 -217.194892)
			(xy 117.317774 -217.550238) (xy 117.340634 -217.554556) (xy 117.365441 -217.559728) (xy 117.413179 -217.576721)
			(xy 117.457756 -217.600818) (xy 117.49812 -217.631451) (xy 117.533323 -217.6679) (xy 117.562534 -217.709305)
			(xy 117.585066 -217.754693) (xy 117.600389 -217.802993) (xy 117.608141 -217.85307) (xy 117.608604 -217.878406)
			(xy 117.608096 -217.904293) (xy 117.599997 -217.955431) (xy 117.583998 -218.004671) (xy 117.560492 -218.050803)
			(xy 117.53006 -218.09269) (xy 117.49345 -218.1293) (xy 117.451563 -218.159732) (xy 117.405431 -218.183238)
			(xy 117.356191 -218.199237) (xy 117.305053 -218.207336) (xy 117.253279 -218.207336) (xy 117.202141 -218.199237)
			(xy 117.152901 -218.183238) (xy 117.106769 -218.159732) (xy 117.064882 -218.1293) (xy 117.028272 -218.09269)
			(xy 116.99784 -218.050803) (xy 116.974334 -218.004671) (xy 116.958335 -217.955431) (xy 116.950236 -217.904293)
			(xy 116.949728 -217.878406) (xy 116.950262 -217.850698) (xy 116.959455 -217.796051) (xy 116.968016 -217.769694)
			(xy 116.97589 -217.747596) (xy 116.770912 -217.392504) (xy 116.748052 -217.388186) (xy 116.723196 -217.383069)
			(xy 116.675348 -217.366166) (xy 116.630656 -217.342128) (xy 116.590177 -217.311523) (xy 116.554867 -217.275076)
			(xy 116.525561 -217.233647) (xy 116.502952 -217.188215) (xy 116.487574 -217.139855) (xy 116.47979 -217.089709)
			(xy 116.47932 -217.064336) (xy 115.259104 -217.064336) (xy 115.258489 -217.091989) (xy 115.249169 -217.146507)
			(xy 115.240562 -217.172794) (xy 115.232942 -217.194892) (xy 115.438174 -217.550238) (xy 115.461034 -217.554556)
			(xy 115.485841 -217.559728) (xy 115.533579 -217.576721) (xy 115.578156 -217.600818) (xy 115.61852 -217.631451)
			(xy 115.653723 -217.6679) (xy 115.682934 -217.709305) (xy 115.705466 -217.754693) (xy 115.720789 -217.802993)
			(xy 115.728541 -217.85307) (xy 115.729004 -217.878406) (xy 115.728496 -217.904293) (xy 115.720397 -217.955431)
			(xy 115.704398 -218.004671) (xy 115.680892 -218.050803) (xy 115.65046 -218.09269) (xy 115.61385 -218.1293)
			(xy 115.571963 -218.159732) (xy 115.525831 -218.183238) (xy 115.476591 -218.199237) (xy 115.425453 -218.207336)
			(xy 115.373679 -218.207336) (xy 115.322541 -218.199237) (xy 115.273301 -218.183238) (xy 115.227169 -218.159732)
			(xy 115.185282 -218.1293) (xy 115.148672 -218.09269) (xy 115.11824 -218.050803) (xy 115.094734 -218.004671)
			(xy 115.078735 -217.955431) (xy 115.070636 -217.904293) (xy 115.070128 -217.878406) (xy 115.070662 -217.850698)
			(xy 115.079855 -217.796051) (xy 115.088416 -217.769694) (xy 115.09629 -217.747596) (xy 114.891312 -217.392504)
			(xy 114.868452 -217.388186) (xy 114.843596 -217.383069) (xy 114.795748 -217.366166) (xy 114.751056 -217.342128)
			(xy 114.710577 -217.311523) (xy 114.675267 -217.275076) (xy 114.645961 -217.233647) (xy 114.623352 -217.188215)
			(xy 114.607974 -217.139855) (xy 114.60019 -217.089709) (xy 114.59972 -217.064336) (xy 113.379504 -217.064336)
			(xy 113.378889 -217.091989) (xy 113.369569 -217.146507) (xy 113.360962 -217.172794) (xy 113.353342 -217.194892)
			(xy 113.558574 -217.550238) (xy 113.581434 -217.554556) (xy 113.606241 -217.559728) (xy 113.653979 -217.576721)
			(xy 113.698556 -217.600818) (xy 113.73892 -217.631451) (xy 113.774123 -217.6679) (xy 113.803334 -217.709305)
			(xy 113.825866 -217.754693) (xy 113.841189 -217.802993) (xy 113.848941 -217.85307) (xy 113.849404 -217.878406)
			(xy 113.848896 -217.904293) (xy 113.840797 -217.955431) (xy 113.824798 -218.004671) (xy 113.801292 -218.050803)
			(xy 113.77086 -218.09269) (xy 113.73425 -218.1293) (xy 113.692363 -218.159732) (xy 113.646231 -218.183238)
			(xy 113.596991 -218.199237) (xy 113.545853 -218.207336) (xy 113.494079 -218.207336) (xy 113.442941 -218.199237)
			(xy 113.393701 -218.183238) (xy 113.347569 -218.159732) (xy 113.305682 -218.1293) (xy 113.269072 -218.09269)
			(xy 113.23864 -218.050803) (xy 113.215134 -218.004671) (xy 113.199135 -217.955431) (xy 113.191036 -217.904293)
			(xy 113.190528 -217.878406) (xy 113.191062 -217.850698) (xy 113.200255 -217.796051) (xy 113.208816 -217.769694)
			(xy 113.21669 -217.747596) (xy 113.011712 -217.392504) (xy 112.988852 -217.388186) (xy 112.963996 -217.383069)
			(xy 112.916148 -217.366166) (xy 112.871456 -217.342128) (xy 112.830977 -217.311523) (xy 112.795667 -217.275076)
			(xy 112.766361 -217.233647) (xy 112.743752 -217.188215) (xy 112.728374 -217.139855) (xy 112.72059 -217.089709)
			(xy 112.72012 -217.064336) (xy 111.499904 -217.064336) (xy 111.499412 -217.08968) (xy 111.491635 -217.13977)
			(xy 111.476286 -217.188079) (xy 111.453725 -217.233471) (xy 111.424484 -217.274876) (xy 111.389252 -217.311319)
			(xy 111.348859 -217.341943) (xy 111.304255 -217.366024) (xy 111.256492 -217.382998) (xy 111.23168 -217.388186)
			(xy 111.20882 -217.392504) (xy 111.003842 -217.747596) (xy 111.011716 -217.76944) (xy 111.020306 -217.795856)
			(xy 111.029495 -217.850633) (xy 111.030004 -217.878406) (xy 111.029496 -217.904293) (xy 111.021397 -217.955431)
			(xy 111.005398 -218.004671) (xy 110.981892 -218.050803) (xy 110.95146 -218.09269) (xy 110.91485 -218.1293)
			(xy 110.872963 -218.159732) (xy 110.826831 -218.183238) (xy 110.777591 -218.199237) (xy 110.726453 -218.207336)
			(xy 110.674679 -218.207336) (xy 110.623541 -218.199237) (xy 110.574301 -218.183238) (xy 110.528169 -218.159732)
			(xy 110.486282 -218.1293) (xy 110.449672 -218.09269) (xy 110.41924 -218.050803) (xy 110.395734 -218.004671)
			(xy 110.379735 -217.955431) (xy 110.371636 -217.904293) (xy 110.371128 -217.878406) (xy 110.090204 -217.878406)
			(xy 110.089676 -217.906114) (xy 110.08048 -217.960761) (xy 110.071916 -217.987118) (xy 110.064296 -218.008962)
			(xy 110.269274 -218.364054) (xy 110.292134 -218.368372) (xy 110.316944 -218.373529) (xy 110.364684 -218.390523)
			(xy 110.409261 -218.414621) (xy 110.449626 -218.445257) (xy 110.484829 -218.481707) (xy 110.51404 -218.523115)
			(xy 110.536571 -218.568504) (xy 110.551892 -218.616807) (xy 110.559642 -218.666885) (xy 110.560104 -218.692222)
			(xy 111.78032 -218.692222) (xy 111.780845 -218.666878) (xy 111.788614 -218.616789) (xy 111.803957 -218.56848)
			(xy 111.826512 -218.523087) (xy 111.855749 -218.481681) (xy 111.890978 -218.445236) (xy 111.931369 -218.414613)
			(xy 111.97597 -218.390531) (xy 112.023732 -218.373559) (xy 112.048544 -218.368372) (xy 112.071404 -218.364054)
			(xy 112.276636 -218.008708) (xy 112.268762 -217.98661) (xy 112.260294 -217.960366) (xy 112.251224 -217.905977)
			(xy 112.250728 -217.878406) (xy 112.251236 -217.852519) (xy 112.259335 -217.801381) (xy 112.275334 -217.752141)
			(xy 112.29884 -217.706009) (xy 112.329272 -217.664122) (xy 112.365882 -217.627512) (xy 112.407769 -217.59708)
			(xy 112.453901 -217.573574) (xy 112.503141 -217.557575) (xy 112.554279 -217.549476) (xy 112.606053 -217.549476)
			(xy 112.657191 -217.557575) (xy 112.706431 -217.573574) (xy 112.752563 -217.59708) (xy 112.79445 -217.627512)
			(xy 112.83106 -217.664122) (xy 112.861492 -217.706009) (xy 112.884998 -217.752141) (xy 112.900997 -217.801381)
			(xy 112.909096 -217.852519) (xy 112.909604 -217.878406) (xy 112.909131 -217.90378) (xy 112.901362 -217.953931)
			(xy 112.885993 -218.002296) (xy 112.863388 -218.047732) (xy 112.834082 -218.089163) (xy 112.798768 -218.125609)
			(xy 112.758282 -218.156208) (xy 112.713582 -218.180235) (xy 112.665726 -218.197122) (xy 112.640872 -218.202256)
			(xy 112.618012 -218.206574) (xy 112.413288 -218.561412) (xy 112.421162 -218.583256) (xy 112.429814 -218.609662)
			(xy 112.43913 -218.66444) (xy 112.439704 -218.692222) (xy 113.660428 -218.692222) (xy 113.660908 -218.666887)
			(xy 113.668658 -218.616813) (xy 113.683979 -218.568515) (xy 113.70651 -218.52313) (xy 113.73572 -218.481727)
			(xy 113.770922 -218.445282) (xy 113.811285 -218.414651) (xy 113.855861 -218.390558) (xy 113.903598 -218.37357)
			(xy 113.928398 -218.368372) (xy 113.951258 -218.364054) (xy 114.156236 -218.008962) (xy 114.148616 -217.986864)
			(xy 114.140092 -217.960694) (xy 114.130901 -217.906431) (xy 114.130328 -217.878914) (xy 114.130328 -217.878406)
			(xy 114.130836 -217.852519) (xy 114.138935 -217.801381) (xy 114.154934 -217.752141) (xy 114.17844 -217.706009)
			(xy 114.208872 -217.664122) (xy 114.245482 -217.627512) (xy 114.287369 -217.59708) (xy 114.333501 -217.573574)
			(xy 114.382741 -217.557575) (xy 114.433879 -217.549476) (xy 114.485653 -217.549476) (xy 114.536791 -217.557575)
			(xy 114.586031 -217.573574) (xy 114.632163 -217.59708) (xy 114.67405 -217.627512) (xy 114.71066 -217.664122)
			(xy 114.741092 -217.706009) (xy 114.764598 -217.752141) (xy 114.780597 -217.801381) (xy 114.788696 -217.852519)
			(xy 114.789204 -217.878406) (xy 114.788769 -217.903771) (xy 114.781019 -217.953906) (xy 114.765673 -218.002259)
			(xy 114.743093 -218.047686) (xy 114.713814 -218.089114) (xy 114.678529 -218.125562) (xy 114.638071 -218.156167)
			(xy 114.593399 -218.180207) (xy 114.545568 -218.197111) (xy 114.520726 -218.202256) (xy 114.497866 -218.206574)
			(xy 114.293142 -218.561412) (xy 114.301016 -218.583256) (xy 114.309609 -218.609671) (xy 114.318797 -218.664449)
			(xy 114.319304 -218.692222) (xy 115.53952 -218.692222) (xy 115.540045 -218.666878) (xy 115.547814 -218.616789)
			(xy 115.563157 -218.56848) (xy 115.585712 -218.523087) (xy 115.614949 -218.481681) (xy 115.650178 -218.445236)
			(xy 115.690569 -218.414613) (xy 115.73517 -218.390531) (xy 115.782932 -218.373559) (xy 115.807744 -218.368372)
			(xy 115.830604 -218.364054) (xy 116.035836 -218.008708) (xy 116.027962 -217.98661) (xy 116.019494 -217.960366)
			(xy 116.010424 -217.905977) (xy 116.009928 -217.878406) (xy 116.010436 -217.852519) (xy 116.018535 -217.801381)
			(xy 116.034534 -217.752141) (xy 116.05804 -217.706009) (xy 116.088472 -217.664122) (xy 116.125082 -217.627512)
			(xy 116.166969 -217.59708) (xy 116.213101 -217.573574) (xy 116.262341 -217.557575) (xy 116.313479 -217.549476)
			(xy 116.365253 -217.549476) (xy 116.416391 -217.557575) (xy 116.465631 -217.573574) (xy 116.511763 -217.59708)
			(xy 116.55365 -217.627512) (xy 116.59026 -217.664122) (xy 116.620692 -217.706009) (xy 116.644198 -217.752141)
			(xy 116.660197 -217.801381) (xy 116.668296 -217.852519) (xy 116.668804 -217.878406) (xy 116.668331 -217.90378)
			(xy 116.660562 -217.953931) (xy 116.645193 -218.002296) (xy 116.622588 -218.047732) (xy 116.593282 -218.089163)
			(xy 116.557968 -218.125609) (xy 116.517482 -218.156208) (xy 116.472782 -218.180235) (xy 116.424926 -218.197122)
			(xy 116.400072 -218.202256) (xy 116.377212 -218.206574) (xy 116.172488 -218.561412) (xy 116.180362 -218.583256)
			(xy 116.189014 -218.609662) (xy 116.19833 -218.66444) (xy 116.198904 -218.692222) (xy 117.41912 -218.692222)
			(xy 117.419645 -218.666878) (xy 117.427414 -218.616789) (xy 117.442757 -218.56848) (xy 117.465312 -218.523087)
			(xy 117.494549 -218.481681) (xy 117.529778 -218.445236) (xy 117.570169 -218.414613) (xy 117.61477 -218.390531)
			(xy 117.662532 -218.373559) (xy 117.687344 -218.368372) (xy 117.710204 -218.364054) (xy 117.915436 -218.008708)
			(xy 117.907562 -217.98661) (xy 117.899094 -217.960366) (xy 117.890024 -217.905977) (xy 117.889528 -217.878406)
			(xy 117.890036 -217.852519) (xy 117.898135 -217.801381) (xy 117.914134 -217.752141) (xy 117.93764 -217.706009)
			(xy 117.968072 -217.664122) (xy 118.004682 -217.627512) (xy 118.046569 -217.59708) (xy 118.092701 -217.573574)
			(xy 118.141941 -217.557575) (xy 118.193079 -217.549476) (xy 118.244853 -217.549476) (xy 118.295991 -217.557575)
			(xy 118.345231 -217.573574) (xy 118.391363 -217.59708) (xy 118.43325 -217.627512) (xy 118.46986 -217.664122)
			(xy 118.500292 -217.706009) (xy 118.523798 -217.752141) (xy 118.539797 -217.801381) (xy 118.547896 -217.852519)
			(xy 118.548404 -217.878406) (xy 118.547931 -217.90378) (xy 118.540162 -217.953931) (xy 118.524793 -218.002296)
			(xy 118.502188 -218.047732) (xy 118.472882 -218.089163) (xy 118.437568 -218.125609) (xy 118.397082 -218.156208)
			(xy 118.352382 -218.180235) (xy 118.304526 -218.197122) (xy 118.279672 -218.202256) (xy 118.256812 -218.206574)
			(xy 118.052088 -218.561412) (xy 118.059962 -218.583256) (xy 118.068614 -218.609662) (xy 118.07793 -218.66444)
			(xy 118.078504 -218.692222) (xy 119.29872 -218.692222) (xy 119.299245 -218.666878) (xy 119.307014 -218.616789)
			(xy 119.322357 -218.56848) (xy 119.344912 -218.523087) (xy 119.374149 -218.481681) (xy 119.409378 -218.445236)
			(xy 119.449769 -218.414613) (xy 119.49437 -218.390531) (xy 119.542132 -218.373559) (xy 119.566944 -218.368372)
			(xy 119.589804 -218.364054) (xy 119.795036 -218.008708) (xy 119.787162 -217.98661) (xy 119.778694 -217.960366)
			(xy 119.769624 -217.905977) (xy 119.769128 -217.878406) (xy 119.769636 -217.852519) (xy 119.777735 -217.801381)
			(xy 119.793734 -217.752141) (xy 119.81724 -217.706009) (xy 119.847672 -217.664122) (xy 119.884282 -217.627512)
			(xy 119.926169 -217.59708) (xy 119.972301 -217.573574) (xy 120.021541 -217.557575) (xy 120.072679 -217.549476)
			(xy 120.124453 -217.549476) (xy 120.175591 -217.557575) (xy 120.224831 -217.573574) (xy 120.270963 -217.59708)
			(xy 120.31285 -217.627512) (xy 120.34946 -217.664122) (xy 120.379892 -217.706009) (xy 120.403398 -217.752141)
			(xy 120.419397 -217.801381) (xy 120.427496 -217.852519) (xy 120.428004 -217.878406) (xy 120.427531 -217.90378)
			(xy 120.419762 -217.953931) (xy 120.404393 -218.002296) (xy 120.381788 -218.047732) (xy 120.352482 -218.089163)
			(xy 120.317168 -218.125609) (xy 120.276682 -218.156208) (xy 120.231982 -218.180235) (xy 120.184126 -218.197122)
			(xy 120.159272 -218.202256) (xy 120.136412 -218.206574) (xy 119.931688 -218.561412) (xy 119.939562 -218.583256)
			(xy 119.948214 -218.609662) (xy 119.95753 -218.66444) (xy 119.958104 -218.692222) (xy 121.17832 -218.692222)
			(xy 121.178845 -218.666878) (xy 121.186614 -218.616789) (xy 121.201957 -218.56848) (xy 121.224512 -218.523087)
			(xy 121.253749 -218.481681) (xy 121.288978 -218.445236) (xy 121.329369 -218.414613) (xy 121.37397 -218.390531)
			(xy 121.421732 -218.373559) (xy 121.446544 -218.368372) (xy 121.469404 -218.364054) (xy 121.674636 -218.008708)
			(xy 121.666762 -217.98661) (xy 121.658294 -217.960366) (xy 121.649224 -217.905977) (xy 121.648728 -217.878406)
			(xy 121.649236 -217.852519) (xy 121.657335 -217.801381) (xy 121.673334 -217.752141) (xy 121.69684 -217.706009)
			(xy 121.727272 -217.664122) (xy 121.763882 -217.627512) (xy 121.805769 -217.59708) (xy 121.851901 -217.573574)
			(xy 121.901141 -217.557575) (xy 121.952279 -217.549476) (xy 122.004053 -217.549476) (xy 122.055191 -217.557575)
			(xy 122.104431 -217.573574) (xy 122.150563 -217.59708) (xy 122.19245 -217.627512) (xy 122.22906 -217.664122)
			(xy 122.259492 -217.706009) (xy 122.282998 -217.752141) (xy 122.298997 -217.801381) (xy 122.307096 -217.852519)
			(xy 122.307604 -217.878406) (xy 122.307131 -217.90378) (xy 122.299362 -217.953931) (xy 122.283993 -218.002296)
			(xy 122.261388 -218.047732) (xy 122.232082 -218.089163) (xy 122.196768 -218.125609) (xy 122.156282 -218.156208)
			(xy 122.111582 -218.180235) (xy 122.063726 -218.197122) (xy 122.038872 -218.202256) (xy 122.016012 -218.206574)
			(xy 121.811288 -218.561412) (xy 121.819162 -218.583256) (xy 121.827814 -218.609662) (xy 121.83713 -218.66444)
			(xy 121.837704 -218.692222) (xy 123.05792 -218.692222) (xy 123.058445 -218.666878) (xy 123.066214 -218.616789)
			(xy 123.081557 -218.56848) (xy 123.104112 -218.523087) (xy 123.133349 -218.481681) (xy 123.168578 -218.445236)
			(xy 123.208969 -218.414613) (xy 123.25357 -218.390531) (xy 123.301332 -218.373559) (xy 123.326144 -218.368372)
			(xy 123.349004 -218.364054) (xy 123.554236 -218.008708) (xy 123.546362 -217.98661) (xy 123.537894 -217.960366)
			(xy 123.528824 -217.905977) (xy 123.528328 -217.878406) (xy 123.528836 -217.852519) (xy 123.536935 -217.801381)
			(xy 123.552934 -217.752141) (xy 123.57644 -217.706009) (xy 123.606872 -217.664122) (xy 123.643482 -217.627512)
			(xy 123.685369 -217.59708) (xy 123.731501 -217.573574) (xy 123.780741 -217.557575) (xy 123.831879 -217.549476)
			(xy 123.883653 -217.549476) (xy 123.934791 -217.557575) (xy 123.984031 -217.573574) (xy 124.030163 -217.59708)
			(xy 124.07205 -217.627512) (xy 124.10866 -217.664122) (xy 124.139092 -217.706009) (xy 124.162598 -217.752141)
			(xy 124.178597 -217.801381) (xy 124.186696 -217.852519) (xy 124.187204 -217.878406) (xy 124.186731 -217.90378)
			(xy 124.178962 -217.953931) (xy 124.163593 -218.002296) (xy 124.140988 -218.047732) (xy 124.111682 -218.089163)
			(xy 124.076368 -218.125609) (xy 124.035882 -218.156208) (xy 123.991182 -218.180235) (xy 123.943326 -218.197122)
			(xy 123.918472 -218.202256) (xy 123.895612 -218.206574) (xy 123.690888 -218.561412) (xy 123.698762 -218.583256)
			(xy 123.707414 -218.609662) (xy 123.71673 -218.66444) (xy 123.717304 -218.692222) (xy 124.93752 -218.692222)
			(xy 124.938045 -218.666878) (xy 124.945814 -218.616789) (xy 124.961157 -218.56848) (xy 124.983712 -218.523087)
			(xy 125.012949 -218.481681) (xy 125.048178 -218.445236) (xy 125.088569 -218.414613) (xy 125.13317 -218.390531)
			(xy 125.180932 -218.373559) (xy 125.205744 -218.368372) (xy 125.228604 -218.364054) (xy 125.433836 -218.008708)
			(xy 125.425962 -217.98661) (xy 125.417494 -217.960366) (xy 125.408424 -217.905977) (xy 125.407928 -217.878406)
			(xy 125.408436 -217.852519) (xy 125.416535 -217.801381) (xy 125.432534 -217.752141) (xy 125.45604 -217.706009)
			(xy 125.486472 -217.664122) (xy 125.523082 -217.627512) (xy 125.564969 -217.59708) (xy 125.611101 -217.573574)
			(xy 125.660341 -217.557575) (xy 125.711479 -217.549476) (xy 125.763253 -217.549476) (xy 125.814391 -217.557575)
			(xy 125.863631 -217.573574) (xy 125.909763 -217.59708) (xy 125.95165 -217.627512) (xy 125.98826 -217.664122)
			(xy 126.018692 -217.706009) (xy 126.042198 -217.752141) (xy 126.058197 -217.801381) (xy 126.066296 -217.852519)
			(xy 126.066804 -217.878406) (xy 126.066331 -217.90378) (xy 126.058562 -217.953931) (xy 126.043193 -218.002296)
			(xy 126.020588 -218.047732) (xy 125.991282 -218.089163) (xy 125.955968 -218.125609) (xy 125.915482 -218.156208)
			(xy 125.870782 -218.180235) (xy 125.822926 -218.197122) (xy 125.798072 -218.202256) (xy 125.775212 -218.206574)
			(xy 125.570488 -218.561412) (xy 125.578362 -218.583256) (xy 125.587014 -218.609662) (xy 125.59633 -218.66444)
			(xy 125.596904 -218.692222) (xy 126.81712 -218.692222) (xy 126.817645 -218.666878) (xy 126.825414 -218.616789)
			(xy 126.840757 -218.56848) (xy 126.863312 -218.523087) (xy 126.892549 -218.481681) (xy 126.927778 -218.445236)
			(xy 126.968169 -218.414613) (xy 127.01277 -218.390531) (xy 127.060532 -218.373559) (xy 127.085344 -218.368372)
			(xy 127.108204 -218.364054) (xy 127.313436 -218.008708) (xy 127.305562 -217.98661) (xy 127.297094 -217.960366)
			(xy 127.288024 -217.905977) (xy 127.287528 -217.878406) (xy 127.288036 -217.852519) (xy 127.296135 -217.801381)
			(xy 127.312134 -217.752141) (xy 127.33564 -217.706009) (xy 127.366072 -217.664122) (xy 127.402682 -217.627512)
			(xy 127.444569 -217.59708) (xy 127.490701 -217.573574) (xy 127.539941 -217.557575) (xy 127.591079 -217.549476)
			(xy 127.642853 -217.549476) (xy 127.693991 -217.557575) (xy 127.743231 -217.573574) (xy 127.789363 -217.59708)
			(xy 127.83125 -217.627512) (xy 127.86786 -217.664122) (xy 127.898292 -217.706009) (xy 127.921798 -217.752141)
			(xy 127.937797 -217.801381) (xy 127.945896 -217.852519) (xy 127.946404 -217.878406) (xy 127.945931 -217.90378)
			(xy 127.938162 -217.953931) (xy 127.922793 -218.002296) (xy 127.900188 -218.047732) (xy 127.870882 -218.089163)
			(xy 127.835568 -218.125609) (xy 127.795082 -218.156208) (xy 127.750382 -218.180235) (xy 127.702526 -218.197122)
			(xy 127.677672 -218.202256) (xy 127.654812 -218.206574) (xy 127.450088 -218.561412) (xy 127.457962 -218.583256)
			(xy 127.466614 -218.609662) (xy 127.47593 -218.66444) (xy 127.476504 -218.692222) (xy 128.69672 -218.692222)
			(xy 128.697245 -218.666878) (xy 128.705014 -218.616789) (xy 128.720357 -218.56848) (xy 128.742912 -218.523087)
			(xy 128.772149 -218.481681) (xy 128.807378 -218.445236) (xy 128.847769 -218.414613) (xy 128.89237 -218.390531)
			(xy 128.940132 -218.373559) (xy 128.964944 -218.368372) (xy 128.987804 -218.364054) (xy 129.193036 -218.008708)
			(xy 129.185162 -217.98661) (xy 129.176694 -217.960366) (xy 129.167624 -217.905977) (xy 129.167128 -217.878406)
			(xy 129.167636 -217.852519) (xy 129.175735 -217.801381) (xy 129.191734 -217.752141) (xy 129.21524 -217.706009)
			(xy 129.245672 -217.664122) (xy 129.282282 -217.627512) (xy 129.324169 -217.59708) (xy 129.370301 -217.573574)
			(xy 129.419541 -217.557575) (xy 129.470679 -217.549476) (xy 129.522453 -217.549476) (xy 129.573591 -217.557575)
			(xy 129.622831 -217.573574) (xy 129.668963 -217.59708) (xy 129.71085 -217.627512) (xy 129.74746 -217.664122)
			(xy 129.777892 -217.706009) (xy 129.801398 -217.752141) (xy 129.817397 -217.801381) (xy 129.825496 -217.852519)
			(xy 129.826004 -217.878406) (xy 129.825531 -217.90378) (xy 129.817762 -217.953931) (xy 129.802393 -218.002296)
			(xy 129.779788 -218.047732) (xy 129.750482 -218.089163) (xy 129.715168 -218.125609) (xy 129.674682 -218.156208)
			(xy 129.629982 -218.180235) (xy 129.582126 -218.197122) (xy 129.557272 -218.202256) (xy 129.534412 -218.206574)
			(xy 129.329688 -218.561412) (xy 129.337562 -218.583256) (xy 129.346214 -218.609662) (xy 129.35553 -218.66444)
			(xy 129.356104 -218.692222) (xy 130.57632 -218.692222) (xy 130.576845 -218.666878) (xy 130.584614 -218.616789)
			(xy 130.599957 -218.56848) (xy 130.622512 -218.523087) (xy 130.651749 -218.481681) (xy 130.686978 -218.445236)
			(xy 130.727369 -218.414613) (xy 130.77197 -218.390531) (xy 130.819732 -218.373559) (xy 130.844544 -218.368372)
			(xy 130.867404 -218.364054) (xy 131.072636 -218.008708) (xy 131.064762 -217.98661) (xy 131.056294 -217.960366)
			(xy 131.047224 -217.905977) (xy 131.046728 -217.878406) (xy 131.047236 -217.852519) (xy 131.055335 -217.801381)
			(xy 131.071334 -217.752141) (xy 131.09484 -217.706009) (xy 131.125272 -217.664122) (xy 131.161882 -217.627512)
			(xy 131.203769 -217.59708) (xy 131.249901 -217.573574) (xy 131.299141 -217.557575) (xy 131.350279 -217.549476)
			(xy 131.402053 -217.549476) (xy 131.453191 -217.557575) (xy 131.502431 -217.573574) (xy 131.548563 -217.59708)
			(xy 131.59045 -217.627512) (xy 131.62706 -217.664122) (xy 131.657492 -217.706009) (xy 131.680998 -217.752141)
			(xy 131.696997 -217.801381) (xy 131.705096 -217.852519) (xy 131.705604 -217.878406) (xy 131.705131 -217.90378)
			(xy 131.697362 -217.953931) (xy 131.681993 -218.002296) (xy 131.659388 -218.047732) (xy 131.630082 -218.089163)
			(xy 131.594768 -218.125609) (xy 131.554282 -218.156208) (xy 131.509582 -218.180235) (xy 131.461726 -218.197122)
			(xy 131.436872 -218.202256) (xy 131.414012 -218.206574) (xy 131.209288 -218.561412) (xy 131.217162 -218.583256)
			(xy 131.225814 -218.609662) (xy 131.23513 -218.66444) (xy 131.235704 -218.692222) (xy 132.45592 -218.692222)
			(xy 132.456445 -218.666878) (xy 132.464214 -218.616789) (xy 132.479557 -218.56848) (xy 132.502112 -218.523087)
			(xy 132.531349 -218.481681) (xy 132.566578 -218.445236) (xy 132.606969 -218.414613) (xy 132.65157 -218.390531)
			(xy 132.699332 -218.373559) (xy 132.724144 -218.368372) (xy 132.747004 -218.364054) (xy 132.952236 -218.008708)
			(xy 132.944362 -217.98661) (xy 132.935894 -217.960366) (xy 132.926824 -217.905977) (xy 132.926328 -217.878406)
			(xy 132.926836 -217.852519) (xy 132.934935 -217.801381) (xy 132.950934 -217.752141) (xy 132.97444 -217.706009)
			(xy 133.004872 -217.664122) (xy 133.041482 -217.627512) (xy 133.083369 -217.59708) (xy 133.129501 -217.573574)
			(xy 133.178741 -217.557575) (xy 133.229879 -217.549476) (xy 133.281653 -217.549476) (xy 133.332791 -217.557575)
			(xy 133.382031 -217.573574) (xy 133.428163 -217.59708) (xy 133.47005 -217.627512) (xy 133.50666 -217.664122)
			(xy 133.537092 -217.706009) (xy 133.560598 -217.752141) (xy 133.576597 -217.801381) (xy 133.584696 -217.852519)
			(xy 133.585204 -217.878406) (xy 133.584731 -217.90378) (xy 133.576962 -217.953931) (xy 133.561593 -218.002296)
			(xy 133.538988 -218.047732) (xy 133.509682 -218.089163) (xy 133.474368 -218.125609) (xy 133.433882 -218.156208)
			(xy 133.389182 -218.180235) (xy 133.341326 -218.197122) (xy 133.316472 -218.202256) (xy 133.293612 -218.206574)
			(xy 133.088888 -218.561412) (xy 133.096762 -218.583256) (xy 133.105414 -218.609662) (xy 133.11473 -218.66444)
			(xy 133.115304 -218.692222) (xy 133.114796 -218.718129) (xy 133.10669 -218.769306) (xy 133.090678 -218.818585)
			(xy 133.067155 -218.864752) (xy 133.036699 -218.906671) (xy 133.000061 -218.943309) (xy 132.958142 -218.973765)
			(xy 132.911975 -218.997288) (xy 132.862696 -219.0133) (xy 132.811519 -219.021406) (xy 132.759705 -219.021406)
			(xy 132.708528 -219.0133) (xy 132.659249 -218.997288) (xy 132.613082 -218.973765) (xy 132.571163 -218.943309)
			(xy 132.534525 -218.906671) (xy 132.504069 -218.864752) (xy 132.480546 -218.818585) (xy 132.464534 -218.769306)
			(xy 132.456428 -218.718129) (xy 132.45592 -218.692222) (xy 131.235704 -218.692222) (xy 131.235196 -218.718129)
			(xy 131.22709 -218.769306) (xy 131.211078 -218.818585) (xy 131.187555 -218.864752) (xy 131.157099 -218.906671)
			(xy 131.120461 -218.943309) (xy 131.078542 -218.973765) (xy 131.032375 -218.997288) (xy 130.983096 -219.0133)
			(xy 130.931919 -219.021406) (xy 130.880105 -219.021406) (xy 130.828928 -219.0133) (xy 130.779649 -218.997288)
			(xy 130.733482 -218.973765) (xy 130.691563 -218.943309) (xy 130.654925 -218.906671) (xy 130.624469 -218.864752)
			(xy 130.600946 -218.818585) (xy 130.584934 -218.769306) (xy 130.576828 -218.718129) (xy 130.57632 -218.692222)
			(xy 129.356104 -218.692222) (xy 129.355596 -218.718129) (xy 129.34749 -218.769306) (xy 129.331478 -218.818585)
			(xy 129.307955 -218.864752) (xy 129.277499 -218.906671) (xy 129.240861 -218.943309) (xy 129.198942 -218.973765)
			(xy 129.152775 -218.997288) (xy 129.103496 -219.0133) (xy 129.052319 -219.021406) (xy 129.000505 -219.021406)
			(xy 128.949328 -219.0133) (xy 128.900049 -218.997288) (xy 128.853882 -218.973765) (xy 128.811963 -218.943309)
			(xy 128.775325 -218.906671) (xy 128.744869 -218.864752) (xy 128.721346 -218.818585) (xy 128.705334 -218.769306)
			(xy 128.697228 -218.718129) (xy 128.69672 -218.692222) (xy 127.476504 -218.692222) (xy 127.475996 -218.718129)
			(xy 127.46789 -218.769306) (xy 127.451878 -218.818585) (xy 127.428355 -218.864752) (xy 127.397899 -218.906671)
			(xy 127.361261 -218.943309) (xy 127.319342 -218.973765) (xy 127.273175 -218.997288) (xy 127.223896 -219.0133)
			(xy 127.172719 -219.021406) (xy 127.120905 -219.021406) (xy 127.069728 -219.0133) (xy 127.020449 -218.997288)
			(xy 126.974282 -218.973765) (xy 126.932363 -218.943309) (xy 126.895725 -218.906671) (xy 126.865269 -218.864752)
			(xy 126.841746 -218.818585) (xy 126.825734 -218.769306) (xy 126.817628 -218.718129) (xy 126.81712 -218.692222)
			(xy 125.596904 -218.692222) (xy 125.596396 -218.718129) (xy 125.58829 -218.769306) (xy 125.572278 -218.818585)
			(xy 125.548755 -218.864752) (xy 125.518299 -218.906671) (xy 125.481661 -218.943309) (xy 125.439742 -218.973765)
			(xy 125.393575 -218.997288) (xy 125.344296 -219.0133) (xy 125.293119 -219.021406) (xy 125.241305 -219.021406)
			(xy 125.190128 -219.0133) (xy 125.140849 -218.997288) (xy 125.094682 -218.973765) (xy 125.052763 -218.943309)
			(xy 125.016125 -218.906671) (xy 124.985669 -218.864752) (xy 124.962146 -218.818585) (xy 124.946134 -218.769306)
			(xy 124.938028 -218.718129) (xy 124.93752 -218.692222) (xy 123.717304 -218.692222) (xy 123.716796 -218.718129)
			(xy 123.70869 -218.769306) (xy 123.692678 -218.818585) (xy 123.669155 -218.864752) (xy 123.638699 -218.906671)
			(xy 123.602061 -218.943309) (xy 123.560142 -218.973765) (xy 123.513975 -218.997288) (xy 123.464696 -219.0133)
			(xy 123.413519 -219.021406) (xy 123.361705 -219.021406) (xy 123.310528 -219.0133) (xy 123.261249 -218.997288)
			(xy 123.215082 -218.973765) (xy 123.173163 -218.943309) (xy 123.136525 -218.906671) (xy 123.106069 -218.864752)
			(xy 123.082546 -218.818585) (xy 123.066534 -218.769306) (xy 123.058428 -218.718129) (xy 123.05792 -218.692222)
			(xy 121.837704 -218.692222) (xy 121.837196 -218.718129) (xy 121.82909 -218.769306) (xy 121.813078 -218.818585)
			(xy 121.789555 -218.864752) (xy 121.759099 -218.906671) (xy 121.722461 -218.943309) (xy 121.680542 -218.973765)
			(xy 121.634375 -218.997288) (xy 121.585096 -219.0133) (xy 121.533919 -219.021406) (xy 121.482105 -219.021406)
			(xy 121.430928 -219.0133) (xy 121.381649 -218.997288) (xy 121.335482 -218.973765) (xy 121.293563 -218.943309)
			(xy 121.256925 -218.906671) (xy 121.226469 -218.864752) (xy 121.202946 -218.818585) (xy 121.186934 -218.769306)
			(xy 121.178828 -218.718129) (xy 121.17832 -218.692222) (xy 119.958104 -218.692222) (xy 119.957596 -218.718129)
			(xy 119.94949 -218.769306) (xy 119.933478 -218.818585) (xy 119.909955 -218.864752) (xy 119.879499 -218.906671)
			(xy 119.842861 -218.943309) (xy 119.800942 -218.973765) (xy 119.754775 -218.997288) (xy 119.705496 -219.0133)
			(xy 119.654319 -219.021406) (xy 119.602505 -219.021406) (xy 119.551328 -219.0133) (xy 119.502049 -218.997288)
			(xy 119.455882 -218.973765) (xy 119.413963 -218.943309) (xy 119.377325 -218.906671) (xy 119.346869 -218.864752)
			(xy 119.323346 -218.818585) (xy 119.307334 -218.769306) (xy 119.299228 -218.718129) (xy 119.29872 -218.692222)
			(xy 118.078504 -218.692222) (xy 118.077996 -218.718129) (xy 118.06989 -218.769306) (xy 118.053878 -218.818585)
			(xy 118.030355 -218.864752) (xy 117.999899 -218.906671) (xy 117.963261 -218.943309) (xy 117.921342 -218.973765)
			(xy 117.875175 -218.997288) (xy 117.825896 -219.0133) (xy 117.774719 -219.021406) (xy 117.722905 -219.021406)
			(xy 117.671728 -219.0133) (xy 117.622449 -218.997288) (xy 117.576282 -218.973765) (xy 117.534363 -218.943309)
			(xy 117.497725 -218.906671) (xy 117.467269 -218.864752) (xy 117.443746 -218.818585) (xy 117.427734 -218.769306)
			(xy 117.419628 -218.718129) (xy 117.41912 -218.692222) (xy 116.198904 -218.692222) (xy 116.198396 -218.718129)
			(xy 116.19029 -218.769306) (xy 116.174278 -218.818585) (xy 116.150755 -218.864752) (xy 116.120299 -218.906671)
			(xy 116.083661 -218.943309) (xy 116.041742 -218.973765) (xy 115.995575 -218.997288) (xy 115.946296 -219.0133)
			(xy 115.895119 -219.021406) (xy 115.843305 -219.021406) (xy 115.792128 -219.0133) (xy 115.742849 -218.997288)
			(xy 115.696682 -218.973765) (xy 115.654763 -218.943309) (xy 115.618125 -218.906671) (xy 115.587669 -218.864752)
			(xy 115.564146 -218.818585) (xy 115.548134 -218.769306) (xy 115.540028 -218.718129) (xy 115.53952 -218.692222)
			(xy 114.319304 -218.692222) (xy 114.318796 -218.718109) (xy 114.310697 -218.769247) (xy 114.294698 -218.818487)
			(xy 114.271192 -218.864619) (xy 114.24076 -218.906506) (xy 114.20415 -218.943116) (xy 114.162263 -218.973548)
			(xy 114.116131 -218.997054) (xy 114.066891 -219.013053) (xy 114.015753 -219.021152) (xy 113.963979 -219.021152)
			(xy 113.912841 -219.013053) (xy 113.863601 -218.997054) (xy 113.817469 -218.973548) (xy 113.775582 -218.943116)
			(xy 113.738972 -218.906506) (xy 113.70854 -218.864619) (xy 113.685034 -218.818487) (xy 113.669035 -218.769247)
			(xy 113.660936 -218.718109) (xy 113.660428 -218.692222) (xy 112.439704 -218.692222) (xy 112.439196 -218.718129)
			(xy 112.43109 -218.769306) (xy 112.415078 -218.818585) (xy 112.391555 -218.864752) (xy 112.361099 -218.906671)
			(xy 112.324461 -218.943309) (xy 112.282542 -218.973765) (xy 112.236375 -218.997288) (xy 112.187096 -219.0133)
			(xy 112.135919 -219.021406) (xy 112.084105 -219.021406) (xy 112.032928 -219.0133) (xy 111.983649 -218.997288)
			(xy 111.937482 -218.973765) (xy 111.895563 -218.943309) (xy 111.858925 -218.906671) (xy 111.828469 -218.864752)
			(xy 111.804946 -218.818585) (xy 111.788934 -218.769306) (xy 111.780828 -218.718129) (xy 111.78032 -218.692222)
			(xy 110.560104 -218.692222) (xy 110.559596 -218.718109) (xy 110.551497 -218.769247) (xy 110.535498 -218.818487)
			(xy 110.511992 -218.864619) (xy 110.48156 -218.906506) (xy 110.44495 -218.943116) (xy 110.403063 -218.973548)
			(xy 110.356931 -218.997054) (xy 110.307691 -219.013053) (xy 110.256553 -219.021152) (xy 110.204779 -219.021152)
			(xy 110.153641 -219.013053) (xy 110.104401 -218.997054) (xy 110.058269 -218.973548) (xy 110.016382 -218.943116)
			(xy 109.979772 -218.906506) (xy 109.94934 -218.864619) (xy 109.925834 -218.818487) (xy 109.909835 -218.769247)
			(xy 109.901736 -218.718109) (xy 109.901228 -218.692222) (xy 109.901766 -218.664514) (xy 109.910956 -218.609868)
			(xy 109.919516 -218.58351) (xy 109.92739 -218.561412) (xy 109.722412 -218.206574) (xy 109.699552 -218.202256)
			(xy 109.67472 -218.197133) (xy 109.626938 -218.180175) (xy 109.582316 -218.1561) (xy 109.541908 -218.125474)
			(xy 109.506667 -218.089022) (xy 109.477424 -218.047602) (xy 109.45487 -218.002192) (xy 109.439537 -217.953864)
			(xy 109.431786 -217.903757) (xy 109.431328 -217.878406) (xy 109.150404 -217.878406) (xy 109.149896 -217.904293)
			(xy 109.141797 -217.955431) (xy 109.125798 -218.004671) (xy 109.102292 -218.050803) (xy 109.07186 -218.09269)
			(xy 109.03525 -218.1293) (xy 108.993363 -218.159732) (xy 108.947231 -218.183238) (xy 108.897991 -218.199237)
			(xy 108.846853 -218.207336) (xy 108.795079 -218.207336) (xy 108.743941 -218.199237) (xy 108.694701 -218.183238)
			(xy 108.648569 -218.159732) (xy 108.606682 -218.1293) (xy 108.570072 -218.09269) (xy 108.53964 -218.050803)
			(xy 108.516134 -218.004671) (xy 108.500135 -217.955431) (xy 108.492036 -217.904293) (xy 108.491528 -217.878406)
			(xy 108.210604 -217.878406) (xy 108.210076 -217.906114) (xy 108.20088 -217.960761) (xy 108.192316 -217.987118)
			(xy 108.184442 -218.009216) (xy 108.38942 -218.364054) (xy 108.41228 -218.368372) (xy 108.4371 -218.37354)
			(xy 108.484878 -218.390497) (xy 108.529495 -218.41457) (xy 108.5699 -218.44519) (xy 108.60514 -218.481637)
			(xy 108.634384 -218.52305) (xy 108.656942 -218.568452) (xy 108.672281 -218.616773) (xy 108.680041 -218.666873)
			(xy 108.680504 -218.692222) (xy 108.679996 -218.718129) (xy 108.67189 -218.769306) (xy 108.655878 -218.818585)
			(xy 108.632355 -218.864752) (xy 108.601899 -218.906671) (xy 108.565261 -218.943309) (xy 108.523342 -218.973765)
			(xy 108.477175 -218.997288) (xy 108.427896 -219.0133) (xy 108.376719 -219.021406) (xy 108.324905 -219.021406)
			(xy 108.273728 -219.0133) (xy 108.224449 -218.997288) (xy 108.178282 -218.973765) (xy 108.136363 -218.943309)
			(xy 108.099725 -218.906671) (xy 108.069269 -218.864752) (xy 108.045746 -218.818585) (xy 108.029734 -218.769306)
			(xy 108.021628 -218.718129) (xy 108.02112 -218.692222) (xy 108.021718 -218.664505) (xy 108.031039 -218.609858)
			(xy 108.039662 -218.58351) (xy 108.047536 -218.561412) (xy 107.842558 -218.206574) (xy 107.819698 -218.202256)
			(xy 107.794899 -218.197049) (xy 107.747162 -218.180062) (xy 107.702585 -218.15597) (xy 107.66222 -218.125341)
			(xy 107.627017 -218.088897) (xy 107.597804 -218.047495) (xy 107.575271 -218.002112) (xy 107.559946 -217.953814)
			(xy 107.552192 -217.903741) (xy 107.551728 -217.878406) (xy 107.270804 -217.878406) (xy 107.270296 -217.904293)
			(xy 107.262197 -217.955431) (xy 107.246198 -218.004671) (xy 107.222692 -218.050803) (xy 107.19226 -218.09269)
			(xy 107.15565 -218.1293) (xy 107.113763 -218.159732) (xy 107.067631 -218.183238) (xy 107.018391 -218.199237)
			(xy 106.967253 -218.207336) (xy 106.915479 -218.207336) (xy 106.864341 -218.199237) (xy 106.815101 -218.183238)
			(xy 106.768969 -218.159732) (xy 106.727082 -218.1293) (xy 106.690472 -218.09269) (xy 106.66004 -218.050803)
			(xy 106.636534 -218.004671) (xy 106.620535 -217.955431) (xy 106.612436 -217.904293) (xy 106.611928 -217.878406)
			(xy 106.331004 -217.878406) (xy 106.330476 -217.906114) (xy 106.32128 -217.960761) (xy 106.312716 -217.987118)
			(xy 106.304842 -218.009216) (xy 106.50982 -218.364054) (xy 106.53268 -218.368372) (xy 106.5575 -218.37354)
			(xy 106.605278 -218.390497) (xy 106.649895 -218.41457) (xy 106.6903 -218.44519) (xy 106.72554 -218.481637)
			(xy 106.754784 -218.52305) (xy 106.777342 -218.568452) (xy 106.792681 -218.616773) (xy 106.800441 -218.666873)
			(xy 106.800904 -218.692222) (xy 106.800396 -218.718129) (xy 106.79229 -218.769306) (xy 106.776278 -218.818585)
			(xy 106.752755 -218.864752) (xy 106.722299 -218.906671) (xy 106.685661 -218.943309) (xy 106.643742 -218.973765)
			(xy 106.597575 -218.997288) (xy 106.548296 -219.0133) (xy 106.497119 -219.021406) (xy 106.445305 -219.021406)
			(xy 106.394128 -219.0133) (xy 106.344849 -218.997288) (xy 106.298682 -218.973765) (xy 106.256763 -218.943309)
			(xy 106.220125 -218.906671) (xy 106.189669 -218.864752) (xy 106.166146 -218.818585) (xy 106.150134 -218.769306)
			(xy 106.142028 -218.718129) (xy 106.14152 -218.692222) (xy 106.142118 -218.664505) (xy 106.151439 -218.609858)
			(xy 106.160062 -218.58351) (xy 106.167936 -218.561412) (xy 105.962958 -218.206574) (xy 105.940098 -218.202256)
			(xy 105.915299 -218.197049) (xy 105.867562 -218.180062) (xy 105.822985 -218.15597) (xy 105.78262 -218.125341)
			(xy 105.747417 -218.088897) (xy 105.718204 -218.047495) (xy 105.695671 -218.002112) (xy 105.680346 -217.953814)
			(xy 105.672592 -217.903741) (xy 105.672128 -217.878406) (xy 105.391204 -217.878406) (xy 105.390696 -217.904293)
			(xy 105.382597 -217.955431) (xy 105.366598 -218.004671) (xy 105.343092 -218.050803) (xy 105.31266 -218.09269)
			(xy 105.27605 -218.1293) (xy 105.234163 -218.159732) (xy 105.188031 -218.183238) (xy 105.138791 -218.199237)
			(xy 105.087653 -218.207336) (xy 105.035879 -218.207336) (xy 104.984741 -218.199237) (xy 104.935501 -218.183238)
			(xy 104.889369 -218.159732) (xy 104.847482 -218.1293) (xy 104.810872 -218.09269) (xy 104.78044 -218.050803)
			(xy 104.756934 -218.004671) (xy 104.740935 -217.955431) (xy 104.732836 -217.904293) (xy 104.732328 -217.878406)
			(xy 104.451404 -217.878406) (xy 104.450876 -217.906114) (xy 104.44168 -217.960761) (xy 104.433116 -217.987118)
			(xy 104.425242 -218.009216) (xy 104.63022 -218.364054) (xy 104.65308 -218.368372) (xy 104.6779 -218.37354)
			(xy 104.725678 -218.390497) (xy 104.770295 -218.41457) (xy 104.8107 -218.44519) (xy 104.84594 -218.481637)
			(xy 104.875184 -218.52305) (xy 104.897742 -218.568452) (xy 104.913081 -218.616773) (xy 104.920841 -218.666873)
			(xy 104.921304 -218.692222) (xy 104.920796 -218.718129) (xy 104.91269 -218.769306) (xy 104.896678 -218.818585)
			(xy 104.873155 -218.864752) (xy 104.842699 -218.906671) (xy 104.806061 -218.943309) (xy 104.764142 -218.973765)
			(xy 104.717975 -218.997288) (xy 104.668696 -219.0133) (xy 104.617519 -219.021406) (xy 104.565705 -219.021406)
			(xy 104.514528 -219.0133) (xy 104.465249 -218.997288) (xy 104.419082 -218.973765) (xy 104.377163 -218.943309)
			(xy 104.340525 -218.906671) (xy 104.310069 -218.864752) (xy 104.286546 -218.818585) (xy 104.270534 -218.769306)
			(xy 104.262428 -218.718129) (xy 104.26192 -218.692222) (xy 104.262518 -218.664505) (xy 104.271839 -218.609858)
			(xy 104.280462 -218.58351) (xy 104.288336 -218.561412) (xy 104.083358 -218.206574) (xy 104.060498 -218.202256)
			(xy 104.035699 -218.197049) (xy 103.987962 -218.180062) (xy 103.943385 -218.15597) (xy 103.90302 -218.125341)
			(xy 103.867817 -218.088897) (xy 103.838604 -218.047495) (xy 103.816071 -218.002112) (xy 103.800746 -217.953814)
			(xy 103.792992 -217.903741) (xy 103.792528 -217.878406) (xy 103.511604 -217.878406) (xy 103.511096 -217.904293)
			(xy 103.502997 -217.955431) (xy 103.486998 -218.004671) (xy 103.463492 -218.050803) (xy 103.43306 -218.09269)
			(xy 103.39645 -218.1293) (xy 103.354563 -218.159732) (xy 103.308431 -218.183238) (xy 103.259191 -218.199237)
			(xy 103.208053 -218.207336) (xy 103.156279 -218.207336) (xy 103.105141 -218.199237) (xy 103.055901 -218.183238)
			(xy 103.009769 -218.159732) (xy 102.967882 -218.1293) (xy 102.931272 -218.09269) (xy 102.90084 -218.050803)
			(xy 102.877334 -218.004671) (xy 102.861335 -217.955431) (xy 102.853236 -217.904293) (xy 102.852728 -217.878406)
			(xy 102.571804 -217.878406) (xy 102.571276 -217.906114) (xy 102.56208 -217.960761) (xy 102.553516 -217.987118)
			(xy 102.545642 -218.009216) (xy 102.75062 -218.364054) (xy 102.77348 -218.368372) (xy 102.7983 -218.37354)
			(xy 102.846078 -218.390497) (xy 102.890695 -218.41457) (xy 102.9311 -218.44519) (xy 102.96634 -218.481637)
			(xy 102.995584 -218.52305) (xy 103.018142 -218.568452) (xy 103.033481 -218.616773) (xy 103.041241 -218.666873)
			(xy 103.041704 -218.692222) (xy 103.041196 -218.718129) (xy 103.03309 -218.769306) (xy 103.017078 -218.818585)
			(xy 102.993555 -218.864752) (xy 102.963099 -218.906671) (xy 102.926461 -218.943309) (xy 102.884542 -218.973765)
			(xy 102.838375 -218.997288) (xy 102.789096 -219.0133) (xy 102.737919 -219.021406) (xy 102.686105 -219.021406)
			(xy 102.634928 -219.0133) (xy 102.585649 -218.997288) (xy 102.539482 -218.973765) (xy 102.497563 -218.943309)
			(xy 102.460925 -218.906671) (xy 102.430469 -218.864752) (xy 102.406946 -218.818585) (xy 102.390934 -218.769306)
			(xy 102.382828 -218.718129) (xy 102.38232 -218.692222) (xy 102.382918 -218.664505) (xy 102.392239 -218.609858)
			(xy 102.400862 -218.58351) (xy 102.408736 -218.561412) (xy 102.203758 -218.206574) (xy 102.180898 -218.202256)
			(xy 102.156099 -218.197049) (xy 102.108362 -218.180062) (xy 102.063785 -218.15597) (xy 102.02342 -218.125341)
			(xy 101.988217 -218.088897) (xy 101.959004 -218.047495) (xy 101.936471 -218.002112) (xy 101.921146 -217.953814)
			(xy 101.913392 -217.903741) (xy 101.912928 -217.878406) (xy 101.632004 -217.878406) (xy 101.631496 -217.904293)
			(xy 101.623397 -217.955431) (xy 101.607398 -218.004671) (xy 101.583892 -218.050803) (xy 101.55346 -218.09269)
			(xy 101.51685 -218.1293) (xy 101.474963 -218.159732) (xy 101.428831 -218.183238) (xy 101.379591 -218.199237)
			(xy 101.328453 -218.207336) (xy 101.276679 -218.207336) (xy 101.225541 -218.199237) (xy 101.176301 -218.183238)
			(xy 101.130169 -218.159732) (xy 101.088282 -218.1293) (xy 101.051672 -218.09269) (xy 101.02124 -218.050803)
			(xy 100.997734 -218.004671) (xy 100.981735 -217.955431) (xy 100.973636 -217.904293) (xy 100.973128 -217.878406)
			(xy 100.692204 -217.878406) (xy 100.691676 -217.906114) (xy 100.68248 -217.960761) (xy 100.673916 -217.987118)
			(xy 100.666042 -218.009216) (xy 100.87102 -218.364054) (xy 100.89388 -218.368372) (xy 100.9187 -218.37354)
			(xy 100.966478 -218.390497) (xy 101.011095 -218.41457) (xy 101.0515 -218.44519) (xy 101.08674 -218.481637)
			(xy 101.115984 -218.52305) (xy 101.138542 -218.568452) (xy 101.153881 -218.616773) (xy 101.161641 -218.666873)
			(xy 101.162104 -218.692222) (xy 101.161596 -218.718129) (xy 101.15349 -218.769306) (xy 101.137478 -218.818585)
			(xy 101.113955 -218.864752) (xy 101.083499 -218.906671) (xy 101.046861 -218.943309) (xy 101.004942 -218.973765)
			(xy 100.958775 -218.997288) (xy 100.909496 -219.0133) (xy 100.858319 -219.021406) (xy 100.806505 -219.021406)
			(xy 100.755328 -219.0133) (xy 100.706049 -218.997288) (xy 100.659882 -218.973765) (xy 100.617963 -218.943309)
			(xy 100.581325 -218.906671) (xy 100.550869 -218.864752) (xy 100.527346 -218.818585) (xy 100.511334 -218.769306)
			(xy 100.503228 -218.718129) (xy 100.50272 -218.692222) (xy 100.503318 -218.664505) (xy 100.512639 -218.609858)
			(xy 100.521262 -218.58351) (xy 100.529136 -218.561412) (xy 100.324158 -218.206574) (xy 100.301298 -218.202256)
			(xy 100.276499 -218.197049) (xy 100.228762 -218.180062) (xy 100.184185 -218.15597) (xy 100.14382 -218.125341)
			(xy 100.108617 -218.088897) (xy 100.079404 -218.047495) (xy 100.056871 -218.002112) (xy 100.041546 -217.953814)
			(xy 100.033792 -217.903741) (xy 100.033328 -217.878406) (xy 99.752404 -217.878406) (xy 99.751896 -217.904293)
			(xy 99.743797 -217.955431) (xy 99.727798 -218.004671) (xy 99.704292 -218.050803) (xy 99.67386 -218.09269)
			(xy 99.63725 -218.1293) (xy 99.595363 -218.159732) (xy 99.549231 -218.183238) (xy 99.499991 -218.199237)
			(xy 99.448853 -218.207336) (xy 99.397079 -218.207336) (xy 99.345941 -218.199237) (xy 99.296701 -218.183238)
			(xy 99.250569 -218.159732) (xy 99.208682 -218.1293) (xy 99.172072 -218.09269) (xy 99.14164 -218.050803)
			(xy 99.118134 -218.004671) (xy 99.102135 -217.955431) (xy 99.094036 -217.904293) (xy 99.093528 -217.878406)
			(xy 98.812604 -217.878406) (xy 98.812076 -217.906114) (xy 98.80288 -217.960761) (xy 98.794316 -217.987118)
			(xy 98.786442 -218.009216) (xy 98.99142 -218.364054) (xy 99.01428 -218.368372) (xy 99.0391 -218.37354)
			(xy 99.086878 -218.390497) (xy 99.131495 -218.41457) (xy 99.1719 -218.44519) (xy 99.20714 -218.481637)
			(xy 99.236384 -218.52305) (xy 99.258942 -218.568452) (xy 99.274281 -218.616773) (xy 99.282041 -218.666873)
			(xy 99.282504 -218.692222) (xy 99.281996 -218.718129) (xy 99.27389 -218.769306) (xy 99.257878 -218.818585)
			(xy 99.234355 -218.864752) (xy 99.203899 -218.906671) (xy 99.167261 -218.943309) (xy 99.125342 -218.973765)
			(xy 99.079175 -218.997288) (xy 99.029896 -219.0133) (xy 98.978719 -219.021406) (xy 98.926905 -219.021406)
			(xy 98.875728 -219.0133) (xy 98.826449 -218.997288) (xy 98.780282 -218.973765) (xy 98.738363 -218.943309)
			(xy 98.701725 -218.906671) (xy 98.671269 -218.864752) (xy 98.647746 -218.818585) (xy 98.631734 -218.769306)
			(xy 98.623628 -218.718129) (xy 98.62312 -218.692222) (xy 98.623718 -218.664505) (xy 98.633039 -218.609858)
			(xy 98.641662 -218.58351) (xy 98.649536 -218.561412) (xy 98.444558 -218.206574) (xy 98.421698 -218.202256)
			(xy 98.396899 -218.197049) (xy 98.349162 -218.180062) (xy 98.304585 -218.15597) (xy 98.26422 -218.125341)
			(xy 98.229017 -218.088897) (xy 98.199804 -218.047495) (xy 98.177271 -218.002112) (xy 98.161946 -217.953814)
			(xy 98.154192 -217.903741) (xy 98.153728 -217.878406) (xy 97.872804 -217.878406) (xy 97.872296 -217.904293)
			(xy 97.864197 -217.955431) (xy 97.848198 -218.004671) (xy 97.824692 -218.050803) (xy 97.79426 -218.09269)
			(xy 97.75765 -218.1293) (xy 97.715763 -218.159732) (xy 97.669631 -218.183238) (xy 97.620391 -218.199237)
			(xy 97.569253 -218.207336) (xy 97.517479 -218.207336) (xy 97.466341 -218.199237) (xy 97.417101 -218.183238)
			(xy 97.370969 -218.159732) (xy 97.329082 -218.1293) (xy 97.292472 -218.09269) (xy 97.26204 -218.050803)
			(xy 97.238534 -218.004671) (xy 97.222535 -217.955431) (xy 97.214436 -217.904293) (xy 97.213928 -217.878406)
			(xy 96.933004 -217.878406) (xy 96.932476 -217.906114) (xy 96.92328 -217.960761) (xy 96.914716 -217.987118)
			(xy 96.906842 -218.009216) (xy 97.11182 -218.364054) (xy 97.13468 -218.368372) (xy 97.1595 -218.37354)
			(xy 97.207278 -218.390497) (xy 97.251895 -218.41457) (xy 97.2923 -218.44519) (xy 97.32754 -218.481637)
			(xy 97.356784 -218.52305) (xy 97.379342 -218.568452) (xy 97.394681 -218.616773) (xy 97.402441 -218.666873)
			(xy 97.402904 -218.692222) (xy 97.402396 -218.718129) (xy 97.39429 -218.769306) (xy 97.378278 -218.818585)
			(xy 97.354755 -218.864752) (xy 97.324299 -218.906671) (xy 97.287661 -218.943309) (xy 97.245742 -218.973765)
			(xy 97.199575 -218.997288) (xy 97.150296 -219.0133) (xy 97.099119 -219.021406) (xy 97.047305 -219.021406)
			(xy 96.996128 -219.0133) (xy 96.946849 -218.997288) (xy 96.900682 -218.973765) (xy 96.858763 -218.943309)
			(xy 96.822125 -218.906671) (xy 96.791669 -218.864752) (xy 96.768146 -218.818585) (xy 96.752134 -218.769306)
			(xy 96.744028 -218.718129) (xy 96.74352 -218.692222) (xy 96.744118 -218.664505) (xy 96.753439 -218.609858)
			(xy 96.762062 -218.58351) (xy 96.769936 -218.561412) (xy 96.564958 -218.206574) (xy 96.542098 -218.202256)
			(xy 96.517299 -218.197049) (xy 96.469562 -218.180062) (xy 96.424985 -218.15597) (xy 96.38462 -218.125341)
			(xy 96.349417 -218.088897) (xy 96.320204 -218.047495) (xy 96.297671 -218.002112) (xy 96.282346 -217.953814)
			(xy 96.274592 -217.903741) (xy 96.274128 -217.878406) (xy 95.993204 -217.878406) (xy 95.992696 -217.904293)
			(xy 95.984597 -217.955431) (xy 95.968598 -218.004671) (xy 95.945092 -218.050803) (xy 95.91466 -218.09269)
			(xy 95.87805 -218.1293) (xy 95.836163 -218.159732) (xy 95.790031 -218.183238) (xy 95.740791 -218.199237)
			(xy 95.689653 -218.207336) (xy 95.637879 -218.207336) (xy 95.586741 -218.199237) (xy 95.537501 -218.183238)
			(xy 95.491369 -218.159732) (xy 95.449482 -218.1293) (xy 95.412872 -218.09269) (xy 95.38244 -218.050803)
			(xy 95.358934 -218.004671) (xy 95.342935 -217.955431) (xy 95.334836 -217.904293) (xy 95.334328 -217.878406)
			(xy 95.053404 -217.878406) (xy 95.052876 -217.906114) (xy 95.04368 -217.960761) (xy 95.035116 -217.987118)
			(xy 95.027242 -218.009216) (xy 95.23222 -218.364054) (xy 95.25508 -218.368372) (xy 95.2799 -218.37354)
			(xy 95.327678 -218.390497) (xy 95.372295 -218.41457) (xy 95.4127 -218.44519) (xy 95.44794 -218.481637)
			(xy 95.477184 -218.52305) (xy 95.499742 -218.568452) (xy 95.515081 -218.616773) (xy 95.522841 -218.666873)
			(xy 95.523304 -218.692222) (xy 95.522796 -218.718129) (xy 95.51469 -218.769306) (xy 95.498678 -218.818585)
			(xy 95.475155 -218.864752) (xy 95.444699 -218.906671) (xy 95.408061 -218.943309) (xy 95.366142 -218.973765)
			(xy 95.319975 -218.997288) (xy 95.270696 -219.0133) (xy 95.219519 -219.021406) (xy 95.167705 -219.021406)
			(xy 95.116528 -219.0133) (xy 95.067249 -218.997288) (xy 95.021082 -218.973765) (xy 94.979163 -218.943309)
			(xy 94.942525 -218.906671) (xy 94.912069 -218.864752) (xy 94.888546 -218.818585) (xy 94.872534 -218.769306)
			(xy 94.864428 -218.718129) (xy 94.86392 -218.692222) (xy 94.864518 -218.664505) (xy 94.873839 -218.609858)
			(xy 94.882462 -218.58351) (xy 94.890336 -218.561412) (xy 94.685358 -218.206574) (xy 94.662498 -218.202256)
			(xy 94.637699 -218.197049) (xy 94.589962 -218.180062) (xy 94.545385 -218.15597) (xy 94.50502 -218.125341)
			(xy 94.469817 -218.088897) (xy 94.440604 -218.047495) (xy 94.418071 -218.002112) (xy 94.402746 -217.953814)
			(xy 94.394992 -217.903741) (xy 94.394528 -217.878406) (xy 94.113604 -217.878406) (xy 94.113096 -217.904293)
			(xy 94.104997 -217.955431) (xy 94.088998 -218.004671) (xy 94.065492 -218.050803) (xy 94.03506 -218.09269)
			(xy 93.99845 -218.1293) (xy 93.956563 -218.159732) (xy 93.910431 -218.183238) (xy 93.861191 -218.199237)
			(xy 93.810053 -218.207336) (xy 93.758279 -218.207336) (xy 93.707141 -218.199237) (xy 93.657901 -218.183238)
			(xy 93.611769 -218.159732) (xy 93.569882 -218.1293) (xy 93.533272 -218.09269) (xy 93.50284 -218.050803)
			(xy 93.479334 -218.004671) (xy 93.463335 -217.955431) (xy 93.455236 -217.904293) (xy 93.454728 -217.878406)
			(xy 93.173804 -217.878406) (xy 93.173276 -217.906114) (xy 93.16408 -217.960761) (xy 93.155516 -217.987118)
			(xy 93.147642 -218.009216) (xy 93.35262 -218.364054) (xy 93.37548 -218.368372) (xy 93.4003 -218.37354)
			(xy 93.448078 -218.390497) (xy 93.492695 -218.41457) (xy 93.5331 -218.44519) (xy 93.56834 -218.481637)
			(xy 93.597584 -218.52305) (xy 93.620142 -218.568452) (xy 93.635481 -218.616773) (xy 93.643241 -218.666873)
			(xy 93.643704 -218.692222) (xy 93.643196 -218.718129) (xy 93.63509 -218.769306) (xy 93.619078 -218.818585)
			(xy 93.595555 -218.864752) (xy 93.565099 -218.906671) (xy 93.528461 -218.943309) (xy 93.486542 -218.973765)
			(xy 93.440375 -218.997288) (xy 93.391096 -219.0133) (xy 93.339919 -219.021406) (xy 93.288105 -219.021406)
			(xy 93.236928 -219.0133) (xy 93.187649 -218.997288) (xy 93.141482 -218.973765) (xy 93.099563 -218.943309)
			(xy 93.062925 -218.906671) (xy 93.032469 -218.864752) (xy 93.008946 -218.818585) (xy 92.992934 -218.769306)
			(xy 92.984828 -218.718129) (xy 92.98432 -218.692222) (xy 92.984918 -218.664505) (xy 92.994239 -218.609858)
			(xy 93.002862 -218.58351) (xy 93.010736 -218.561412) (xy 92.805758 -218.206574) (xy 92.782898 -218.202256)
			(xy 92.758099 -218.197049) (xy 92.710362 -218.180062) (xy 92.665785 -218.15597) (xy 92.62542 -218.125341)
			(xy 92.590217 -218.088897) (xy 92.561004 -218.047495) (xy 92.538471 -218.002112) (xy 92.523146 -217.953814)
			(xy 92.515392 -217.903741) (xy 92.514928 -217.878406) (xy 92.234004 -217.878406) (xy 92.233496 -217.904293)
			(xy 92.225397 -217.955431) (xy 92.209398 -218.004671) (xy 92.185892 -218.050803) (xy 92.15546 -218.09269)
			(xy 92.11885 -218.1293) (xy 92.076963 -218.159732) (xy 92.030831 -218.183238) (xy 91.981591 -218.199237)
			(xy 91.930453 -218.207336) (xy 91.878679 -218.207336) (xy 91.827541 -218.199237) (xy 91.778301 -218.183238)
			(xy 91.732169 -218.159732) (xy 91.690282 -218.1293) (xy 91.653672 -218.09269) (xy 91.62324 -218.050803)
			(xy 91.599734 -218.004671) (xy 91.583735 -217.955431) (xy 91.575636 -217.904293) (xy 91.575128 -217.878406)
			(xy 91.294204 -217.878406) (xy 91.293676 -217.906114) (xy 91.28448 -217.960761) (xy 91.275916 -217.987118)
			(xy 91.268042 -218.009216) (xy 91.47302 -218.364054) (xy 91.49588 -218.368372) (xy 91.5207 -218.37354)
			(xy 91.568478 -218.390497) (xy 91.613095 -218.41457) (xy 91.6535 -218.44519) (xy 91.68874 -218.481637)
			(xy 91.717984 -218.52305) (xy 91.740542 -218.568452) (xy 91.755881 -218.616773) (xy 91.763641 -218.666873)
			(xy 91.764104 -218.692222) (xy 91.763596 -218.718129) (xy 91.75549 -218.769306) (xy 91.739478 -218.818585)
			(xy 91.715955 -218.864752) (xy 91.685499 -218.906671) (xy 91.648861 -218.943309) (xy 91.606942 -218.973765)
			(xy 91.560775 -218.997288) (xy 91.511496 -219.0133) (xy 91.460319 -219.021406) (xy 91.408505 -219.021406)
			(xy 91.357328 -219.0133) (xy 91.308049 -218.997288) (xy 91.261882 -218.973765) (xy 91.219963 -218.943309)
			(xy 91.183325 -218.906671) (xy 91.152869 -218.864752) (xy 91.129346 -218.818585) (xy 91.113334 -218.769306)
			(xy 91.105228 -218.718129) (xy 91.10472 -218.692222) (xy 91.105318 -218.664505) (xy 91.114639 -218.609858)
			(xy 91.123262 -218.58351) (xy 91.131136 -218.561412) (xy 90.926158 -218.206574) (xy 90.903298 -218.202256)
			(xy 90.878499 -218.197049) (xy 90.830762 -218.180062) (xy 90.786185 -218.15597) (xy 90.74582 -218.125341)
			(xy 90.710617 -218.088897) (xy 90.681404 -218.047495) (xy 90.658871 -218.002112) (xy 90.643546 -217.953814)
			(xy 90.635792 -217.903741) (xy 90.635328 -217.878406) (xy 90.354404 -217.878406) (xy 90.353896 -217.904293)
			(xy 90.345797 -217.955431) (xy 90.329798 -218.004671) (xy 90.306292 -218.050803) (xy 90.27586 -218.09269)
			(xy 90.23925 -218.1293) (xy 90.197363 -218.159732) (xy 90.151231 -218.183238) (xy 90.101991 -218.199237)
			(xy 90.050853 -218.207336) (xy 89.999079 -218.207336) (xy 89.947941 -218.199237) (xy 89.898701 -218.183238)
			(xy 89.852569 -218.159732) (xy 89.810682 -218.1293) (xy 89.774072 -218.09269) (xy 89.74364 -218.050803)
			(xy 89.720134 -218.004671) (xy 89.704135 -217.955431) (xy 89.696036 -217.904293) (xy 89.695528 -217.878406)
			(xy 89.414604 -217.878406) (xy 89.414076 -217.906114) (xy 89.40488 -217.960761) (xy 89.396316 -217.987118)
			(xy 89.388442 -218.009216) (xy 89.59342 -218.364054) (xy 89.61628 -218.368372) (xy 89.6411 -218.37354)
			(xy 89.688878 -218.390497) (xy 89.733495 -218.41457) (xy 89.7739 -218.44519) (xy 89.80914 -218.481637)
			(xy 89.838384 -218.52305) (xy 89.860942 -218.568452) (xy 89.876281 -218.616773) (xy 89.884041 -218.666873)
			(xy 89.884504 -218.692222) (xy 89.883996 -218.718129) (xy 89.87589 -218.769306) (xy 89.859878 -218.818585)
			(xy 89.836355 -218.864752) (xy 89.805899 -218.906671) (xy 89.769261 -218.943309) (xy 89.727342 -218.973765)
			(xy 89.681175 -218.997288) (xy 89.631896 -219.0133) (xy 89.580719 -219.021406) (xy 89.528905 -219.021406)
			(xy 89.477728 -219.0133) (xy 89.428449 -218.997288) (xy 89.382282 -218.973765) (xy 89.340363 -218.943309)
			(xy 89.303725 -218.906671) (xy 89.273269 -218.864752) (xy 89.249746 -218.818585) (xy 89.233734 -218.769306)
			(xy 89.225628 -218.718129) (xy 89.22512 -218.692222) (xy 89.225718 -218.664505) (xy 89.235039 -218.609858)
			(xy 89.243662 -218.58351) (xy 89.251536 -218.561412) (xy 89.046558 -218.206574) (xy 89.023698 -218.202256)
			(xy 88.998899 -218.197049) (xy 88.951162 -218.180062) (xy 88.906585 -218.15597) (xy 88.86622 -218.125341)
			(xy 88.831017 -218.088897) (xy 88.801804 -218.047495) (xy 88.779271 -218.002112) (xy 88.763946 -217.953814)
			(xy 88.756192 -217.903741) (xy 88.755728 -217.878406) (xy 2.509012 -217.878406) (xy 2.509012 -221.133924)
			(xy 88.755728 -221.133924) (xy 88.756236 -221.108037) (xy 88.764335 -221.056899) (xy 88.780334 -221.007659)
			(xy 88.80384 -220.961527) (xy 88.834272 -220.91964) (xy 88.870882 -220.88303) (xy 88.912769 -220.852598)
			(xy 88.958901 -220.829092) (xy 89.008141 -220.813093) (xy 89.059279 -220.804994) (xy 89.111053 -220.804994)
			(xy 89.162191 -220.813093) (xy 89.211431 -220.829092) (xy 89.257563 -220.852598) (xy 89.29945 -220.88303)
			(xy 89.33606 -220.91964) (xy 89.366492 -220.961527) (xy 89.389998 -221.007659) (xy 89.405997 -221.056899)
			(xy 89.414096 -221.108037) (xy 89.414604 -221.133924) (xy 89.695528 -221.133924) (xy 89.69601 -221.108589)
			(xy 89.70376 -221.058515) (xy 89.71908 -221.010217) (xy 89.741611 -220.964832) (xy 89.770821 -220.923429)
			(xy 89.806022 -220.886984) (xy 89.846386 -220.856354) (xy 89.890961 -220.83226) (xy 89.938698 -220.815272)
			(xy 89.963498 -220.810074) (xy 89.986358 -220.805756) (xy 90.191336 -220.450664) (xy 90.183462 -220.42882)
			(xy 90.174829 -220.402408) (xy 90.1655 -220.347635) (xy 90.16492 -220.319854) (xy 90.165428 -220.293947)
			(xy 90.173534 -220.24277) (xy 90.189546 -220.193491) (xy 90.213069 -220.147324) (xy 90.243525 -220.105405)
			(xy 90.280163 -220.068767) (xy 90.322082 -220.038311) (xy 90.368249 -220.014788) (xy 90.417528 -219.998776)
			(xy 90.468705 -219.99067) (xy 90.520519 -219.99067) (xy 90.571696 -219.998776) (xy 90.620975 -220.014788)
			(xy 90.667142 -220.038311) (xy 90.709061 -220.068767) (xy 90.745699 -220.105405) (xy 90.776155 -220.147324)
			(xy 90.799678 -220.193491) (xy 90.81569 -220.24277) (xy 90.823796 -220.293947) (xy 90.824304 -220.319854)
			(xy 90.823828 -220.345199) (xy 90.816049 -220.395289) (xy 90.800697 -220.443599) (xy 90.778134 -220.48899)
			(xy 90.748891 -220.530396) (xy 90.713657 -220.566839) (xy 90.673262 -220.597461) (xy 90.628657 -220.621543)
			(xy 90.580893 -220.638516) (xy 90.55608 -220.643704) (xy 90.53322 -220.648022) (xy 90.328242 -221.003114)
			(xy 90.336116 -221.024958) (xy 90.34471 -221.051373) (xy 90.353897 -221.106151) (xy 90.354404 -221.133924)
			(xy 90.635328 -221.133924) (xy 90.635836 -221.108037) (xy 90.643935 -221.056899) (xy 90.659934 -221.007659)
			(xy 90.68344 -220.961527) (xy 90.713872 -220.91964) (xy 90.750482 -220.88303) (xy 90.792369 -220.852598)
			(xy 90.838501 -220.829092) (xy 90.887741 -220.813093) (xy 90.938879 -220.804994) (xy 90.990653 -220.804994)
			(xy 91.041791 -220.813093) (xy 91.091031 -220.829092) (xy 91.137163 -220.852598) (xy 91.17905 -220.88303)
			(xy 91.21566 -220.91964) (xy 91.246092 -220.961527) (xy 91.269598 -221.007659) (xy 91.285597 -221.056899)
			(xy 91.293696 -221.108037) (xy 91.294204 -221.133924) (xy 91.575128 -221.133924) (xy 91.57561 -221.108589)
			(xy 91.58336 -221.058515) (xy 91.59868 -221.010217) (xy 91.621211 -220.964832) (xy 91.650421 -220.923429)
			(xy 91.685622 -220.886984) (xy 91.725986 -220.856354) (xy 91.770561 -220.83226) (xy 91.818298 -220.815272)
			(xy 91.843098 -220.810074) (xy 91.865958 -220.805756) (xy 92.070936 -220.450664) (xy 92.063062 -220.42882)
			(xy 92.054429 -220.402408) (xy 92.0451 -220.347635) (xy 92.04452 -220.319854) (xy 92.045028 -220.293947)
			(xy 92.053134 -220.24277) (xy 92.069146 -220.193491) (xy 92.092669 -220.147324) (xy 92.123125 -220.105405)
			(xy 92.159763 -220.068767) (xy 92.201682 -220.038311) (xy 92.247849 -220.014788) (xy 92.297128 -219.998776)
			(xy 92.348305 -219.99067) (xy 92.400119 -219.99067) (xy 92.451296 -219.998776) (xy 92.500575 -220.014788)
			(xy 92.546742 -220.038311) (xy 92.588661 -220.068767) (xy 92.625299 -220.105405) (xy 92.655755 -220.147324)
			(xy 92.679278 -220.193491) (xy 92.69529 -220.24277) (xy 92.703396 -220.293947) (xy 92.703904 -220.319854)
			(xy 92.703428 -220.345199) (xy 92.695649 -220.395289) (xy 92.680297 -220.443599) (xy 92.657734 -220.48899)
			(xy 92.628491 -220.530396) (xy 92.593257 -220.566839) (xy 92.552862 -220.597461) (xy 92.508257 -220.621543)
			(xy 92.460493 -220.638516) (xy 92.43568 -220.643704) (xy 92.41282 -220.648022) (xy 92.207842 -221.003114)
			(xy 92.215716 -221.024958) (xy 92.22431 -221.051373) (xy 92.233497 -221.106151) (xy 92.234004 -221.133924)
			(xy 92.514928 -221.133924) (xy 92.515436 -221.108037) (xy 92.523535 -221.056899) (xy 92.539534 -221.007659)
			(xy 92.56304 -220.961527) (xy 92.593472 -220.91964) (xy 92.630082 -220.88303) (xy 92.671969 -220.852598)
			(xy 92.718101 -220.829092) (xy 92.767341 -220.813093) (xy 92.818479 -220.804994) (xy 92.870253 -220.804994)
			(xy 92.921391 -220.813093) (xy 92.970631 -220.829092) (xy 93.016763 -220.852598) (xy 93.05865 -220.88303)
			(xy 93.09526 -220.91964) (xy 93.125692 -220.961527) (xy 93.149198 -221.007659) (xy 93.165197 -221.056899)
			(xy 93.173296 -221.108037) (xy 93.173804 -221.133924) (xy 93.454728 -221.133924) (xy 93.45521 -221.108589)
			(xy 93.46296 -221.058515) (xy 93.47828 -221.010217) (xy 93.500811 -220.964832) (xy 93.530021 -220.923429)
			(xy 93.565222 -220.886984) (xy 93.605586 -220.856354) (xy 93.650161 -220.83226) (xy 93.697898 -220.815272)
			(xy 93.722698 -220.810074) (xy 93.745558 -220.805756) (xy 93.950536 -220.450664) (xy 93.942662 -220.42882)
			(xy 93.934029 -220.402408) (xy 93.9247 -220.347635) (xy 93.92412 -220.319854) (xy 93.924628 -220.293947)
			(xy 93.932734 -220.24277) (xy 93.948746 -220.193491) (xy 93.972269 -220.147324) (xy 94.002725 -220.105405)
			(xy 94.039363 -220.068767) (xy 94.081282 -220.038311) (xy 94.127449 -220.014788) (xy 94.176728 -219.998776)
			(xy 94.227905 -219.99067) (xy 94.279719 -219.99067) (xy 94.330896 -219.998776) (xy 94.380175 -220.014788)
			(xy 94.426342 -220.038311) (xy 94.468261 -220.068767) (xy 94.504899 -220.105405) (xy 94.535355 -220.147324)
			(xy 94.558878 -220.193491) (xy 94.57489 -220.24277) (xy 94.582996 -220.293947) (xy 94.583504 -220.319854)
			(xy 94.583028 -220.345199) (xy 94.575249 -220.395289) (xy 94.559897 -220.443599) (xy 94.537334 -220.48899)
			(xy 94.508091 -220.530396) (xy 94.472857 -220.566839) (xy 94.432462 -220.597461) (xy 94.387857 -220.621543)
			(xy 94.340093 -220.638516) (xy 94.31528 -220.643704) (xy 94.29242 -220.648022) (xy 94.087442 -221.003114)
			(xy 94.095316 -221.024958) (xy 94.10391 -221.051373) (xy 94.113097 -221.106151) (xy 94.113604 -221.133924)
			(xy 94.394528 -221.133924) (xy 94.395036 -221.108037) (xy 94.403135 -221.056899) (xy 94.419134 -221.007659)
			(xy 94.44264 -220.961527) (xy 94.473072 -220.91964) (xy 94.509682 -220.88303) (xy 94.551569 -220.852598)
			(xy 94.597701 -220.829092) (xy 94.646941 -220.813093) (xy 94.698079 -220.804994) (xy 94.749853 -220.804994)
			(xy 94.800991 -220.813093) (xy 94.850231 -220.829092) (xy 94.896363 -220.852598) (xy 94.93825 -220.88303)
			(xy 94.97486 -220.91964) (xy 95.005292 -220.961527) (xy 95.028798 -221.007659) (xy 95.044797 -221.056899)
			(xy 95.052896 -221.108037) (xy 95.053404 -221.133924) (xy 95.334328 -221.133924) (xy 95.33481 -221.108589)
			(xy 95.34256 -221.058515) (xy 95.35788 -221.010217) (xy 95.380411 -220.964832) (xy 95.409621 -220.923429)
			(xy 95.444822 -220.886984) (xy 95.485186 -220.856354) (xy 95.529761 -220.83226) (xy 95.577498 -220.815272)
			(xy 95.602298 -220.810074) (xy 95.625158 -220.805756) (xy 95.830136 -220.450664) (xy 95.822262 -220.42882)
			(xy 95.813629 -220.402408) (xy 95.8043 -220.347635) (xy 95.80372 -220.319854) (xy 95.804228 -220.293947)
			(xy 95.812334 -220.24277) (xy 95.828346 -220.193491) (xy 95.851869 -220.147324) (xy 95.882325 -220.105405)
			(xy 95.918963 -220.068767) (xy 95.960882 -220.038311) (xy 96.007049 -220.014788) (xy 96.056328 -219.998776)
			(xy 96.107505 -219.99067) (xy 96.159319 -219.99067) (xy 96.210496 -219.998776) (xy 96.259775 -220.014788)
			(xy 96.305942 -220.038311) (xy 96.347861 -220.068767) (xy 96.384499 -220.105405) (xy 96.414955 -220.147324)
			(xy 96.438478 -220.193491) (xy 96.45449 -220.24277) (xy 96.462596 -220.293947) (xy 96.463104 -220.319854)
			(xy 96.462628 -220.345199) (xy 96.454849 -220.395289) (xy 96.439497 -220.443599) (xy 96.416934 -220.48899)
			(xy 96.387691 -220.530396) (xy 96.352457 -220.566839) (xy 96.312062 -220.597461) (xy 96.267457 -220.621543)
			(xy 96.219693 -220.638516) (xy 96.19488 -220.643704) (xy 96.17202 -220.648022) (xy 95.967042 -221.003114)
			(xy 95.974916 -221.024958) (xy 95.98351 -221.051373) (xy 95.992697 -221.106151) (xy 95.993204 -221.133924)
			(xy 96.274128 -221.133924) (xy 96.274636 -221.108037) (xy 96.282735 -221.056899) (xy 96.298734 -221.007659)
			(xy 96.32224 -220.961527) (xy 96.352672 -220.91964) (xy 96.389282 -220.88303) (xy 96.431169 -220.852598)
			(xy 96.477301 -220.829092) (xy 96.526541 -220.813093) (xy 96.577679 -220.804994) (xy 96.629453 -220.804994)
			(xy 96.680591 -220.813093) (xy 96.729831 -220.829092) (xy 96.775963 -220.852598) (xy 96.81785 -220.88303)
			(xy 96.85446 -220.91964) (xy 96.884892 -220.961527) (xy 96.908398 -221.007659) (xy 96.924397 -221.056899)
			(xy 96.932496 -221.108037) (xy 96.933004 -221.133924) (xy 97.213928 -221.133924) (xy 97.21441 -221.108589)
			(xy 97.22216 -221.058515) (xy 97.23748 -221.010217) (xy 97.260011 -220.964832) (xy 97.289221 -220.923429)
			(xy 97.324422 -220.886984) (xy 97.364786 -220.856354) (xy 97.409361 -220.83226) (xy 97.457098 -220.815272)
			(xy 97.481898 -220.810074) (xy 97.504758 -220.805756) (xy 97.709736 -220.450664) (xy 97.701862 -220.42882)
			(xy 97.693229 -220.402408) (xy 97.6839 -220.347635) (xy 97.68332 -220.319854) (xy 97.683828 -220.293947)
			(xy 97.691934 -220.24277) (xy 97.707946 -220.193491) (xy 97.731469 -220.147324) (xy 97.761925 -220.105405)
			(xy 97.798563 -220.068767) (xy 97.840482 -220.038311) (xy 97.886649 -220.014788) (xy 97.935928 -219.998776)
			(xy 97.987105 -219.99067) (xy 98.038919 -219.99067) (xy 98.090096 -219.998776) (xy 98.139375 -220.014788)
			(xy 98.185542 -220.038311) (xy 98.227461 -220.068767) (xy 98.264099 -220.105405) (xy 98.294555 -220.147324)
			(xy 98.318078 -220.193491) (xy 98.33409 -220.24277) (xy 98.342196 -220.293947) (xy 98.342704 -220.319854)
			(xy 98.342228 -220.345199) (xy 98.334449 -220.395289) (xy 98.319097 -220.443599) (xy 98.296534 -220.48899)
			(xy 98.267291 -220.530396) (xy 98.232057 -220.566839) (xy 98.191662 -220.597461) (xy 98.147057 -220.621543)
			(xy 98.099293 -220.638516) (xy 98.07448 -220.643704) (xy 98.05162 -220.648022) (xy 97.846642 -221.003114)
			(xy 97.854516 -221.024958) (xy 97.86311 -221.051373) (xy 97.872297 -221.106151) (xy 97.872804 -221.133924)
			(xy 98.153728 -221.133924) (xy 98.154236 -221.108037) (xy 98.162335 -221.056899) (xy 98.178334 -221.007659)
			(xy 98.20184 -220.961527) (xy 98.232272 -220.91964) (xy 98.268882 -220.88303) (xy 98.310769 -220.852598)
			(xy 98.356901 -220.829092) (xy 98.406141 -220.813093) (xy 98.457279 -220.804994) (xy 98.509053 -220.804994)
			(xy 98.560191 -220.813093) (xy 98.609431 -220.829092) (xy 98.655563 -220.852598) (xy 98.69745 -220.88303)
			(xy 98.73406 -220.91964) (xy 98.764492 -220.961527) (xy 98.787998 -221.007659) (xy 98.803997 -221.056899)
			(xy 98.812096 -221.108037) (xy 98.812604 -221.133924) (xy 99.093528 -221.133924) (xy 99.09401 -221.108589)
			(xy 99.10176 -221.058515) (xy 99.11708 -221.010217) (xy 99.139611 -220.964832) (xy 99.168821 -220.923429)
			(xy 99.204022 -220.886984) (xy 99.244386 -220.856354) (xy 99.288961 -220.83226) (xy 99.336698 -220.815272)
			(xy 99.361498 -220.810074) (xy 99.384358 -220.805756) (xy 99.589336 -220.450664) (xy 99.581462 -220.42882)
			(xy 99.572829 -220.402408) (xy 99.5635 -220.347635) (xy 99.56292 -220.319854) (xy 99.563428 -220.293947)
			(xy 99.571534 -220.24277) (xy 99.587546 -220.193491) (xy 99.611069 -220.147324) (xy 99.641525 -220.105405)
			(xy 99.678163 -220.068767) (xy 99.720082 -220.038311) (xy 99.766249 -220.014788) (xy 99.815528 -219.998776)
			(xy 99.866705 -219.99067) (xy 99.918519 -219.99067) (xy 99.969696 -219.998776) (xy 100.018975 -220.014788)
			(xy 100.065142 -220.038311) (xy 100.107061 -220.068767) (xy 100.143699 -220.105405) (xy 100.174155 -220.147324)
			(xy 100.197678 -220.193491) (xy 100.21369 -220.24277) (xy 100.221796 -220.293947) (xy 100.222304 -220.319854)
			(xy 100.221828 -220.345199) (xy 100.214049 -220.395289) (xy 100.198697 -220.443599) (xy 100.176134 -220.48899)
			(xy 100.146891 -220.530396) (xy 100.111657 -220.566839) (xy 100.071262 -220.597461) (xy 100.026657 -220.621543)
			(xy 99.978893 -220.638516) (xy 99.95408 -220.643704) (xy 99.93122 -220.648022) (xy 99.726242 -221.003114)
			(xy 99.734116 -221.024958) (xy 99.74271 -221.051373) (xy 99.751897 -221.106151) (xy 99.752404 -221.133924)
			(xy 100.033328 -221.133924) (xy 100.033836 -221.108037) (xy 100.041935 -221.056899) (xy 100.057934 -221.007659)
			(xy 100.08144 -220.961527) (xy 100.111872 -220.91964) (xy 100.148482 -220.88303) (xy 100.190369 -220.852598)
			(xy 100.236501 -220.829092) (xy 100.285741 -220.813093) (xy 100.336879 -220.804994) (xy 100.388653 -220.804994)
			(xy 100.439791 -220.813093) (xy 100.489031 -220.829092) (xy 100.535163 -220.852598) (xy 100.57705 -220.88303)
			(xy 100.61366 -220.91964) (xy 100.644092 -220.961527) (xy 100.667598 -221.007659) (xy 100.683597 -221.056899)
			(xy 100.691696 -221.108037) (xy 100.692204 -221.133924) (xy 100.973128 -221.133924) (xy 100.97361 -221.108589)
			(xy 100.98136 -221.058515) (xy 100.99668 -221.010217) (xy 101.019211 -220.964832) (xy 101.048421 -220.923429)
			(xy 101.083622 -220.886984) (xy 101.123986 -220.856354) (xy 101.168561 -220.83226) (xy 101.216298 -220.815272)
			(xy 101.241098 -220.810074) (xy 101.263958 -220.805756) (xy 101.468936 -220.450664) (xy 101.461062 -220.42882)
			(xy 101.452429 -220.402408) (xy 101.4431 -220.347635) (xy 101.44252 -220.319854) (xy 101.443028 -220.293947)
			(xy 101.451134 -220.24277) (xy 101.467146 -220.193491) (xy 101.490669 -220.147324) (xy 101.521125 -220.105405)
			(xy 101.557763 -220.068767) (xy 101.599682 -220.038311) (xy 101.645849 -220.014788) (xy 101.695128 -219.998776)
			(xy 101.746305 -219.99067) (xy 101.798119 -219.99067) (xy 101.849296 -219.998776) (xy 101.898575 -220.014788)
			(xy 101.944742 -220.038311) (xy 101.986661 -220.068767) (xy 102.023299 -220.105405) (xy 102.053755 -220.147324)
			(xy 102.077278 -220.193491) (xy 102.09329 -220.24277) (xy 102.101396 -220.293947) (xy 102.101904 -220.319854)
			(xy 102.101428 -220.345199) (xy 102.093649 -220.395289) (xy 102.078297 -220.443599) (xy 102.055734 -220.48899)
			(xy 102.026491 -220.530396) (xy 101.991257 -220.566839) (xy 101.950862 -220.597461) (xy 101.906257 -220.621543)
			(xy 101.858493 -220.638516) (xy 101.83368 -220.643704) (xy 101.81082 -220.648022) (xy 101.605842 -221.003114)
			(xy 101.613716 -221.024958) (xy 101.62231 -221.051373) (xy 101.631497 -221.106151) (xy 101.632004 -221.133924)
			(xy 101.912928 -221.133924) (xy 101.913436 -221.108037) (xy 101.921535 -221.056899) (xy 101.937534 -221.007659)
			(xy 101.96104 -220.961527) (xy 101.991472 -220.91964) (xy 102.028082 -220.88303) (xy 102.069969 -220.852598)
			(xy 102.116101 -220.829092) (xy 102.165341 -220.813093) (xy 102.216479 -220.804994) (xy 102.268253 -220.804994)
			(xy 102.319391 -220.813093) (xy 102.368631 -220.829092) (xy 102.414763 -220.852598) (xy 102.45665 -220.88303)
			(xy 102.49326 -220.91964) (xy 102.523692 -220.961527) (xy 102.547198 -221.007659) (xy 102.563197 -221.056899)
			(xy 102.571296 -221.108037) (xy 102.571804 -221.133924) (xy 102.852728 -221.133924) (xy 102.85321 -221.108589)
			(xy 102.86096 -221.058515) (xy 102.87628 -221.010217) (xy 102.898811 -220.964832) (xy 102.928021 -220.923429)
			(xy 102.963222 -220.886984) (xy 103.003586 -220.856354) (xy 103.048161 -220.83226) (xy 103.095898 -220.815272)
			(xy 103.120698 -220.810074) (xy 103.143558 -220.805756) (xy 103.348536 -220.450664) (xy 103.340662 -220.42882)
			(xy 103.332029 -220.402408) (xy 103.3227 -220.347635) (xy 103.32212 -220.319854) (xy 103.322628 -220.293947)
			(xy 103.330734 -220.24277) (xy 103.346746 -220.193491) (xy 103.370269 -220.147324) (xy 103.400725 -220.105405)
			(xy 103.437363 -220.068767) (xy 103.479282 -220.038311) (xy 103.525449 -220.014788) (xy 103.574728 -219.998776)
			(xy 103.625905 -219.99067) (xy 103.677719 -219.99067) (xy 103.728896 -219.998776) (xy 103.778175 -220.014788)
			(xy 103.824342 -220.038311) (xy 103.866261 -220.068767) (xy 103.902899 -220.105405) (xy 103.933355 -220.147324)
			(xy 103.956878 -220.193491) (xy 103.97289 -220.24277) (xy 103.980996 -220.293947) (xy 103.981504 -220.319854)
			(xy 105.20172 -220.319854) (xy 105.202228 -220.293947) (xy 105.210334 -220.24277) (xy 105.226346 -220.193491)
			(xy 105.249869 -220.147324) (xy 105.280325 -220.105405) (xy 105.316963 -220.068767) (xy 105.358882 -220.038311)
			(xy 105.405049 -220.014788) (xy 105.454328 -219.998776) (xy 105.505505 -219.99067) (xy 105.557319 -219.99067)
			(xy 105.608496 -219.998776) (xy 105.657775 -220.014788) (xy 105.703942 -220.038311) (xy 105.745861 -220.068767)
			(xy 105.782499 -220.105405) (xy 105.812955 -220.147324) (xy 105.836478 -220.193491) (xy 105.85249 -220.24277)
			(xy 105.860596 -220.293947) (xy 105.861104 -220.319854) (xy 107.08132 -220.319854) (xy 107.081828 -220.293947)
			(xy 107.089934 -220.24277) (xy 107.105946 -220.193491) (xy 107.129469 -220.147324) (xy 107.159925 -220.105405)
			(xy 107.196563 -220.068767) (xy 107.238482 -220.038311) (xy 107.284649 -220.014788) (xy 107.333928 -219.998776)
			(xy 107.385105 -219.99067) (xy 107.436919 -219.99067) (xy 107.488096 -219.998776) (xy 107.537375 -220.014788)
			(xy 107.583542 -220.038311) (xy 107.625461 -220.068767) (xy 107.662099 -220.105405) (xy 107.692555 -220.147324)
			(xy 107.716078 -220.193491) (xy 107.73209 -220.24277) (xy 107.740196 -220.293947) (xy 107.740704 -220.319854)
			(xy 108.96092 -220.319854) (xy 108.961428 -220.293947) (xy 108.969534 -220.24277) (xy 108.985546 -220.193491)
			(xy 109.009069 -220.147324) (xy 109.039525 -220.105405) (xy 109.076163 -220.068767) (xy 109.118082 -220.038311)
			(xy 109.164249 -220.014788) (xy 109.213528 -219.998776) (xy 109.264705 -219.99067) (xy 109.316519 -219.99067)
			(xy 109.367696 -219.998776) (xy 109.416975 -220.014788) (xy 109.463142 -220.038311) (xy 109.505061 -220.068767)
			(xy 109.541699 -220.105405) (xy 109.572155 -220.147324) (xy 109.595678 -220.193491) (xy 109.61169 -220.24277)
			(xy 109.619796 -220.293947) (xy 109.620304 -220.319854) (xy 110.84052 -220.319854) (xy 110.841028 -220.293947)
			(xy 110.849134 -220.24277) (xy 110.865146 -220.193491) (xy 110.888669 -220.147324) (xy 110.919125 -220.105405)
			(xy 110.955763 -220.068767) (xy 110.997682 -220.038311) (xy 111.043849 -220.014788) (xy 111.093128 -219.998776)
			(xy 111.144305 -219.99067) (xy 111.196119 -219.99067) (xy 111.247296 -219.998776) (xy 111.296575 -220.014788)
			(xy 111.342742 -220.038311) (xy 111.384661 -220.068767) (xy 111.421299 -220.105405) (xy 111.451755 -220.147324)
			(xy 111.475278 -220.193491) (xy 111.49129 -220.24277) (xy 111.499396 -220.293947) (xy 111.499904 -220.319854)
			(xy 112.72012 -220.319854) (xy 112.720628 -220.293947) (xy 112.728734 -220.24277) (xy 112.744746 -220.193491)
			(xy 112.768269 -220.147324) (xy 112.798725 -220.105405) (xy 112.835363 -220.068767) (xy 112.877282 -220.038311)
			(xy 112.923449 -220.014788) (xy 112.972728 -219.998776) (xy 113.023905 -219.99067) (xy 113.075719 -219.99067)
			(xy 113.126896 -219.998776) (xy 113.176175 -220.014788) (xy 113.222342 -220.038311) (xy 113.264261 -220.068767)
			(xy 113.300899 -220.105405) (xy 113.331355 -220.147324) (xy 113.354878 -220.193491) (xy 113.37089 -220.24277)
			(xy 113.378996 -220.293947) (xy 113.379504 -220.319854) (xy 114.59972 -220.319854) (xy 114.600228 -220.293947)
			(xy 114.608334 -220.24277) (xy 114.624346 -220.193491) (xy 114.647869 -220.147324) (xy 114.678325 -220.105405)
			(xy 114.714963 -220.068767) (xy 114.756882 -220.038311) (xy 114.803049 -220.014788) (xy 114.852328 -219.998776)
			(xy 114.903505 -219.99067) (xy 114.955319 -219.99067) (xy 115.006496 -219.998776) (xy 115.055775 -220.014788)
			(xy 115.101942 -220.038311) (xy 115.143861 -220.068767) (xy 115.180499 -220.105405) (xy 115.210955 -220.147324)
			(xy 115.234478 -220.193491) (xy 115.25049 -220.24277) (xy 115.258596 -220.293947) (xy 115.259104 -220.319854)
			(xy 116.47932 -220.319854) (xy 116.479828 -220.293947) (xy 116.487934 -220.24277) (xy 116.503946 -220.193491)
			(xy 116.527469 -220.147324) (xy 116.557925 -220.105405) (xy 116.594563 -220.068767) (xy 116.636482 -220.038311)
			(xy 116.682649 -220.014788) (xy 116.731928 -219.998776) (xy 116.783105 -219.99067) (xy 116.834919 -219.99067)
			(xy 116.886096 -219.998776) (xy 116.935375 -220.014788) (xy 116.981542 -220.038311) (xy 117.023461 -220.068767)
			(xy 117.060099 -220.105405) (xy 117.090555 -220.147324) (xy 117.114078 -220.193491) (xy 117.13009 -220.24277)
			(xy 117.138196 -220.293947) (xy 117.138704 -220.319854) (xy 118.35892 -220.319854) (xy 118.359428 -220.293947)
			(xy 118.367534 -220.24277) (xy 118.383546 -220.193491) (xy 118.407069 -220.147324) (xy 118.437525 -220.105405)
			(xy 118.474163 -220.068767) (xy 118.516082 -220.038311) (xy 118.562249 -220.014788) (xy 118.611528 -219.998776)
			(xy 118.662705 -219.99067) (xy 118.714519 -219.99067) (xy 118.765696 -219.998776) (xy 118.814975 -220.014788)
			(xy 118.861142 -220.038311) (xy 118.903061 -220.068767) (xy 118.939699 -220.105405) (xy 118.970155 -220.147324)
			(xy 118.993678 -220.193491) (xy 119.00969 -220.24277) (xy 119.017796 -220.293947) (xy 119.018304 -220.319854)
			(xy 120.23852 -220.319854) (xy 120.239028 -220.293947) (xy 120.247134 -220.24277) (xy 120.263146 -220.193491)
			(xy 120.286669 -220.147324) (xy 120.317125 -220.105405) (xy 120.353763 -220.068767) (xy 120.395682 -220.038311)
			(xy 120.441849 -220.014788) (xy 120.491128 -219.998776) (xy 120.542305 -219.99067) (xy 120.594119 -219.99067)
			(xy 120.645296 -219.998776) (xy 120.694575 -220.014788) (xy 120.740742 -220.038311) (xy 120.782661 -220.068767)
			(xy 120.819299 -220.105405) (xy 120.849755 -220.147324) (xy 120.873278 -220.193491) (xy 120.88929 -220.24277)
			(xy 120.897396 -220.293947) (xy 120.897904 -220.319854) (xy 122.11812 -220.319854) (xy 122.118628 -220.293947)
			(xy 122.126734 -220.24277) (xy 122.142746 -220.193491) (xy 122.166269 -220.147324) (xy 122.196725 -220.105405)
			(xy 122.233363 -220.068767) (xy 122.275282 -220.038311) (xy 122.321449 -220.014788) (xy 122.370728 -219.998776)
			(xy 122.421905 -219.99067) (xy 122.473719 -219.99067) (xy 122.524896 -219.998776) (xy 122.574175 -220.014788)
			(xy 122.620342 -220.038311) (xy 122.662261 -220.068767) (xy 122.698899 -220.105405) (xy 122.729355 -220.147324)
			(xy 122.752878 -220.193491) (xy 122.76889 -220.24277) (xy 122.776996 -220.293947) (xy 122.777504 -220.319854)
			(xy 123.99772 -220.319854) (xy 123.998228 -220.293947) (xy 124.006334 -220.24277) (xy 124.022346 -220.193491)
			(xy 124.045869 -220.147324) (xy 124.076325 -220.105405) (xy 124.112963 -220.068767) (xy 124.154882 -220.038311)
			(xy 124.201049 -220.014788) (xy 124.250328 -219.998776) (xy 124.301505 -219.99067) (xy 124.353319 -219.99067)
			(xy 124.404496 -219.998776) (xy 124.453775 -220.014788) (xy 124.499942 -220.038311) (xy 124.541861 -220.068767)
			(xy 124.578499 -220.105405) (xy 124.608955 -220.147324) (xy 124.632478 -220.193491) (xy 124.64849 -220.24277)
			(xy 124.656596 -220.293947) (xy 124.657104 -220.319854) (xy 125.87732 -220.319854) (xy 125.877828 -220.293947)
			(xy 125.885934 -220.24277) (xy 125.901946 -220.193491) (xy 125.925469 -220.147324) (xy 125.955925 -220.105405)
			(xy 125.992563 -220.068767) (xy 126.034482 -220.038311) (xy 126.080649 -220.014788) (xy 126.129928 -219.998776)
			(xy 126.181105 -219.99067) (xy 126.232919 -219.99067) (xy 126.284096 -219.998776) (xy 126.333375 -220.014788)
			(xy 126.379542 -220.038311) (xy 126.421461 -220.068767) (xy 126.458099 -220.105405) (xy 126.488555 -220.147324)
			(xy 126.512078 -220.193491) (xy 126.52809 -220.24277) (xy 126.536196 -220.293947) (xy 126.536704 -220.319854)
			(xy 127.75692 -220.319854) (xy 127.757428 -220.293947) (xy 127.765534 -220.24277) (xy 127.781546 -220.193491)
			(xy 127.805069 -220.147324) (xy 127.835525 -220.105405) (xy 127.872163 -220.068767) (xy 127.914082 -220.038311)
			(xy 127.960249 -220.014788) (xy 128.009528 -219.998776) (xy 128.060705 -219.99067) (xy 128.112519 -219.99067)
			(xy 128.163696 -219.998776) (xy 128.212975 -220.014788) (xy 128.259142 -220.038311) (xy 128.301061 -220.068767)
			(xy 128.337699 -220.105405) (xy 128.368155 -220.147324) (xy 128.391678 -220.193491) (xy 128.40769 -220.24277)
			(xy 128.415796 -220.293947) (xy 128.416304 -220.319854) (xy 129.63652 -220.319854) (xy 129.637028 -220.293947)
			(xy 129.645134 -220.24277) (xy 129.661146 -220.193491) (xy 129.684669 -220.147324) (xy 129.715125 -220.105405)
			(xy 129.751763 -220.068767) (xy 129.793682 -220.038311) (xy 129.839849 -220.014788) (xy 129.889128 -219.998776)
			(xy 129.940305 -219.99067) (xy 129.992119 -219.99067) (xy 130.043296 -219.998776) (xy 130.092575 -220.014788)
			(xy 130.138742 -220.038311) (xy 130.180661 -220.068767) (xy 130.217299 -220.105405) (xy 130.247755 -220.147324)
			(xy 130.271278 -220.193491) (xy 130.28729 -220.24277) (xy 130.295396 -220.293947) (xy 130.295904 -220.319854)
			(xy 131.51612 -220.319854) (xy 131.516628 -220.293947) (xy 131.524734 -220.24277) (xy 131.540746 -220.193491)
			(xy 131.564269 -220.147324) (xy 131.594725 -220.105405) (xy 131.631363 -220.068767) (xy 131.673282 -220.038311)
			(xy 131.719449 -220.014788) (xy 131.768728 -219.998776) (xy 131.819905 -219.99067) (xy 131.871719 -219.99067)
			(xy 131.922896 -219.998776) (xy 131.972175 -220.014788) (xy 132.018342 -220.038311) (xy 132.060261 -220.068767)
			(xy 132.096899 -220.105405) (xy 132.127355 -220.147324) (xy 132.150878 -220.193491) (xy 132.16689 -220.24277)
			(xy 132.174996 -220.293947) (xy 132.175504 -220.319854) (xy 133.396228 -220.319854) (xy 133.396736 -220.293967)
			(xy 133.404835 -220.242829) (xy 133.420834 -220.193589) (xy 133.44434 -220.147457) (xy 133.474772 -220.10557)
			(xy 133.511382 -220.06896) (xy 133.553269 -220.038528) (xy 133.599401 -220.015022) (xy 133.648641 -219.999023)
			(xy 133.699779 -219.990924) (xy 133.751553 -219.990924) (xy 133.802691 -219.999023) (xy 133.851931 -220.015022)
			(xy 133.898063 -220.038528) (xy 133.93995 -220.06896) (xy 133.97656 -220.10557) (xy 134.006992 -220.147457)
			(xy 134.030498 -220.193589) (xy 134.046497 -220.242829) (xy 134.054596 -220.293967) (xy 134.055104 -220.319854)
			(xy 134.054563 -220.347562) (xy 134.045375 -220.402208) (xy 134.036816 -220.428566) (xy 134.029196 -220.450664)
			(xy 134.234174 -220.805756) (xy 134.257034 -220.810074) (xy 134.281845 -220.815229) (xy 134.329584 -220.832223)
			(xy 134.374162 -220.856322) (xy 134.414527 -220.886957) (xy 134.44973 -220.923408) (xy 134.47894 -220.964816)
			(xy 134.501472 -221.010206) (xy 134.516792 -221.058509) (xy 134.524542 -221.108587) (xy 134.525004 -221.133924)
			(xy 134.524496 -221.159811) (xy 134.516397 -221.210949) (xy 134.500398 -221.260189) (xy 134.476892 -221.306321)
			(xy 134.44646 -221.348208) (xy 134.40985 -221.384818) (xy 134.367963 -221.41525) (xy 134.321831 -221.438756)
			(xy 134.272591 -221.454755) (xy 134.221453 -221.462854) (xy 134.169679 -221.462854) (xy 134.118541 -221.454755)
			(xy 134.069301 -221.438756) (xy 134.023169 -221.41525) (xy 133.981282 -221.384818) (xy 133.944672 -221.348208)
			(xy 133.91424 -221.306321) (xy 133.890734 -221.260189) (xy 133.874735 -221.210949) (xy 133.866636 -221.159811)
			(xy 133.866128 -221.133924) (xy 133.866667 -221.106216) (xy 133.875856 -221.05157) (xy 133.884416 -221.025212)
			(xy 133.89229 -221.003114) (xy 133.687312 -220.648022) (xy 133.664452 -220.643704) (xy 133.639631 -220.638536)
			(xy 133.591852 -220.621582) (xy 133.547233 -220.59751) (xy 133.506826 -220.56689) (xy 133.471585 -220.530444)
			(xy 133.442341 -220.48903) (xy 133.419784 -220.443627) (xy 133.404447 -220.395304) (xy 133.39669 -220.345203)
			(xy 133.396228 -220.319854) (xy 132.175504 -220.319854) (xy 132.174894 -220.347507) (xy 132.165571 -220.402025)
			(xy 132.156962 -220.428312) (xy 132.149342 -220.45041) (xy 132.354574 -220.805756) (xy 132.377434 -220.810074)
			(xy 132.402245 -220.815229) (xy 132.449984 -220.832223) (xy 132.494562 -220.856322) (xy 132.534927 -220.886957)
			(xy 132.57013 -220.923408) (xy 132.59934 -220.964816) (xy 132.621872 -221.010206) (xy 132.637192 -221.058509)
			(xy 132.644942 -221.108587) (xy 132.645404 -221.133924) (xy 132.644896 -221.159811) (xy 132.636797 -221.210949)
			(xy 132.620798 -221.260189) (xy 132.597292 -221.306321) (xy 132.56686 -221.348208) (xy 132.53025 -221.384818)
			(xy 132.488363 -221.41525) (xy 132.442231 -221.438756) (xy 132.392991 -221.454755) (xy 132.341853 -221.462854)
			(xy 132.290079 -221.462854) (xy 132.238941 -221.454755) (xy 132.189701 -221.438756) (xy 132.143569 -221.41525)
			(xy 132.101682 -221.384818) (xy 132.065072 -221.348208) (xy 132.03464 -221.306321) (xy 132.011134 -221.260189)
			(xy 131.995135 -221.210949) (xy 131.987036 -221.159811) (xy 131.986528 -221.133924) (xy 131.987067 -221.106216)
			(xy 131.996256 -221.05157) (xy 132.004816 -221.025212) (xy 132.01269 -221.003114) (xy 131.807712 -220.648022)
			(xy 131.784852 -220.643704) (xy 131.76 -220.63857) (xy 131.712153 -220.621668) (xy 131.667462 -220.597632)
			(xy 131.626984 -220.567029) (xy 131.591674 -220.530584) (xy 131.562368 -220.489157) (xy 131.539757 -220.443728)
			(xy 131.524377 -220.39537) (xy 131.516591 -220.345226) (xy 131.51612 -220.319854) (xy 130.295904 -220.319854)
			(xy 130.295294 -220.347507) (xy 130.285971 -220.402025) (xy 130.277362 -220.428312) (xy 130.269742 -220.45041)
			(xy 130.474974 -220.805756) (xy 130.497834 -220.810074) (xy 130.522645 -220.815229) (xy 130.570384 -220.832223)
			(xy 130.614962 -220.856322) (xy 130.655327 -220.886957) (xy 130.69053 -220.923408) (xy 130.71974 -220.964816)
			(xy 130.742272 -221.010206) (xy 130.757592 -221.058509) (xy 130.765342 -221.108587) (xy 130.765804 -221.133924)
			(xy 130.765296 -221.159811) (xy 130.757197 -221.210949) (xy 130.741198 -221.260189) (xy 130.717692 -221.306321)
			(xy 130.68726 -221.348208) (xy 130.65065 -221.384818) (xy 130.608763 -221.41525) (xy 130.562631 -221.438756)
			(xy 130.513391 -221.454755) (xy 130.462253 -221.462854) (xy 130.410479 -221.462854) (xy 130.359341 -221.454755)
			(xy 130.310101 -221.438756) (xy 130.263969 -221.41525) (xy 130.222082 -221.384818) (xy 130.185472 -221.348208)
			(xy 130.15504 -221.306321) (xy 130.131534 -221.260189) (xy 130.115535 -221.210949) (xy 130.107436 -221.159811)
			(xy 130.106928 -221.133924) (xy 130.107467 -221.106216) (xy 130.116656 -221.05157) (xy 130.125216 -221.025212)
			(xy 130.13309 -221.003114) (xy 129.928112 -220.648022) (xy 129.905252 -220.643704) (xy 129.8804 -220.63857)
			(xy 129.832553 -220.621668) (xy 129.787862 -220.597632) (xy 129.747384 -220.567029) (xy 129.712074 -220.530584)
			(xy 129.682768 -220.489157) (xy 129.660157 -220.443728) (xy 129.644777 -220.39537) (xy 129.636991 -220.345226)
			(xy 129.63652 -220.319854) (xy 128.416304 -220.319854) (xy 128.415694 -220.347507) (xy 128.406371 -220.402025)
			(xy 128.397762 -220.428312) (xy 128.390142 -220.45041) (xy 128.595374 -220.805756) (xy 128.618234 -220.810074)
			(xy 128.643045 -220.815229) (xy 128.690784 -220.832223) (xy 128.735362 -220.856322) (xy 128.775727 -220.886957)
			(xy 128.81093 -220.923408) (xy 128.84014 -220.964816) (xy 128.862672 -221.010206) (xy 128.877992 -221.058509)
			(xy 128.885742 -221.108587) (xy 128.886204 -221.133924) (xy 128.885696 -221.159811) (xy 128.877597 -221.210949)
			(xy 128.861598 -221.260189) (xy 128.838092 -221.306321) (xy 128.80766 -221.348208) (xy 128.77105 -221.384818)
			(xy 128.729163 -221.41525) (xy 128.683031 -221.438756) (xy 128.633791 -221.454755) (xy 128.582653 -221.462854)
			(xy 128.530879 -221.462854) (xy 128.479741 -221.454755) (xy 128.430501 -221.438756) (xy 128.384369 -221.41525)
			(xy 128.342482 -221.384818) (xy 128.305872 -221.348208) (xy 128.27544 -221.306321) (xy 128.251934 -221.260189)
			(xy 128.235935 -221.210949) (xy 128.227836 -221.159811) (xy 128.227328 -221.133924) (xy 128.227867 -221.106216)
			(xy 128.237056 -221.05157) (xy 128.245616 -221.025212) (xy 128.25349 -221.003114) (xy 128.048512 -220.648022)
			(xy 128.025652 -220.643704) (xy 128.0008 -220.63857) (xy 127.952953 -220.621668) (xy 127.908262 -220.597632)
			(xy 127.867784 -220.567029) (xy 127.832474 -220.530584) (xy 127.803168 -220.489157) (xy 127.780557 -220.443728)
			(xy 127.765177 -220.39537) (xy 127.757391 -220.345226) (xy 127.75692 -220.319854) (xy 126.536704 -220.319854)
			(xy 126.536094 -220.347507) (xy 126.526771 -220.402025) (xy 126.518162 -220.428312) (xy 126.510542 -220.45041)
			(xy 126.715774 -220.805756) (xy 126.738634 -220.810074) (xy 126.763445 -220.815229) (xy 126.811184 -220.832223)
			(xy 126.855762 -220.856322) (xy 126.896127 -220.886957) (xy 126.93133 -220.923408) (xy 126.96054 -220.964816)
			(xy 126.983072 -221.010206) (xy 126.998392 -221.058509) (xy 127.006142 -221.108587) (xy 127.006604 -221.133924)
			(xy 127.006096 -221.159811) (xy 126.997997 -221.210949) (xy 126.981998 -221.260189) (xy 126.958492 -221.306321)
			(xy 126.92806 -221.348208) (xy 126.89145 -221.384818) (xy 126.849563 -221.41525) (xy 126.803431 -221.438756)
			(xy 126.754191 -221.454755) (xy 126.703053 -221.462854) (xy 126.651279 -221.462854) (xy 126.600141 -221.454755)
			(xy 126.550901 -221.438756) (xy 126.504769 -221.41525) (xy 126.462882 -221.384818) (xy 126.426272 -221.348208)
			(xy 126.39584 -221.306321) (xy 126.372334 -221.260189) (xy 126.356335 -221.210949) (xy 126.348236 -221.159811)
			(xy 126.347728 -221.133924) (xy 126.348267 -221.106216) (xy 126.357456 -221.05157) (xy 126.366016 -221.025212)
			(xy 126.37389 -221.003114) (xy 126.168912 -220.648022) (xy 126.146052 -220.643704) (xy 126.1212 -220.63857)
			(xy 126.073353 -220.621668) (xy 126.028662 -220.597632) (xy 125.988184 -220.567029) (xy 125.952874 -220.530584)
			(xy 125.923568 -220.489157) (xy 125.900957 -220.443728) (xy 125.885577 -220.39537) (xy 125.877791 -220.345226)
			(xy 125.87732 -220.319854) (xy 124.657104 -220.319854) (xy 124.656494 -220.347507) (xy 124.647171 -220.402025)
			(xy 124.638562 -220.428312) (xy 124.630942 -220.45041) (xy 124.836174 -220.805756) (xy 124.859034 -220.810074)
			(xy 124.883845 -220.815229) (xy 124.931584 -220.832223) (xy 124.976162 -220.856322) (xy 125.016527 -220.886957)
			(xy 125.05173 -220.923408) (xy 125.08094 -220.964816) (xy 125.103472 -221.010206) (xy 125.118792 -221.058509)
			(xy 125.126542 -221.108587) (xy 125.127004 -221.133924) (xy 125.126496 -221.159811) (xy 125.118397 -221.210949)
			(xy 125.102398 -221.260189) (xy 125.078892 -221.306321) (xy 125.04846 -221.348208) (xy 125.01185 -221.384818)
			(xy 124.969963 -221.41525) (xy 124.923831 -221.438756) (xy 124.874591 -221.454755) (xy 124.823453 -221.462854)
			(xy 124.771679 -221.462854) (xy 124.720541 -221.454755) (xy 124.671301 -221.438756) (xy 124.625169 -221.41525)
			(xy 124.583282 -221.384818) (xy 124.546672 -221.348208) (xy 124.51624 -221.306321) (xy 124.492734 -221.260189)
			(xy 124.476735 -221.210949) (xy 124.468636 -221.159811) (xy 124.468128 -221.133924) (xy 124.468667 -221.106216)
			(xy 124.477856 -221.05157) (xy 124.486416 -221.025212) (xy 124.49429 -221.003114) (xy 124.289312 -220.648022)
			(xy 124.266452 -220.643704) (xy 124.2416 -220.63857) (xy 124.193753 -220.621668) (xy 124.149062 -220.597632)
			(xy 124.108584 -220.567029) (xy 124.073274 -220.530584) (xy 124.043968 -220.489157) (xy 124.021357 -220.443728)
			(xy 124.005977 -220.39537) (xy 123.998191 -220.345226) (xy 123.99772 -220.319854) (xy 122.777504 -220.319854)
			(xy 122.776894 -220.347507) (xy 122.767571 -220.402025) (xy 122.758962 -220.428312) (xy 122.751342 -220.45041)
			(xy 122.956574 -220.805756) (xy 122.979434 -220.810074) (xy 123.004245 -220.815229) (xy 123.051984 -220.832223)
			(xy 123.096562 -220.856322) (xy 123.136927 -220.886957) (xy 123.17213 -220.923408) (xy 123.20134 -220.964816)
			(xy 123.223872 -221.010206) (xy 123.239192 -221.058509) (xy 123.246942 -221.108587) (xy 123.247404 -221.133924)
			(xy 123.246896 -221.159811) (xy 123.238797 -221.210949) (xy 123.222798 -221.260189) (xy 123.199292 -221.306321)
			(xy 123.16886 -221.348208) (xy 123.13225 -221.384818) (xy 123.090363 -221.41525) (xy 123.044231 -221.438756)
			(xy 122.994991 -221.454755) (xy 122.943853 -221.462854) (xy 122.892079 -221.462854) (xy 122.840941 -221.454755)
			(xy 122.791701 -221.438756) (xy 122.745569 -221.41525) (xy 122.703682 -221.384818) (xy 122.667072 -221.348208)
			(xy 122.63664 -221.306321) (xy 122.613134 -221.260189) (xy 122.597135 -221.210949) (xy 122.589036 -221.159811)
			(xy 122.588528 -221.133924) (xy 122.589067 -221.106216) (xy 122.598256 -221.05157) (xy 122.606816 -221.025212)
			(xy 122.61469 -221.003114) (xy 122.409712 -220.648022) (xy 122.386852 -220.643704) (xy 122.362 -220.63857)
			(xy 122.314153 -220.621668) (xy 122.269462 -220.597632) (xy 122.228984 -220.567029) (xy 122.193674 -220.530584)
			(xy 122.164368 -220.489157) (xy 122.141757 -220.443728) (xy 122.126377 -220.39537) (xy 122.118591 -220.345226)
			(xy 122.11812 -220.319854) (xy 120.897904 -220.319854) (xy 120.897294 -220.347507) (xy 120.887971 -220.402025)
			(xy 120.879362 -220.428312) (xy 120.871742 -220.45041) (xy 121.076974 -220.805756) (xy 121.099834 -220.810074)
			(xy 121.124645 -220.815229) (xy 121.172384 -220.832223) (xy 121.216962 -220.856322) (xy 121.257327 -220.886957)
			(xy 121.29253 -220.923408) (xy 121.32174 -220.964816) (xy 121.344272 -221.010206) (xy 121.359592 -221.058509)
			(xy 121.367342 -221.108587) (xy 121.367804 -221.133924) (xy 121.367296 -221.159811) (xy 121.359197 -221.210949)
			(xy 121.343198 -221.260189) (xy 121.319692 -221.306321) (xy 121.28926 -221.348208) (xy 121.25265 -221.384818)
			(xy 121.210763 -221.41525) (xy 121.164631 -221.438756) (xy 121.115391 -221.454755) (xy 121.064253 -221.462854)
			(xy 121.012479 -221.462854) (xy 120.961341 -221.454755) (xy 120.912101 -221.438756) (xy 120.865969 -221.41525)
			(xy 120.824082 -221.384818) (xy 120.787472 -221.348208) (xy 120.75704 -221.306321) (xy 120.733534 -221.260189)
			(xy 120.717535 -221.210949) (xy 120.709436 -221.159811) (xy 120.708928 -221.133924) (xy 120.709467 -221.106216)
			(xy 120.718656 -221.05157) (xy 120.727216 -221.025212) (xy 120.73509 -221.003114) (xy 120.530112 -220.648022)
			(xy 120.507252 -220.643704) (xy 120.4824 -220.63857) (xy 120.434553 -220.621668) (xy 120.389862 -220.597632)
			(xy 120.349384 -220.567029) (xy 120.314074 -220.530584) (xy 120.284768 -220.489157) (xy 120.262157 -220.443728)
			(xy 120.246777 -220.39537) (xy 120.238991 -220.345226) (xy 120.23852 -220.319854) (xy 119.018304 -220.319854)
			(xy 119.017694 -220.347507) (xy 119.008371 -220.402025) (xy 118.999762 -220.428312) (xy 118.992142 -220.45041)
			(xy 119.197374 -220.805756) (xy 119.220234 -220.810074) (xy 119.245045 -220.815229) (xy 119.292784 -220.832223)
			(xy 119.337362 -220.856322) (xy 119.377727 -220.886957) (xy 119.41293 -220.923408) (xy 119.44214 -220.964816)
			(xy 119.464672 -221.010206) (xy 119.479992 -221.058509) (xy 119.487742 -221.108587) (xy 119.488204 -221.133924)
			(xy 119.487696 -221.159811) (xy 119.479597 -221.210949) (xy 119.463598 -221.260189) (xy 119.440092 -221.306321)
			(xy 119.40966 -221.348208) (xy 119.37305 -221.384818) (xy 119.331163 -221.41525) (xy 119.285031 -221.438756)
			(xy 119.235791 -221.454755) (xy 119.184653 -221.462854) (xy 119.132879 -221.462854) (xy 119.081741 -221.454755)
			(xy 119.032501 -221.438756) (xy 118.986369 -221.41525) (xy 118.944482 -221.384818) (xy 118.907872 -221.348208)
			(xy 118.87744 -221.306321) (xy 118.853934 -221.260189) (xy 118.837935 -221.210949) (xy 118.829836 -221.159811)
			(xy 118.829328 -221.133924) (xy 118.829867 -221.106216) (xy 118.839056 -221.05157) (xy 118.847616 -221.025212)
			(xy 118.85549 -221.003114) (xy 118.650512 -220.648022) (xy 118.627652 -220.643704) (xy 118.6028 -220.63857)
			(xy 118.554953 -220.621668) (xy 118.510262 -220.597632) (xy 118.469784 -220.567029) (xy 118.434474 -220.530584)
			(xy 118.405168 -220.489157) (xy 118.382557 -220.443728) (xy 118.367177 -220.39537) (xy 118.359391 -220.345226)
			(xy 118.35892 -220.319854) (xy 117.138704 -220.319854) (xy 117.138094 -220.347507) (xy 117.128771 -220.402025)
			(xy 117.120162 -220.428312) (xy 117.112542 -220.45041) (xy 117.317774 -220.805756) (xy 117.340634 -220.810074)
			(xy 117.365445 -220.815229) (xy 117.413184 -220.832223) (xy 117.457762 -220.856322) (xy 117.498127 -220.886957)
			(xy 117.53333 -220.923408) (xy 117.56254 -220.964816) (xy 117.585072 -221.010206) (xy 117.600392 -221.058509)
			(xy 117.608142 -221.108587) (xy 117.608604 -221.133924) (xy 117.608096 -221.159811) (xy 117.599997 -221.210949)
			(xy 117.583998 -221.260189) (xy 117.560492 -221.306321) (xy 117.53006 -221.348208) (xy 117.49345 -221.384818)
			(xy 117.451563 -221.41525) (xy 117.405431 -221.438756) (xy 117.356191 -221.454755) (xy 117.305053 -221.462854)
			(xy 117.253279 -221.462854) (xy 117.202141 -221.454755) (xy 117.152901 -221.438756) (xy 117.106769 -221.41525)
			(xy 117.064882 -221.384818) (xy 117.028272 -221.348208) (xy 116.99784 -221.306321) (xy 116.974334 -221.260189)
			(xy 116.958335 -221.210949) (xy 116.950236 -221.159811) (xy 116.949728 -221.133924) (xy 116.950267 -221.106216)
			(xy 116.959456 -221.05157) (xy 116.968016 -221.025212) (xy 116.97589 -221.003114) (xy 116.770912 -220.648022)
			(xy 116.748052 -220.643704) (xy 116.7232 -220.63857) (xy 116.675353 -220.621668) (xy 116.630662 -220.597632)
			(xy 116.590184 -220.567029) (xy 116.554874 -220.530584) (xy 116.525568 -220.489157) (xy 116.502957 -220.443728)
			(xy 116.487577 -220.39537) (xy 116.479791 -220.345226) (xy 116.47932 -220.319854) (xy 115.259104 -220.319854)
			(xy 115.258494 -220.347507) (xy 115.249171 -220.402025) (xy 115.240562 -220.428312) (xy 115.232942 -220.45041)
			(xy 115.438174 -220.805756) (xy 115.461034 -220.810074) (xy 115.485845 -220.815229) (xy 115.533584 -220.832223)
			(xy 115.578162 -220.856322) (xy 115.618527 -220.886957) (xy 115.65373 -220.923408) (xy 115.68294 -220.964816)
			(xy 115.705472 -221.010206) (xy 115.720792 -221.058509) (xy 115.728542 -221.108587) (xy 115.729004 -221.133924)
			(xy 115.728496 -221.159811) (xy 115.720397 -221.210949) (xy 115.704398 -221.260189) (xy 115.680892 -221.306321)
			(xy 115.65046 -221.348208) (xy 115.61385 -221.384818) (xy 115.571963 -221.41525) (xy 115.525831 -221.438756)
			(xy 115.476591 -221.454755) (xy 115.425453 -221.462854) (xy 115.373679 -221.462854) (xy 115.322541 -221.454755)
			(xy 115.273301 -221.438756) (xy 115.227169 -221.41525) (xy 115.185282 -221.384818) (xy 115.148672 -221.348208)
			(xy 115.11824 -221.306321) (xy 115.094734 -221.260189) (xy 115.078735 -221.210949) (xy 115.070636 -221.159811)
			(xy 115.070128 -221.133924) (xy 115.070667 -221.106216) (xy 115.079856 -221.05157) (xy 115.088416 -221.025212)
			(xy 115.09629 -221.003114) (xy 114.891312 -220.648022) (xy 114.868452 -220.643704) (xy 114.8436 -220.63857)
			(xy 114.795753 -220.621668) (xy 114.751062 -220.597632) (xy 114.710584 -220.567029) (xy 114.675274 -220.530584)
			(xy 114.645968 -220.489157) (xy 114.623357 -220.443728) (xy 114.607977 -220.39537) (xy 114.600191 -220.345226)
			(xy 114.59972 -220.319854) (xy 113.379504 -220.319854) (xy 113.378894 -220.347507) (xy 113.369571 -220.402025)
			(xy 113.360962 -220.428312) (xy 113.353342 -220.45041) (xy 113.558574 -220.805756) (xy 113.581434 -220.810074)
			(xy 113.606245 -220.815229) (xy 113.653984 -220.832223) (xy 113.698562 -220.856322) (xy 113.738927 -220.886957)
			(xy 113.77413 -220.923408) (xy 113.80334 -220.964816) (xy 113.825872 -221.010206) (xy 113.841192 -221.058509)
			(xy 113.848942 -221.108587) (xy 113.849404 -221.133924) (xy 113.848896 -221.159811) (xy 113.840797 -221.210949)
			(xy 113.824798 -221.260189) (xy 113.801292 -221.306321) (xy 113.77086 -221.348208) (xy 113.73425 -221.384818)
			(xy 113.692363 -221.41525) (xy 113.646231 -221.438756) (xy 113.596991 -221.454755) (xy 113.545853 -221.462854)
			(xy 113.494079 -221.462854) (xy 113.442941 -221.454755) (xy 113.393701 -221.438756) (xy 113.347569 -221.41525)
			(xy 113.305682 -221.384818) (xy 113.269072 -221.348208) (xy 113.23864 -221.306321) (xy 113.215134 -221.260189)
			(xy 113.199135 -221.210949) (xy 113.191036 -221.159811) (xy 113.190528 -221.133924) (xy 113.191067 -221.106216)
			(xy 113.200256 -221.05157) (xy 113.208816 -221.025212) (xy 113.21669 -221.003114) (xy 113.011712 -220.648022)
			(xy 112.988852 -220.643704) (xy 112.964 -220.63857) (xy 112.916153 -220.621668) (xy 112.871462 -220.597632)
			(xy 112.830984 -220.567029) (xy 112.795674 -220.530584) (xy 112.766368 -220.489157) (xy 112.743757 -220.443728)
			(xy 112.728377 -220.39537) (xy 112.720591 -220.345226) (xy 112.72012 -220.319854) (xy 111.499904 -220.319854)
			(xy 111.499294 -220.347507) (xy 111.489971 -220.402025) (xy 111.481362 -220.428312) (xy 111.473742 -220.45041)
			(xy 111.678974 -220.805756) (xy 111.701834 -220.810074) (xy 111.726645 -220.815229) (xy 111.774384 -220.832223)
			(xy 111.818962 -220.856322) (xy 111.859327 -220.886957) (xy 111.89453 -220.923408) (xy 111.92374 -220.964816)
			(xy 111.946272 -221.010206) (xy 111.961592 -221.058509) (xy 111.969342 -221.108587) (xy 111.969804 -221.133924)
			(xy 111.969296 -221.159811) (xy 111.961197 -221.210949) (xy 111.945198 -221.260189) (xy 111.921692 -221.306321)
			(xy 111.89126 -221.348208) (xy 111.85465 -221.384818) (xy 111.812763 -221.41525) (xy 111.766631 -221.438756)
			(xy 111.717391 -221.454755) (xy 111.666253 -221.462854) (xy 111.614479 -221.462854) (xy 111.563341 -221.454755)
			(xy 111.514101 -221.438756) (xy 111.467969 -221.41525) (xy 111.426082 -221.384818) (xy 111.389472 -221.348208)
			(xy 111.35904 -221.306321) (xy 111.335534 -221.260189) (xy 111.319535 -221.210949) (xy 111.311436 -221.159811)
			(xy 111.310928 -221.133924) (xy 111.311467 -221.106216) (xy 111.320656 -221.05157) (xy 111.329216 -221.025212)
			(xy 111.33709 -221.003114) (xy 111.132112 -220.648022) (xy 111.109252 -220.643704) (xy 111.0844 -220.63857)
			(xy 111.036553 -220.621668) (xy 110.991862 -220.597632) (xy 110.951384 -220.567029) (xy 110.916074 -220.530584)
			(xy 110.886768 -220.489157) (xy 110.864157 -220.443728) (xy 110.848777 -220.39537) (xy 110.840991 -220.345226)
			(xy 110.84052 -220.319854) (xy 109.620304 -220.319854) (xy 109.619694 -220.347507) (xy 109.610371 -220.402025)
			(xy 109.601762 -220.428312) (xy 109.594142 -220.45041) (xy 109.799374 -220.805756) (xy 109.822234 -220.810074)
			(xy 109.847045 -220.815229) (xy 109.894784 -220.832223) (xy 109.939362 -220.856322) (xy 109.979727 -220.886957)
			(xy 110.01493 -220.923408) (xy 110.04414 -220.964816) (xy 110.066672 -221.010206) (xy 110.081992 -221.058509)
			(xy 110.089742 -221.108587) (xy 110.090204 -221.133924) (xy 110.089696 -221.159811) (xy 110.081597 -221.210949)
			(xy 110.065598 -221.260189) (xy 110.042092 -221.306321) (xy 110.01166 -221.348208) (xy 109.97505 -221.384818)
			(xy 109.933163 -221.41525) (xy 109.887031 -221.438756) (xy 109.837791 -221.454755) (xy 109.786653 -221.462854)
			(xy 109.734879 -221.462854) (xy 109.683741 -221.454755) (xy 109.634501 -221.438756) (xy 109.588369 -221.41525)
			(xy 109.546482 -221.384818) (xy 109.509872 -221.348208) (xy 109.47944 -221.306321) (xy 109.455934 -221.260189)
			(xy 109.439935 -221.210949) (xy 109.431836 -221.159811) (xy 109.431328 -221.133924) (xy 109.431867 -221.106216)
			(xy 109.441056 -221.05157) (xy 109.449616 -221.025212) (xy 109.45749 -221.003114) (xy 109.252512 -220.648022)
			(xy 109.229652 -220.643704) (xy 109.2048 -220.63857) (xy 109.156953 -220.621668) (xy 109.112262 -220.597632)
			(xy 109.071784 -220.567029) (xy 109.036474 -220.530584) (xy 109.007168 -220.489157) (xy 108.984557 -220.443728)
			(xy 108.969177 -220.39537) (xy 108.961391 -220.345226) (xy 108.96092 -220.319854) (xy 107.740704 -220.319854)
			(xy 107.740094 -220.347507) (xy 107.730771 -220.402025) (xy 107.722162 -220.428312) (xy 107.714542 -220.45041)
			(xy 107.919774 -220.805756) (xy 107.942634 -220.810074) (xy 107.967445 -220.815229) (xy 108.015184 -220.832223)
			(xy 108.059762 -220.856322) (xy 108.100127 -220.886957) (xy 108.13533 -220.923408) (xy 108.16454 -220.964816)
			(xy 108.187072 -221.010206) (xy 108.202392 -221.058509) (xy 108.210142 -221.108587) (xy 108.210604 -221.133924)
			(xy 108.210096 -221.159811) (xy 108.201997 -221.210949) (xy 108.185998 -221.260189) (xy 108.162492 -221.306321)
			(xy 108.13206 -221.348208) (xy 108.09545 -221.384818) (xy 108.053563 -221.41525) (xy 108.007431 -221.438756)
			(xy 107.958191 -221.454755) (xy 107.907053 -221.462854) (xy 107.855279 -221.462854) (xy 107.804141 -221.454755)
			(xy 107.754901 -221.438756) (xy 107.708769 -221.41525) (xy 107.666882 -221.384818) (xy 107.630272 -221.348208)
			(xy 107.59984 -221.306321) (xy 107.576334 -221.260189) (xy 107.560335 -221.210949) (xy 107.552236 -221.159811)
			(xy 107.551728 -221.133924) (xy 107.552267 -221.106216) (xy 107.561456 -221.05157) (xy 107.570016 -221.025212)
			(xy 107.57789 -221.003114) (xy 107.372912 -220.648022) (xy 107.350052 -220.643704) (xy 107.3252 -220.63857)
			(xy 107.277353 -220.621668) (xy 107.232662 -220.597632) (xy 107.192184 -220.567029) (xy 107.156874 -220.530584)
			(xy 107.127568 -220.489157) (xy 107.104957 -220.443728) (xy 107.089577 -220.39537) (xy 107.081791 -220.345226)
			(xy 107.08132 -220.319854) (xy 105.861104 -220.319854) (xy 105.860494 -220.347507) (xy 105.851171 -220.402025)
			(xy 105.842562 -220.428312) (xy 105.834942 -220.45041) (xy 106.040174 -220.805756) (xy 106.063034 -220.810074)
			(xy 106.087845 -220.815229) (xy 106.135584 -220.832223) (xy 106.180162 -220.856322) (xy 106.220527 -220.886957)
			(xy 106.25573 -220.923408) (xy 106.28494 -220.964816) (xy 106.307472 -221.010206) (xy 106.322792 -221.058509)
			(xy 106.330542 -221.108587) (xy 106.331004 -221.133924) (xy 106.330496 -221.159811) (xy 106.322397 -221.210949)
			(xy 106.306398 -221.260189) (xy 106.282892 -221.306321) (xy 106.25246 -221.348208) (xy 106.21585 -221.384818)
			(xy 106.173963 -221.41525) (xy 106.127831 -221.438756) (xy 106.078591 -221.454755) (xy 106.027453 -221.462854)
			(xy 105.975679 -221.462854) (xy 105.924541 -221.454755) (xy 105.875301 -221.438756) (xy 105.829169 -221.41525)
			(xy 105.787282 -221.384818) (xy 105.750672 -221.348208) (xy 105.72024 -221.306321) (xy 105.696734 -221.260189)
			(xy 105.680735 -221.210949) (xy 105.672636 -221.159811) (xy 105.672128 -221.133924) (xy 105.672667 -221.106216)
			(xy 105.681856 -221.05157) (xy 105.690416 -221.025212) (xy 105.69829 -221.003114) (xy 105.493312 -220.648022)
			(xy 105.470452 -220.643704) (xy 105.4456 -220.63857) (xy 105.397753 -220.621668) (xy 105.353062 -220.597632)
			(xy 105.312584 -220.567029) (xy 105.277274 -220.530584) (xy 105.247968 -220.489157) (xy 105.225357 -220.443728)
			(xy 105.209977 -220.39537) (xy 105.202191 -220.345226) (xy 105.20172 -220.319854) (xy 103.981504 -220.319854)
			(xy 103.981028 -220.345199) (xy 103.973249 -220.395289) (xy 103.957897 -220.443599) (xy 103.935334 -220.48899)
			(xy 103.906091 -220.530396) (xy 103.870857 -220.566839) (xy 103.830462 -220.597461) (xy 103.785857 -220.621543)
			(xy 103.738093 -220.638516) (xy 103.71328 -220.643704) (xy 103.69042 -220.648022) (xy 103.485442 -221.003114)
			(xy 103.493316 -221.024958) (xy 103.50191 -221.051373) (xy 103.511097 -221.106151) (xy 103.511604 -221.133924)
			(xy 103.511096 -221.159811) (xy 103.502997 -221.210949) (xy 103.486998 -221.260189) (xy 103.463492 -221.306321)
			(xy 103.43306 -221.348208) (xy 103.39645 -221.384818) (xy 103.354563 -221.41525) (xy 103.308431 -221.438756)
			(xy 103.259191 -221.454755) (xy 103.208053 -221.462854) (xy 103.156279 -221.462854) (xy 103.105141 -221.454755)
			(xy 103.055901 -221.438756) (xy 103.009769 -221.41525) (xy 102.967882 -221.384818) (xy 102.931272 -221.348208)
			(xy 102.90084 -221.306321) (xy 102.877334 -221.260189) (xy 102.861335 -221.210949) (xy 102.853236 -221.159811)
			(xy 102.852728 -221.133924) (xy 102.571804 -221.133924) (xy 102.57128 -221.161632) (xy 102.562081 -221.216279)
			(xy 102.553516 -221.242636) (xy 102.545642 -221.264734) (xy 102.75062 -221.619572) (xy 102.77348 -221.62389)
			(xy 102.798305 -221.629041) (xy 102.846083 -221.645999) (xy 102.890702 -221.670074) (xy 102.931107 -221.700696)
			(xy 102.966347 -221.737145) (xy 102.99559 -221.778561) (xy 103.018147 -221.823965) (xy 103.033485 -221.872289)
			(xy 103.041242 -221.92239) (xy 103.041704 -221.94774) (xy 104.26192 -221.94774) (xy 104.262371 -221.922394)
			(xy 104.270152 -221.872302) (xy 104.285506 -221.82399) (xy 104.308072 -221.778597) (xy 104.337318 -221.737192)
			(xy 104.372555 -221.700749) (xy 104.412954 -221.670127) (xy 104.457562 -221.646047) (xy 104.50533 -221.629076)
			(xy 104.530144 -221.62389) (xy 104.553004 -221.619572) (xy 104.758236 -221.264226) (xy 104.750362 -221.242128)
			(xy 104.741898 -221.215883) (xy 104.732825 -221.161495) (xy 104.732328 -221.133924) (xy 104.732836 -221.108037)
			(xy 104.740935 -221.056899) (xy 104.756934 -221.007659) (xy 104.78044 -220.961527) (xy 104.810872 -220.91964)
			(xy 104.847482 -220.88303) (xy 104.889369 -220.852598) (xy 104.935501 -220.829092) (xy 104.984741 -220.813093)
			(xy 105.035879 -220.804994) (xy 105.087653 -220.804994) (xy 105.138791 -220.813093) (xy 105.188031 -220.829092)
			(xy 105.234163 -220.852598) (xy 105.27605 -220.88303) (xy 105.31266 -220.91964) (xy 105.343092 -220.961527)
			(xy 105.366598 -221.007659) (xy 105.382597 -221.056899) (xy 105.390696 -221.108037) (xy 105.391204 -221.133924)
			(xy 105.390748 -221.159299) (xy 105.382976 -221.20945) (xy 105.367604 -221.257815) (xy 105.344997 -221.303251)
			(xy 105.315689 -221.344682) (xy 105.280373 -221.381128) (xy 105.239885 -221.411727) (xy 105.195184 -221.435754)
			(xy 105.147326 -221.452641) (xy 105.122472 -221.457774) (xy 105.099612 -221.462092) (xy 104.894888 -221.81693)
			(xy 104.902762 -221.838774) (xy 104.911419 -221.865179) (xy 104.920732 -221.919958) (xy 104.921304 -221.94774)
			(xy 106.14152 -221.94774) (xy 106.141971 -221.922394) (xy 106.149752 -221.872302) (xy 106.165106 -221.82399)
			(xy 106.187672 -221.778597) (xy 106.216918 -221.737192) (xy 106.252155 -221.700749) (xy 106.292554 -221.670127)
			(xy 106.337162 -221.646047) (xy 106.38493 -221.629076) (xy 106.409744 -221.62389) (xy 106.432604 -221.619572)
			(xy 106.637836 -221.264226) (xy 106.629962 -221.242128) (xy 106.621498 -221.215883) (xy 106.612425 -221.161495)
			(xy 106.611928 -221.133924) (xy 106.612436 -221.108037) (xy 106.620535 -221.056899) (xy 106.636534 -221.007659)
			(xy 106.66004 -220.961527) (xy 106.690472 -220.91964) (xy 106.727082 -220.88303) (xy 106.768969 -220.852598)
			(xy 106.815101 -220.829092) (xy 106.864341 -220.813093) (xy 106.915479 -220.804994) (xy 106.967253 -220.804994)
			(xy 107.018391 -220.813093) (xy 107.067631 -220.829092) (xy 107.113763 -220.852598) (xy 107.15565 -220.88303)
			(xy 107.19226 -220.91964) (xy 107.222692 -220.961527) (xy 107.246198 -221.007659) (xy 107.262197 -221.056899)
			(xy 107.270296 -221.108037) (xy 107.270804 -221.133924) (xy 107.270348 -221.159299) (xy 107.262576 -221.20945)
			(xy 107.247204 -221.257815) (xy 107.224597 -221.303251) (xy 107.195289 -221.344682) (xy 107.159973 -221.381128)
			(xy 107.119485 -221.411727) (xy 107.074784 -221.435754) (xy 107.026926 -221.452641) (xy 107.002072 -221.457774)
			(xy 106.979212 -221.462092) (xy 106.774488 -221.81693) (xy 106.782362 -221.838774) (xy 106.791019 -221.865179)
			(xy 106.800332 -221.919958) (xy 106.800904 -221.94774) (xy 108.02112 -221.94774) (xy 108.021571 -221.922394)
			(xy 108.029352 -221.872302) (xy 108.044706 -221.82399) (xy 108.067272 -221.778597) (xy 108.096518 -221.737192)
			(xy 108.131755 -221.700749) (xy 108.172154 -221.670127) (xy 108.216762 -221.646047) (xy 108.26453 -221.629076)
			(xy 108.289344 -221.62389) (xy 108.312204 -221.619572) (xy 108.517436 -221.264226) (xy 108.509562 -221.242128)
			(xy 108.501098 -221.215883) (xy 108.492025 -221.161495) (xy 108.491528 -221.133924) (xy 108.492036 -221.108037)
			(xy 108.500135 -221.056899) (xy 108.516134 -221.007659) (xy 108.53964 -220.961527) (xy 108.570072 -220.91964)
			(xy 108.606682 -220.88303) (xy 108.648569 -220.852598) (xy 108.694701 -220.829092) (xy 108.743941 -220.813093)
			(xy 108.795079 -220.804994) (xy 108.846853 -220.804994) (xy 108.897991 -220.813093) (xy 108.947231 -220.829092)
			(xy 108.993363 -220.852598) (xy 109.03525 -220.88303) (xy 109.07186 -220.91964) (xy 109.102292 -220.961527)
			(xy 109.125798 -221.007659) (xy 109.141797 -221.056899) (xy 109.149896 -221.108037) (xy 109.150404 -221.133924)
			(xy 109.149948 -221.159299) (xy 109.142176 -221.20945) (xy 109.126804 -221.257815) (xy 109.104197 -221.303251)
			(xy 109.074889 -221.344682) (xy 109.039573 -221.381128) (xy 108.999085 -221.411727) (xy 108.954384 -221.435754)
			(xy 108.906526 -221.452641) (xy 108.881672 -221.457774) (xy 108.858812 -221.462092) (xy 108.654088 -221.81693)
			(xy 108.661962 -221.838774) (xy 108.670619 -221.865179) (xy 108.679932 -221.919958) (xy 108.680504 -221.94774)
			(xy 109.901228 -221.94774) (xy 109.901634 -221.922403) (xy 109.909396 -221.872326) (xy 109.924728 -221.824026)
			(xy 109.947269 -221.77864) (xy 109.976489 -221.737238) (xy 110.011699 -221.700794) (xy 110.05207 -221.670165)
			(xy 110.096652 -221.646074) (xy 110.144395 -221.629087) (xy 110.169198 -221.62389) (xy 110.192058 -221.619572)
			(xy 110.397036 -221.26448) (xy 110.389416 -221.242382) (xy 110.380897 -221.216211) (xy 110.371703 -221.161949)
			(xy 110.371128 -221.134432) (xy 110.371128 -221.133924) (xy 110.371636 -221.108037) (xy 110.379735 -221.056899)
			(xy 110.395734 -221.007659) (xy 110.41924 -220.961527) (xy 110.449672 -220.91964) (xy 110.486282 -220.88303)
			(xy 110.528169 -220.852598) (xy 110.574301 -220.829092) (xy 110.623541 -220.813093) (xy 110.674679 -220.804994)
			(xy 110.726453 -220.804994) (xy 110.777591 -220.813093) (xy 110.826831 -220.829092) (xy 110.872963 -220.852598)
			(xy 110.91485 -220.88303) (xy 110.95146 -220.91964) (xy 110.981892 -220.961527) (xy 111.005398 -221.007659)
			(xy 111.021397 -221.056899) (xy 111.029496 -221.108037) (xy 111.030004 -221.133924) (xy 111.029585 -221.15929)
			(xy 111.021833 -221.209425) (xy 111.006484 -221.257778) (xy 110.983902 -221.303206) (xy 110.954621 -221.344633)
			(xy 110.919333 -221.381081) (xy 110.878874 -221.411686) (xy 110.8342 -221.435725) (xy 110.786369 -221.45263)
			(xy 110.761526 -221.457774) (xy 110.738666 -221.462092) (xy 110.533942 -221.81693) (xy 110.541816 -221.838774)
			(xy 110.550414 -221.865187) (xy 110.559598 -221.919967) (xy 110.560104 -221.94774) (xy 111.78032 -221.94774)
			(xy 111.780771 -221.922394) (xy 111.788552 -221.872302) (xy 111.803906 -221.82399) (xy 111.826472 -221.778597)
			(xy 111.855718 -221.737192) (xy 111.890955 -221.700749) (xy 111.931354 -221.670127) (xy 111.975962 -221.646047)
			(xy 112.02373 -221.629076) (xy 112.048544 -221.62389) (xy 112.071404 -221.619572) (xy 112.276636 -221.264226)
			(xy 112.268762 -221.242128) (xy 112.260298 -221.215883) (xy 112.251225 -221.161495) (xy 112.250728 -221.133924)
			(xy 112.251236 -221.108037) (xy 112.259335 -221.056899) (xy 112.275334 -221.007659) (xy 112.29884 -220.961527)
			(xy 112.329272 -220.91964) (xy 112.365882 -220.88303) (xy 112.407769 -220.852598) (xy 112.453901 -220.829092)
			(xy 112.503141 -220.813093) (xy 112.554279 -220.804994) (xy 112.606053 -220.804994) (xy 112.657191 -220.813093)
			(xy 112.706431 -220.829092) (xy 112.752563 -220.852598) (xy 112.79445 -220.88303) (xy 112.83106 -220.91964)
			(xy 112.861492 -220.961527) (xy 112.884998 -221.007659) (xy 112.900997 -221.056899) (xy 112.909096 -221.108037)
			(xy 112.909604 -221.133924) (xy 112.909148 -221.159299) (xy 112.901376 -221.20945) (xy 112.886004 -221.257815)
			(xy 112.863397 -221.303251) (xy 112.834089 -221.344682) (xy 112.798773 -221.381128) (xy 112.758285 -221.411727)
			(xy 112.713584 -221.435754) (xy 112.665726 -221.452641) (xy 112.640872 -221.457774) (xy 112.618012 -221.462092)
			(xy 112.413288 -221.81693) (xy 112.421162 -221.838774) (xy 112.429819 -221.865179) (xy 112.439132 -221.919958)
			(xy 112.439704 -221.94774) (xy 113.660428 -221.94774) (xy 113.660834 -221.922403) (xy 113.668596 -221.872326)
			(xy 113.683928 -221.824026) (xy 113.706469 -221.77864) (xy 113.735689 -221.737238) (xy 113.770899 -221.700794)
			(xy 113.81127 -221.670165) (xy 113.855852 -221.646074) (xy 113.903595 -221.629087) (xy 113.928398 -221.62389)
			(xy 113.951258 -221.619572) (xy 114.156236 -221.26448) (xy 114.148616 -221.242382) (xy 114.140097 -221.216211)
			(xy 114.130903 -221.161949) (xy 114.130328 -221.134432) (xy 114.130328 -221.133924) (xy 114.130836 -221.108037)
			(xy 114.138935 -221.056899) (xy 114.154934 -221.007659) (xy 114.17844 -220.961527) (xy 114.208872 -220.91964)
			(xy 114.245482 -220.88303) (xy 114.287369 -220.852598) (xy 114.333501 -220.829092) (xy 114.382741 -220.813093)
			(xy 114.433879 -220.804994) (xy 114.485653 -220.804994) (xy 114.536791 -220.813093) (xy 114.586031 -220.829092)
			(xy 114.632163 -220.852598) (xy 114.67405 -220.88303) (xy 114.71066 -220.91964) (xy 114.741092 -220.961527)
			(xy 114.764598 -221.007659) (xy 114.780597 -221.056899) (xy 114.788696 -221.108037) (xy 114.789204 -221.133924)
			(xy 114.788785 -221.15929) (xy 114.781033 -221.209425) (xy 114.765684 -221.257778) (xy 114.743102 -221.303206)
			(xy 114.713821 -221.344633) (xy 114.678533 -221.381081) (xy 114.638074 -221.411686) (xy 114.5934 -221.435725)
			(xy 114.545569 -221.45263) (xy 114.520726 -221.457774) (xy 114.497866 -221.462092) (xy 114.293142 -221.81693)
			(xy 114.301016 -221.838774) (xy 114.309614 -221.865187) (xy 114.318798 -221.919967) (xy 114.319304 -221.94774)
			(xy 115.53952 -221.94774) (xy 115.539971 -221.922394) (xy 115.547752 -221.872302) (xy 115.563106 -221.82399)
			(xy 115.585672 -221.778597) (xy 115.614918 -221.737192) (xy 115.650155 -221.700749) (xy 115.690554 -221.670127)
			(xy 115.735162 -221.646047) (xy 115.78293 -221.629076) (xy 115.807744 -221.62389) (xy 115.830604 -221.619572)
			(xy 116.035836 -221.264226) (xy 116.027962 -221.242128) (xy 116.019498 -221.215883) (xy 116.010425 -221.161495)
			(xy 116.009928 -221.133924) (xy 116.010436 -221.108037) (xy 116.018535 -221.056899) (xy 116.034534 -221.007659)
			(xy 116.05804 -220.961527) (xy 116.088472 -220.91964) (xy 116.125082 -220.88303) (xy 116.166969 -220.852598)
			(xy 116.213101 -220.829092) (xy 116.262341 -220.813093) (xy 116.313479 -220.804994) (xy 116.365253 -220.804994)
			(xy 116.416391 -220.813093) (xy 116.465631 -220.829092) (xy 116.511763 -220.852598) (xy 116.55365 -220.88303)
			(xy 116.59026 -220.91964) (xy 116.620692 -220.961527) (xy 116.644198 -221.007659) (xy 116.660197 -221.056899)
			(xy 116.668296 -221.108037) (xy 116.668804 -221.133924) (xy 116.668348 -221.159299) (xy 116.660576 -221.20945)
			(xy 116.645204 -221.257815) (xy 116.622597 -221.303251) (xy 116.593289 -221.344682) (xy 116.557973 -221.381128)
			(xy 116.517485 -221.411727) (xy 116.472784 -221.435754) (xy 116.424926 -221.452641) (xy 116.400072 -221.457774)
			(xy 116.377212 -221.462092) (xy 116.172488 -221.81693) (xy 116.180362 -221.838774) (xy 116.189019 -221.865179)
			(xy 116.198332 -221.919958) (xy 116.198904 -221.94774) (xy 117.41912 -221.94774) (xy 117.419571 -221.922394)
			(xy 117.427352 -221.872302) (xy 117.442706 -221.82399) (xy 117.465272 -221.778597) (xy 117.494518 -221.737192)
			(xy 117.529755 -221.700749) (xy 117.570154 -221.670127) (xy 117.614762 -221.646047) (xy 117.66253 -221.629076)
			(xy 117.687344 -221.62389) (xy 117.710204 -221.619572) (xy 117.915436 -221.264226) (xy 117.907562 -221.242128)
			(xy 117.899098 -221.215883) (xy 117.890025 -221.161495) (xy 117.889528 -221.133924) (xy 117.890036 -221.108037)
			(xy 117.898135 -221.056899) (xy 117.914134 -221.007659) (xy 117.93764 -220.961527) (xy 117.968072 -220.91964)
			(xy 118.004682 -220.88303) (xy 118.046569 -220.852598) (xy 118.092701 -220.829092) (xy 118.141941 -220.813093)
			(xy 118.193079 -220.804994) (xy 118.244853 -220.804994) (xy 118.295991 -220.813093) (xy 118.345231 -220.829092)
			(xy 118.391363 -220.852598) (xy 118.43325 -220.88303) (xy 118.46986 -220.91964) (xy 118.500292 -220.961527)
			(xy 118.523798 -221.007659) (xy 118.539797 -221.056899) (xy 118.547896 -221.108037) (xy 118.548404 -221.133924)
			(xy 118.547948 -221.159299) (xy 118.540176 -221.20945) (xy 118.524804 -221.257815) (xy 118.502197 -221.303251)
			(xy 118.472889 -221.344682) (xy 118.437573 -221.381128) (xy 118.397085 -221.411727) (xy 118.352384 -221.435754)
			(xy 118.304526 -221.452641) (xy 118.279672 -221.457774) (xy 118.256812 -221.462092) (xy 118.052088 -221.81693)
			(xy 118.059962 -221.838774) (xy 118.068619 -221.865179) (xy 118.077932 -221.919958) (xy 118.078504 -221.94774)
			(xy 121.17832 -221.94774) (xy 121.178771 -221.922394) (xy 121.186552 -221.872302) (xy 121.201906 -221.82399)
			(xy 121.224472 -221.778597) (xy 121.253718 -221.737192) (xy 121.288955 -221.700749) (xy 121.329354 -221.670127)
			(xy 121.373962 -221.646047) (xy 121.42173 -221.629076) (xy 121.446544 -221.62389) (xy 121.469404 -221.619572)
			(xy 121.674636 -221.264226) (xy 121.666762 -221.242128) (xy 121.658298 -221.215883) (xy 121.649225 -221.161495)
			(xy 121.648728 -221.133924) (xy 121.649236 -221.108037) (xy 121.657335 -221.056899) (xy 121.673334 -221.007659)
			(xy 121.69684 -220.961527) (xy 121.727272 -220.91964) (xy 121.763882 -220.88303) (xy 121.805769 -220.852598)
			(xy 121.851901 -220.829092) (xy 121.901141 -220.813093) (xy 121.952279 -220.804994) (xy 122.004053 -220.804994)
			(xy 122.055191 -220.813093) (xy 122.104431 -220.829092) (xy 122.150563 -220.852598) (xy 122.19245 -220.88303)
			(xy 122.22906 -220.91964) (xy 122.259492 -220.961527) (xy 122.282998 -221.007659) (xy 122.298997 -221.056899)
			(xy 122.307096 -221.108037) (xy 122.307604 -221.133924) (xy 122.307148 -221.159299) (xy 122.299376 -221.20945)
			(xy 122.284004 -221.257815) (xy 122.261397 -221.303251) (xy 122.232089 -221.344682) (xy 122.196773 -221.381128)
			(xy 122.156285 -221.411727) (xy 122.111584 -221.435754) (xy 122.063726 -221.452641) (xy 122.038872 -221.457774)
			(xy 122.016012 -221.462092) (xy 121.811288 -221.81693) (xy 121.819162 -221.838774) (xy 121.827819 -221.865179)
			(xy 121.837132 -221.919958) (xy 121.837704 -221.94774) (xy 123.05792 -221.94774) (xy 123.058371 -221.922394)
			(xy 123.066152 -221.872302) (xy 123.081506 -221.82399) (xy 123.104072 -221.778597) (xy 123.133318 -221.737192)
			(xy 123.168555 -221.700749) (xy 123.208954 -221.670127) (xy 123.253562 -221.646047) (xy 123.30133 -221.629076)
			(xy 123.326144 -221.62389) (xy 123.349004 -221.619572) (xy 123.554236 -221.264226) (xy 123.546362 -221.242128)
			(xy 123.537898 -221.215883) (xy 123.528825 -221.161495) (xy 123.528328 -221.133924) (xy 123.528836 -221.108037)
			(xy 123.536935 -221.056899) (xy 123.552934 -221.007659) (xy 123.57644 -220.961527) (xy 123.606872 -220.91964)
			(xy 123.643482 -220.88303) (xy 123.685369 -220.852598) (xy 123.731501 -220.829092) (xy 123.780741 -220.813093)
			(xy 123.831879 -220.804994) (xy 123.883653 -220.804994) (xy 123.934791 -220.813093) (xy 123.984031 -220.829092)
			(xy 124.030163 -220.852598) (xy 124.07205 -220.88303) (xy 124.10866 -220.91964) (xy 124.139092 -220.961527)
			(xy 124.162598 -221.007659) (xy 124.178597 -221.056899) (xy 124.186696 -221.108037) (xy 124.187204 -221.133924)
			(xy 124.186748 -221.159299) (xy 124.178976 -221.20945) (xy 124.163604 -221.257815) (xy 124.140997 -221.303251)
			(xy 124.111689 -221.344682) (xy 124.076373 -221.381128) (xy 124.035885 -221.411727) (xy 123.991184 -221.435754)
			(xy 123.943326 -221.452641) (xy 123.918472 -221.457774) (xy 123.895612 -221.462092) (xy 123.690888 -221.81693)
			(xy 123.698762 -221.838774) (xy 123.707419 -221.865179) (xy 123.716732 -221.919958) (xy 123.717304 -221.94774)
			(xy 124.93752 -221.94774) (xy 124.937971 -221.922394) (xy 124.945752 -221.872302) (xy 124.961106 -221.82399)
			(xy 124.983672 -221.778597) (xy 125.012918 -221.737192) (xy 125.048155 -221.700749) (xy 125.088554 -221.670127)
			(xy 125.133162 -221.646047) (xy 125.18093 -221.629076) (xy 125.205744 -221.62389) (xy 125.228604 -221.619572)
			(xy 125.433836 -221.264226) (xy 125.425962 -221.242128) (xy 125.417498 -221.215883) (xy 125.408425 -221.161495)
			(xy 125.407928 -221.133924) (xy 125.408436 -221.108037) (xy 125.416535 -221.056899) (xy 125.432534 -221.007659)
			(xy 125.45604 -220.961527) (xy 125.486472 -220.91964) (xy 125.523082 -220.88303) (xy 125.564969 -220.852598)
			(xy 125.611101 -220.829092) (xy 125.660341 -220.813093) (xy 125.711479 -220.804994) (xy 125.763253 -220.804994)
			(xy 125.814391 -220.813093) (xy 125.863631 -220.829092) (xy 125.909763 -220.852598) (xy 125.95165 -220.88303)
			(xy 125.98826 -220.91964) (xy 126.018692 -220.961527) (xy 126.042198 -221.007659) (xy 126.058197 -221.056899)
			(xy 126.066296 -221.108037) (xy 126.066804 -221.133924) (xy 126.066348 -221.159299) (xy 126.058576 -221.20945)
			(xy 126.043204 -221.257815) (xy 126.020597 -221.303251) (xy 125.991289 -221.344682) (xy 125.955973 -221.381128)
			(xy 125.915485 -221.411727) (xy 125.870784 -221.435754) (xy 125.822926 -221.452641) (xy 125.798072 -221.457774)
			(xy 125.775212 -221.462092) (xy 125.570488 -221.81693) (xy 125.578362 -221.838774) (xy 125.587019 -221.865179)
			(xy 125.596332 -221.919958) (xy 125.596904 -221.94774) (xy 126.81712 -221.94774) (xy 126.817571 -221.922394)
			(xy 126.825352 -221.872302) (xy 126.840706 -221.82399) (xy 126.863272 -221.778597) (xy 126.892518 -221.737192)
			(xy 126.927755 -221.700749) (xy 126.968154 -221.670127) (xy 127.012762 -221.646047) (xy 127.06053 -221.629076)
			(xy 127.085344 -221.62389) (xy 127.108204 -221.619572) (xy 127.313436 -221.264226) (xy 127.305562 -221.242128)
			(xy 127.297098 -221.215883) (xy 127.288025 -221.161495) (xy 127.287528 -221.133924) (xy 127.288036 -221.108037)
			(xy 127.296135 -221.056899) (xy 127.312134 -221.007659) (xy 127.33564 -220.961527) (xy 127.366072 -220.91964)
			(xy 127.402682 -220.88303) (xy 127.444569 -220.852598) (xy 127.490701 -220.829092) (xy 127.539941 -220.813093)
			(xy 127.591079 -220.804994) (xy 127.642853 -220.804994) (xy 127.693991 -220.813093) (xy 127.743231 -220.829092)
			(xy 127.789363 -220.852598) (xy 127.83125 -220.88303) (xy 127.86786 -220.91964) (xy 127.898292 -220.961527)
			(xy 127.921798 -221.007659) (xy 127.937797 -221.056899) (xy 127.945896 -221.108037) (xy 127.946404 -221.133924)
			(xy 127.945948 -221.159299) (xy 127.938176 -221.20945) (xy 127.922804 -221.257815) (xy 127.900197 -221.303251)
			(xy 127.870889 -221.344682) (xy 127.835573 -221.381128) (xy 127.795085 -221.411727) (xy 127.750384 -221.435754)
			(xy 127.702526 -221.452641) (xy 127.677672 -221.457774) (xy 127.654812 -221.462092) (xy 127.450088 -221.81693)
			(xy 127.457962 -221.838774) (xy 127.466619 -221.865179) (xy 127.475932 -221.919958) (xy 127.476504 -221.94774)
			(xy 128.69672 -221.94774) (xy 128.697171 -221.922394) (xy 128.704952 -221.872302) (xy 128.720306 -221.82399)
			(xy 128.742872 -221.778597) (xy 128.772118 -221.737192) (xy 128.807355 -221.700749) (xy 128.847754 -221.670127)
			(xy 128.892362 -221.646047) (xy 128.94013 -221.629076) (xy 128.964944 -221.62389) (xy 128.987804 -221.619572)
			(xy 129.193036 -221.264226) (xy 129.185162 -221.242128) (xy 129.176698 -221.215883) (xy 129.167625 -221.161495)
			(xy 129.167128 -221.133924) (xy 129.167636 -221.108037) (xy 129.175735 -221.056899) (xy 129.191734 -221.007659)
			(xy 129.21524 -220.961527) (xy 129.245672 -220.91964) (xy 129.282282 -220.88303) (xy 129.324169 -220.852598)
			(xy 129.370301 -220.829092) (xy 129.419541 -220.813093) (xy 129.470679 -220.804994) (xy 129.522453 -220.804994)
			(xy 129.573591 -220.813093) (xy 129.622831 -220.829092) (xy 129.668963 -220.852598) (xy 129.71085 -220.88303)
			(xy 129.74746 -220.91964) (xy 129.777892 -220.961527) (xy 129.801398 -221.007659) (xy 129.817397 -221.056899)
			(xy 129.825496 -221.108037) (xy 129.826004 -221.133924) (xy 129.825548 -221.159299) (xy 129.817776 -221.20945)
			(xy 129.802404 -221.257815) (xy 129.779797 -221.303251) (xy 129.750489 -221.344682) (xy 129.715173 -221.381128)
			(xy 129.674685 -221.411727) (xy 129.629984 -221.435754) (xy 129.582126 -221.452641) (xy 129.557272 -221.457774)
			(xy 129.534412 -221.462092) (xy 129.329688 -221.81693) (xy 129.337562 -221.838774) (xy 129.346219 -221.865179)
			(xy 129.355532 -221.919958) (xy 129.356104 -221.94774) (xy 130.57632 -221.94774) (xy 130.576771 -221.922394)
			(xy 130.584552 -221.872302) (xy 130.599906 -221.82399) (xy 130.622472 -221.778597) (xy 130.651718 -221.737192)
			(xy 130.686955 -221.700749) (xy 130.727354 -221.670127) (xy 130.771962 -221.646047) (xy 130.81973 -221.629076)
			(xy 130.844544 -221.62389) (xy 130.867404 -221.619572) (xy 131.072636 -221.264226) (xy 131.064762 -221.242128)
			(xy 131.056298 -221.215883) (xy 131.047225 -221.161495) (xy 131.046728 -221.133924) (xy 131.047236 -221.108037)
			(xy 131.055335 -221.056899) (xy 131.071334 -221.007659) (xy 131.09484 -220.961527) (xy 131.125272 -220.91964)
			(xy 131.161882 -220.88303) (xy 131.203769 -220.852598) (xy 131.249901 -220.829092) (xy 131.299141 -220.813093)
			(xy 131.350279 -220.804994) (xy 131.402053 -220.804994) (xy 131.453191 -220.813093) (xy 131.502431 -220.829092)
			(xy 131.548563 -220.852598) (xy 131.59045 -220.88303) (xy 131.62706 -220.91964) (xy 131.657492 -220.961527)
			(xy 131.680998 -221.007659) (xy 131.696997 -221.056899) (xy 131.705096 -221.108037) (xy 131.705604 -221.133924)
			(xy 131.705148 -221.159299) (xy 131.697376 -221.20945) (xy 131.682004 -221.257815) (xy 131.659397 -221.303251)
			(xy 131.630089 -221.344682) (xy 131.594773 -221.381128) (xy 131.554285 -221.411727) (xy 131.509584 -221.435754)
			(xy 131.461726 -221.452641) (xy 131.436872 -221.457774) (xy 131.414012 -221.462092) (xy 131.209288 -221.81693)
			(xy 131.217162 -221.838774) (xy 131.225819 -221.865179) (xy 131.235132 -221.919958) (xy 131.235704 -221.94774)
			(xy 132.45592 -221.94774) (xy 132.456371 -221.922394) (xy 132.464152 -221.872302) (xy 132.479506 -221.82399)
			(xy 132.502072 -221.778597) (xy 132.531318 -221.737192) (xy 132.566555 -221.700749) (xy 132.606954 -221.670127)
			(xy 132.651562 -221.646047) (xy 132.69933 -221.629076) (xy 132.724144 -221.62389) (xy 132.747004 -221.619572)
			(xy 132.951982 -221.263972) (xy 132.944362 -221.242128) (xy 132.935911 -221.215946) (xy 132.92684 -221.161685)
			(xy 132.926328 -221.134178) (xy 132.926328 -221.133924) (xy 132.926836 -221.108037) (xy 132.934935 -221.056899)
			(xy 132.950934 -221.007659) (xy 132.97444 -220.961527) (xy 133.004872 -220.91964) (xy 133.041482 -220.88303)
			(xy 133.083369 -220.852598) (xy 133.129501 -220.829092) (xy 133.178741 -220.813093) (xy 133.229879 -220.804994)
			(xy 133.281653 -220.804994) (xy 133.332791 -220.813093) (xy 133.382031 -220.829092) (xy 133.428163 -220.852598)
			(xy 133.47005 -220.88303) (xy 133.50666 -220.91964) (xy 133.537092 -220.961527) (xy 133.560598 -221.007659)
			(xy 133.576597 -221.056899) (xy 133.584696 -221.108037) (xy 133.585204 -221.133924) (xy 133.584785 -221.15929)
			(xy 133.577033 -221.209425) (xy 133.561684 -221.257778) (xy 133.539102 -221.303206) (xy 133.509821 -221.344633)
			(xy 133.474533 -221.381081) (xy 133.434074 -221.411686) (xy 133.3894 -221.435725) (xy 133.341569 -221.45263)
			(xy 133.316726 -221.457774) (xy 133.293866 -221.462092) (xy 133.089142 -221.81693) (xy 133.096762 -221.838774)
			(xy 133.105377 -221.865059) (xy 133.114698 -221.919578) (xy 133.115304 -221.947232) (xy 133.115304 -221.94774)
			(xy 134.33552 -221.94774) (xy 134.335971 -221.922394) (xy 134.343752 -221.872302) (xy 134.359106 -221.82399)
			(xy 134.381672 -221.778597) (xy 134.410918 -221.737192) (xy 134.446155 -221.700749) (xy 134.486554 -221.670127)
			(xy 134.531162 -221.646047) (xy 134.57893 -221.629076) (xy 134.603744 -221.62389) (xy 134.626604 -221.619572)
			(xy 134.831582 -221.263972) (xy 134.823962 -221.242128) (xy 134.815511 -221.215946) (xy 134.80644 -221.161685)
			(xy 134.805928 -221.134178) (xy 134.805928 -221.133924) (xy 134.806436 -221.108037) (xy 134.814535 -221.056899)
			(xy 134.830534 -221.007659) (xy 134.85404 -220.961527) (xy 134.884472 -220.91964) (xy 134.921082 -220.88303)
			(xy 134.962969 -220.852598) (xy 135.009101 -220.829092) (xy 135.058341 -220.813093) (xy 135.109479 -220.804994)
			(xy 135.161253 -220.804994) (xy 135.212391 -220.813093) (xy 135.261631 -220.829092) (xy 135.307763 -220.852598)
			(xy 135.34965 -220.88303) (xy 135.38626 -220.91964) (xy 135.416692 -220.961527) (xy 135.440198 -221.007659)
			(xy 135.456197 -221.056899) (xy 135.464296 -221.108037) (xy 135.464804 -221.133924) (xy 336.695796 -221.133924)
			(xy 336.696304 -221.108037) (xy 336.704403 -221.056899) (xy 336.720402 -221.007659) (xy 336.743908 -220.961527)
			(xy 336.77434 -220.91964) (xy 336.81095 -220.88303) (xy 336.852837 -220.852598) (xy 336.898969 -220.829092)
			(xy 336.948209 -220.813093) (xy 336.999347 -220.804994) (xy 337.051121 -220.804994) (xy 337.102259 -220.813093)
			(xy 337.151499 -220.829092) (xy 337.197631 -220.852598) (xy 337.239518 -220.88303) (xy 337.276128 -220.91964)
			(xy 337.30656 -220.961527) (xy 337.330066 -221.007659) (xy 337.346065 -221.056899) (xy 337.354164 -221.108037)
			(xy 337.354672 -221.133924) (xy 337.635596 -221.133924) (xy 337.636104 -221.10859) (xy 337.643853 -221.058519)
			(xy 337.659172 -221.010223) (xy 337.6817 -220.96484) (xy 337.710906 -220.923438) (xy 337.746104 -220.886992)
			(xy 337.786463 -220.856361) (xy 337.831034 -220.832266) (xy 337.878767 -220.815274) (xy 337.903566 -220.810074)
			(xy 337.926426 -220.805756) (xy 338.131404 -220.450664) (xy 338.12353 -220.42882) (xy 338.114896 -220.402408)
			(xy 338.105568 -220.347635) (xy 338.104988 -220.319854) (xy 338.105496 -220.293947) (xy 338.113602 -220.24277)
			(xy 338.129614 -220.193491) (xy 338.153137 -220.147324) (xy 338.183593 -220.105405) (xy 338.220231 -220.068767)
			(xy 338.26215 -220.038311) (xy 338.308317 -220.014788) (xy 338.357596 -219.998776) (xy 338.408773 -219.99067)
			(xy 338.460587 -219.99067) (xy 338.511764 -219.998776) (xy 338.561043 -220.014788) (xy 338.60721 -220.038311)
			(xy 338.649129 -220.068767) (xy 338.685767 -220.105405) (xy 338.716223 -220.147324) (xy 338.739746 -220.193491)
			(xy 338.755758 -220.24277) (xy 338.763864 -220.293947) (xy 338.764372 -220.319854) (xy 338.763922 -220.3452)
			(xy 338.756142 -220.395293) (xy 338.740788 -220.443604) (xy 338.718222 -220.488998) (xy 338.688976 -220.530404)
			(xy 338.653739 -220.566847) (xy 338.61334 -220.597469) (xy 338.568731 -220.621548) (xy 338.520963 -220.638518)
			(xy 338.496148 -220.643704) (xy 338.473288 -220.648022) (xy 338.26831 -221.003114) (xy 338.276184 -221.024958)
			(xy 338.284777 -221.051373) (xy 338.293965 -221.106151) (xy 338.294472 -221.133924) (xy 338.575396 -221.133924)
			(xy 338.575904 -221.108037) (xy 338.584003 -221.056899) (xy 338.600002 -221.007659) (xy 338.623508 -220.961527)
			(xy 338.65394 -220.91964) (xy 338.69055 -220.88303) (xy 338.732437 -220.852598) (xy 338.778569 -220.829092)
			(xy 338.827809 -220.813093) (xy 338.878947 -220.804994) (xy 338.930721 -220.804994) (xy 338.981859 -220.813093)
			(xy 339.031099 -220.829092) (xy 339.077231 -220.852598) (xy 339.119118 -220.88303) (xy 339.155728 -220.91964)
			(xy 339.18616 -220.961527) (xy 339.209666 -221.007659) (xy 339.225665 -221.056899) (xy 339.233764 -221.108037)
			(xy 339.234272 -221.133924) (xy 339.515196 -221.133924) (xy 339.515704 -221.10859) (xy 339.523453 -221.058519)
			(xy 339.538772 -221.010223) (xy 339.5613 -220.96484) (xy 339.590506 -220.923438) (xy 339.625704 -220.886992)
			(xy 339.666063 -220.856361) (xy 339.710634 -220.832266) (xy 339.758367 -220.815274) (xy 339.783166 -220.810074)
			(xy 339.806026 -220.805756) (xy 340.011004 -220.450664) (xy 340.00313 -220.42882) (xy 339.994496 -220.402408)
			(xy 339.985168 -220.347635) (xy 339.984588 -220.319854) (xy 339.985096 -220.293947) (xy 339.993202 -220.24277)
			(xy 340.009214 -220.193491) (xy 340.032737 -220.147324) (xy 340.063193 -220.105405) (xy 340.099831 -220.068767)
			(xy 340.14175 -220.038311) (xy 340.187917 -220.014788) (xy 340.237196 -219.998776) (xy 340.288373 -219.99067)
			(xy 340.340187 -219.99067) (xy 340.391364 -219.998776) (xy 340.440643 -220.014788) (xy 340.48681 -220.038311)
			(xy 340.528729 -220.068767) (xy 340.565367 -220.105405) (xy 340.595823 -220.147324) (xy 340.619346 -220.193491)
			(xy 340.635358 -220.24277) (xy 340.643464 -220.293947) (xy 340.643972 -220.319854) (xy 340.643522 -220.3452)
			(xy 340.635742 -220.395293) (xy 340.620388 -220.443604) (xy 340.597822 -220.488998) (xy 340.568576 -220.530404)
			(xy 340.533339 -220.566847) (xy 340.49294 -220.597469) (xy 340.448331 -220.621548) (xy 340.400563 -220.638518)
			(xy 340.375748 -220.643704) (xy 340.352888 -220.648022) (xy 340.14791 -221.003114) (xy 340.155784 -221.024958)
			(xy 340.164377 -221.051373) (xy 340.173565 -221.106151) (xy 340.174072 -221.133924) (xy 340.454996 -221.133924)
			(xy 340.455504 -221.108037) (xy 340.463603 -221.056899) (xy 340.479602 -221.007659) (xy 340.503108 -220.961527)
			(xy 340.53354 -220.91964) (xy 340.57015 -220.88303) (xy 340.612037 -220.852598) (xy 340.658169 -220.829092)
			(xy 340.707409 -220.813093) (xy 340.758547 -220.804994) (xy 340.810321 -220.804994) (xy 340.861459 -220.813093)
			(xy 340.910699 -220.829092) (xy 340.956831 -220.852598) (xy 340.998718 -220.88303) (xy 341.035328 -220.91964)
			(xy 341.06576 -220.961527) (xy 341.089266 -221.007659) (xy 341.105265 -221.056899) (xy 341.113364 -221.108037)
			(xy 341.113872 -221.133924) (xy 341.394796 -221.133924) (xy 341.395304 -221.10859) (xy 341.403053 -221.058519)
			(xy 341.418372 -221.010223) (xy 341.4409 -220.96484) (xy 341.470106 -220.923438) (xy 341.505304 -220.886992)
			(xy 341.545663 -220.856361) (xy 341.590234 -220.832266) (xy 341.637967 -220.815274) (xy 341.662766 -220.810074)
			(xy 341.685626 -220.805756) (xy 341.890604 -220.450664) (xy 341.88273 -220.42882) (xy 341.874096 -220.402408)
			(xy 341.864768 -220.347635) (xy 341.864188 -220.319854) (xy 341.864696 -220.293947) (xy 341.872802 -220.24277)
			(xy 341.888814 -220.193491) (xy 341.912337 -220.147324) (xy 341.942793 -220.105405) (xy 341.979431 -220.068767)
			(xy 342.02135 -220.038311) (xy 342.067517 -220.014788) (xy 342.116796 -219.998776) (xy 342.167973 -219.99067)
			(xy 342.219787 -219.99067) (xy 342.270964 -219.998776) (xy 342.320243 -220.014788) (xy 342.36641 -220.038311)
			(xy 342.408329 -220.068767) (xy 342.444967 -220.105405) (xy 342.475423 -220.147324) (xy 342.498946 -220.193491)
			(xy 342.514958 -220.24277) (xy 342.523064 -220.293947) (xy 342.523572 -220.319854) (xy 342.523122 -220.3452)
			(xy 342.515342 -220.395293) (xy 342.499988 -220.443604) (xy 342.477422 -220.488998) (xy 342.448176 -220.530404)
			(xy 342.412939 -220.566847) (xy 342.37254 -220.597469) (xy 342.327931 -220.621548) (xy 342.280163 -220.638518)
			(xy 342.255348 -220.643704) (xy 342.232488 -220.648022) (xy 342.02751 -221.003114) (xy 342.035384 -221.024958)
			(xy 342.043977 -221.051373) (xy 342.053165 -221.106151) (xy 342.053672 -221.133924) (xy 342.334596 -221.133924)
			(xy 342.335104 -221.108037) (xy 342.343203 -221.056899) (xy 342.359202 -221.007659) (xy 342.382708 -220.961527)
			(xy 342.41314 -220.91964) (xy 342.44975 -220.88303) (xy 342.491637 -220.852598) (xy 342.537769 -220.829092)
			(xy 342.587009 -220.813093) (xy 342.638147 -220.804994) (xy 342.689921 -220.804994) (xy 342.741059 -220.813093)
			(xy 342.790299 -220.829092) (xy 342.836431 -220.852598) (xy 342.878318 -220.88303) (xy 342.914928 -220.91964)
			(xy 342.94536 -220.961527) (xy 342.968866 -221.007659) (xy 342.984865 -221.056899) (xy 342.992964 -221.108037)
			(xy 342.993472 -221.133924) (xy 343.274396 -221.133924) (xy 343.274904 -221.10859) (xy 343.282653 -221.058519)
			(xy 343.297972 -221.010223) (xy 343.3205 -220.96484) (xy 343.349706 -220.923438) (xy 343.384904 -220.886992)
			(xy 343.425263 -220.856361) (xy 343.469834 -220.832266) (xy 343.517567 -220.815274) (xy 343.542366 -220.810074)
			(xy 343.565226 -220.805756) (xy 343.770204 -220.450664) (xy 343.76233 -220.42882) (xy 343.753696 -220.402408)
			(xy 343.744368 -220.347635) (xy 343.743788 -220.319854) (xy 343.744296 -220.293947) (xy 343.752402 -220.24277)
			(xy 343.768414 -220.193491) (xy 343.791937 -220.147324) (xy 343.822393 -220.105405) (xy 343.859031 -220.068767)
			(xy 343.90095 -220.038311) (xy 343.947117 -220.014788) (xy 343.996396 -219.998776) (xy 344.047573 -219.99067)
			(xy 344.099387 -219.99067) (xy 344.150564 -219.998776) (xy 344.199843 -220.014788) (xy 344.24601 -220.038311)
			(xy 344.287929 -220.068767) (xy 344.324567 -220.105405) (xy 344.355023 -220.147324) (xy 344.378546 -220.193491)
			(xy 344.394558 -220.24277) (xy 344.402664 -220.293947) (xy 344.403172 -220.319854) (xy 344.402722 -220.3452)
			(xy 344.394942 -220.395293) (xy 344.379588 -220.443604) (xy 344.357022 -220.488998) (xy 344.327776 -220.530404)
			(xy 344.292539 -220.566847) (xy 344.25214 -220.597469) (xy 344.207531 -220.621548) (xy 344.159763 -220.638518)
			(xy 344.134948 -220.643704) (xy 344.112088 -220.648022) (xy 343.90711 -221.003114) (xy 343.914984 -221.024958)
			(xy 343.923577 -221.051373) (xy 343.932765 -221.106151) (xy 343.933272 -221.133924) (xy 344.214196 -221.133924)
			(xy 344.214704 -221.108037) (xy 344.222803 -221.056899) (xy 344.238802 -221.007659) (xy 344.262308 -220.961527)
			(xy 344.29274 -220.91964) (xy 344.32935 -220.88303) (xy 344.371237 -220.852598) (xy 344.417369 -220.829092)
			(xy 344.466609 -220.813093) (xy 344.517747 -220.804994) (xy 344.569521 -220.804994) (xy 344.620659 -220.813093)
			(xy 344.669899 -220.829092) (xy 344.716031 -220.852598) (xy 344.757918 -220.88303) (xy 344.794528 -220.91964)
			(xy 344.82496 -220.961527) (xy 344.848466 -221.007659) (xy 344.864465 -221.056899) (xy 344.872564 -221.108037)
			(xy 344.873072 -221.133924) (xy 345.153996 -221.133924) (xy 345.154504 -221.10859) (xy 345.162253 -221.058519)
			(xy 345.177572 -221.010223) (xy 345.2001 -220.96484) (xy 345.229306 -220.923438) (xy 345.264504 -220.886992)
			(xy 345.304863 -220.856361) (xy 345.349434 -220.832266) (xy 345.397167 -220.815274) (xy 345.421966 -220.810074)
			(xy 345.444826 -220.805756) (xy 345.649804 -220.450664) (xy 345.64193 -220.42882) (xy 345.633296 -220.402408)
			(xy 345.623968 -220.347635) (xy 345.623388 -220.319854) (xy 345.623896 -220.293947) (xy 345.632002 -220.24277)
			(xy 345.648014 -220.193491) (xy 345.671537 -220.147324) (xy 345.701993 -220.105405) (xy 345.738631 -220.068767)
			(xy 345.78055 -220.038311) (xy 345.826717 -220.014788) (xy 345.875996 -219.998776) (xy 345.927173 -219.99067)
			(xy 345.978987 -219.99067) (xy 346.030164 -219.998776) (xy 346.079443 -220.014788) (xy 346.12561 -220.038311)
			(xy 346.167529 -220.068767) (xy 346.204167 -220.105405) (xy 346.234623 -220.147324) (xy 346.258146 -220.193491)
			(xy 346.274158 -220.24277) (xy 346.282264 -220.293947) (xy 346.282772 -220.319854) (xy 346.282322 -220.3452)
			(xy 346.274542 -220.395293) (xy 346.259188 -220.443604) (xy 346.236622 -220.488998) (xy 346.207376 -220.530404)
			(xy 346.172139 -220.566847) (xy 346.13174 -220.597469) (xy 346.087131 -220.621548) (xy 346.039363 -220.638518)
			(xy 346.014548 -220.643704) (xy 345.991688 -220.648022) (xy 345.78671 -221.003114) (xy 345.794584 -221.024958)
			(xy 345.803177 -221.051373) (xy 345.812365 -221.106151) (xy 345.812872 -221.133924) (xy 346.093796 -221.133924)
			(xy 346.094304 -221.108037) (xy 346.102403 -221.056899) (xy 346.118402 -221.007659) (xy 346.141908 -220.961527)
			(xy 346.17234 -220.91964) (xy 346.20895 -220.88303) (xy 346.250837 -220.852598) (xy 346.296969 -220.829092)
			(xy 346.346209 -220.813093) (xy 346.397347 -220.804994) (xy 346.449121 -220.804994) (xy 346.500259 -220.813093)
			(xy 346.549499 -220.829092) (xy 346.595631 -220.852598) (xy 346.637518 -220.88303) (xy 346.674128 -220.91964)
			(xy 346.70456 -220.961527) (xy 346.728066 -221.007659) (xy 346.744065 -221.056899) (xy 346.752164 -221.108037)
			(xy 346.752672 -221.133924) (xy 347.033596 -221.133924) (xy 347.034104 -221.10859) (xy 347.041853 -221.058519)
			(xy 347.057172 -221.010223) (xy 347.0797 -220.96484) (xy 347.108906 -220.923438) (xy 347.144104 -220.886992)
			(xy 347.184463 -220.856361) (xy 347.229034 -220.832266) (xy 347.276767 -220.815274) (xy 347.301566 -220.810074)
			(xy 347.324426 -220.805756) (xy 347.529404 -220.450664) (xy 347.52153 -220.42882) (xy 347.512896 -220.402408)
			(xy 347.503568 -220.347635) (xy 347.502988 -220.319854) (xy 347.503496 -220.293947) (xy 347.511602 -220.24277)
			(xy 347.527614 -220.193491) (xy 347.551137 -220.147324) (xy 347.581593 -220.105405) (xy 347.618231 -220.068767)
			(xy 347.66015 -220.038311) (xy 347.706317 -220.014788) (xy 347.755596 -219.998776) (xy 347.806773 -219.99067)
			(xy 347.858587 -219.99067) (xy 347.909764 -219.998776) (xy 347.959043 -220.014788) (xy 348.00521 -220.038311)
			(xy 348.047129 -220.068767) (xy 348.083767 -220.105405) (xy 348.114223 -220.147324) (xy 348.137746 -220.193491)
			(xy 348.153758 -220.24277) (xy 348.161864 -220.293947) (xy 348.162372 -220.319854) (xy 348.161922 -220.3452)
			(xy 348.154142 -220.395293) (xy 348.138788 -220.443604) (xy 348.116222 -220.488998) (xy 348.086976 -220.530404)
			(xy 348.051739 -220.566847) (xy 348.01134 -220.597469) (xy 347.966731 -220.621548) (xy 347.918963 -220.638518)
			(xy 347.894148 -220.643704) (xy 347.871288 -220.648022) (xy 347.66631 -221.003114) (xy 347.674184 -221.024958)
			(xy 347.682777 -221.051373) (xy 347.691965 -221.106151) (xy 347.692472 -221.133924) (xy 347.973396 -221.133924)
			(xy 347.973904 -221.108037) (xy 347.982003 -221.056899) (xy 347.998002 -221.007659) (xy 348.021508 -220.961527)
			(xy 348.05194 -220.91964) (xy 348.08855 -220.88303) (xy 348.130437 -220.852598) (xy 348.176569 -220.829092)
			(xy 348.225809 -220.813093) (xy 348.276947 -220.804994) (xy 348.328721 -220.804994) (xy 348.379859 -220.813093)
			(xy 348.429099 -220.829092) (xy 348.475231 -220.852598) (xy 348.517118 -220.88303) (xy 348.553728 -220.91964)
			(xy 348.58416 -220.961527) (xy 348.607666 -221.007659) (xy 348.623665 -221.056899) (xy 348.631764 -221.108037)
			(xy 348.632272 -221.133924) (xy 348.913196 -221.133924) (xy 348.913704 -221.10859) (xy 348.921453 -221.058519)
			(xy 348.936772 -221.010223) (xy 348.9593 -220.96484) (xy 348.988506 -220.923438) (xy 349.023704 -220.886992)
			(xy 349.064063 -220.856361) (xy 349.108634 -220.832266) (xy 349.156367 -220.815274) (xy 349.181166 -220.810074)
			(xy 349.204026 -220.805756) (xy 349.409004 -220.450664) (xy 349.40113 -220.42882) (xy 349.392496 -220.402408)
			(xy 349.383168 -220.347635) (xy 349.382588 -220.319854) (xy 349.383096 -220.293947) (xy 349.391202 -220.24277)
			(xy 349.407214 -220.193491) (xy 349.430737 -220.147324) (xy 349.461193 -220.105405) (xy 349.497831 -220.068767)
			(xy 349.53975 -220.038311) (xy 349.585917 -220.014788) (xy 349.635196 -219.998776) (xy 349.686373 -219.99067)
			(xy 349.738187 -219.99067) (xy 349.789364 -219.998776) (xy 349.838643 -220.014788) (xy 349.88481 -220.038311)
			(xy 349.926729 -220.068767) (xy 349.963367 -220.105405) (xy 349.993823 -220.147324) (xy 350.017346 -220.193491)
			(xy 350.033358 -220.24277) (xy 350.041464 -220.293947) (xy 350.041972 -220.319854) (xy 350.041522 -220.3452)
			(xy 350.033742 -220.395293) (xy 350.018388 -220.443604) (xy 349.995822 -220.488998) (xy 349.966576 -220.530404)
			(xy 349.931339 -220.566847) (xy 349.89094 -220.597469) (xy 349.846331 -220.621548) (xy 349.798563 -220.638518)
			(xy 349.773748 -220.643704) (xy 349.750888 -220.648022) (xy 349.54591 -221.003114) (xy 349.553784 -221.024958)
			(xy 349.562377 -221.051373) (xy 349.571565 -221.106151) (xy 349.572072 -221.133924) (xy 349.852996 -221.133924)
			(xy 349.853504 -221.108037) (xy 349.861603 -221.056899) (xy 349.877602 -221.007659) (xy 349.901108 -220.961527)
			(xy 349.93154 -220.91964) (xy 349.96815 -220.88303) (xy 350.010037 -220.852598) (xy 350.056169 -220.829092)
			(xy 350.105409 -220.813093) (xy 350.156547 -220.804994) (xy 350.208321 -220.804994) (xy 350.259459 -220.813093)
			(xy 350.308699 -220.829092) (xy 350.354831 -220.852598) (xy 350.396718 -220.88303) (xy 350.433328 -220.91964)
			(xy 350.46376 -220.961527) (xy 350.487266 -221.007659) (xy 350.503265 -221.056899) (xy 350.511364 -221.108037)
			(xy 350.511872 -221.133924) (xy 350.792796 -221.133924) (xy 350.793304 -221.10859) (xy 350.801053 -221.058519)
			(xy 350.816372 -221.010223) (xy 350.8389 -220.96484) (xy 350.868106 -220.923438) (xy 350.903304 -220.886992)
			(xy 350.943663 -220.856361) (xy 350.988234 -220.832266) (xy 351.035967 -220.815274) (xy 351.060766 -220.810074)
			(xy 351.083626 -220.805756) (xy 351.288604 -220.450664) (xy 351.28073 -220.42882) (xy 351.272096 -220.402408)
			(xy 351.262768 -220.347635) (xy 351.262188 -220.319854) (xy 351.262696 -220.293947) (xy 351.270802 -220.24277)
			(xy 351.286814 -220.193491) (xy 351.310337 -220.147324) (xy 351.340793 -220.105405) (xy 351.377431 -220.068767)
			(xy 351.41935 -220.038311) (xy 351.465517 -220.014788) (xy 351.514796 -219.998776) (xy 351.565973 -219.99067)
			(xy 351.617787 -219.99067) (xy 351.668964 -219.998776) (xy 351.718243 -220.014788) (xy 351.76441 -220.038311)
			(xy 351.806329 -220.068767) (xy 351.842967 -220.105405) (xy 351.873423 -220.147324) (xy 351.896946 -220.193491)
			(xy 351.912958 -220.24277) (xy 351.921064 -220.293947) (xy 351.921572 -220.319854) (xy 353.141788 -220.319854)
			(xy 353.142296 -220.293947) (xy 353.150402 -220.24277) (xy 353.166414 -220.193491) (xy 353.189937 -220.147324)
			(xy 353.220393 -220.105405) (xy 353.257031 -220.068767) (xy 353.29895 -220.038311) (xy 353.345117 -220.014788)
			(xy 353.394396 -219.998776) (xy 353.445573 -219.99067) (xy 353.497387 -219.99067) (xy 353.548564 -219.998776)
			(xy 353.597843 -220.014788) (xy 353.64401 -220.038311) (xy 353.685929 -220.068767) (xy 353.722567 -220.105405)
			(xy 353.753023 -220.147324) (xy 353.776546 -220.193491) (xy 353.792558 -220.24277) (xy 353.800664 -220.293947)
			(xy 353.801172 -220.319854) (xy 355.021388 -220.319854) (xy 355.021896 -220.293947) (xy 355.030002 -220.24277)
			(xy 355.046014 -220.193491) (xy 355.069537 -220.147324) (xy 355.099993 -220.105405) (xy 355.136631 -220.068767)
			(xy 355.17855 -220.038311) (xy 355.224717 -220.014788) (xy 355.273996 -219.998776) (xy 355.325173 -219.99067)
			(xy 355.376987 -219.99067) (xy 355.428164 -219.998776) (xy 355.477443 -220.014788) (xy 355.52361 -220.038311)
			(xy 355.565529 -220.068767) (xy 355.602167 -220.105405) (xy 355.632623 -220.147324) (xy 355.656146 -220.193491)
			(xy 355.672158 -220.24277) (xy 355.680264 -220.293947) (xy 355.680772 -220.319854) (xy 356.900988 -220.319854)
			(xy 356.901496 -220.293947) (xy 356.909602 -220.24277) (xy 356.925614 -220.193491) (xy 356.949137 -220.147324)
			(xy 356.979593 -220.105405) (xy 357.016231 -220.068767) (xy 357.05815 -220.038311) (xy 357.104317 -220.014788)
			(xy 357.153596 -219.998776) (xy 357.204773 -219.99067) (xy 357.256587 -219.99067) (xy 357.307764 -219.998776)
			(xy 357.357043 -220.014788) (xy 357.40321 -220.038311) (xy 357.445129 -220.068767) (xy 357.481767 -220.105405)
			(xy 357.512223 -220.147324) (xy 357.535746 -220.193491) (xy 357.551758 -220.24277) (xy 357.559864 -220.293947)
			(xy 357.560372 -220.319854) (xy 358.780588 -220.319854) (xy 358.781096 -220.293947) (xy 358.789202 -220.24277)
			(xy 358.805214 -220.193491) (xy 358.828737 -220.147324) (xy 358.859193 -220.105405) (xy 358.895831 -220.068767)
			(xy 358.93775 -220.038311) (xy 358.983917 -220.014788) (xy 359.033196 -219.998776) (xy 359.084373 -219.99067)
			(xy 359.136187 -219.99067) (xy 359.187364 -219.998776) (xy 359.236643 -220.014788) (xy 359.28281 -220.038311)
			(xy 359.324729 -220.068767) (xy 359.361367 -220.105405) (xy 359.391823 -220.147324) (xy 359.415346 -220.193491)
			(xy 359.431358 -220.24277) (xy 359.439464 -220.293947) (xy 359.439972 -220.319854) (xy 360.660188 -220.319854)
			(xy 360.660696 -220.293947) (xy 360.668802 -220.24277) (xy 360.684814 -220.193491) (xy 360.708337 -220.147324)
			(xy 360.738793 -220.105405) (xy 360.775431 -220.068767) (xy 360.81735 -220.038311) (xy 360.863517 -220.014788)
			(xy 360.912796 -219.998776) (xy 360.963973 -219.99067) (xy 361.015787 -219.99067) (xy 361.066964 -219.998776)
			(xy 361.116243 -220.014788) (xy 361.16241 -220.038311) (xy 361.204329 -220.068767) (xy 361.240967 -220.105405)
			(xy 361.271423 -220.147324) (xy 361.294946 -220.193491) (xy 361.310958 -220.24277) (xy 361.319064 -220.293947)
			(xy 361.319572 -220.319854) (xy 362.539788 -220.319854) (xy 362.540296 -220.293947) (xy 362.548402 -220.24277)
			(xy 362.564414 -220.193491) (xy 362.587937 -220.147324) (xy 362.618393 -220.105405) (xy 362.655031 -220.068767)
			(xy 362.69695 -220.038311) (xy 362.743117 -220.014788) (xy 362.792396 -219.998776) (xy 362.843573 -219.99067)
			(xy 362.895387 -219.99067) (xy 362.946564 -219.998776) (xy 362.995843 -220.014788) (xy 363.04201 -220.038311)
			(xy 363.083929 -220.068767) (xy 363.120567 -220.105405) (xy 363.151023 -220.147324) (xy 363.174546 -220.193491)
			(xy 363.190558 -220.24277) (xy 363.198664 -220.293947) (xy 363.199172 -220.319854) (xy 364.419388 -220.319854)
			(xy 364.419896 -220.293947) (xy 364.428002 -220.24277) (xy 364.444014 -220.193491) (xy 364.467537 -220.147324)
			(xy 364.497993 -220.105405) (xy 364.534631 -220.068767) (xy 364.57655 -220.038311) (xy 364.622717 -220.014788)
			(xy 364.671996 -219.998776) (xy 364.723173 -219.99067) (xy 364.774987 -219.99067) (xy 364.826164 -219.998776)
			(xy 364.875443 -220.014788) (xy 364.92161 -220.038311) (xy 364.963529 -220.068767) (xy 365.000167 -220.105405)
			(xy 365.030623 -220.147324) (xy 365.054146 -220.193491) (xy 365.070158 -220.24277) (xy 365.078264 -220.293947)
			(xy 365.078772 -220.319854) (xy 366.298988 -220.319854) (xy 366.299496 -220.293947) (xy 366.307602 -220.24277)
			(xy 366.323614 -220.193491) (xy 366.347137 -220.147324) (xy 366.377593 -220.105405) (xy 366.414231 -220.068767)
			(xy 366.45615 -220.038311) (xy 366.502317 -220.014788) (xy 366.551596 -219.998776) (xy 366.602773 -219.99067)
			(xy 366.654587 -219.99067) (xy 366.705764 -219.998776) (xy 366.755043 -220.014788) (xy 366.80121 -220.038311)
			(xy 366.843129 -220.068767) (xy 366.879767 -220.105405) (xy 366.910223 -220.147324) (xy 366.933746 -220.193491)
			(xy 366.949758 -220.24277) (xy 366.957864 -220.293947) (xy 366.958372 -220.319854) (xy 368.178588 -220.319854)
			(xy 368.179096 -220.293947) (xy 368.187202 -220.24277) (xy 368.203214 -220.193491) (xy 368.226737 -220.147324)
			(xy 368.257193 -220.105405) (xy 368.293831 -220.068767) (xy 368.33575 -220.038311) (xy 368.381917 -220.014788)
			(xy 368.431196 -219.998776) (xy 368.482373 -219.99067) (xy 368.534187 -219.99067) (xy 368.585364 -219.998776)
			(xy 368.634643 -220.014788) (xy 368.68081 -220.038311) (xy 368.722729 -220.068767) (xy 368.759367 -220.105405)
			(xy 368.789823 -220.147324) (xy 368.813346 -220.193491) (xy 368.829358 -220.24277) (xy 368.837464 -220.293947)
			(xy 368.837972 -220.319854) (xy 370.058188 -220.319854) (xy 370.058696 -220.293947) (xy 370.066802 -220.24277)
			(xy 370.082814 -220.193491) (xy 370.106337 -220.147324) (xy 370.136793 -220.105405) (xy 370.173431 -220.068767)
			(xy 370.21535 -220.038311) (xy 370.261517 -220.014788) (xy 370.310796 -219.998776) (xy 370.361973 -219.99067)
			(xy 370.413787 -219.99067) (xy 370.464964 -219.998776) (xy 370.514243 -220.014788) (xy 370.56041 -220.038311)
			(xy 370.602329 -220.068767) (xy 370.638967 -220.105405) (xy 370.669423 -220.147324) (xy 370.692946 -220.193491)
			(xy 370.708958 -220.24277) (xy 370.717064 -220.293947) (xy 370.717572 -220.319854) (xy 371.937788 -220.319854)
			(xy 371.938296 -220.293947) (xy 371.946402 -220.24277) (xy 371.962414 -220.193491) (xy 371.985937 -220.147324)
			(xy 372.016393 -220.105405) (xy 372.053031 -220.068767) (xy 372.09495 -220.038311) (xy 372.141117 -220.014788)
			(xy 372.190396 -219.998776) (xy 372.241573 -219.99067) (xy 372.293387 -219.99067) (xy 372.344564 -219.998776)
			(xy 372.393843 -220.014788) (xy 372.44001 -220.038311) (xy 372.481929 -220.068767) (xy 372.518567 -220.105405)
			(xy 372.549023 -220.147324) (xy 372.572546 -220.193491) (xy 372.588558 -220.24277) (xy 372.596664 -220.293947)
			(xy 372.597172 -220.319854) (xy 373.817388 -220.319854) (xy 373.817896 -220.293947) (xy 373.826002 -220.24277)
			(xy 373.842014 -220.193491) (xy 373.865537 -220.147324) (xy 373.895993 -220.105405) (xy 373.932631 -220.068767)
			(xy 373.97455 -220.038311) (xy 374.020717 -220.014788) (xy 374.069996 -219.998776) (xy 374.121173 -219.99067)
			(xy 374.172987 -219.99067) (xy 374.224164 -219.998776) (xy 374.273443 -220.014788) (xy 374.31961 -220.038311)
			(xy 374.361529 -220.068767) (xy 374.398167 -220.105405) (xy 374.428623 -220.147324) (xy 374.452146 -220.193491)
			(xy 374.468158 -220.24277) (xy 374.476264 -220.293947) (xy 374.476772 -220.319854) (xy 375.696988 -220.319854)
			(xy 375.697496 -220.293947) (xy 375.705602 -220.24277) (xy 375.721614 -220.193491) (xy 375.745137 -220.147324)
			(xy 375.775593 -220.105405) (xy 375.812231 -220.068767) (xy 375.85415 -220.038311) (xy 375.900317 -220.014788)
			(xy 375.949596 -219.998776) (xy 376.000773 -219.99067) (xy 376.052587 -219.99067) (xy 376.103764 -219.998776)
			(xy 376.153043 -220.014788) (xy 376.19921 -220.038311) (xy 376.241129 -220.068767) (xy 376.277767 -220.105405)
			(xy 376.308223 -220.147324) (xy 376.331746 -220.193491) (xy 376.347758 -220.24277) (xy 376.355864 -220.293947)
			(xy 376.356372 -220.319854) (xy 377.576588 -220.319854) (xy 377.577096 -220.293947) (xy 377.585202 -220.24277)
			(xy 377.601214 -220.193491) (xy 377.624737 -220.147324) (xy 377.655193 -220.105405) (xy 377.691831 -220.068767)
			(xy 377.73375 -220.038311) (xy 377.779917 -220.014788) (xy 377.829196 -219.998776) (xy 377.880373 -219.99067)
			(xy 377.932187 -219.99067) (xy 377.983364 -219.998776) (xy 378.032643 -220.014788) (xy 378.07881 -220.038311)
			(xy 378.120729 -220.068767) (xy 378.157367 -220.105405) (xy 378.187823 -220.147324) (xy 378.211346 -220.193491)
			(xy 378.227358 -220.24277) (xy 378.235464 -220.293947) (xy 378.235972 -220.319854) (xy 379.456188 -220.319854)
			(xy 379.456696 -220.293947) (xy 379.464802 -220.24277) (xy 379.480814 -220.193491) (xy 379.504337 -220.147324)
			(xy 379.534793 -220.105405) (xy 379.571431 -220.068767) (xy 379.61335 -220.038311) (xy 379.659517 -220.014788)
			(xy 379.708796 -219.998776) (xy 379.759973 -219.99067) (xy 379.811787 -219.99067) (xy 379.862964 -219.998776)
			(xy 379.912243 -220.014788) (xy 379.95841 -220.038311) (xy 380.000329 -220.068767) (xy 380.036967 -220.105405)
			(xy 380.067423 -220.147324) (xy 380.090946 -220.193491) (xy 380.106958 -220.24277) (xy 380.115064 -220.293947)
			(xy 380.115572 -220.319854) (xy 381.336296 -220.319854) (xy 381.336804 -220.293967) (xy 381.344903 -220.242829)
			(xy 381.360902 -220.193589) (xy 381.384408 -220.147457) (xy 381.41484 -220.10557) (xy 381.45145 -220.06896)
			(xy 381.493337 -220.038528) (xy 381.539469 -220.015022) (xy 381.588709 -219.999023) (xy 381.639847 -219.990924)
			(xy 381.691621 -219.990924) (xy 381.742759 -219.999023) (xy 381.791999 -220.015022) (xy 381.838131 -220.038528)
			(xy 381.880018 -220.06896) (xy 381.916628 -220.10557) (xy 381.94706 -220.147457) (xy 381.970566 -220.193589)
			(xy 381.986565 -220.242829) (xy 381.994664 -220.293967) (xy 381.995172 -220.319854) (xy 381.994628 -220.347561)
			(xy 381.985442 -220.402208) (xy 381.976884 -220.428566) (xy 381.969264 -220.450664) (xy 382.174242 -220.805756)
			(xy 382.197102 -220.810074) (xy 382.221908 -220.815252) (xy 382.269647 -220.832242) (xy 382.314225 -220.856337)
			(xy 382.354591 -220.886969) (xy 382.389795 -220.923417) (xy 382.419006 -220.964822) (xy 382.441538 -221.01021)
			(xy 382.45686 -221.058511) (xy 382.46461 -221.108588) (xy 382.465072 -221.133924) (xy 382.464564 -221.159811)
			(xy 382.456465 -221.210949) (xy 382.440466 -221.260189) (xy 382.41696 -221.306321) (xy 382.386528 -221.348208)
			(xy 382.349918 -221.384818) (xy 382.308031 -221.41525) (xy 382.261899 -221.438756) (xy 382.212659 -221.454755)
			(xy 382.161521 -221.462854) (xy 382.109747 -221.462854) (xy 382.058609 -221.454755) (xy 382.009369 -221.438756)
			(xy 381.963237 -221.41525) (xy 381.92135 -221.384818) (xy 381.88474 -221.348208) (xy 381.854308 -221.306321)
			(xy 381.830802 -221.260189) (xy 381.814803 -221.210949) (xy 381.806704 -221.159811) (xy 381.806196 -221.133924)
			(xy 381.806732 -221.106216) (xy 381.815923 -221.051569) (xy 381.824484 -221.025212) (xy 381.832358 -221.003114)
			(xy 381.62738 -220.648022) (xy 381.60452 -220.643704) (xy 381.579694 -220.638559) (xy 381.531915 -220.6216)
			(xy 381.487296 -220.597525) (xy 381.446891 -220.566902) (xy 381.41165 -220.530452) (xy 381.382408 -220.489036)
			(xy 381.359851 -220.44363) (xy 381.344514 -220.395306) (xy 381.336758 -220.345204) (xy 381.336296 -220.319854)
			(xy 380.115572 -220.319854) (xy 380.114963 -220.347508) (xy 380.105639 -220.402026) (xy 380.09703 -220.428312)
			(xy 380.08941 -220.45041) (xy 380.294642 -220.805756) (xy 380.317502 -220.810074) (xy 380.342308 -220.815252)
			(xy 380.390047 -220.832242) (xy 380.434625 -220.856337) (xy 380.474991 -220.886969) (xy 380.510195 -220.923417)
			(xy 380.539406 -220.964822) (xy 380.561938 -221.01021) (xy 380.57726 -221.058511) (xy 380.58501 -221.108588)
			(xy 380.585472 -221.133924) (xy 380.584964 -221.159811) (xy 380.576865 -221.210949) (xy 380.560866 -221.260189)
			(xy 380.53736 -221.306321) (xy 380.506928 -221.348208) (xy 380.470318 -221.384818) (xy 380.428431 -221.41525)
			(xy 380.382299 -221.438756) (xy 380.333059 -221.454755) (xy 380.281921 -221.462854) (xy 380.230147 -221.462854)
			(xy 380.179009 -221.454755) (xy 380.129769 -221.438756) (xy 380.083637 -221.41525) (xy 380.04175 -221.384818)
			(xy 380.00514 -221.348208) (xy 379.974708 -221.306321) (xy 379.951202 -221.260189) (xy 379.935203 -221.210949)
			(xy 379.927104 -221.159811) (xy 379.926596 -221.133924) (xy 379.927132 -221.106216) (xy 379.936323 -221.051569)
			(xy 379.944884 -221.025212) (xy 379.952758 -221.003114) (xy 379.74778 -220.648022) (xy 379.72492 -220.643704)
			(xy 379.700079 -220.638521) (xy 379.652232 -220.621628) (xy 379.60754 -220.5976) (xy 379.567059 -220.567005)
			(xy 379.531748 -220.530566) (xy 379.502439 -220.489145) (xy 379.479827 -220.44372) (xy 379.464446 -220.395365)
			(xy 379.456659 -220.345225) (xy 379.456188 -220.319854) (xy 378.235972 -220.319854) (xy 378.235363 -220.347508)
			(xy 378.226039 -220.402026) (xy 378.21743 -220.428312) (xy 378.20981 -220.45041) (xy 378.415042 -220.805756)
			(xy 378.437902 -220.810074) (xy 378.462708 -220.815252) (xy 378.510447 -220.832242) (xy 378.555025 -220.856337)
			(xy 378.595391 -220.886969) (xy 378.630595 -220.923417) (xy 378.659806 -220.964822) (xy 378.682338 -221.01021)
			(xy 378.69766 -221.058511) (xy 378.70541 -221.108588) (xy 378.705872 -221.133924) (xy 378.705364 -221.159811)
			(xy 378.697265 -221.210949) (xy 378.681266 -221.260189) (xy 378.65776 -221.306321) (xy 378.627328 -221.348208)
			(xy 378.590718 -221.384818) (xy 378.548831 -221.41525) (xy 378.502699 -221.438756) (xy 378.453459 -221.454755)
			(xy 378.402321 -221.462854) (xy 378.350547 -221.462854) (xy 378.299409 -221.454755) (xy 378.250169 -221.438756)
			(xy 378.204037 -221.41525) (xy 378.16215 -221.384818) (xy 378.12554 -221.348208) (xy 378.095108 -221.306321)
			(xy 378.071602 -221.260189) (xy 378.055603 -221.210949) (xy 378.047504 -221.159811) (xy 378.046996 -221.133924)
			(xy 378.047532 -221.106216) (xy 378.056723 -221.051569) (xy 378.065284 -221.025212) (xy 378.073158 -221.003114)
			(xy 377.86818 -220.648022) (xy 377.84532 -220.643704) (xy 377.820479 -220.638521) (xy 377.772632 -220.621628)
			(xy 377.72794 -220.5976) (xy 377.687459 -220.567005) (xy 377.652148 -220.530566) (xy 377.622839 -220.489145)
			(xy 377.600227 -220.44372) (xy 377.584846 -220.395365) (xy 377.577059 -220.345225) (xy 377.576588 -220.319854)
			(xy 376.356372 -220.319854) (xy 376.355763 -220.347508) (xy 376.346439 -220.402026) (xy 376.33783 -220.428312)
			(xy 376.33021 -220.45041) (xy 376.535442 -220.805756) (xy 376.558302 -220.810074) (xy 376.583108 -220.815252)
			(xy 376.630847 -220.832242) (xy 376.675425 -220.856337) (xy 376.715791 -220.886969) (xy 376.750995 -220.923417)
			(xy 376.780206 -220.964822) (xy 376.802738 -221.01021) (xy 376.81806 -221.058511) (xy 376.82581 -221.108588)
			(xy 376.826272 -221.133924) (xy 376.825764 -221.159811) (xy 376.817665 -221.210949) (xy 376.801666 -221.260189)
			(xy 376.77816 -221.306321) (xy 376.747728 -221.348208) (xy 376.711118 -221.384818) (xy 376.669231 -221.41525)
			(xy 376.623099 -221.438756) (xy 376.573859 -221.454755) (xy 376.522721 -221.462854) (xy 376.470947 -221.462854)
			(xy 376.419809 -221.454755) (xy 376.370569 -221.438756) (xy 376.324437 -221.41525) (xy 376.28255 -221.384818)
			(xy 376.24594 -221.348208) (xy 376.215508 -221.306321) (xy 376.192002 -221.260189) (xy 376.176003 -221.210949)
			(xy 376.167904 -221.159811) (xy 376.167396 -221.133924) (xy 376.167932 -221.106216) (xy 376.177123 -221.051569)
			(xy 376.185684 -221.025212) (xy 376.193558 -221.003114) (xy 375.98858 -220.648022) (xy 375.96572 -220.643704)
			(xy 375.940879 -220.638521) (xy 375.893032 -220.621628) (xy 375.84834 -220.5976) (xy 375.807859 -220.567005)
			(xy 375.772548 -220.530566) (xy 375.743239 -220.489145) (xy 375.720627 -220.44372) (xy 375.705246 -220.395365)
			(xy 375.697459 -220.345225) (xy 375.696988 -220.319854) (xy 374.476772 -220.319854) (xy 374.476163 -220.347508)
			(xy 374.466839 -220.402026) (xy 374.45823 -220.428312) (xy 374.45061 -220.45041) (xy 374.655842 -220.805756)
			(xy 374.678702 -220.810074) (xy 374.703508 -220.815252) (xy 374.751247 -220.832242) (xy 374.795825 -220.856337)
			(xy 374.836191 -220.886969) (xy 374.871395 -220.923417) (xy 374.900606 -220.964822) (xy 374.923138 -221.01021)
			(xy 374.93846 -221.058511) (xy 374.94621 -221.108588) (xy 374.946672 -221.133924) (xy 374.946164 -221.159811)
			(xy 374.938065 -221.210949) (xy 374.922066 -221.260189) (xy 374.89856 -221.306321) (xy 374.868128 -221.348208)
			(xy 374.831518 -221.384818) (xy 374.789631 -221.41525) (xy 374.743499 -221.438756) (xy 374.694259 -221.454755)
			(xy 374.643121 -221.462854) (xy 374.591347 -221.462854) (xy 374.540209 -221.454755) (xy 374.490969 -221.438756)
			(xy 374.444837 -221.41525) (xy 374.40295 -221.384818) (xy 374.36634 -221.348208) (xy 374.335908 -221.306321)
			(xy 374.312402 -221.260189) (xy 374.296403 -221.210949) (xy 374.288304 -221.159811) (xy 374.287796 -221.133924)
			(xy 374.288332 -221.106216) (xy 374.297523 -221.051569) (xy 374.306084 -221.025212) (xy 374.313958 -221.003114)
			(xy 374.10898 -220.648022) (xy 374.08612 -220.643704) (xy 374.061279 -220.638521) (xy 374.013432 -220.621628)
			(xy 373.96874 -220.5976) (xy 373.928259 -220.567005) (xy 373.892948 -220.530566) (xy 373.863639 -220.489145)
			(xy 373.841027 -220.44372) (xy 373.825646 -220.395365) (xy 373.817859 -220.345225) (xy 373.817388 -220.319854)
			(xy 372.597172 -220.319854) (xy 372.596563 -220.347508) (xy 372.587239 -220.402026) (xy 372.57863 -220.428312)
			(xy 372.57101 -220.45041) (xy 372.776242 -220.805756) (xy 372.799102 -220.810074) (xy 372.823908 -220.815252)
			(xy 372.871647 -220.832242) (xy 372.916225 -220.856337) (xy 372.956591 -220.886969) (xy 372.991795 -220.923417)
			(xy 373.021006 -220.964822) (xy 373.043538 -221.01021) (xy 373.05886 -221.058511) (xy 373.06661 -221.108588)
			(xy 373.067072 -221.133924) (xy 373.066564 -221.159811) (xy 373.058465 -221.210949) (xy 373.042466 -221.260189)
			(xy 373.01896 -221.306321) (xy 372.988528 -221.348208) (xy 372.951918 -221.384818) (xy 372.910031 -221.41525)
			(xy 372.863899 -221.438756) (xy 372.814659 -221.454755) (xy 372.763521 -221.462854) (xy 372.711747 -221.462854)
			(xy 372.660609 -221.454755) (xy 372.611369 -221.438756) (xy 372.565237 -221.41525) (xy 372.52335 -221.384818)
			(xy 372.48674 -221.348208) (xy 372.456308 -221.306321) (xy 372.432802 -221.260189) (xy 372.416803 -221.210949)
			(xy 372.408704 -221.159811) (xy 372.408196 -221.133924) (xy 372.408732 -221.106216) (xy 372.417923 -221.051569)
			(xy 372.426484 -221.025212) (xy 372.434358 -221.003114) (xy 372.22938 -220.648022) (xy 372.20652 -220.643704)
			(xy 372.181679 -220.638521) (xy 372.133832 -220.621628) (xy 372.08914 -220.5976) (xy 372.048659 -220.567005)
			(xy 372.013348 -220.530566) (xy 371.984039 -220.489145) (xy 371.961427 -220.44372) (xy 371.946046 -220.395365)
			(xy 371.938259 -220.345225) (xy 371.937788 -220.319854) (xy 370.717572 -220.319854) (xy 370.716963 -220.347508)
			(xy 370.707639 -220.402026) (xy 370.69903 -220.428312) (xy 370.69141 -220.45041) (xy 370.896642 -220.805756)
			(xy 370.919502 -220.810074) (xy 370.944308 -220.815252) (xy 370.992047 -220.832242) (xy 371.036625 -220.856337)
			(xy 371.076991 -220.886969) (xy 371.112195 -220.923417) (xy 371.141406 -220.964822) (xy 371.163938 -221.01021)
			(xy 371.17926 -221.058511) (xy 371.18701 -221.108588) (xy 371.187472 -221.133924) (xy 371.186964 -221.159811)
			(xy 371.178865 -221.210949) (xy 371.162866 -221.260189) (xy 371.13936 -221.306321) (xy 371.108928 -221.348208)
			(xy 371.072318 -221.384818) (xy 371.030431 -221.41525) (xy 370.984299 -221.438756) (xy 370.935059 -221.454755)
			(xy 370.883921 -221.462854) (xy 370.832147 -221.462854) (xy 370.781009 -221.454755) (xy 370.731769 -221.438756)
			(xy 370.685637 -221.41525) (xy 370.64375 -221.384818) (xy 370.60714 -221.348208) (xy 370.576708 -221.306321)
			(xy 370.553202 -221.260189) (xy 370.537203 -221.210949) (xy 370.529104 -221.159811) (xy 370.528596 -221.133924)
			(xy 370.529132 -221.106216) (xy 370.538323 -221.051569) (xy 370.546884 -221.025212) (xy 370.554758 -221.003114)
			(xy 370.34978 -220.648022) (xy 370.32692 -220.643704) (xy 370.302079 -220.638521) (xy 370.254232 -220.621628)
			(xy 370.20954 -220.5976) (xy 370.169059 -220.567005) (xy 370.133748 -220.530566) (xy 370.104439 -220.489145)
			(xy 370.081827 -220.44372) (xy 370.066446 -220.395365) (xy 370.058659 -220.345225) (xy 370.058188 -220.319854)
			(xy 368.837972 -220.319854) (xy 368.837363 -220.347508) (xy 368.828039 -220.402026) (xy 368.81943 -220.428312)
			(xy 368.81181 -220.45041) (xy 369.017042 -220.805756) (xy 369.039902 -220.810074) (xy 369.064708 -220.815252)
			(xy 369.112447 -220.832242) (xy 369.157025 -220.856337) (xy 369.197391 -220.886969) (xy 369.232595 -220.923417)
			(xy 369.261806 -220.964822) (xy 369.284338 -221.01021) (xy 369.29966 -221.058511) (xy 369.30741 -221.108588)
			(xy 369.307872 -221.133924) (xy 369.307364 -221.159811) (xy 369.299265 -221.210949) (xy 369.283266 -221.260189)
			(xy 369.25976 -221.306321) (xy 369.229328 -221.348208) (xy 369.192718 -221.384818) (xy 369.150831 -221.41525)
			(xy 369.104699 -221.438756) (xy 369.055459 -221.454755) (xy 369.004321 -221.462854) (xy 368.952547 -221.462854)
			(xy 368.901409 -221.454755) (xy 368.852169 -221.438756) (xy 368.806037 -221.41525) (xy 368.76415 -221.384818)
			(xy 368.72754 -221.348208) (xy 368.697108 -221.306321) (xy 368.673602 -221.260189) (xy 368.657603 -221.210949)
			(xy 368.649504 -221.159811) (xy 368.648996 -221.133924) (xy 368.649532 -221.106216) (xy 368.658723 -221.051569)
			(xy 368.667284 -221.025212) (xy 368.675158 -221.003114) (xy 368.47018 -220.648022) (xy 368.44732 -220.643704)
			(xy 368.422479 -220.638521) (xy 368.374632 -220.621628) (xy 368.32994 -220.5976) (xy 368.289459 -220.567005)
			(xy 368.254148 -220.530566) (xy 368.224839 -220.489145) (xy 368.202227 -220.44372) (xy 368.186846 -220.395365)
			(xy 368.179059 -220.345225) (xy 368.178588 -220.319854) (xy 366.958372 -220.319854) (xy 366.957763 -220.347508)
			(xy 366.948439 -220.402026) (xy 366.93983 -220.428312) (xy 366.93221 -220.45041) (xy 367.137442 -220.805756)
			(xy 367.160302 -220.810074) (xy 367.185108 -220.815252) (xy 367.232847 -220.832242) (xy 367.277425 -220.856337)
			(xy 367.317791 -220.886969) (xy 367.352995 -220.923417) (xy 367.382206 -220.964822) (xy 367.404738 -221.01021)
			(xy 367.42006 -221.058511) (xy 367.42781 -221.108588) (xy 367.428272 -221.133924) (xy 367.427764 -221.159811)
			(xy 367.419665 -221.210949) (xy 367.403666 -221.260189) (xy 367.38016 -221.306321) (xy 367.349728 -221.348208)
			(xy 367.313118 -221.384818) (xy 367.271231 -221.41525) (xy 367.225099 -221.438756) (xy 367.175859 -221.454755)
			(xy 367.124721 -221.462854) (xy 367.072947 -221.462854) (xy 367.021809 -221.454755) (xy 366.972569 -221.438756)
			(xy 366.926437 -221.41525) (xy 366.88455 -221.384818) (xy 366.84794 -221.348208) (xy 366.817508 -221.306321)
			(xy 366.794002 -221.260189) (xy 366.778003 -221.210949) (xy 366.769904 -221.159811) (xy 366.769396 -221.133924)
			(xy 366.769932 -221.106216) (xy 366.779123 -221.051569) (xy 366.787684 -221.025212) (xy 366.795558 -221.003114)
			(xy 366.59058 -220.648022) (xy 366.56772 -220.643704) (xy 366.542879 -220.638521) (xy 366.495032 -220.621628)
			(xy 366.45034 -220.5976) (xy 366.409859 -220.567005) (xy 366.374548 -220.530566) (xy 366.345239 -220.489145)
			(xy 366.322627 -220.44372) (xy 366.307246 -220.395365) (xy 366.299459 -220.345225) (xy 366.298988 -220.319854)
			(xy 365.078772 -220.319854) (xy 365.078163 -220.347508) (xy 365.068839 -220.402026) (xy 365.06023 -220.428312)
			(xy 365.05261 -220.45041) (xy 365.257842 -220.805756) (xy 365.280702 -220.810074) (xy 365.305508 -220.815252)
			(xy 365.353247 -220.832242) (xy 365.397825 -220.856337) (xy 365.438191 -220.886969) (xy 365.473395 -220.923417)
			(xy 365.502606 -220.964822) (xy 365.525138 -221.01021) (xy 365.54046 -221.058511) (xy 365.54821 -221.108588)
			(xy 365.548672 -221.133924) (xy 365.548164 -221.159811) (xy 365.540065 -221.210949) (xy 365.524066 -221.260189)
			(xy 365.50056 -221.306321) (xy 365.470128 -221.348208) (xy 365.433518 -221.384818) (xy 365.391631 -221.41525)
			(xy 365.345499 -221.438756) (xy 365.296259 -221.454755) (xy 365.245121 -221.462854) (xy 365.193347 -221.462854)
			(xy 365.142209 -221.454755) (xy 365.092969 -221.438756) (xy 365.046837 -221.41525) (xy 365.00495 -221.384818)
			(xy 364.96834 -221.348208) (xy 364.937908 -221.306321) (xy 364.914402 -221.260189) (xy 364.898403 -221.210949)
			(xy 364.890304 -221.159811) (xy 364.889796 -221.133924) (xy 364.890332 -221.106216) (xy 364.899523 -221.051569)
			(xy 364.908084 -221.025212) (xy 364.915958 -221.003114) (xy 364.71098 -220.648022) (xy 364.68812 -220.643704)
			(xy 364.663279 -220.638521) (xy 364.615432 -220.621628) (xy 364.57074 -220.5976) (xy 364.530259 -220.567005)
			(xy 364.494948 -220.530566) (xy 364.465639 -220.489145) (xy 364.443027 -220.44372) (xy 364.427646 -220.395365)
			(xy 364.419859 -220.345225) (xy 364.419388 -220.319854) (xy 363.199172 -220.319854) (xy 363.198563 -220.347508)
			(xy 363.189239 -220.402026) (xy 363.18063 -220.428312) (xy 363.17301 -220.45041) (xy 363.378242 -220.805756)
			(xy 363.401102 -220.810074) (xy 363.425908 -220.815252) (xy 363.473647 -220.832242) (xy 363.518225 -220.856337)
			(xy 363.558591 -220.886969) (xy 363.593795 -220.923417) (xy 363.623006 -220.964822) (xy 363.645538 -221.01021)
			(xy 363.66086 -221.058511) (xy 363.66861 -221.108588) (xy 363.669072 -221.133924) (xy 363.668564 -221.159811)
			(xy 363.660465 -221.210949) (xy 363.644466 -221.260189) (xy 363.62096 -221.306321) (xy 363.590528 -221.348208)
			(xy 363.553918 -221.384818) (xy 363.512031 -221.41525) (xy 363.465899 -221.438756) (xy 363.416659 -221.454755)
			(xy 363.365521 -221.462854) (xy 363.313747 -221.462854) (xy 363.262609 -221.454755) (xy 363.213369 -221.438756)
			(xy 363.167237 -221.41525) (xy 363.12535 -221.384818) (xy 363.08874 -221.348208) (xy 363.058308 -221.306321)
			(xy 363.034802 -221.260189) (xy 363.018803 -221.210949) (xy 363.010704 -221.159811) (xy 363.010196 -221.133924)
			(xy 363.010732 -221.106216) (xy 363.019923 -221.051569) (xy 363.028484 -221.025212) (xy 363.036358 -221.003114)
			(xy 362.83138 -220.648022) (xy 362.80852 -220.643704) (xy 362.783679 -220.638521) (xy 362.735832 -220.621628)
			(xy 362.69114 -220.5976) (xy 362.650659 -220.567005) (xy 362.615348 -220.530566) (xy 362.586039 -220.489145)
			(xy 362.563427 -220.44372) (xy 362.548046 -220.395365) (xy 362.540259 -220.345225) (xy 362.539788 -220.319854)
			(xy 361.319572 -220.319854) (xy 361.318963 -220.347508) (xy 361.309639 -220.402026) (xy 361.30103 -220.428312)
			(xy 361.29341 -220.45041) (xy 361.498642 -220.805756) (xy 361.521502 -220.810074) (xy 361.546308 -220.815252)
			(xy 361.594047 -220.832242) (xy 361.638625 -220.856337) (xy 361.678991 -220.886969) (xy 361.714195 -220.923417)
			(xy 361.743406 -220.964822) (xy 361.765938 -221.01021) (xy 361.78126 -221.058511) (xy 361.78901 -221.108588)
			(xy 361.789472 -221.133924) (xy 361.788964 -221.159811) (xy 361.780865 -221.210949) (xy 361.764866 -221.260189)
			(xy 361.74136 -221.306321) (xy 361.710928 -221.348208) (xy 361.674318 -221.384818) (xy 361.632431 -221.41525)
			(xy 361.586299 -221.438756) (xy 361.537059 -221.454755) (xy 361.485921 -221.462854) (xy 361.434147 -221.462854)
			(xy 361.383009 -221.454755) (xy 361.333769 -221.438756) (xy 361.287637 -221.41525) (xy 361.24575 -221.384818)
			(xy 361.20914 -221.348208) (xy 361.178708 -221.306321) (xy 361.155202 -221.260189) (xy 361.139203 -221.210949)
			(xy 361.131104 -221.159811) (xy 361.130596 -221.133924) (xy 361.131132 -221.106216) (xy 361.140323 -221.051569)
			(xy 361.148884 -221.025212) (xy 361.156758 -221.003114) (xy 360.95178 -220.648022) (xy 360.92892 -220.643704)
			(xy 360.904079 -220.638521) (xy 360.856232 -220.621628) (xy 360.81154 -220.5976) (xy 360.771059 -220.567005)
			(xy 360.735748 -220.530566) (xy 360.706439 -220.489145) (xy 360.683827 -220.44372) (xy 360.668446 -220.395365)
			(xy 360.660659 -220.345225) (xy 360.660188 -220.319854) (xy 359.439972 -220.319854) (xy 359.439363 -220.347508)
			(xy 359.430039 -220.402026) (xy 359.42143 -220.428312) (xy 359.41381 -220.45041) (xy 359.619042 -220.805756)
			(xy 359.641902 -220.810074) (xy 359.666708 -220.815252) (xy 359.714447 -220.832242) (xy 359.759025 -220.856337)
			(xy 359.799391 -220.886969) (xy 359.834595 -220.923417) (xy 359.863806 -220.964822) (xy 359.886338 -221.01021)
			(xy 359.90166 -221.058511) (xy 359.90941 -221.108588) (xy 359.909872 -221.133924) (xy 359.909364 -221.159811)
			(xy 359.901265 -221.210949) (xy 359.885266 -221.260189) (xy 359.86176 -221.306321) (xy 359.831328 -221.348208)
			(xy 359.794718 -221.384818) (xy 359.752831 -221.41525) (xy 359.706699 -221.438756) (xy 359.657459 -221.454755)
			(xy 359.606321 -221.462854) (xy 359.554547 -221.462854) (xy 359.503409 -221.454755) (xy 359.454169 -221.438756)
			(xy 359.408037 -221.41525) (xy 359.36615 -221.384818) (xy 359.32954 -221.348208) (xy 359.299108 -221.306321)
			(xy 359.275602 -221.260189) (xy 359.259603 -221.210949) (xy 359.251504 -221.159811) (xy 359.250996 -221.133924)
			(xy 359.251532 -221.106216) (xy 359.260723 -221.051569) (xy 359.269284 -221.025212) (xy 359.277158 -221.003114)
			(xy 359.07218 -220.648022) (xy 359.04932 -220.643704) (xy 359.024479 -220.638521) (xy 358.976632 -220.621628)
			(xy 358.93194 -220.5976) (xy 358.891459 -220.567005) (xy 358.856148 -220.530566) (xy 358.826839 -220.489145)
			(xy 358.804227 -220.44372) (xy 358.788846 -220.395365) (xy 358.781059 -220.345225) (xy 358.780588 -220.319854)
			(xy 357.560372 -220.319854) (xy 357.559763 -220.347508) (xy 357.550439 -220.402026) (xy 357.54183 -220.428312)
			(xy 357.53421 -220.45041) (xy 357.739442 -220.805756) (xy 357.762302 -220.810074) (xy 357.787108 -220.815252)
			(xy 357.834847 -220.832242) (xy 357.879425 -220.856337) (xy 357.919791 -220.886969) (xy 357.954995 -220.923417)
			(xy 357.984206 -220.964822) (xy 358.006738 -221.01021) (xy 358.02206 -221.058511) (xy 358.02981 -221.108588)
			(xy 358.030272 -221.133924) (xy 358.029764 -221.159811) (xy 358.021665 -221.210949) (xy 358.005666 -221.260189)
			(xy 357.98216 -221.306321) (xy 357.951728 -221.348208) (xy 357.915118 -221.384818) (xy 357.873231 -221.41525)
			(xy 357.827099 -221.438756) (xy 357.777859 -221.454755) (xy 357.726721 -221.462854) (xy 357.674947 -221.462854)
			(xy 357.623809 -221.454755) (xy 357.574569 -221.438756) (xy 357.528437 -221.41525) (xy 357.48655 -221.384818)
			(xy 357.44994 -221.348208) (xy 357.419508 -221.306321) (xy 357.396002 -221.260189) (xy 357.380003 -221.210949)
			(xy 357.371904 -221.159811) (xy 357.371396 -221.133924) (xy 357.371932 -221.106216) (xy 357.381123 -221.051569)
			(xy 357.389684 -221.025212) (xy 357.397558 -221.003114) (xy 357.19258 -220.648022) (xy 357.16972 -220.643704)
			(xy 357.144879 -220.638521) (xy 357.097032 -220.621628) (xy 357.05234 -220.5976) (xy 357.011859 -220.567005)
			(xy 356.976548 -220.530566) (xy 356.947239 -220.489145) (xy 356.924627 -220.44372) (xy 356.909246 -220.395365)
			(xy 356.901459 -220.345225) (xy 356.900988 -220.319854) (xy 355.680772 -220.319854) (xy 355.680163 -220.347508)
			(xy 355.670839 -220.402026) (xy 355.66223 -220.428312) (xy 355.65461 -220.45041) (xy 355.859842 -220.805756)
			(xy 355.882702 -220.810074) (xy 355.907508 -220.815252) (xy 355.955247 -220.832242) (xy 355.999825 -220.856337)
			(xy 356.040191 -220.886969) (xy 356.075395 -220.923417) (xy 356.104606 -220.964822) (xy 356.127138 -221.01021)
			(xy 356.14246 -221.058511) (xy 356.15021 -221.108588) (xy 356.150672 -221.133924) (xy 356.150164 -221.159811)
			(xy 356.142065 -221.210949) (xy 356.126066 -221.260189) (xy 356.10256 -221.306321) (xy 356.072128 -221.348208)
			(xy 356.035518 -221.384818) (xy 355.993631 -221.41525) (xy 355.947499 -221.438756) (xy 355.898259 -221.454755)
			(xy 355.847121 -221.462854) (xy 355.795347 -221.462854) (xy 355.744209 -221.454755) (xy 355.694969 -221.438756)
			(xy 355.648837 -221.41525) (xy 355.60695 -221.384818) (xy 355.57034 -221.348208) (xy 355.539908 -221.306321)
			(xy 355.516402 -221.260189) (xy 355.500403 -221.210949) (xy 355.492304 -221.159811) (xy 355.491796 -221.133924)
			(xy 355.492332 -221.106216) (xy 355.501523 -221.051569) (xy 355.510084 -221.025212) (xy 355.517958 -221.003114)
			(xy 355.31298 -220.648022) (xy 355.29012 -220.643704) (xy 355.265279 -220.638521) (xy 355.217432 -220.621628)
			(xy 355.17274 -220.5976) (xy 355.132259 -220.567005) (xy 355.096948 -220.530566) (xy 355.067639 -220.489145)
			(xy 355.045027 -220.44372) (xy 355.029646 -220.395365) (xy 355.021859 -220.345225) (xy 355.021388 -220.319854)
			(xy 353.801172 -220.319854) (xy 353.800563 -220.347508) (xy 353.791239 -220.402026) (xy 353.78263 -220.428312)
			(xy 353.77501 -220.45041) (xy 353.980242 -220.805756) (xy 354.003102 -220.810074) (xy 354.027908 -220.815252)
			(xy 354.075647 -220.832242) (xy 354.120225 -220.856337) (xy 354.160591 -220.886969) (xy 354.195795 -220.923417)
			(xy 354.225006 -220.964822) (xy 354.247538 -221.01021) (xy 354.26286 -221.058511) (xy 354.27061 -221.108588)
			(xy 354.271072 -221.133924) (xy 354.270564 -221.159811) (xy 354.262465 -221.210949) (xy 354.246466 -221.260189)
			(xy 354.22296 -221.306321) (xy 354.192528 -221.348208) (xy 354.155918 -221.384818) (xy 354.114031 -221.41525)
			(xy 354.067899 -221.438756) (xy 354.018659 -221.454755) (xy 353.967521 -221.462854) (xy 353.915747 -221.462854)
			(xy 353.864609 -221.454755) (xy 353.815369 -221.438756) (xy 353.769237 -221.41525) (xy 353.72735 -221.384818)
			(xy 353.69074 -221.348208) (xy 353.660308 -221.306321) (xy 353.636802 -221.260189) (xy 353.620803 -221.210949)
			(xy 353.612704 -221.159811) (xy 353.612196 -221.133924) (xy 353.612732 -221.106216) (xy 353.621923 -221.051569)
			(xy 353.630484 -221.025212) (xy 353.638358 -221.003114) (xy 353.43338 -220.648022) (xy 353.41052 -220.643704)
			(xy 353.385679 -220.638521) (xy 353.337832 -220.621628) (xy 353.29314 -220.5976) (xy 353.252659 -220.567005)
			(xy 353.217348 -220.530566) (xy 353.188039 -220.489145) (xy 353.165427 -220.44372) (xy 353.150046 -220.395365)
			(xy 353.142259 -220.345225) (xy 353.141788 -220.319854) (xy 351.921572 -220.319854) (xy 351.921122 -220.3452)
			(xy 351.913342 -220.395293) (xy 351.897988 -220.443604) (xy 351.875422 -220.488998) (xy 351.846176 -220.530404)
			(xy 351.810939 -220.566847) (xy 351.77054 -220.597469) (xy 351.725931 -220.621548) (xy 351.678163 -220.638518)
			(xy 351.653348 -220.643704) (xy 351.630488 -220.648022) (xy 351.42551 -221.003114) (xy 351.433384 -221.024958)
			(xy 351.441977 -221.051373) (xy 351.451165 -221.106151) (xy 351.451672 -221.133924) (xy 351.451164 -221.159811)
			(xy 351.443065 -221.210949) (xy 351.427066 -221.260189) (xy 351.40356 -221.306321) (xy 351.373128 -221.348208)
			(xy 351.336518 -221.384818) (xy 351.294631 -221.41525) (xy 351.248499 -221.438756) (xy 351.199259 -221.454755)
			(xy 351.148121 -221.462854) (xy 351.096347 -221.462854) (xy 351.045209 -221.454755) (xy 350.995969 -221.438756)
			(xy 350.949837 -221.41525) (xy 350.90795 -221.384818) (xy 350.87134 -221.348208) (xy 350.840908 -221.306321)
			(xy 350.817402 -221.260189) (xy 350.801403 -221.210949) (xy 350.793304 -221.159811) (xy 350.792796 -221.133924)
			(xy 350.511872 -221.133924) (xy 350.511345 -221.161632) (xy 350.502148 -221.216279) (xy 350.493584 -221.242636)
			(xy 350.48571 -221.264734) (xy 350.690688 -221.619572) (xy 350.713548 -221.62389) (xy 350.738367 -221.629064)
			(xy 350.786146 -221.646018) (xy 350.830765 -221.670088) (xy 350.871172 -221.700708) (xy 350.906413 -221.737154)
			(xy 350.935657 -221.778566) (xy 350.958214 -221.823969) (xy 350.973552 -221.872291) (xy 350.98131 -221.922391)
			(xy 350.981772 -221.94774) (xy 352.201988 -221.94774) (xy 352.202465 -221.922395) (xy 352.210245 -221.872306)
			(xy 352.225597 -221.823996) (xy 352.24816 -221.778605) (xy 352.277403 -221.7372) (xy 352.312637 -221.700757)
			(xy 352.353031 -221.670134) (xy 352.397636 -221.646052) (xy 352.445399 -221.629078) (xy 352.470212 -221.62389)
			(xy 352.493072 -221.619572) (xy 352.698304 -221.264226) (xy 352.69043 -221.242128) (xy 352.681965 -221.215883)
			(xy 352.672893 -221.161495) (xy 352.672396 -221.133924) (xy 352.672904 -221.108037) (xy 352.681003 -221.056899)
			(xy 352.697002 -221.007659) (xy 352.720508 -220.961527) (xy 352.75094 -220.91964) (xy 352.78755 -220.88303)
			(xy 352.829437 -220.852598) (xy 352.875569 -220.829092) (xy 352.924809 -220.813093) (xy 352.975947 -220.804994)
			(xy 353.027721 -220.804994) (xy 353.078859 -220.813093) (xy 353.128099 -220.829092) (xy 353.174231 -220.852598)
			(xy 353.216118 -220.88303) (xy 353.252728 -220.91964) (xy 353.28316 -220.961527) (xy 353.306666 -221.007659)
			(xy 353.322665 -221.056899) (xy 353.330764 -221.108037) (xy 353.331272 -221.133924) (xy 353.330842 -221.1593)
			(xy 353.323069 -221.209454) (xy 353.307696 -221.257821) (xy 353.285086 -221.303259) (xy 353.255774 -221.344691)
			(xy 353.220455 -221.381137) (xy 353.179963 -221.411734) (xy 353.135258 -221.435759) (xy 353.087396 -221.452643)
			(xy 353.06254 -221.457774) (xy 353.03968 -221.462092) (xy 352.834956 -221.81693) (xy 352.84283 -221.838774)
			(xy 352.851486 -221.865179) (xy 352.8608 -221.919958) (xy 352.861372 -221.94774) (xy 354.081588 -221.94774)
			(xy 354.082065 -221.922395) (xy 354.089845 -221.872306) (xy 354.105197 -221.823996) (xy 354.12776 -221.778605)
			(xy 354.157003 -221.7372) (xy 354.192237 -221.700757) (xy 354.232631 -221.670134) (xy 354.277236 -221.646052)
			(xy 354.324999 -221.629078) (xy 354.349812 -221.62389) (xy 354.372672 -221.619572) (xy 354.577904 -221.264226)
			(xy 354.57003 -221.242128) (xy 354.561565 -221.215883) (xy 354.552493 -221.161495) (xy 354.551996 -221.133924)
			(xy 354.552504 -221.108037) (xy 354.560603 -221.056899) (xy 354.576602 -221.007659) (xy 354.600108 -220.961527)
			(xy 354.63054 -220.91964) (xy 354.66715 -220.88303) (xy 354.709037 -220.852598) (xy 354.755169 -220.829092)
			(xy 354.804409 -220.813093) (xy 354.855547 -220.804994) (xy 354.907321 -220.804994) (xy 354.958459 -220.813093)
			(xy 355.007699 -220.829092) (xy 355.053831 -220.852598) (xy 355.095718 -220.88303) (xy 355.132328 -220.91964)
			(xy 355.16276 -220.961527) (xy 355.186266 -221.007659) (xy 355.202265 -221.056899) (xy 355.210364 -221.108037)
			(xy 355.210872 -221.133924) (xy 355.210442 -221.1593) (xy 355.202669 -221.209454) (xy 355.187296 -221.257821)
			(xy 355.164686 -221.303259) (xy 355.135374 -221.344691) (xy 355.100055 -221.381137) (xy 355.059563 -221.411734)
			(xy 355.014858 -221.435759) (xy 354.966996 -221.452643) (xy 354.94214 -221.457774) (xy 354.91928 -221.462092)
			(xy 354.714556 -221.81693) (xy 354.72243 -221.838774) (xy 354.731086 -221.865179) (xy 354.7404 -221.919958)
			(xy 354.740972 -221.94774) (xy 355.961188 -221.94774) (xy 355.961665 -221.922395) (xy 355.969445 -221.872306)
			(xy 355.984797 -221.823996) (xy 356.00736 -221.778605) (xy 356.036603 -221.7372) (xy 356.071837 -221.700757)
			(xy 356.112231 -221.670134) (xy 356.156836 -221.646052) (xy 356.204599 -221.629078) (xy 356.229412 -221.62389)
			(xy 356.252272 -221.619572) (xy 356.457504 -221.264226) (xy 356.44963 -221.242128) (xy 356.441165 -221.215883)
			(xy 356.432093 -221.161495) (xy 356.431596 -221.133924) (xy 356.432104 -221.108037) (xy 356.440203 -221.056899)
			(xy 356.456202 -221.007659) (xy 356.479708 -220.961527) (xy 356.51014 -220.91964) (xy 356.54675 -220.88303)
			(xy 356.588637 -220.852598) (xy 356.634769 -220.829092) (xy 356.684009 -220.813093) (xy 356.735147 -220.804994)
			(xy 356.786921 -220.804994) (xy 356.838059 -220.813093) (xy 356.887299 -220.829092) (xy 356.933431 -220.852598)
			(xy 356.975318 -220.88303) (xy 357.011928 -220.91964) (xy 357.04236 -220.961527) (xy 357.065866 -221.007659)
			(xy 357.081865 -221.056899) (xy 357.089964 -221.108037) (xy 357.090472 -221.133924) (xy 357.090042 -221.1593)
			(xy 357.082269 -221.209454) (xy 357.066896 -221.257821) (xy 357.044286 -221.303259) (xy 357.014974 -221.344691)
			(xy 356.979655 -221.381137) (xy 356.939163 -221.411734) (xy 356.894458 -221.435759) (xy 356.846596 -221.452643)
			(xy 356.82174 -221.457774) (xy 356.79888 -221.462092) (xy 356.594156 -221.81693) (xy 356.60203 -221.838774)
			(xy 356.610686 -221.865179) (xy 356.62 -221.919958) (xy 356.620572 -221.94774) (xy 357.841296 -221.94774)
			(xy 357.841727 -221.922404) (xy 357.849489 -221.872329) (xy 357.864819 -221.824032) (xy 357.887358 -221.778648)
			(xy 357.916574 -221.737246) (xy 357.95178 -221.700802) (xy 357.992148 -221.670172) (xy 358.036725 -221.646079)
			(xy 358.084465 -221.629089) (xy 358.109266 -221.62389) (xy 358.132126 -221.619572) (xy 358.337104 -221.26448)
			(xy 358.329484 -221.242382) (xy 358.320964 -221.216211) (xy 358.311771 -221.161949) (xy 358.311196 -221.134432)
			(xy 358.311196 -221.133924) (xy 358.311704 -221.108037) (xy 358.319803 -221.056899) (xy 358.335802 -221.007659)
			(xy 358.359308 -220.961527) (xy 358.38974 -220.91964) (xy 358.42635 -220.88303) (xy 358.468237 -220.852598)
			(xy 358.514369 -220.829092) (xy 358.563609 -220.813093) (xy 358.614747 -220.804994) (xy 358.666521 -220.804994)
			(xy 358.717659 -220.813093) (xy 358.766899 -220.829092) (xy 358.813031 -220.852598) (xy 358.854918 -220.88303)
			(xy 358.891528 -220.91964) (xy 358.92196 -220.961527) (xy 358.945466 -221.007659) (xy 358.961465 -221.056899)
			(xy 358.969564 -221.108037) (xy 358.970072 -221.133924) (xy 358.969679 -221.159291) (xy 358.961926 -221.209429)
			(xy 358.946575 -221.257784) (xy 358.923991 -221.303213) (xy 358.894706 -221.344642) (xy 358.859415 -221.381089)
			(xy 358.818952 -221.411694) (xy 358.774274 -221.435731) (xy 358.726438 -221.452632) (xy 358.701594 -221.457774)
			(xy 358.678734 -221.462092) (xy 358.47401 -221.81693) (xy 358.481884 -221.838774) (xy 358.490481 -221.865188)
			(xy 358.499666 -221.919967) (xy 358.500172 -221.94774) (xy 359.720388 -221.94774) (xy 359.720865 -221.922395)
			(xy 359.728645 -221.872306) (xy 359.743997 -221.823996) (xy 359.76656 -221.778605) (xy 359.795803 -221.7372)
			(xy 359.831037 -221.700757) (xy 359.871431 -221.670134) (xy 359.916036 -221.646052) (xy 359.963799 -221.629078)
			(xy 359.988612 -221.62389) (xy 360.011472 -221.619572) (xy 360.216704 -221.264226) (xy 360.20883 -221.242128)
			(xy 360.200365 -221.215883) (xy 360.191293 -221.161495) (xy 360.190796 -221.133924) (xy 360.191304 -221.108037)
			(xy 360.199403 -221.056899) (xy 360.215402 -221.007659) (xy 360.238908 -220.961527) (xy 360.26934 -220.91964)
			(xy 360.30595 -220.88303) (xy 360.347837 -220.852598) (xy 360.393969 -220.829092) (xy 360.443209 -220.813093)
			(xy 360.494347 -220.804994) (xy 360.546121 -220.804994) (xy 360.597259 -220.813093) (xy 360.646499 -220.829092)
			(xy 360.692631 -220.852598) (xy 360.734518 -220.88303) (xy 360.771128 -220.91964) (xy 360.80156 -220.961527)
			(xy 360.825066 -221.007659) (xy 360.841065 -221.056899) (xy 360.849164 -221.108037) (xy 360.849672 -221.133924)
			(xy 360.849242 -221.1593) (xy 360.841469 -221.209454) (xy 360.826096 -221.257821) (xy 360.803486 -221.303259)
			(xy 360.774174 -221.344691) (xy 360.738855 -221.381137) (xy 360.698363 -221.411734) (xy 360.653658 -221.435759)
			(xy 360.605796 -221.452643) (xy 360.58094 -221.457774) (xy 360.55808 -221.462092) (xy 360.353356 -221.81693)
			(xy 360.36123 -221.838774) (xy 360.369886 -221.865179) (xy 360.3792 -221.919958) (xy 360.379772 -221.94774)
			(xy 361.600496 -221.94774) (xy 361.600927 -221.922404) (xy 361.608689 -221.872329) (xy 361.624019 -221.824032)
			(xy 361.646558 -221.778648) (xy 361.675774 -221.737246) (xy 361.71098 -221.700802) (xy 361.751348 -221.670172)
			(xy 361.795925 -221.646079) (xy 361.843665 -221.629089) (xy 361.868466 -221.62389) (xy 361.891326 -221.619572)
			(xy 362.096304 -221.26448) (xy 362.088684 -221.242382) (xy 362.080164 -221.216211) (xy 362.070971 -221.161949)
			(xy 362.070396 -221.134432) (xy 362.070396 -221.133924) (xy 362.070904 -221.108037) (xy 362.079003 -221.056899)
			(xy 362.095002 -221.007659) (xy 362.118508 -220.961527) (xy 362.14894 -220.91964) (xy 362.18555 -220.88303)
			(xy 362.227437 -220.852598) (xy 362.273569 -220.829092) (xy 362.322809 -220.813093) (xy 362.373947 -220.804994)
			(xy 362.425721 -220.804994) (xy 362.476859 -220.813093) (xy 362.526099 -220.829092) (xy 362.572231 -220.852598)
			(xy 362.614118 -220.88303) (xy 362.650728 -220.91964) (xy 362.68116 -220.961527) (xy 362.704666 -221.007659)
			(xy 362.720665 -221.056899) (xy 362.728764 -221.108037) (xy 362.729272 -221.133924) (xy 362.728879 -221.159291)
			(xy 362.721126 -221.209429) (xy 362.705775 -221.257784) (xy 362.683191 -221.303213) (xy 362.653906 -221.344642)
			(xy 362.618615 -221.381089) (xy 362.578152 -221.411694) (xy 362.533474 -221.435731) (xy 362.485638 -221.452632)
			(xy 362.460794 -221.457774) (xy 362.437934 -221.462092) (xy 362.23321 -221.81693) (xy 362.241084 -221.838774)
			(xy 362.249681 -221.865188) (xy 362.258866 -221.919967) (xy 362.259372 -221.94774) (xy 363.479588 -221.94774)
			(xy 363.480065 -221.922395) (xy 363.487845 -221.872306) (xy 363.503197 -221.823996) (xy 363.52576 -221.778605)
			(xy 363.555003 -221.7372) (xy 363.590237 -221.700757) (xy 363.630631 -221.670134) (xy 363.675236 -221.646052)
			(xy 363.722999 -221.629078) (xy 363.747812 -221.62389) (xy 363.770672 -221.619572) (xy 363.975904 -221.264226)
			(xy 363.96803 -221.242128) (xy 363.959565 -221.215883) (xy 363.950493 -221.161495) (xy 363.949996 -221.133924)
			(xy 363.950504 -221.108037) (xy 363.958603 -221.056899) (xy 363.974602 -221.007659) (xy 363.998108 -220.961527)
			(xy 364.02854 -220.91964) (xy 364.06515 -220.88303) (xy 364.107037 -220.852598) (xy 364.153169 -220.829092)
			(xy 364.202409 -220.813093) (xy 364.253547 -220.804994) (xy 364.305321 -220.804994) (xy 364.356459 -220.813093)
			(xy 364.405699 -220.829092) (xy 364.451831 -220.852598) (xy 364.493718 -220.88303) (xy 364.530328 -220.91964)
			(xy 364.56076 -220.961527) (xy 364.584266 -221.007659) (xy 364.600265 -221.056899) (xy 364.608364 -221.108037)
			(xy 364.608872 -221.133924) (xy 364.608442 -221.1593) (xy 364.600669 -221.209454) (xy 364.585296 -221.257821)
			(xy 364.562686 -221.303259) (xy 364.533374 -221.344691) (xy 364.498055 -221.381137) (xy 364.457563 -221.411734)
			(xy 364.412858 -221.435759) (xy 364.364996 -221.452643) (xy 364.34014 -221.457774) (xy 364.31728 -221.462092)
			(xy 364.112556 -221.81693) (xy 364.12043 -221.838774) (xy 364.129086 -221.865179) (xy 364.1384 -221.919958)
			(xy 364.138972 -221.94774) (xy 365.359188 -221.94774) (xy 365.359665 -221.922395) (xy 365.367445 -221.872306)
			(xy 365.382797 -221.823996) (xy 365.40536 -221.778605) (xy 365.434603 -221.7372) (xy 365.469837 -221.700757)
			(xy 365.510231 -221.670134) (xy 365.554836 -221.646052) (xy 365.602599 -221.629078) (xy 365.627412 -221.62389)
			(xy 365.650272 -221.619572) (xy 365.855504 -221.264226) (xy 365.84763 -221.242128) (xy 365.839165 -221.215883)
			(xy 365.830093 -221.161495) (xy 365.829596 -221.133924) (xy 365.830104 -221.108037) (xy 365.838203 -221.056899)
			(xy 365.854202 -221.007659) (xy 365.877708 -220.961527) (xy 365.90814 -220.91964) (xy 365.94475 -220.88303)
			(xy 365.986637 -220.852598) (xy 366.032769 -220.829092) (xy 366.082009 -220.813093) (xy 366.133147 -220.804994)
			(xy 366.184921 -220.804994) (xy 366.236059 -220.813093) (xy 366.285299 -220.829092) (xy 366.331431 -220.852598)
			(xy 366.373318 -220.88303) (xy 366.409928 -220.91964) (xy 366.44036 -220.961527) (xy 366.463866 -221.007659)
			(xy 366.479865 -221.056899) (xy 366.487964 -221.108037) (xy 366.488472 -221.133924) (xy 366.488042 -221.1593)
			(xy 366.480269 -221.209454) (xy 366.464896 -221.257821) (xy 366.442286 -221.303259) (xy 366.412974 -221.344691)
			(xy 366.377655 -221.381137) (xy 366.337163 -221.411734) (xy 366.292458 -221.435759) (xy 366.244596 -221.452643)
			(xy 366.21974 -221.457774) (xy 366.19688 -221.462092) (xy 365.992156 -221.81693) (xy 366.00003 -221.838774)
			(xy 366.008686 -221.865179) (xy 366.018 -221.919958) (xy 366.018572 -221.94774) (xy 369.118388 -221.94774)
			(xy 369.118865 -221.922395) (xy 369.126645 -221.872306) (xy 369.141997 -221.823996) (xy 369.16456 -221.778605)
			(xy 369.193803 -221.7372) (xy 369.229037 -221.700757) (xy 369.269431 -221.670134) (xy 369.314036 -221.646052)
			(xy 369.361799 -221.629078) (xy 369.386612 -221.62389) (xy 369.409472 -221.619572) (xy 369.614704 -221.264226)
			(xy 369.60683 -221.242128) (xy 369.598365 -221.215883) (xy 369.589293 -221.161495) (xy 369.588796 -221.133924)
			(xy 369.589304 -221.108037) (xy 369.597403 -221.056899) (xy 369.613402 -221.007659) (xy 369.636908 -220.961527)
			(xy 369.66734 -220.91964) (xy 369.70395 -220.88303) (xy 369.745837 -220.852598) (xy 369.791969 -220.829092)
			(xy 369.841209 -220.813093) (xy 369.892347 -220.804994) (xy 369.944121 -220.804994) (xy 369.995259 -220.813093)
			(xy 370.044499 -220.829092) (xy 370.090631 -220.852598) (xy 370.132518 -220.88303) (xy 370.169128 -220.91964)
			(xy 370.19956 -220.961527) (xy 370.223066 -221.007659) (xy 370.239065 -221.056899) (xy 370.247164 -221.108037)
			(xy 370.247672 -221.133924) (xy 370.247242 -221.1593) (xy 370.239469 -221.209454) (xy 370.224096 -221.257821)
			(xy 370.201486 -221.303259) (xy 370.172174 -221.344691) (xy 370.136855 -221.381137) (xy 370.096363 -221.411734)
			(xy 370.051658 -221.435759) (xy 370.003796 -221.452643) (xy 369.97894 -221.457774) (xy 369.95608 -221.462092)
			(xy 369.751356 -221.81693) (xy 369.75923 -221.838774) (xy 369.767886 -221.865179) (xy 369.7772 -221.919958)
			(xy 369.777772 -221.94774) (xy 370.997988 -221.94774) (xy 370.998465 -221.922395) (xy 371.006245 -221.872306)
			(xy 371.021597 -221.823996) (xy 371.04416 -221.778605) (xy 371.073403 -221.7372) (xy 371.108637 -221.700757)
			(xy 371.149031 -221.670134) (xy 371.193636 -221.646052) (xy 371.241399 -221.629078) (xy 371.266212 -221.62389)
			(xy 371.289072 -221.619572) (xy 371.494304 -221.264226) (xy 371.48643 -221.242128) (xy 371.477965 -221.215883)
			(xy 371.468893 -221.161495) (xy 371.468396 -221.133924) (xy 371.468904 -221.108037) (xy 371.477003 -221.056899)
			(xy 371.493002 -221.007659) (xy 371.516508 -220.961527) (xy 371.54694 -220.91964) (xy 371.58355 -220.88303)
			(xy 371.625437 -220.852598) (xy 371.671569 -220.829092) (xy 371.720809 -220.813093) (xy 371.771947 -220.804994)
			(xy 371.823721 -220.804994) (xy 371.874859 -220.813093) (xy 371.924099 -220.829092) (xy 371.970231 -220.852598)
			(xy 372.012118 -220.88303) (xy 372.048728 -220.91964) (xy 372.07916 -220.961527) (xy 372.102666 -221.007659)
			(xy 372.118665 -221.056899) (xy 372.126764 -221.108037) (xy 372.127272 -221.133924) (xy 372.126842 -221.1593)
			(xy 372.119069 -221.209454) (xy 372.103696 -221.257821) (xy 372.081086 -221.303259) (xy 372.051774 -221.344691)
			(xy 372.016455 -221.381137) (xy 371.975963 -221.411734) (xy 371.931258 -221.435759) (xy 371.883396 -221.452643)
			(xy 371.85854 -221.457774) (xy 371.83568 -221.462092) (xy 371.630956 -221.81693) (xy 371.63883 -221.838774)
			(xy 371.647486 -221.865179) (xy 371.6568 -221.919958) (xy 371.657372 -221.94774) (xy 372.877588 -221.94774)
			(xy 372.878065 -221.922395) (xy 372.885845 -221.872306) (xy 372.901197 -221.823996) (xy 372.92376 -221.778605)
			(xy 372.953003 -221.7372) (xy 372.988237 -221.700757) (xy 373.028631 -221.670134) (xy 373.073236 -221.646052)
			(xy 373.120999 -221.629078) (xy 373.145812 -221.62389) (xy 373.168672 -221.619572) (xy 373.373904 -221.264226)
			(xy 373.36603 -221.242128) (xy 373.357565 -221.215883) (xy 373.348493 -221.161495) (xy 373.347996 -221.133924)
			(xy 373.348504 -221.108037) (xy 373.356603 -221.056899) (xy 373.372602 -221.007659) (xy 373.396108 -220.961527)
			(xy 373.42654 -220.91964) (xy 373.46315 -220.88303) (xy 373.505037 -220.852598) (xy 373.551169 -220.829092)
			(xy 373.600409 -220.813093) (xy 373.651547 -220.804994) (xy 373.703321 -220.804994) (xy 373.754459 -220.813093)
			(xy 373.803699 -220.829092) (xy 373.849831 -220.852598) (xy 373.891718 -220.88303) (xy 373.928328 -220.91964)
			(xy 373.95876 -220.961527) (xy 373.982266 -221.007659) (xy 373.998265 -221.056899) (xy 374.006364 -221.108037)
			(xy 374.006872 -221.133924) (xy 374.006442 -221.1593) (xy 373.998669 -221.209454) (xy 373.983296 -221.257821)
			(xy 373.960686 -221.303259) (xy 373.931374 -221.344691) (xy 373.896055 -221.381137) (xy 373.855563 -221.411734)
			(xy 373.810858 -221.435759) (xy 373.762996 -221.452643) (xy 373.73814 -221.457774) (xy 373.71528 -221.462092)
			(xy 373.510556 -221.81693) (xy 373.51843 -221.838774) (xy 373.527086 -221.865179) (xy 373.5364 -221.919958)
			(xy 373.536972 -221.94774) (xy 374.757188 -221.94774) (xy 374.757665 -221.922395) (xy 374.765445 -221.872306)
			(xy 374.780797 -221.823996) (xy 374.80336 -221.778605) (xy 374.832603 -221.7372) (xy 374.867837 -221.700757)
			(xy 374.908231 -221.670134) (xy 374.952836 -221.646052) (xy 375.000599 -221.629078) (xy 375.025412 -221.62389)
			(xy 375.048272 -221.619572) (xy 375.253504 -221.264226) (xy 375.24563 -221.242128) (xy 375.237165 -221.215883)
			(xy 375.228093 -221.161495) (xy 375.227596 -221.133924) (xy 375.228104 -221.108037) (xy 375.236203 -221.056899)
			(xy 375.252202 -221.007659) (xy 375.275708 -220.961527) (xy 375.30614 -220.91964) (xy 375.34275 -220.88303)
			(xy 375.384637 -220.852598) (xy 375.430769 -220.829092) (xy 375.480009 -220.813093) (xy 375.531147 -220.804994)
			(xy 375.582921 -220.804994) (xy 375.634059 -220.813093) (xy 375.683299 -220.829092) (xy 375.729431 -220.852598)
			(xy 375.771318 -220.88303) (xy 375.807928 -220.91964) (xy 375.83836 -220.961527) (xy 375.861866 -221.007659)
			(xy 375.877865 -221.056899) (xy 375.885964 -221.108037) (xy 375.886472 -221.133924) (xy 375.886042 -221.1593)
			(xy 375.878269 -221.209454) (xy 375.862896 -221.257821) (xy 375.840286 -221.303259) (xy 375.810974 -221.344691)
			(xy 375.775655 -221.381137) (xy 375.735163 -221.411734) (xy 375.690458 -221.435759) (xy 375.642596 -221.452643)
			(xy 375.61774 -221.457774) (xy 375.59488 -221.462092) (xy 375.390156 -221.81693) (xy 375.39803 -221.838774)
			(xy 375.406686 -221.865179) (xy 375.416 -221.919958) (xy 375.416572 -221.94774) (xy 376.636788 -221.94774)
			(xy 376.637265 -221.922395) (xy 376.645045 -221.872306) (xy 376.660397 -221.823996) (xy 376.68296 -221.778605)
			(xy 376.712203 -221.7372) (xy 376.747437 -221.700757) (xy 376.787831 -221.670134) (xy 376.832436 -221.646052)
			(xy 376.880199 -221.629078) (xy 376.905012 -221.62389) (xy 376.927872 -221.619572) (xy 377.133104 -221.264226)
			(xy 377.12523 -221.242128) (xy 377.116765 -221.215883) (xy 377.107693 -221.161495) (xy 377.107196 -221.133924)
			(xy 377.107704 -221.108037) (xy 377.115803 -221.056899) (xy 377.131802 -221.007659) (xy 377.155308 -220.961527)
			(xy 377.18574 -220.91964) (xy 377.22235 -220.88303) (xy 377.264237 -220.852598) (xy 377.310369 -220.829092)
			(xy 377.359609 -220.813093) (xy 377.410747 -220.804994) (xy 377.462521 -220.804994) (xy 377.513659 -220.813093)
			(xy 377.562899 -220.829092) (xy 377.609031 -220.852598) (xy 377.650918 -220.88303) (xy 377.687528 -220.91964)
			(xy 377.71796 -220.961527) (xy 377.741466 -221.007659) (xy 377.757465 -221.056899) (xy 377.765564 -221.108037)
			(xy 377.766072 -221.133924) (xy 377.765642 -221.1593) (xy 377.757869 -221.209454) (xy 377.742496 -221.257821)
			(xy 377.719886 -221.303259) (xy 377.690574 -221.344691) (xy 377.655255 -221.381137) (xy 377.614763 -221.411734)
			(xy 377.570058 -221.435759) (xy 377.522196 -221.452643) (xy 377.49734 -221.457774) (xy 377.47448 -221.462092)
			(xy 377.269756 -221.81693) (xy 377.27763 -221.838774) (xy 377.286286 -221.865179) (xy 377.2956 -221.919958)
			(xy 377.296172 -221.94774) (xy 378.516388 -221.94774) (xy 378.516865 -221.922395) (xy 378.524645 -221.872306)
			(xy 378.539997 -221.823996) (xy 378.56256 -221.778605) (xy 378.591803 -221.7372) (xy 378.627037 -221.700757)
			(xy 378.667431 -221.670134) (xy 378.712036 -221.646052) (xy 378.759799 -221.629078) (xy 378.784612 -221.62389)
			(xy 378.807472 -221.619572) (xy 379.012704 -221.264226) (xy 379.00483 -221.242128) (xy 378.996365 -221.215883)
			(xy 378.987293 -221.161495) (xy 378.986796 -221.133924) (xy 378.987304 -221.108037) (xy 378.995403 -221.056899)
			(xy 379.011402 -221.007659) (xy 379.034908 -220.961527) (xy 379.06534 -220.91964) (xy 379.10195 -220.88303)
			(xy 379.143837 -220.852598) (xy 379.189969 -220.829092) (xy 379.239209 -220.813093) (xy 379.290347 -220.804994)
			(xy 379.342121 -220.804994) (xy 379.393259 -220.813093) (xy 379.442499 -220.829092) (xy 379.488631 -220.852598)
			(xy 379.530518 -220.88303) (xy 379.567128 -220.91964) (xy 379.59756 -220.961527) (xy 379.621066 -221.007659)
			(xy 379.637065 -221.056899) (xy 379.645164 -221.108037) (xy 379.645672 -221.133924) (xy 379.645242 -221.1593)
			(xy 379.637469 -221.209454) (xy 379.622096 -221.257821) (xy 379.599486 -221.303259) (xy 379.570174 -221.344691)
			(xy 379.534855 -221.381137) (xy 379.494363 -221.411734) (xy 379.449658 -221.435759) (xy 379.401796 -221.452643)
			(xy 379.37694 -221.457774) (xy 379.35408 -221.462092) (xy 379.149356 -221.81693) (xy 379.15723 -221.838774)
			(xy 379.165886 -221.865179) (xy 379.1752 -221.919958) (xy 379.175772 -221.94774) (xy 380.395988 -221.94774)
			(xy 380.396465 -221.922395) (xy 380.404245 -221.872306) (xy 380.419597 -221.823996) (xy 380.44216 -221.778605)
			(xy 380.471403 -221.7372) (xy 380.506637 -221.700757) (xy 380.547031 -221.670134) (xy 380.591636 -221.646052)
			(xy 380.639399 -221.629078) (xy 380.664212 -221.62389) (xy 380.687072 -221.619572) (xy 380.89205 -221.263972)
			(xy 380.88443 -221.242128) (xy 380.875981 -221.215945) (xy 380.866909 -221.161685) (xy 380.866396 -221.134178)
			(xy 380.866396 -221.133924) (xy 380.866904 -221.108037) (xy 380.875003 -221.056899) (xy 380.891002 -221.007659)
			(xy 380.914508 -220.961527) (xy 380.94494 -220.91964) (xy 380.98155 -220.88303) (xy 381.023437 -220.852598)
			(xy 381.069569 -220.829092) (xy 381.118809 -220.813093) (xy 381.169947 -220.804994) (xy 381.221721 -220.804994)
			(xy 381.272859 -220.813093) (xy 381.322099 -220.829092) (xy 381.368231 -220.852598) (xy 381.410118 -220.88303)
			(xy 381.446728 -220.91964) (xy 381.47716 -220.961527) (xy 381.500666 -221.007659) (xy 381.516665 -221.056899)
			(xy 381.524764 -221.108037) (xy 381.525272 -221.133924) (xy 381.524879 -221.159291) (xy 381.517126 -221.209429)
			(xy 381.501775 -221.257784) (xy 381.479191 -221.303213) (xy 381.449906 -221.344642) (xy 381.414615 -221.381089)
			(xy 381.374152 -221.411694) (xy 381.329474 -221.435731) (xy 381.281638 -221.452632) (xy 381.256794 -221.457774)
			(xy 381.233934 -221.462092) (xy 381.02921 -221.81693) (xy 381.03683 -221.838774) (xy 381.045444 -221.865059)
			(xy 381.054766 -221.919578) (xy 381.055372 -221.947232) (xy 381.055372 -221.94774) (xy 382.275588 -221.94774)
			(xy 382.276065 -221.922395) (xy 382.283845 -221.872306) (xy 382.299197 -221.823996) (xy 382.32176 -221.778605)
			(xy 382.351003 -221.7372) (xy 382.386237 -221.700757) (xy 382.426631 -221.670134) (xy 382.471236 -221.646052)
			(xy 382.518999 -221.629078) (xy 382.543812 -221.62389) (xy 382.566672 -221.619572) (xy 382.77165 -221.263972)
			(xy 382.76403 -221.242128) (xy 382.755581 -221.215945) (xy 382.746509 -221.161685) (xy 382.745996 -221.134178)
			(xy 382.745996 -221.133924) (xy 382.746504 -221.108037) (xy 382.754603 -221.056899) (xy 382.770602 -221.007659)
			(xy 382.794108 -220.961527) (xy 382.82454 -220.91964) (xy 382.86115 -220.88303) (xy 382.903037 -220.852598)
			(xy 382.949169 -220.829092) (xy 382.998409 -220.813093) (xy 383.049547 -220.804994) (xy 383.101321 -220.804994)
			(xy 383.152459 -220.813093) (xy 383.201699 -220.829092) (xy 383.247831 -220.852598) (xy 383.289718 -220.88303)
			(xy 383.326328 -220.91964) (xy 383.35676 -220.961527) (xy 383.380266 -221.007659) (xy 383.396265 -221.056899)
			(xy 383.404364 -221.108037) (xy 383.404872 -221.133924) (xy 383.404479 -221.159291) (xy 383.396726 -221.209429)
			(xy 383.381375 -221.257784) (xy 383.358791 -221.303213) (xy 383.329506 -221.344642) (xy 383.294215 -221.381089)
			(xy 383.253752 -221.411694) (xy 383.209074 -221.435731) (xy 383.161238 -221.452632) (xy 383.136394 -221.457774)
			(xy 383.113534 -221.462092) (xy 382.90881 -221.81693) (xy 382.91643 -221.838774) (xy 382.925044 -221.865059)
			(xy 382.934366 -221.919578) (xy 382.934972 -221.947232) (xy 382.934972 -221.94774) (xy 382.934464 -221.973647)
			(xy 382.926358 -222.024824) (xy 382.910346 -222.074103) (xy 382.886823 -222.12027) (xy 382.856367 -222.162189)
			(xy 382.819729 -222.198827) (xy 382.77781 -222.229283) (xy 382.731643 -222.252806) (xy 382.682364 -222.268818)
			(xy 382.631187 -222.276924) (xy 382.579373 -222.276924) (xy 382.528196 -222.268818) (xy 382.478917 -222.252806)
			(xy 382.43275 -222.229283) (xy 382.390831 -222.198827) (xy 382.354193 -222.162189) (xy 382.323737 -222.12027)
			(xy 382.300214 -222.074103) (xy 382.284202 -222.024824) (xy 382.276096 -221.973647) (xy 382.275588 -221.94774)
			(xy 381.055372 -221.94774) (xy 381.054864 -221.973647) (xy 381.046758 -222.024824) (xy 381.030746 -222.074103)
			(xy 381.007223 -222.12027) (xy 380.976767 -222.162189) (xy 380.940129 -222.198827) (xy 380.89821 -222.229283)
			(xy 380.852043 -222.252806) (xy 380.802764 -222.268818) (xy 380.751587 -222.276924) (xy 380.699773 -222.276924)
			(xy 380.648596 -222.268818) (xy 380.599317 -222.252806) (xy 380.55315 -222.229283) (xy 380.511231 -222.198827)
			(xy 380.474593 -222.162189) (xy 380.444137 -222.12027) (xy 380.420614 -222.074103) (xy 380.404602 -222.024824)
			(xy 380.396496 -221.973647) (xy 380.395988 -221.94774) (xy 379.175772 -221.94774) (xy 379.175264 -221.973647)
			(xy 379.167158 -222.024824) (xy 379.151146 -222.074103) (xy 379.127623 -222.12027) (xy 379.097167 -222.162189)
			(xy 379.060529 -222.198827) (xy 379.01861 -222.229283) (xy 378.972443 -222.252806) (xy 378.923164 -222.268818)
			(xy 378.871987 -222.276924) (xy 378.820173 -222.276924) (xy 378.768996 -222.268818) (xy 378.719717 -222.252806)
			(xy 378.67355 -222.229283) (xy 378.631631 -222.198827) (xy 378.594993 -222.162189) (xy 378.564537 -222.12027)
			(xy 378.541014 -222.074103) (xy 378.525002 -222.024824) (xy 378.516896 -221.973647) (xy 378.516388 -221.94774)
			(xy 377.296172 -221.94774) (xy 377.295664 -221.973647) (xy 377.287558 -222.024824) (xy 377.271546 -222.074103)
			(xy 377.248023 -222.12027) (xy 377.217567 -222.162189) (xy 377.180929 -222.198827) (xy 377.13901 -222.229283)
			(xy 377.092843 -222.252806) (xy 377.043564 -222.268818) (xy 376.992387 -222.276924) (xy 376.940573 -222.276924)
			(xy 376.889396 -222.268818) (xy 376.840117 -222.252806) (xy 376.79395 -222.229283) (xy 376.752031 -222.198827)
			(xy 376.715393 -222.162189) (xy 376.684937 -222.12027) (xy 376.661414 -222.074103) (xy 376.645402 -222.024824)
			(xy 376.637296 -221.973647) (xy 376.636788 -221.94774) (xy 375.416572 -221.94774) (xy 375.416064 -221.973647)
			(xy 375.407958 -222.024824) (xy 375.391946 -222.074103) (xy 375.368423 -222.12027) (xy 375.337967 -222.162189)
			(xy 375.301329 -222.198827) (xy 375.25941 -222.229283) (xy 375.213243 -222.252806) (xy 375.163964 -222.268818)
			(xy 375.112787 -222.276924) (xy 375.060973 -222.276924) (xy 375.009796 -222.268818) (xy 374.960517 -222.252806)
			(xy 374.91435 -222.229283) (xy 374.872431 -222.198827) (xy 374.835793 -222.162189) (xy 374.805337 -222.12027)
			(xy 374.781814 -222.074103) (xy 374.765802 -222.024824) (xy 374.757696 -221.973647) (xy 374.757188 -221.94774)
			(xy 373.536972 -221.94774) (xy 373.536464 -221.973647) (xy 373.528358 -222.024824) (xy 373.512346 -222.074103)
			(xy 373.488823 -222.12027) (xy 373.458367 -222.162189) (xy 373.421729 -222.198827) (xy 373.37981 -222.229283)
			(xy 373.333643 -222.252806) (xy 373.284364 -222.268818) (xy 373.233187 -222.276924) (xy 373.181373 -222.276924)
			(xy 373.130196 -222.268818) (xy 373.080917 -222.252806) (xy 373.03475 -222.229283) (xy 372.992831 -222.198827)
			(xy 372.956193 -222.162189) (xy 372.925737 -222.12027) (xy 372.902214 -222.074103) (xy 372.886202 -222.024824)
			(xy 372.878096 -221.973647) (xy 372.877588 -221.94774) (xy 371.657372 -221.94774) (xy 371.656864 -221.973647)
			(xy 371.648758 -222.024824) (xy 371.632746 -222.074103) (xy 371.609223 -222.12027) (xy 371.578767 -222.162189)
			(xy 371.542129 -222.198827) (xy 371.50021 -222.229283) (xy 371.454043 -222.252806) (xy 371.404764 -222.268818)
			(xy 371.353587 -222.276924) (xy 371.301773 -222.276924) (xy 371.250596 -222.268818) (xy 371.201317 -222.252806)
			(xy 371.15515 -222.229283) (xy 371.113231 -222.198827) (xy 371.076593 -222.162189) (xy 371.046137 -222.12027)
			(xy 371.022614 -222.074103) (xy 371.006602 -222.024824) (xy 370.998496 -221.973647) (xy 370.997988 -221.94774)
			(xy 369.777772 -221.94774) (xy 369.777264 -221.973647) (xy 369.769158 -222.024824) (xy 369.753146 -222.074103)
			(xy 369.729623 -222.12027) (xy 369.699167 -222.162189) (xy 369.662529 -222.198827) (xy 369.62061 -222.229283)
			(xy 369.574443 -222.252806) (xy 369.525164 -222.268818) (xy 369.473987 -222.276924) (xy 369.422173 -222.276924)
			(xy 369.370996 -222.268818) (xy 369.321717 -222.252806) (xy 369.27555 -222.229283) (xy 369.233631 -222.198827)
			(xy 369.196993 -222.162189) (xy 369.166537 -222.12027) (xy 369.143014 -222.074103) (xy 369.127002 -222.024824)
			(xy 369.118896 -221.973647) (xy 369.118388 -221.94774) (xy 366.018572 -221.94774) (xy 366.018064 -221.973647)
			(xy 366.009958 -222.024824) (xy 365.993946 -222.074103) (xy 365.970423 -222.12027) (xy 365.939967 -222.162189)
			(xy 365.903329 -222.198827) (xy 365.86141 -222.229283) (xy 365.815243 -222.252806) (xy 365.765964 -222.268818)
			(xy 365.714787 -222.276924) (xy 365.662973 -222.276924) (xy 365.611796 -222.268818) (xy 365.562517 -222.252806)
			(xy 365.51635 -222.229283) (xy 365.474431 -222.198827) (xy 365.437793 -222.162189) (xy 365.407337 -222.12027)
			(xy 365.383814 -222.074103) (xy 365.367802 -222.024824) (xy 365.359696 -221.973647) (xy 365.359188 -221.94774)
			(xy 364.138972 -221.94774) (xy 364.138464 -221.973647) (xy 364.130358 -222.024824) (xy 364.114346 -222.074103)
			(xy 364.090823 -222.12027) (xy 364.060367 -222.162189) (xy 364.023729 -222.198827) (xy 363.98181 -222.229283)
			(xy 363.935643 -222.252806) (xy 363.886364 -222.268818) (xy 363.835187 -222.276924) (xy 363.783373 -222.276924)
			(xy 363.732196 -222.268818) (xy 363.682917 -222.252806) (xy 363.63675 -222.229283) (xy 363.594831 -222.198827)
			(xy 363.558193 -222.162189) (xy 363.527737 -222.12027) (xy 363.504214 -222.074103) (xy 363.488202 -222.024824)
			(xy 363.480096 -221.973647) (xy 363.479588 -221.94774) (xy 362.259372 -221.94774) (xy 362.258864 -221.973627)
			(xy 362.250765 -222.024765) (xy 362.234766 -222.074005) (xy 362.21126 -222.120137) (xy 362.180828 -222.162024)
			(xy 362.144218 -222.198634) (xy 362.102331 -222.229066) (xy 362.056199 -222.252572) (xy 362.006959 -222.268571)
			(xy 361.955821 -222.27667) (xy 361.904047 -222.27667) (xy 361.852909 -222.268571) (xy 361.803669 -222.252572)
			(xy 361.757537 -222.229066) (xy 361.71565 -222.198634) (xy 361.67904 -222.162024) (xy 361.648608 -222.120137)
			(xy 361.625102 -222.074005) (xy 361.609103 -222.024765) (xy 361.601004 -221.973627) (xy 361.600496 -221.94774)
			(xy 360.379772 -221.94774) (xy 360.379264 -221.973647) (xy 360.371158 -222.024824) (xy 360.355146 -222.074103)
			(xy 360.331623 -222.12027) (xy 360.301167 -222.162189) (xy 360.264529 -222.198827) (xy 360.22261 -222.229283)
			(xy 360.176443 -222.252806) (xy 360.127164 -222.268818) (xy 360.075987 -222.276924) (xy 360.024173 -222.276924)
			(xy 359.972996 -222.268818) (xy 359.923717 -222.252806) (xy 359.87755 -222.229283) (xy 359.835631 -222.198827)
			(xy 359.798993 -222.162189) (xy 359.768537 -222.12027) (xy 359.745014 -222.074103) (xy 359.729002 -222.024824)
			(xy 359.720896 -221.973647) (xy 359.720388 -221.94774) (xy 358.500172 -221.94774) (xy 358.499664 -221.973627)
			(xy 358.491565 -222.024765) (xy 358.475566 -222.074005) (xy 358.45206 -222.120137) (xy 358.421628 -222.162024)
			(xy 358.385018 -222.198634) (xy 358.343131 -222.229066) (xy 358.296999 -222.252572) (xy 358.247759 -222.268571)
			(xy 358.196621 -222.27667) (xy 358.144847 -222.27667) (xy 358.093709 -222.268571) (xy 358.044469 -222.252572)
			(xy 357.998337 -222.229066) (xy 357.95645 -222.198634) (xy 357.91984 -222.162024) (xy 357.889408 -222.120137)
			(xy 357.865902 -222.074005) (xy 357.849903 -222.024765) (xy 357.841804 -221.973627) (xy 357.841296 -221.94774)
			(xy 356.620572 -221.94774) (xy 356.620064 -221.973647) (xy 356.611958 -222.024824) (xy 356.595946 -222.074103)
			(xy 356.572423 -222.12027) (xy 356.541967 -222.162189) (xy 356.505329 -222.198827) (xy 356.46341 -222.229283)
			(xy 356.417243 -222.252806) (xy 356.367964 -222.268818) (xy 356.316787 -222.276924) (xy 356.264973 -222.276924)
			(xy 356.213796 -222.268818) (xy 356.164517 -222.252806) (xy 356.11835 -222.229283) (xy 356.076431 -222.198827)
			(xy 356.039793 -222.162189) (xy 356.009337 -222.12027) (xy 355.985814 -222.074103) (xy 355.969802 -222.024824)
			(xy 355.961696 -221.973647) (xy 355.961188 -221.94774) (xy 354.740972 -221.94774) (xy 354.740464 -221.973647)
			(xy 354.732358 -222.024824) (xy 354.716346 -222.074103) (xy 354.692823 -222.12027) (xy 354.662367 -222.162189)
			(xy 354.625729 -222.198827) (xy 354.58381 -222.229283) (xy 354.537643 -222.252806) (xy 354.488364 -222.268818)
			(xy 354.437187 -222.276924) (xy 354.385373 -222.276924) (xy 354.334196 -222.268818) (xy 354.284917 -222.252806)
			(xy 354.23875 -222.229283) (xy 354.196831 -222.198827) (xy 354.160193 -222.162189) (xy 354.129737 -222.12027)
			(xy 354.106214 -222.074103) (xy 354.090202 -222.024824) (xy 354.082096 -221.973647) (xy 354.081588 -221.94774)
			(xy 352.861372 -221.94774) (xy 352.860864 -221.973647) (xy 352.852758 -222.024824) (xy 352.836746 -222.074103)
			(xy 352.813223 -222.12027) (xy 352.782767 -222.162189) (xy 352.746129 -222.198827) (xy 352.70421 -222.229283)
			(xy 352.658043 -222.252806) (xy 352.608764 -222.268818) (xy 352.557587 -222.276924) (xy 352.505773 -222.276924)
			(xy 352.454596 -222.268818) (xy 352.405317 -222.252806) (xy 352.35915 -222.229283) (xy 352.317231 -222.198827)
			(xy 352.280593 -222.162189) (xy 352.250137 -222.12027) (xy 352.226614 -222.074103) (xy 352.210602 -222.024824)
			(xy 352.202496 -221.973647) (xy 352.201988 -221.94774) (xy 350.981772 -221.94774) (xy 350.981264 -221.973647)
			(xy 350.973158 -222.024824) (xy 350.957146 -222.074103) (xy 350.933623 -222.12027) (xy 350.903167 -222.162189)
			(xy 350.866529 -222.198827) (xy 350.82461 -222.229283) (xy 350.778443 -222.252806) (xy 350.729164 -222.268818)
			(xy 350.677987 -222.276924) (xy 350.626173 -222.276924) (xy 350.574996 -222.268818) (xy 350.525717 -222.252806)
			(xy 350.47955 -222.229283) (xy 350.437631 -222.198827) (xy 350.400993 -222.162189) (xy 350.370537 -222.12027)
			(xy 350.347014 -222.074103) (xy 350.331002 -222.024824) (xy 350.322896 -221.973647) (xy 350.322388 -221.94774)
			(xy 350.322992 -221.920023) (xy 350.332309 -221.865377) (xy 350.34093 -221.839028) (xy 350.348804 -221.81693)
			(xy 350.143826 -221.462092) (xy 350.120966 -221.457774) (xy 350.096166 -221.452574) (xy 350.04843 -221.435583)
			(xy 350.003855 -221.411489) (xy 349.963491 -221.380859) (xy 349.928289 -221.344414) (xy 349.899076 -221.303012)
			(xy 349.876542 -221.257629) (xy 349.861217 -221.209332) (xy 349.853461 -221.159259) (xy 349.852996 -221.133924)
			(xy 349.572072 -221.133924) (xy 349.571564 -221.159811) (xy 349.563465 -221.210949) (xy 349.547466 -221.260189)
			(xy 349.52396 -221.306321) (xy 349.493528 -221.348208) (xy 349.456918 -221.384818) (xy 349.415031 -221.41525)
			(xy 349.368899 -221.438756) (xy 349.319659 -221.454755) (xy 349.268521 -221.462854) (xy 349.216747 -221.462854)
			(xy 349.165609 -221.454755) (xy 349.116369 -221.438756) (xy 349.070237 -221.41525) (xy 349.02835 -221.384818)
			(xy 348.99174 -221.348208) (xy 348.961308 -221.306321) (xy 348.937802 -221.260189) (xy 348.921803 -221.210949)
			(xy 348.913704 -221.159811) (xy 348.913196 -221.133924) (xy 348.632272 -221.133924) (xy 348.631745 -221.161632)
			(xy 348.622548 -221.216279) (xy 348.613984 -221.242636) (xy 348.60611 -221.264734) (xy 348.811088 -221.619572)
			(xy 348.833948 -221.62389) (xy 348.858767 -221.629064) (xy 348.906546 -221.646018) (xy 348.951165 -221.670088)
			(xy 348.991572 -221.700708) (xy 349.026813 -221.737154) (xy 349.056057 -221.778566) (xy 349.078614 -221.823969)
			(xy 349.093952 -221.872291) (xy 349.10171 -221.922391) (xy 349.102172 -221.94774) (xy 349.101664 -221.973647)
			(xy 349.093558 -222.024824) (xy 349.077546 -222.074103) (xy 349.054023 -222.12027) (xy 349.023567 -222.162189)
			(xy 348.986929 -222.198827) (xy 348.94501 -222.229283) (xy 348.898843 -222.252806) (xy 348.849564 -222.268818)
			(xy 348.798387 -222.276924) (xy 348.746573 -222.276924) (xy 348.695396 -222.268818) (xy 348.646117 -222.252806)
			(xy 348.59995 -222.229283) (xy 348.558031 -222.198827) (xy 348.521393 -222.162189) (xy 348.490937 -222.12027)
			(xy 348.467414 -222.074103) (xy 348.451402 -222.024824) (xy 348.443296 -221.973647) (xy 348.442788 -221.94774)
			(xy 348.443392 -221.920023) (xy 348.452709 -221.865377) (xy 348.46133 -221.839028) (xy 348.469204 -221.81693)
			(xy 348.264226 -221.462092) (xy 348.241366 -221.457774) (xy 348.216566 -221.452574) (xy 348.16883 -221.435583)
			(xy 348.124255 -221.411489) (xy 348.083891 -221.380859) (xy 348.048689 -221.344414) (xy 348.019476 -221.303012)
			(xy 347.996942 -221.257629) (xy 347.981617 -221.209332) (xy 347.973861 -221.159259) (xy 347.973396 -221.133924)
			(xy 347.692472 -221.133924) (xy 347.691964 -221.159811) (xy 347.683865 -221.210949) (xy 347.667866 -221.260189)
			(xy 347.64436 -221.306321) (xy 347.613928 -221.348208) (xy 347.577318 -221.384818) (xy 347.535431 -221.41525)
			(xy 347.489299 -221.438756) (xy 347.440059 -221.454755) (xy 347.388921 -221.462854) (xy 347.337147 -221.462854)
			(xy 347.286009 -221.454755) (xy 347.236769 -221.438756) (xy 347.190637 -221.41525) (xy 347.14875 -221.384818)
			(xy 347.11214 -221.348208) (xy 347.081708 -221.306321) (xy 347.058202 -221.260189) (xy 347.042203 -221.210949)
			(xy 347.034104 -221.159811) (xy 347.033596 -221.133924) (xy 346.752672 -221.133924) (xy 346.752145 -221.161632)
			(xy 346.742948 -221.216279) (xy 346.734384 -221.242636) (xy 346.72651 -221.264734) (xy 346.931488 -221.619572)
			(xy 346.954348 -221.62389) (xy 346.979167 -221.629064) (xy 347.026946 -221.646018) (xy 347.071565 -221.670088)
			(xy 347.111972 -221.700708) (xy 347.147213 -221.737154) (xy 347.176457 -221.778566) (xy 347.199014 -221.823969)
			(xy 347.214352 -221.872291) (xy 347.22211 -221.922391) (xy 347.222572 -221.94774) (xy 347.222064 -221.973647)
			(xy 347.213958 -222.024824) (xy 347.197946 -222.074103) (xy 347.174423 -222.12027) (xy 347.143967 -222.162189)
			(xy 347.107329 -222.198827) (xy 347.06541 -222.229283) (xy 347.019243 -222.252806) (xy 346.969964 -222.268818)
			(xy 346.918787 -222.276924) (xy 346.866973 -222.276924) (xy 346.815796 -222.268818) (xy 346.766517 -222.252806)
			(xy 346.72035 -222.229283) (xy 346.678431 -222.198827) (xy 346.641793 -222.162189) (xy 346.611337 -222.12027)
			(xy 346.587814 -222.074103) (xy 346.571802 -222.024824) (xy 346.563696 -221.973647) (xy 346.563188 -221.94774)
			(xy 346.563792 -221.920023) (xy 346.573109 -221.865377) (xy 346.58173 -221.839028) (xy 346.589604 -221.81693)
			(xy 346.384626 -221.462092) (xy 346.361766 -221.457774) (xy 346.336966 -221.452574) (xy 346.28923 -221.435583)
			(xy 346.244655 -221.411489) (xy 346.204291 -221.380859) (xy 346.169089 -221.344414) (xy 346.139876 -221.303012)
			(xy 346.117342 -221.257629) (xy 346.102017 -221.209332) (xy 346.094261 -221.159259) (xy 346.093796 -221.133924)
			(xy 345.812872 -221.133924) (xy 345.812364 -221.159811) (xy 345.804265 -221.210949) (xy 345.788266 -221.260189)
			(xy 345.76476 -221.306321) (xy 345.734328 -221.348208) (xy 345.697718 -221.384818) (xy 345.655831 -221.41525)
			(xy 345.609699 -221.438756) (xy 345.560459 -221.454755) (xy 345.509321 -221.462854) (xy 345.457547 -221.462854)
			(xy 345.406409 -221.454755) (xy 345.357169 -221.438756) (xy 345.311037 -221.41525) (xy 345.26915 -221.384818)
			(xy 345.23254 -221.348208) (xy 345.202108 -221.306321) (xy 345.178602 -221.260189) (xy 345.162603 -221.210949)
			(xy 345.154504 -221.159811) (xy 345.153996 -221.133924) (xy 344.873072 -221.133924) (xy 344.872545 -221.161632)
			(xy 344.863348 -221.216279) (xy 344.854784 -221.242636) (xy 344.84691 -221.264734) (xy 345.051888 -221.619572)
			(xy 345.074748 -221.62389) (xy 345.099567 -221.629064) (xy 345.147346 -221.646018) (xy 345.191965 -221.670088)
			(xy 345.232372 -221.700708) (xy 345.267613 -221.737154) (xy 345.296857 -221.778566) (xy 345.319414 -221.823969)
			(xy 345.334752 -221.872291) (xy 345.34251 -221.922391) (xy 345.342972 -221.94774) (xy 345.342464 -221.973647)
			(xy 345.334358 -222.024824) (xy 345.318346 -222.074103) (xy 345.294823 -222.12027) (xy 345.264367 -222.162189)
			(xy 345.227729 -222.198827) (xy 345.18581 -222.229283) (xy 345.139643 -222.252806) (xy 345.090364 -222.268818)
			(xy 345.039187 -222.276924) (xy 344.987373 -222.276924) (xy 344.936196 -222.268818) (xy 344.886917 -222.252806)
			(xy 344.84075 -222.229283) (xy 344.798831 -222.198827) (xy 344.762193 -222.162189) (xy 344.731737 -222.12027)
			(xy 344.708214 -222.074103) (xy 344.692202 -222.024824) (xy 344.684096 -221.973647) (xy 344.683588 -221.94774)
			(xy 344.684192 -221.920023) (xy 344.693509 -221.865377) (xy 344.70213 -221.839028) (xy 344.710004 -221.81693)
			(xy 344.505026 -221.462092) (xy 344.482166 -221.457774) (xy 344.457366 -221.452574) (xy 344.40963 -221.435583)
			(xy 344.365055 -221.411489) (xy 344.324691 -221.380859) (xy 344.289489 -221.344414) (xy 344.260276 -221.303012)
			(xy 344.237742 -221.257629) (xy 344.222417 -221.209332) (xy 344.214661 -221.159259) (xy 344.214196 -221.133924)
			(xy 343.933272 -221.133924) (xy 343.932764 -221.159811) (xy 343.924665 -221.210949) (xy 343.908666 -221.260189)
			(xy 343.88516 -221.306321) (xy 343.854728 -221.348208) (xy 343.818118 -221.384818) (xy 343.776231 -221.41525)
			(xy 343.730099 -221.438756) (xy 343.680859 -221.454755) (xy 343.629721 -221.462854) (xy 343.577947 -221.462854)
			(xy 343.526809 -221.454755) (xy 343.477569 -221.438756) (xy 343.431437 -221.41525) (xy 343.38955 -221.384818)
			(xy 343.35294 -221.348208) (xy 343.322508 -221.306321) (xy 343.299002 -221.260189) (xy 343.283003 -221.210949)
			(xy 343.274904 -221.159811) (xy 343.274396 -221.133924) (xy 342.993472 -221.133924) (xy 342.992945 -221.161632)
			(xy 342.983748 -221.216279) (xy 342.975184 -221.242636) (xy 342.96731 -221.264734) (xy 343.172288 -221.619572)
			(xy 343.195148 -221.62389) (xy 343.219967 -221.629064) (xy 343.267746 -221.646018) (xy 343.312365 -221.670088)
			(xy 343.352772 -221.700708) (xy 343.388013 -221.737154) (xy 343.417257 -221.778566) (xy 343.439814 -221.823969)
			(xy 343.455152 -221.872291) (xy 343.46291 -221.922391) (xy 343.463372 -221.94774) (xy 343.462864 -221.973647)
			(xy 343.454758 -222.024824) (xy 343.438746 -222.074103) (xy 343.415223 -222.12027) (xy 343.384767 -222.162189)
			(xy 343.348129 -222.198827) (xy 343.30621 -222.229283) (xy 343.260043 -222.252806) (xy 343.210764 -222.268818)
			(xy 343.159587 -222.276924) (xy 343.107773 -222.276924) (xy 343.056596 -222.268818) (xy 343.007317 -222.252806)
			(xy 342.96115 -222.229283) (xy 342.919231 -222.198827) (xy 342.882593 -222.162189) (xy 342.852137 -222.12027)
			(xy 342.828614 -222.074103) (xy 342.812602 -222.024824) (xy 342.804496 -221.973647) (xy 342.803988 -221.94774)
			(xy 342.804592 -221.920023) (xy 342.813909 -221.865377) (xy 342.82253 -221.839028) (xy 342.830404 -221.81693)
			(xy 342.625426 -221.462092) (xy 342.602566 -221.457774) (xy 342.577766 -221.452574) (xy 342.53003 -221.435583)
			(xy 342.485455 -221.411489) (xy 342.445091 -221.380859) (xy 342.409889 -221.344414) (xy 342.380676 -221.303012)
			(xy 342.358142 -221.257629) (xy 342.342817 -221.209332) (xy 342.335061 -221.159259) (xy 342.334596 -221.133924)
			(xy 342.053672 -221.133924) (xy 342.053164 -221.159811) (xy 342.045065 -221.210949) (xy 342.029066 -221.260189)
			(xy 342.00556 -221.306321) (xy 341.975128 -221.348208) (xy 341.938518 -221.384818) (xy 341.896631 -221.41525)
			(xy 341.850499 -221.438756) (xy 341.801259 -221.454755) (xy 341.750121 -221.462854) (xy 341.698347 -221.462854)
			(xy 341.647209 -221.454755) (xy 341.597969 -221.438756) (xy 341.551837 -221.41525) (xy 341.50995 -221.384818)
			(xy 341.47334 -221.348208) (xy 341.442908 -221.306321) (xy 341.419402 -221.260189) (xy 341.403403 -221.210949)
			(xy 341.395304 -221.159811) (xy 341.394796 -221.133924) (xy 341.113872 -221.133924) (xy 341.113345 -221.161632)
			(xy 341.104148 -221.216279) (xy 341.095584 -221.242636) (xy 341.08771 -221.264734) (xy 341.292688 -221.619572)
			(xy 341.315548 -221.62389) (xy 341.340367 -221.629064) (xy 341.388146 -221.646018) (xy 341.432765 -221.670088)
			(xy 341.473172 -221.700708) (xy 341.508413 -221.737154) (xy 341.537657 -221.778566) (xy 341.560214 -221.823969)
			(xy 341.575552 -221.872291) (xy 341.58331 -221.922391) (xy 341.583772 -221.94774) (xy 341.583264 -221.973647)
			(xy 341.575158 -222.024824) (xy 341.559146 -222.074103) (xy 341.535623 -222.12027) (xy 341.505167 -222.162189)
			(xy 341.468529 -222.198827) (xy 341.42661 -222.229283) (xy 341.380443 -222.252806) (xy 341.331164 -222.268818)
			(xy 341.279987 -222.276924) (xy 341.228173 -222.276924) (xy 341.176996 -222.268818) (xy 341.127717 -222.252806)
			(xy 341.08155 -222.229283) (xy 341.039631 -222.198827) (xy 341.002993 -222.162189) (xy 340.972537 -222.12027)
			(xy 340.949014 -222.074103) (xy 340.933002 -222.024824) (xy 340.924896 -221.973647) (xy 340.924388 -221.94774)
			(xy 340.924992 -221.920023) (xy 340.934309 -221.865377) (xy 340.94293 -221.839028) (xy 340.950804 -221.81693)
			(xy 340.745826 -221.462092) (xy 340.722966 -221.457774) (xy 340.698166 -221.452574) (xy 340.65043 -221.435583)
			(xy 340.605855 -221.411489) (xy 340.565491 -221.380859) (xy 340.530289 -221.344414) (xy 340.501076 -221.303012)
			(xy 340.478542 -221.257629) (xy 340.463217 -221.209332) (xy 340.455461 -221.159259) (xy 340.454996 -221.133924)
			(xy 340.174072 -221.133924) (xy 340.173564 -221.159811) (xy 340.165465 -221.210949) (xy 340.149466 -221.260189)
			(xy 340.12596 -221.306321) (xy 340.095528 -221.348208) (xy 340.058918 -221.384818) (xy 340.017031 -221.41525)
			(xy 339.970899 -221.438756) (xy 339.921659 -221.454755) (xy 339.870521 -221.462854) (xy 339.818747 -221.462854)
			(xy 339.767609 -221.454755) (xy 339.718369 -221.438756) (xy 339.672237 -221.41525) (xy 339.63035 -221.384818)
			(xy 339.59374 -221.348208) (xy 339.563308 -221.306321) (xy 339.539802 -221.260189) (xy 339.523803 -221.210949)
			(xy 339.515704 -221.159811) (xy 339.515196 -221.133924) (xy 339.234272 -221.133924) (xy 339.233745 -221.161632)
			(xy 339.224548 -221.216279) (xy 339.215984 -221.242636) (xy 339.20811 -221.264734) (xy 339.413088 -221.619572)
			(xy 339.435948 -221.62389) (xy 339.460767 -221.629064) (xy 339.508546 -221.646018) (xy 339.553165 -221.670088)
			(xy 339.593572 -221.700708) (xy 339.628813 -221.737154) (xy 339.658057 -221.778566) (xy 339.680614 -221.823969)
			(xy 339.695952 -221.872291) (xy 339.70371 -221.922391) (xy 339.704172 -221.94774) (xy 339.703664 -221.973647)
			(xy 339.695558 -222.024824) (xy 339.679546 -222.074103) (xy 339.656023 -222.12027) (xy 339.625567 -222.162189)
			(xy 339.588929 -222.198827) (xy 339.54701 -222.229283) (xy 339.500843 -222.252806) (xy 339.451564 -222.268818)
			(xy 339.400387 -222.276924) (xy 339.348573 -222.276924) (xy 339.297396 -222.268818) (xy 339.248117 -222.252806)
			(xy 339.20195 -222.229283) (xy 339.160031 -222.198827) (xy 339.123393 -222.162189) (xy 339.092937 -222.12027)
			(xy 339.069414 -222.074103) (xy 339.053402 -222.024824) (xy 339.045296 -221.973647) (xy 339.044788 -221.94774)
			(xy 339.045392 -221.920023) (xy 339.054709 -221.865377) (xy 339.06333 -221.839028) (xy 339.071204 -221.81693)
			(xy 338.866226 -221.462092) (xy 338.843366 -221.457774) (xy 338.818566 -221.452574) (xy 338.77083 -221.435583)
			(xy 338.726255 -221.411489) (xy 338.685891 -221.380859) (xy 338.650689 -221.344414) (xy 338.621476 -221.303012)
			(xy 338.598942 -221.257629) (xy 338.583617 -221.209332) (xy 338.575861 -221.159259) (xy 338.575396 -221.133924)
			(xy 338.294472 -221.133924) (xy 338.293964 -221.159811) (xy 338.285865 -221.210949) (xy 338.269866 -221.260189)
			(xy 338.24636 -221.306321) (xy 338.215928 -221.348208) (xy 338.179318 -221.384818) (xy 338.137431 -221.41525)
			(xy 338.091299 -221.438756) (xy 338.042059 -221.454755) (xy 337.990921 -221.462854) (xy 337.939147 -221.462854)
			(xy 337.888009 -221.454755) (xy 337.838769 -221.438756) (xy 337.792637 -221.41525) (xy 337.75075 -221.384818)
			(xy 337.71414 -221.348208) (xy 337.683708 -221.306321) (xy 337.660202 -221.260189) (xy 337.644203 -221.210949)
			(xy 337.636104 -221.159811) (xy 337.635596 -221.133924) (xy 337.354672 -221.133924) (xy 337.354145 -221.161632)
			(xy 337.344948 -221.216279) (xy 337.336384 -221.242636) (xy 337.32851 -221.264734) (xy 337.533488 -221.619572)
			(xy 337.556348 -221.62389) (xy 337.581167 -221.629064) (xy 337.628946 -221.646018) (xy 337.673565 -221.670088)
			(xy 337.713972 -221.700708) (xy 337.749213 -221.737154) (xy 337.778457 -221.778566) (xy 337.801014 -221.823969)
			(xy 337.816352 -221.872291) (xy 337.82411 -221.922391) (xy 337.824572 -221.94774) (xy 337.824064 -221.973647)
			(xy 337.815958 -222.024824) (xy 337.799946 -222.074103) (xy 337.776423 -222.12027) (xy 337.745967 -222.162189)
			(xy 337.709329 -222.198827) (xy 337.66741 -222.229283) (xy 337.621243 -222.252806) (xy 337.571964 -222.268818)
			(xy 337.520787 -222.276924) (xy 337.468973 -222.276924) (xy 337.417796 -222.268818) (xy 337.368517 -222.252806)
			(xy 337.32235 -222.229283) (xy 337.280431 -222.198827) (xy 337.243793 -222.162189) (xy 337.213337 -222.12027)
			(xy 337.189814 -222.074103) (xy 337.173802 -222.024824) (xy 337.165696 -221.973647) (xy 337.165188 -221.94774)
			(xy 337.165792 -221.920023) (xy 337.175109 -221.865377) (xy 337.18373 -221.839028) (xy 337.191604 -221.81693)
			(xy 336.986626 -221.462092) (xy 336.963766 -221.457774) (xy 336.938966 -221.452574) (xy 336.89123 -221.435583)
			(xy 336.846655 -221.411489) (xy 336.806291 -221.380859) (xy 336.771089 -221.344414) (xy 336.741876 -221.303012)
			(xy 336.719342 -221.257629) (xy 336.704017 -221.209332) (xy 336.696261 -221.159259) (xy 336.695796 -221.133924)
			(xy 135.464804 -221.133924) (xy 135.464385 -221.15929) (xy 135.456633 -221.209425) (xy 135.441284 -221.257778)
			(xy 135.418702 -221.303206) (xy 135.389421 -221.344633) (xy 135.354133 -221.381081) (xy 135.313674 -221.411686)
			(xy 135.269 -221.435725) (xy 135.221169 -221.45263) (xy 135.196326 -221.457774) (xy 135.173466 -221.462092)
			(xy 134.968742 -221.81693) (xy 134.976362 -221.838774) (xy 134.984977 -221.865059) (xy 134.994298 -221.919578)
			(xy 134.994904 -221.947232) (xy 134.994904 -221.94774) (xy 134.994396 -221.973647) (xy 134.98629 -222.024824)
			(xy 134.970278 -222.074103) (xy 134.946755 -222.12027) (xy 134.916299 -222.162189) (xy 134.879661 -222.198827)
			(xy 134.837742 -222.229283) (xy 134.791575 -222.252806) (xy 134.742296 -222.268818) (xy 134.691119 -222.276924)
			(xy 134.639305 -222.276924) (xy 134.588128 -222.268818) (xy 134.538849 -222.252806) (xy 134.492682 -222.229283)
			(xy 134.450763 -222.198827) (xy 134.414125 -222.162189) (xy 134.383669 -222.12027) (xy 134.360146 -222.074103)
			(xy 134.344134 -222.024824) (xy 134.336028 -221.973647) (xy 134.33552 -221.94774) (xy 133.115304 -221.94774)
			(xy 133.114796 -221.973647) (xy 133.10669 -222.024824) (xy 133.090678 -222.074103) (xy 133.067155 -222.12027)
			(xy 133.036699 -222.162189) (xy 133.000061 -222.198827) (xy 132.958142 -222.229283) (xy 132.911975 -222.252806)
			(xy 132.862696 -222.268818) (xy 132.811519 -222.276924) (xy 132.759705 -222.276924) (xy 132.708528 -222.268818)
			(xy 132.659249 -222.252806) (xy 132.613082 -222.229283) (xy 132.571163 -222.198827) (xy 132.534525 -222.162189)
			(xy 132.504069 -222.12027) (xy 132.480546 -222.074103) (xy 132.464534 -222.024824) (xy 132.456428 -221.973647)
			(xy 132.45592 -221.94774) (xy 131.235704 -221.94774) (xy 131.235196 -221.973647) (xy 131.22709 -222.024824)
			(xy 131.211078 -222.074103) (xy 131.187555 -222.12027) (xy 131.157099 -222.162189) (xy 131.120461 -222.198827)
			(xy 131.078542 -222.229283) (xy 131.032375 -222.252806) (xy 130.983096 -222.268818) (xy 130.931919 -222.276924)
			(xy 130.880105 -222.276924) (xy 130.828928 -222.268818) (xy 130.779649 -222.252806) (xy 130.733482 -222.229283)
			(xy 130.691563 -222.198827) (xy 130.654925 -222.162189) (xy 130.624469 -222.12027) (xy 130.600946 -222.074103)
			(xy 130.584934 -222.024824) (xy 130.576828 -221.973647) (xy 130.57632 -221.94774) (xy 129.356104 -221.94774)
			(xy 129.355596 -221.973647) (xy 129.34749 -222.024824) (xy 129.331478 -222.074103) (xy 129.307955 -222.12027)
			(xy 129.277499 -222.162189) (xy 129.240861 -222.198827) (xy 129.198942 -222.229283) (xy 129.152775 -222.252806)
			(xy 129.103496 -222.268818) (xy 129.052319 -222.276924) (xy 129.000505 -222.276924) (xy 128.949328 -222.268818)
			(xy 128.900049 -222.252806) (xy 128.853882 -222.229283) (xy 128.811963 -222.198827) (xy 128.775325 -222.162189)
			(xy 128.744869 -222.12027) (xy 128.721346 -222.074103) (xy 128.705334 -222.024824) (xy 128.697228 -221.973647)
			(xy 128.69672 -221.94774) (xy 127.476504 -221.94774) (xy 127.475996 -221.973647) (xy 127.46789 -222.024824)
			(xy 127.451878 -222.074103) (xy 127.428355 -222.12027) (xy 127.397899 -222.162189) (xy 127.361261 -222.198827)
			(xy 127.319342 -222.229283) (xy 127.273175 -222.252806) (xy 127.223896 -222.268818) (xy 127.172719 -222.276924)
			(xy 127.120905 -222.276924) (xy 127.069728 -222.268818) (xy 127.020449 -222.252806) (xy 126.974282 -222.229283)
			(xy 126.932363 -222.198827) (xy 126.895725 -222.162189) (xy 126.865269 -222.12027) (xy 126.841746 -222.074103)
			(xy 126.825734 -222.024824) (xy 126.817628 -221.973647) (xy 126.81712 -221.94774) (xy 125.596904 -221.94774)
			(xy 125.596396 -221.973647) (xy 125.58829 -222.024824) (xy 125.572278 -222.074103) (xy 125.548755 -222.12027)
			(xy 125.518299 -222.162189) (xy 125.481661 -222.198827) (xy 125.439742 -222.229283) (xy 125.393575 -222.252806)
			(xy 125.344296 -222.268818) (xy 125.293119 -222.276924) (xy 125.241305 -222.276924) (xy 125.190128 -222.268818)
			(xy 125.140849 -222.252806) (xy 125.094682 -222.229283) (xy 125.052763 -222.198827) (xy 125.016125 -222.162189)
			(xy 124.985669 -222.12027) (xy 124.962146 -222.074103) (xy 124.946134 -222.024824) (xy 124.938028 -221.973647)
			(xy 124.93752 -221.94774) (xy 123.717304 -221.94774) (xy 123.716796 -221.973647) (xy 123.70869 -222.024824)
			(xy 123.692678 -222.074103) (xy 123.669155 -222.12027) (xy 123.638699 -222.162189) (xy 123.602061 -222.198827)
			(xy 123.560142 -222.229283) (xy 123.513975 -222.252806) (xy 123.464696 -222.268818) (xy 123.413519 -222.276924)
			(xy 123.361705 -222.276924) (xy 123.310528 -222.268818) (xy 123.261249 -222.252806) (xy 123.215082 -222.229283)
			(xy 123.173163 -222.198827) (xy 123.136525 -222.162189) (xy 123.106069 -222.12027) (xy 123.082546 -222.074103)
			(xy 123.066534 -222.024824) (xy 123.058428 -221.973647) (xy 123.05792 -221.94774) (xy 121.837704 -221.94774)
			(xy 121.837196 -221.973647) (xy 121.82909 -222.024824) (xy 121.813078 -222.074103) (xy 121.789555 -222.12027)
			(xy 121.759099 -222.162189) (xy 121.722461 -222.198827) (xy 121.680542 -222.229283) (xy 121.634375 -222.252806)
			(xy 121.585096 -222.268818) (xy 121.533919 -222.276924) (xy 121.482105 -222.276924) (xy 121.430928 -222.268818)
			(xy 121.381649 -222.252806) (xy 121.335482 -222.229283) (xy 121.293563 -222.198827) (xy 121.256925 -222.162189)
			(xy 121.226469 -222.12027) (xy 121.202946 -222.074103) (xy 121.186934 -222.024824) (xy 121.178828 -221.973647)
			(xy 121.17832 -221.94774) (xy 118.078504 -221.94774) (xy 118.077996 -221.973647) (xy 118.06989 -222.024824)
			(xy 118.053878 -222.074103) (xy 118.030355 -222.12027) (xy 117.999899 -222.162189) (xy 117.963261 -222.198827)
			(xy 117.921342 -222.229283) (xy 117.875175 -222.252806) (xy 117.825896 -222.268818) (xy 117.774719 -222.276924)
			(xy 117.722905 -222.276924) (xy 117.671728 -222.268818) (xy 117.622449 -222.252806) (xy 117.576282 -222.229283)
			(xy 117.534363 -222.198827) (xy 117.497725 -222.162189) (xy 117.467269 -222.12027) (xy 117.443746 -222.074103)
			(xy 117.427734 -222.024824) (xy 117.419628 -221.973647) (xy 117.41912 -221.94774) (xy 116.198904 -221.94774)
			(xy 116.198396 -221.973647) (xy 116.19029 -222.024824) (xy 116.174278 -222.074103) (xy 116.150755 -222.12027)
			(xy 116.120299 -222.162189) (xy 116.083661 -222.198827) (xy 116.041742 -222.229283) (xy 115.995575 -222.252806)
			(xy 115.946296 -222.268818) (xy 115.895119 -222.276924) (xy 115.843305 -222.276924) (xy 115.792128 -222.268818)
			(xy 115.742849 -222.252806) (xy 115.696682 -222.229283) (xy 115.654763 -222.198827) (xy 115.618125 -222.162189)
			(xy 115.587669 -222.12027) (xy 115.564146 -222.074103) (xy 115.548134 -222.024824) (xy 115.540028 -221.973647)
			(xy 115.53952 -221.94774) (xy 114.319304 -221.94774) (xy 114.318796 -221.973627) (xy 114.310697 -222.024765)
			(xy 114.294698 -222.074005) (xy 114.271192 -222.120137) (xy 114.24076 -222.162024) (xy 114.20415 -222.198634)
			(xy 114.162263 -222.229066) (xy 114.116131 -222.252572) (xy 114.066891 -222.268571) (xy 114.015753 -222.27667)
			(xy 113.963979 -222.27667) (xy 113.912841 -222.268571) (xy 113.863601 -222.252572) (xy 113.817469 -222.229066)
			(xy 113.775582 -222.198634) (xy 113.738972 -222.162024) (xy 113.70854 -222.120137) (xy 113.685034 -222.074005)
			(xy 113.669035 -222.024765) (xy 113.660936 -221.973627) (xy 113.660428 -221.94774) (xy 112.439704 -221.94774)
			(xy 112.439196 -221.973647) (xy 112.43109 -222.024824) (xy 112.415078 -222.074103) (xy 112.391555 -222.12027)
			(xy 112.361099 -222.162189) (xy 112.324461 -222.198827) (xy 112.282542 -222.229283) (xy 112.236375 -222.252806)
			(xy 112.187096 -222.268818) (xy 112.135919 -222.276924) (xy 112.084105 -222.276924) (xy 112.032928 -222.268818)
			(xy 111.983649 -222.252806) (xy 111.937482 -222.229283) (xy 111.895563 -222.198827) (xy 111.858925 -222.162189)
			(xy 111.828469 -222.12027) (xy 111.804946 -222.074103) (xy 111.788934 -222.024824) (xy 111.780828 -221.973647)
			(xy 111.78032 -221.94774) (xy 110.560104 -221.94774) (xy 110.559596 -221.973627) (xy 110.551497 -222.024765)
			(xy 110.535498 -222.074005) (xy 110.511992 -222.120137) (xy 110.48156 -222.162024) (xy 110.44495 -222.198634)
			(xy 110.403063 -222.229066) (xy 110.356931 -222.252572) (xy 110.307691 -222.268571) (xy 110.256553 -222.27667)
			(xy 110.204779 -222.27667) (xy 110.153641 -222.268571) (xy 110.104401 -222.252572) (xy 110.058269 -222.229066)
			(xy 110.016382 -222.198634) (xy 109.979772 -222.162024) (xy 109.94934 -222.120137) (xy 109.925834 -222.074005)
			(xy 109.909835 -222.024765) (xy 109.901736 -221.973627) (xy 109.901228 -221.94774) (xy 108.680504 -221.94774)
			(xy 108.679996 -221.973647) (xy 108.67189 -222.024824) (xy 108.655878 -222.074103) (xy 108.632355 -222.12027)
			(xy 108.601899 -222.162189) (xy 108.565261 -222.198827) (xy 108.523342 -222.229283) (xy 108.477175 -222.252806)
			(xy 108.427896 -222.268818) (xy 108.376719 -222.276924) (xy 108.324905 -222.276924) (xy 108.273728 -222.268818)
			(xy 108.224449 -222.252806) (xy 108.178282 -222.229283) (xy 108.136363 -222.198827) (xy 108.099725 -222.162189)
			(xy 108.069269 -222.12027) (xy 108.045746 -222.074103) (xy 108.029734 -222.024824) (xy 108.021628 -221.973647)
			(xy 108.02112 -221.94774) (xy 106.800904 -221.94774) (xy 106.800396 -221.973647) (xy 106.79229 -222.024824)
			(xy 106.776278 -222.074103) (xy 106.752755 -222.12027) (xy 106.722299 -222.162189) (xy 106.685661 -222.198827)
			(xy 106.643742 -222.229283) (xy 106.597575 -222.252806) (xy 106.548296 -222.268818) (xy 106.497119 -222.276924)
			(xy 106.445305 -222.276924) (xy 106.394128 -222.268818) (xy 106.344849 -222.252806) (xy 106.298682 -222.229283)
			(xy 106.256763 -222.198827) (xy 106.220125 -222.162189) (xy 106.189669 -222.12027) (xy 106.166146 -222.074103)
			(xy 106.150134 -222.024824) (xy 106.142028 -221.973647) (xy 106.14152 -221.94774) (xy 104.921304 -221.94774)
			(xy 104.920796 -221.973647) (xy 104.91269 -222.024824) (xy 104.896678 -222.074103) (xy 104.873155 -222.12027)
			(xy 104.842699 -222.162189) (xy 104.806061 -222.198827) (xy 104.764142 -222.229283) (xy 104.717975 -222.252806)
			(xy 104.668696 -222.268818) (xy 104.617519 -222.276924) (xy 104.565705 -222.276924) (xy 104.514528 -222.268818)
			(xy 104.465249 -222.252806) (xy 104.419082 -222.229283) (xy 104.377163 -222.198827) (xy 104.340525 -222.162189)
			(xy 104.310069 -222.12027) (xy 104.286546 -222.074103) (xy 104.270534 -222.024824) (xy 104.262428 -221.973647)
			(xy 104.26192 -221.94774) (xy 103.041704 -221.94774) (xy 103.041196 -221.973647) (xy 103.03309 -222.024824)
			(xy 103.017078 -222.074103) (xy 102.993555 -222.12027) (xy 102.963099 -222.162189) (xy 102.926461 -222.198827)
			(xy 102.884542 -222.229283) (xy 102.838375 -222.252806) (xy 102.789096 -222.268818) (xy 102.737919 -222.276924)
			(xy 102.686105 -222.276924) (xy 102.634928 -222.268818) (xy 102.585649 -222.252806) (xy 102.539482 -222.229283)
			(xy 102.497563 -222.198827) (xy 102.460925 -222.162189) (xy 102.430469 -222.12027) (xy 102.406946 -222.074103)
			(xy 102.390934 -222.024824) (xy 102.382828 -221.973647) (xy 102.38232 -221.94774) (xy 102.382923 -221.920023)
			(xy 102.39224 -221.865377) (xy 102.400862 -221.839028) (xy 102.408736 -221.81693) (xy 102.203758 -221.462092)
			(xy 102.180898 -221.457774) (xy 102.156103 -221.45255) (xy 102.108367 -221.435564) (xy 102.063792 -221.411474)
			(xy 102.023427 -221.380847) (xy 101.988224 -221.344405) (xy 101.959011 -221.303006) (xy 101.936476 -221.257625)
			(xy 101.92115 -221.20933) (xy 101.913394 -221.159258) (xy 101.912928 -221.133924) (xy 101.632004 -221.133924)
			(xy 101.631496 -221.159811) (xy 101.623397 -221.210949) (xy 101.607398 -221.260189) (xy 101.583892 -221.306321)
			(xy 101.55346 -221.348208) (xy 101.51685 -221.384818) (xy 101.474963 -221.41525) (xy 101.428831 -221.438756)
			(xy 101.379591 -221.454755) (xy 101.328453 -221.462854) (xy 101.276679 -221.462854) (xy 101.225541 -221.454755)
			(xy 101.176301 -221.438756) (xy 101.130169 -221.41525) (xy 101.088282 -221.384818) (xy 101.051672 -221.348208)
			(xy 101.02124 -221.306321) (xy 100.997734 -221.260189) (xy 100.981735 -221.210949) (xy 100.973636 -221.159811)
			(xy 100.973128 -221.133924) (xy 100.692204 -221.133924) (xy 100.69168 -221.161632) (xy 100.682481 -221.216279)
			(xy 100.673916 -221.242636) (xy 100.666042 -221.264734) (xy 100.87102 -221.619572) (xy 100.89388 -221.62389)
			(xy 100.918705 -221.629041) (xy 100.966483 -221.645999) (xy 101.011102 -221.670074) (xy 101.051507 -221.700696)
			(xy 101.086747 -221.737145) (xy 101.11599 -221.778561) (xy 101.138547 -221.823965) (xy 101.153885 -221.872289)
			(xy 101.161642 -221.92239) (xy 101.162104 -221.94774) (xy 101.161596 -221.973647) (xy 101.15349 -222.024824)
			(xy 101.137478 -222.074103) (xy 101.113955 -222.12027) (xy 101.083499 -222.162189) (xy 101.046861 -222.198827)
			(xy 101.004942 -222.229283) (xy 100.958775 -222.252806) (xy 100.909496 -222.268818) (xy 100.858319 -222.276924)
			(xy 100.806505 -222.276924) (xy 100.755328 -222.268818) (xy 100.706049 -222.252806) (xy 100.659882 -222.229283)
			(xy 100.617963 -222.198827) (xy 100.581325 -222.162189) (xy 100.550869 -222.12027) (xy 100.527346 -222.074103)
			(xy 100.511334 -222.024824) (xy 100.503228 -221.973647) (xy 100.50272 -221.94774) (xy 100.503323 -221.920023)
			(xy 100.51264 -221.865377) (xy 100.521262 -221.839028) (xy 100.529136 -221.81693) (xy 100.324158 -221.462092)
			(xy 100.301298 -221.457774) (xy 100.276503 -221.45255) (xy 100.228767 -221.435564) (xy 100.184192 -221.411474)
			(xy 100.143827 -221.380847) (xy 100.108624 -221.344405) (xy 100.079411 -221.303006) (xy 100.056876 -221.257625)
			(xy 100.04155 -221.20933) (xy 100.033794 -221.159258) (xy 100.033328 -221.133924) (xy 99.752404 -221.133924)
			(xy 99.751896 -221.159811) (xy 99.743797 -221.210949) (xy 99.727798 -221.260189) (xy 99.704292 -221.306321)
			(xy 99.67386 -221.348208) (xy 99.63725 -221.384818) (xy 99.595363 -221.41525) (xy 99.549231 -221.438756)
			(xy 99.499991 -221.454755) (xy 99.448853 -221.462854) (xy 99.397079 -221.462854) (xy 99.345941 -221.454755)
			(xy 99.296701 -221.438756) (xy 99.250569 -221.41525) (xy 99.208682 -221.384818) (xy 99.172072 -221.348208)
			(xy 99.14164 -221.306321) (xy 99.118134 -221.260189) (xy 99.102135 -221.210949) (xy 99.094036 -221.159811)
			(xy 99.093528 -221.133924) (xy 98.812604 -221.133924) (xy 98.81208 -221.161632) (xy 98.802881 -221.216279)
			(xy 98.794316 -221.242636) (xy 98.786442 -221.264734) (xy 98.99142 -221.619572) (xy 99.01428 -221.62389)
			(xy 99.039105 -221.629041) (xy 99.086883 -221.645999) (xy 99.131502 -221.670074) (xy 99.171907 -221.700696)
			(xy 99.207147 -221.737145) (xy 99.23639 -221.778561) (xy 99.258947 -221.823965) (xy 99.274285 -221.872289)
			(xy 99.282042 -221.92239) (xy 99.282504 -221.94774) (xy 99.281996 -221.973647) (xy 99.27389 -222.024824)
			(xy 99.257878 -222.074103) (xy 99.234355 -222.12027) (xy 99.203899 -222.162189) (xy 99.167261 -222.198827)
			(xy 99.125342 -222.229283) (xy 99.079175 -222.252806) (xy 99.029896 -222.268818) (xy 98.978719 -222.276924)
			(xy 98.926905 -222.276924) (xy 98.875728 -222.268818) (xy 98.826449 -222.252806) (xy 98.780282 -222.229283)
			(xy 98.738363 -222.198827) (xy 98.701725 -222.162189) (xy 98.671269 -222.12027) (xy 98.647746 -222.074103)
			(xy 98.631734 -222.024824) (xy 98.623628 -221.973647) (xy 98.62312 -221.94774) (xy 98.623723 -221.920023)
			(xy 98.63304 -221.865377) (xy 98.641662 -221.839028) (xy 98.649536 -221.81693) (xy 98.444558 -221.462092)
			(xy 98.421698 -221.457774) (xy 98.396903 -221.45255) (xy 98.349167 -221.435564) (xy 98.304592 -221.411474)
			(xy 98.264227 -221.380847) (xy 98.229024 -221.344405) (xy 98.199811 -221.303006) (xy 98.177276 -221.257625)
			(xy 98.16195 -221.20933) (xy 98.154194 -221.159258) (xy 98.153728 -221.133924) (xy 97.872804 -221.133924)
			(xy 97.872296 -221.159811) (xy 97.864197 -221.210949) (xy 97.848198 -221.260189) (xy 97.824692 -221.306321)
			(xy 97.79426 -221.348208) (xy 97.75765 -221.384818) (xy 97.715763 -221.41525) (xy 97.669631 -221.438756)
			(xy 97.620391 -221.454755) (xy 97.569253 -221.462854) (xy 97.517479 -221.462854) (xy 97.466341 -221.454755)
			(xy 97.417101 -221.438756) (xy 97.370969 -221.41525) (xy 97.329082 -221.384818) (xy 97.292472 -221.348208)
			(xy 97.26204 -221.306321) (xy 97.238534 -221.260189) (xy 97.222535 -221.210949) (xy 97.214436 -221.159811)
			(xy 97.213928 -221.133924) (xy 96.933004 -221.133924) (xy 96.93248 -221.161632) (xy 96.923281 -221.216279)
			(xy 96.914716 -221.242636) (xy 96.906842 -221.264734) (xy 97.11182 -221.619572) (xy 97.13468 -221.62389)
			(xy 97.159505 -221.629041) (xy 97.207283 -221.645999) (xy 97.251902 -221.670074) (xy 97.292307 -221.700696)
			(xy 97.327547 -221.737145) (xy 97.35679 -221.778561) (xy 97.379347 -221.823965) (xy 97.394685 -221.872289)
			(xy 97.402442 -221.92239) (xy 97.402904 -221.94774) (xy 97.402396 -221.973647) (xy 97.39429 -222.024824)
			(xy 97.378278 -222.074103) (xy 97.354755 -222.12027) (xy 97.324299 -222.162189) (xy 97.287661 -222.198827)
			(xy 97.245742 -222.229283) (xy 97.199575 -222.252806) (xy 97.150296 -222.268818) (xy 97.099119 -222.276924)
			(xy 97.047305 -222.276924) (xy 96.996128 -222.268818) (xy 96.946849 -222.252806) (xy 96.900682 -222.229283)
			(xy 96.858763 -222.198827) (xy 96.822125 -222.162189) (xy 96.791669 -222.12027) (xy 96.768146 -222.074103)
			(xy 96.752134 -222.024824) (xy 96.744028 -221.973647) (xy 96.74352 -221.94774) (xy 96.744123 -221.920023)
			(xy 96.75344 -221.865377) (xy 96.762062 -221.839028) (xy 96.769936 -221.81693) (xy 96.564958 -221.462092)
			(xy 96.542098 -221.457774) (xy 96.517303 -221.45255) (xy 96.469567 -221.435564) (xy 96.424992 -221.411474)
			(xy 96.384627 -221.380847) (xy 96.349424 -221.344405) (xy 96.320211 -221.303006) (xy 96.297676 -221.257625)
			(xy 96.28235 -221.20933) (xy 96.274594 -221.159258) (xy 96.274128 -221.133924) (xy 95.993204 -221.133924)
			(xy 95.992696 -221.159811) (xy 95.984597 -221.210949) (xy 95.968598 -221.260189) (xy 95.945092 -221.306321)
			(xy 95.91466 -221.348208) (xy 95.87805 -221.384818) (xy 95.836163 -221.41525) (xy 95.790031 -221.438756)
			(xy 95.740791 -221.454755) (xy 95.689653 -221.462854) (xy 95.637879 -221.462854) (xy 95.586741 -221.454755)
			(xy 95.537501 -221.438756) (xy 95.491369 -221.41525) (xy 95.449482 -221.384818) (xy 95.412872 -221.348208)
			(xy 95.38244 -221.306321) (xy 95.358934 -221.260189) (xy 95.342935 -221.210949) (xy 95.334836 -221.159811)
			(xy 95.334328 -221.133924) (xy 95.053404 -221.133924) (xy 95.05288 -221.161632) (xy 95.043681 -221.216279)
			(xy 95.035116 -221.242636) (xy 95.027242 -221.264734) (xy 95.23222 -221.619572) (xy 95.25508 -221.62389)
			(xy 95.279905 -221.629041) (xy 95.327683 -221.645999) (xy 95.372302 -221.670074) (xy 95.412707 -221.700696)
			(xy 95.447947 -221.737145) (xy 95.47719 -221.778561) (xy 95.499747 -221.823965) (xy 95.515085 -221.872289)
			(xy 95.522842 -221.92239) (xy 95.523304 -221.94774) (xy 95.522796 -221.973647) (xy 95.51469 -222.024824)
			(xy 95.498678 -222.074103) (xy 95.475155 -222.12027) (xy 95.444699 -222.162189) (xy 95.408061 -222.198827)
			(xy 95.366142 -222.229283) (xy 95.319975 -222.252806) (xy 95.270696 -222.268818) (xy 95.219519 -222.276924)
			(xy 95.167705 -222.276924) (xy 95.116528 -222.268818) (xy 95.067249 -222.252806) (xy 95.021082 -222.229283)
			(xy 94.979163 -222.198827) (xy 94.942525 -222.162189) (xy 94.912069 -222.12027) (xy 94.888546 -222.074103)
			(xy 94.872534 -222.024824) (xy 94.864428 -221.973647) (xy 94.86392 -221.94774) (xy 94.864523 -221.920023)
			(xy 94.87384 -221.865377) (xy 94.882462 -221.839028) (xy 94.890336 -221.81693) (xy 94.685358 -221.462092)
			(xy 94.662498 -221.457774) (xy 94.637703 -221.45255) (xy 94.589967 -221.435564) (xy 94.545392 -221.411474)
			(xy 94.505027 -221.380847) (xy 94.469824 -221.344405) (xy 94.440611 -221.303006) (xy 94.418076 -221.257625)
			(xy 94.40275 -221.20933) (xy 94.394994 -221.159258) (xy 94.394528 -221.133924) (xy 94.113604 -221.133924)
			(xy 94.113096 -221.159811) (xy 94.104997 -221.210949) (xy 94.088998 -221.260189) (xy 94.065492 -221.306321)
			(xy 94.03506 -221.348208) (xy 93.99845 -221.384818) (xy 93.956563 -221.41525) (xy 93.910431 -221.438756)
			(xy 93.861191 -221.454755) (xy 93.810053 -221.462854) (xy 93.758279 -221.462854) (xy 93.707141 -221.454755)
			(xy 93.657901 -221.438756) (xy 93.611769 -221.41525) (xy 93.569882 -221.384818) (xy 93.533272 -221.348208)
			(xy 93.50284 -221.306321) (xy 93.479334 -221.260189) (xy 93.463335 -221.210949) (xy 93.455236 -221.159811)
			(xy 93.454728 -221.133924) (xy 93.173804 -221.133924) (xy 93.17328 -221.161632) (xy 93.164081 -221.216279)
			(xy 93.155516 -221.242636) (xy 93.147642 -221.264734) (xy 93.35262 -221.619572) (xy 93.37548 -221.62389)
			(xy 93.400305 -221.629041) (xy 93.448083 -221.645999) (xy 93.492702 -221.670074) (xy 93.533107 -221.700696)
			(xy 93.568347 -221.737145) (xy 93.59759 -221.778561) (xy 93.620147 -221.823965) (xy 93.635485 -221.872289)
			(xy 93.643242 -221.92239) (xy 93.643704 -221.94774) (xy 93.643196 -221.973647) (xy 93.63509 -222.024824)
			(xy 93.619078 -222.074103) (xy 93.595555 -222.12027) (xy 93.565099 -222.162189) (xy 93.528461 -222.198827)
			(xy 93.486542 -222.229283) (xy 93.440375 -222.252806) (xy 93.391096 -222.268818) (xy 93.339919 -222.276924)
			(xy 93.288105 -222.276924) (xy 93.236928 -222.268818) (xy 93.187649 -222.252806) (xy 93.141482 -222.229283)
			(xy 93.099563 -222.198827) (xy 93.062925 -222.162189) (xy 93.032469 -222.12027) (xy 93.008946 -222.074103)
			(xy 92.992934 -222.024824) (xy 92.984828 -221.973647) (xy 92.98432 -221.94774) (xy 92.984923 -221.920023)
			(xy 92.99424 -221.865377) (xy 93.002862 -221.839028) (xy 93.010736 -221.81693) (xy 92.805758 -221.462092)
			(xy 92.782898 -221.457774) (xy 92.758103 -221.45255) (xy 92.710367 -221.435564) (xy 92.665792 -221.411474)
			(xy 92.625427 -221.380847) (xy 92.590224 -221.344405) (xy 92.561011 -221.303006) (xy 92.538476 -221.257625)
			(xy 92.52315 -221.20933) (xy 92.515394 -221.159258) (xy 92.514928 -221.133924) (xy 92.234004 -221.133924)
			(xy 92.233496 -221.159811) (xy 92.225397 -221.210949) (xy 92.209398 -221.260189) (xy 92.185892 -221.306321)
			(xy 92.15546 -221.348208) (xy 92.11885 -221.384818) (xy 92.076963 -221.41525) (xy 92.030831 -221.438756)
			(xy 91.981591 -221.454755) (xy 91.930453 -221.462854) (xy 91.878679 -221.462854) (xy 91.827541 -221.454755)
			(xy 91.778301 -221.438756) (xy 91.732169 -221.41525) (xy 91.690282 -221.384818) (xy 91.653672 -221.348208)
			(xy 91.62324 -221.306321) (xy 91.599734 -221.260189) (xy 91.583735 -221.210949) (xy 91.575636 -221.159811)
			(xy 91.575128 -221.133924) (xy 91.294204 -221.133924) (xy 91.29368 -221.161632) (xy 91.284481 -221.216279)
			(xy 91.275916 -221.242636) (xy 91.268042 -221.264734) (xy 91.47302 -221.619572) (xy 91.49588 -221.62389)
			(xy 91.520705 -221.629041) (xy 91.568483 -221.645999) (xy 91.613102 -221.670074) (xy 91.653507 -221.700696)
			(xy 91.688747 -221.737145) (xy 91.71799 -221.778561) (xy 91.740547 -221.823965) (xy 91.755885 -221.872289)
			(xy 91.763642 -221.92239) (xy 91.764104 -221.94774) (xy 91.763596 -221.973647) (xy 91.75549 -222.024824)
			(xy 91.739478 -222.074103) (xy 91.715955 -222.12027) (xy 91.685499 -222.162189) (xy 91.648861 -222.198827)
			(xy 91.606942 -222.229283) (xy 91.560775 -222.252806) (xy 91.511496 -222.268818) (xy 91.460319 -222.276924)
			(xy 91.408505 -222.276924) (xy 91.357328 -222.268818) (xy 91.308049 -222.252806) (xy 91.261882 -222.229283)
			(xy 91.219963 -222.198827) (xy 91.183325 -222.162189) (xy 91.152869 -222.12027) (xy 91.129346 -222.074103)
			(xy 91.113334 -222.024824) (xy 91.105228 -221.973647) (xy 91.10472 -221.94774) (xy 91.105323 -221.920023)
			(xy 91.11464 -221.865377) (xy 91.123262 -221.839028) (xy 91.131136 -221.81693) (xy 90.926158 -221.462092)
			(xy 90.903298 -221.457774) (xy 90.878503 -221.45255) (xy 90.830767 -221.435564) (xy 90.786192 -221.411474)
			(xy 90.745827 -221.380847) (xy 90.710624 -221.344405) (xy 90.681411 -221.303006) (xy 90.658876 -221.257625)
			(xy 90.64355 -221.20933) (xy 90.635794 -221.159258) (xy 90.635328 -221.133924) (xy 90.354404 -221.133924)
			(xy 90.353896 -221.159811) (xy 90.345797 -221.210949) (xy 90.329798 -221.260189) (xy 90.306292 -221.306321)
			(xy 90.27586 -221.348208) (xy 90.23925 -221.384818) (xy 90.197363 -221.41525) (xy 90.151231 -221.438756)
			(xy 90.101991 -221.454755) (xy 90.050853 -221.462854) (xy 89.999079 -221.462854) (xy 89.947941 -221.454755)
			(xy 89.898701 -221.438756) (xy 89.852569 -221.41525) (xy 89.810682 -221.384818) (xy 89.774072 -221.348208)
			(xy 89.74364 -221.306321) (xy 89.720134 -221.260189) (xy 89.704135 -221.210949) (xy 89.696036 -221.159811)
			(xy 89.695528 -221.133924) (xy 89.414604 -221.133924) (xy 89.41408 -221.161632) (xy 89.404881 -221.216279)
			(xy 89.396316 -221.242636) (xy 89.388442 -221.264734) (xy 89.59342 -221.619572) (xy 89.61628 -221.62389)
			(xy 89.641105 -221.629041) (xy 89.688883 -221.645999) (xy 89.733502 -221.670074) (xy 89.773907 -221.700696)
			(xy 89.809147 -221.737145) (xy 89.83839 -221.778561) (xy 89.860947 -221.823965) (xy 89.876285 -221.872289)
			(xy 89.884042 -221.92239) (xy 89.884504 -221.94774) (xy 89.883996 -221.973647) (xy 89.87589 -222.024824)
			(xy 89.859878 -222.074103) (xy 89.836355 -222.12027) (xy 89.805899 -222.162189) (xy 89.769261 -222.198827)
			(xy 89.727342 -222.229283) (xy 89.681175 -222.252806) (xy 89.631896 -222.268818) (xy 89.580719 -222.276924)
			(xy 89.528905 -222.276924) (xy 89.477728 -222.268818) (xy 89.428449 -222.252806) (xy 89.382282 -222.229283)
			(xy 89.340363 -222.198827) (xy 89.303725 -222.162189) (xy 89.273269 -222.12027) (xy 89.249746 -222.074103)
			(xy 89.233734 -222.024824) (xy 89.225628 -221.973647) (xy 89.22512 -221.94774) (xy 89.225723 -221.920023)
			(xy 89.23504 -221.865377) (xy 89.243662 -221.839028) (xy 89.251536 -221.81693) (xy 89.046558 -221.462092)
			(xy 89.023698 -221.457774) (xy 88.998903 -221.45255) (xy 88.951167 -221.435564) (xy 88.906592 -221.411474)
			(xy 88.866227 -221.380847) (xy 88.831024 -221.344405) (xy 88.801811 -221.303006) (xy 88.779276 -221.257625)
			(xy 88.76395 -221.20933) (xy 88.756194 -221.159258) (xy 88.755728 -221.133924) (xy 2.509012 -221.133924)
			(xy 2.509012 -224.389442) (xy 89.695528 -224.389442) (xy 89.695935 -224.364105) (xy 89.703697 -224.314028)
			(xy 89.719029 -224.265728) (xy 89.74157 -224.220343) (xy 89.770789 -224.17894) (xy 89.805999 -224.142496)
			(xy 89.84637 -224.111867) (xy 89.890952 -224.087776) (xy 89.938695 -224.070789) (xy 89.963498 -224.065592)
			(xy 89.986358 -224.061274) (xy 90.191082 -223.706182) (xy 90.183462 -223.684338) (xy 90.174817 -223.657995)
			(xy 90.165504 -223.603345) (xy 90.16492 -223.575626) (xy 90.165428 -223.549719) (xy 90.173534 -223.498542)
			(xy 90.189546 -223.449263) (xy 90.213069 -223.403096) (xy 90.243525 -223.361177) (xy 90.280163 -223.324539)
			(xy 90.322082 -223.294083) (xy 90.368249 -223.27056) (xy 90.417528 -223.254548) (xy 90.468705 -223.246442)
			(xy 90.520519 -223.246442) (xy 90.571696 -223.254548) (xy 90.620975 -223.27056) (xy 90.667142 -223.294083)
			(xy 90.709061 -223.324539) (xy 90.745699 -223.361177) (xy 90.776155 -223.403096) (xy 90.799678 -223.449263)
			(xy 90.81569 -223.498542) (xy 90.823796 -223.549719) (xy 90.824304 -223.575626) (xy 90.823803 -223.60097)
			(xy 90.816028 -223.651059) (xy 90.800679 -223.699368) (xy 90.77812 -223.74476) (xy 90.74888 -223.786165)
			(xy 90.713649 -223.822609) (xy 90.673257 -223.853232) (xy 90.628654 -223.877314) (xy 90.580892 -223.894288)
			(xy 90.55608 -223.899476) (xy 90.53322 -223.903794) (xy 90.328496 -224.258632) (xy 90.336116 -224.280476)
			(xy 90.344672 -224.306769) (xy 90.353865 -224.361289) (xy 90.354404 -224.388934) (xy 90.354404 -224.389442)
			(xy 90.635328 -224.389442) (xy 90.635836 -224.363555) (xy 90.643935 -224.312417) (xy 90.659934 -224.263177)
			(xy 90.68344 -224.217045) (xy 90.713872 -224.175158) (xy 90.750482 -224.138548) (xy 90.792369 -224.108116)
			(xy 90.838501 -224.08461) (xy 90.887741 -224.068611) (xy 90.938879 -224.060512) (xy 90.990653 -224.060512)
			(xy 91.041791 -224.068611) (xy 91.091031 -224.08461) (xy 91.137163 -224.108116) (xy 91.17905 -224.138548)
			(xy 91.21566 -224.175158) (xy 91.246092 -224.217045) (xy 91.269598 -224.263177) (xy 91.285597 -224.312417)
			(xy 91.293696 -224.363555) (xy 91.294204 -224.389442) (xy 91.575128 -224.389442) (xy 91.575535 -224.364105)
			(xy 91.583297 -224.314028) (xy 91.598629 -224.265728) (xy 91.62117 -224.220343) (xy 91.650389 -224.17894)
			(xy 91.685599 -224.142496) (xy 91.72597 -224.111867) (xy 91.770552 -224.087776) (xy 91.818295 -224.070789)
			(xy 91.843098 -224.065592) (xy 91.865958 -224.061274) (xy 92.070682 -223.706182) (xy 92.063062 -223.684338)
			(xy 92.054417 -223.657995) (xy 92.045104 -223.603345) (xy 92.04452 -223.575626) (xy 92.045028 -223.549719)
			(xy 92.053134 -223.498542) (xy 92.069146 -223.449263) (xy 92.092669 -223.403096) (xy 92.123125 -223.361177)
			(xy 92.159763 -223.324539) (xy 92.201682 -223.294083) (xy 92.247849 -223.27056) (xy 92.297128 -223.254548)
			(xy 92.348305 -223.246442) (xy 92.400119 -223.246442) (xy 92.451296 -223.254548) (xy 92.500575 -223.27056)
			(xy 92.546742 -223.294083) (xy 92.588661 -223.324539) (xy 92.625299 -223.361177) (xy 92.655755 -223.403096)
			(xy 92.679278 -223.449263) (xy 92.69529 -223.498542) (xy 92.703396 -223.549719) (xy 92.703904 -223.575626)
			(xy 92.703403 -223.60097) (xy 92.695628 -223.651059) (xy 92.680279 -223.699368) (xy 92.65772 -223.74476)
			(xy 92.62848 -223.786165) (xy 92.593249 -223.822609) (xy 92.552857 -223.853232) (xy 92.508254 -223.877314)
			(xy 92.460492 -223.894288) (xy 92.43568 -223.899476) (xy 92.41282 -223.903794) (xy 92.208096 -224.258632)
			(xy 92.215716 -224.280476) (xy 92.224272 -224.306769) (xy 92.233465 -224.361289) (xy 92.234004 -224.388934)
			(xy 92.234004 -224.389442) (xy 92.514928 -224.389442) (xy 92.515436 -224.363555) (xy 92.523535 -224.312417)
			(xy 92.539534 -224.263177) (xy 92.56304 -224.217045) (xy 92.593472 -224.175158) (xy 92.630082 -224.138548)
			(xy 92.671969 -224.108116) (xy 92.718101 -224.08461) (xy 92.767341 -224.068611) (xy 92.818479 -224.060512)
			(xy 92.870253 -224.060512) (xy 92.921391 -224.068611) (xy 92.970631 -224.08461) (xy 93.016763 -224.108116)
			(xy 93.05865 -224.138548) (xy 93.09526 -224.175158) (xy 93.125692 -224.217045) (xy 93.149198 -224.263177)
			(xy 93.165197 -224.312417) (xy 93.173296 -224.363555) (xy 93.173804 -224.389442) (xy 93.454728 -224.389442)
			(xy 93.455135 -224.364105) (xy 93.462897 -224.314028) (xy 93.478229 -224.265728) (xy 93.50077 -224.220343)
			(xy 93.529989 -224.17894) (xy 93.565199 -224.142496) (xy 93.60557 -224.111867) (xy 93.650152 -224.087776)
			(xy 93.697895 -224.070789) (xy 93.722698 -224.065592) (xy 93.745558 -224.061274) (xy 93.950282 -223.706436)
			(xy 93.942662 -223.684338) (xy 93.934031 -223.657991) (xy 93.92471 -223.603344) (xy 93.92412 -223.575626)
			(xy 93.924628 -223.549719) (xy 93.932734 -223.498542) (xy 93.948746 -223.449263) (xy 93.972269 -223.403096)
			(xy 94.002725 -223.361177) (xy 94.039363 -223.324539) (xy 94.081282 -223.294083) (xy 94.127449 -223.27056)
			(xy 94.176728 -223.254548) (xy 94.227905 -223.246442) (xy 94.279719 -223.246442) (xy 94.330896 -223.254548)
			(xy 94.380175 -223.27056) (xy 94.426342 -223.294083) (xy 94.468261 -223.324539) (xy 94.504899 -223.361177)
			(xy 94.535355 -223.403096) (xy 94.558878 -223.449263) (xy 94.57489 -223.498542) (xy 94.582996 -223.549719)
			(xy 94.583504 -223.575626) (xy 94.583087 -223.600992) (xy 94.575334 -223.651127) (xy 94.559985 -223.69948)
			(xy 94.537403 -223.744908) (xy 94.508122 -223.786336) (xy 94.472834 -223.822783) (xy 94.432375 -223.853388)
			(xy 94.387701 -223.877427) (xy 94.339869 -223.894332) (xy 94.315026 -223.899476) (xy 94.292166 -223.903794)
			(xy 94.087442 -224.258632) (xy 94.095316 -224.280476) (xy 94.10389 -224.306896) (xy 94.11309 -224.36167)
			(xy 94.113604 -224.389442) (xy 94.394528 -224.389442) (xy 94.395036 -224.363555) (xy 94.403135 -224.312417)
			(xy 94.419134 -224.263177) (xy 94.44264 -224.217045) (xy 94.473072 -224.175158) (xy 94.509682 -224.138548)
			(xy 94.551569 -224.108116) (xy 94.597701 -224.08461) (xy 94.646941 -224.068611) (xy 94.698079 -224.060512)
			(xy 94.749853 -224.060512) (xy 94.800991 -224.068611) (xy 94.850231 -224.08461) (xy 94.896363 -224.108116)
			(xy 94.93825 -224.138548) (xy 94.97486 -224.175158) (xy 95.005292 -224.217045) (xy 95.028798 -224.263177)
			(xy 95.044797 -224.312417) (xy 95.052896 -224.363555) (xy 95.053404 -224.389442) (xy 95.334328 -224.389442)
			(xy 95.334735 -224.364105) (xy 95.342497 -224.314028) (xy 95.357829 -224.265728) (xy 95.38037 -224.220343)
			(xy 95.409589 -224.17894) (xy 95.444799 -224.142496) (xy 95.48517 -224.111867) (xy 95.529752 -224.087776)
			(xy 95.577495 -224.070789) (xy 95.602298 -224.065592) (xy 95.625158 -224.061274) (xy 95.829882 -223.706436)
			(xy 95.822262 -223.684338) (xy 95.813631 -223.657991) (xy 95.80431 -223.603344) (xy 95.80372 -223.575626)
			(xy 95.804228 -223.549719) (xy 95.812334 -223.498542) (xy 95.828346 -223.449263) (xy 95.851869 -223.403096)
			(xy 95.882325 -223.361177) (xy 95.918963 -223.324539) (xy 95.960882 -223.294083) (xy 96.007049 -223.27056)
			(xy 96.056328 -223.254548) (xy 96.107505 -223.246442) (xy 96.159319 -223.246442) (xy 96.210496 -223.254548)
			(xy 96.259775 -223.27056) (xy 96.305942 -223.294083) (xy 96.347861 -223.324539) (xy 96.384499 -223.361177)
			(xy 96.414955 -223.403096) (xy 96.438478 -223.449263) (xy 96.45449 -223.498542) (xy 96.462596 -223.549719)
			(xy 96.463104 -223.575626) (xy 96.462687 -223.600992) (xy 96.454934 -223.651127) (xy 96.439585 -223.69948)
			(xy 96.417003 -223.744908) (xy 96.387722 -223.786336) (xy 96.352434 -223.822783) (xy 96.311975 -223.853388)
			(xy 96.267301 -223.877427) (xy 96.219469 -223.894332) (xy 96.194626 -223.899476) (xy 96.171766 -223.903794)
			(xy 95.967042 -224.258632) (xy 95.974916 -224.280476) (xy 95.98349 -224.306896) (xy 95.99269 -224.36167)
			(xy 95.993204 -224.389442) (xy 96.274128 -224.389442) (xy 96.274636 -224.363555) (xy 96.282735 -224.312417)
			(xy 96.298734 -224.263177) (xy 96.32224 -224.217045) (xy 96.352672 -224.175158) (xy 96.389282 -224.138548)
			(xy 96.431169 -224.108116) (xy 96.477301 -224.08461) (xy 96.526541 -224.068611) (xy 96.577679 -224.060512)
			(xy 96.629453 -224.060512) (xy 96.680591 -224.068611) (xy 96.729831 -224.08461) (xy 96.775963 -224.108116)
			(xy 96.81785 -224.138548) (xy 96.85446 -224.175158) (xy 96.884892 -224.217045) (xy 96.908398 -224.263177)
			(xy 96.924397 -224.312417) (xy 96.932496 -224.363555) (xy 96.933004 -224.389442) (xy 97.213928 -224.389442)
			(xy 97.214335 -224.364105) (xy 97.222097 -224.314028) (xy 97.237429 -224.265728) (xy 97.25997 -224.220343)
			(xy 97.289189 -224.17894) (xy 97.324399 -224.142496) (xy 97.36477 -224.111867) (xy 97.409352 -224.087776)
			(xy 97.457095 -224.070789) (xy 97.481898 -224.065592) (xy 97.504758 -224.061274) (xy 97.709482 -223.706436)
			(xy 97.701862 -223.684338) (xy 97.693231 -223.657991) (xy 97.68391 -223.603344) (xy 97.68332 -223.575626)
			(xy 97.683828 -223.549719) (xy 97.691934 -223.498542) (xy 97.707946 -223.449263) (xy 97.731469 -223.403096)
			(xy 97.761925 -223.361177) (xy 97.798563 -223.324539) (xy 97.840482 -223.294083) (xy 97.886649 -223.27056)
			(xy 97.935928 -223.254548) (xy 97.987105 -223.246442) (xy 98.038919 -223.246442) (xy 98.090096 -223.254548)
			(xy 98.139375 -223.27056) (xy 98.185542 -223.294083) (xy 98.227461 -223.324539) (xy 98.264099 -223.361177)
			(xy 98.294555 -223.403096) (xy 98.318078 -223.449263) (xy 98.33409 -223.498542) (xy 98.342196 -223.549719)
			(xy 98.342704 -223.575626) (xy 98.342287 -223.600992) (xy 98.334534 -223.651127) (xy 98.319185 -223.69948)
			(xy 98.296603 -223.744908) (xy 98.267322 -223.786336) (xy 98.232034 -223.822783) (xy 98.191575 -223.853388)
			(xy 98.146901 -223.877427) (xy 98.099069 -223.894332) (xy 98.074226 -223.899476) (xy 98.051366 -223.903794)
			(xy 97.846642 -224.258632) (xy 97.854516 -224.280476) (xy 97.86309 -224.306896) (xy 97.87229 -224.36167)
			(xy 97.872804 -224.389442) (xy 98.153728 -224.389442) (xy 98.154236 -224.363555) (xy 98.162335 -224.312417)
			(xy 98.178334 -224.263177) (xy 98.20184 -224.217045) (xy 98.232272 -224.175158) (xy 98.268882 -224.138548)
			(xy 98.310769 -224.108116) (xy 98.356901 -224.08461) (xy 98.406141 -224.068611) (xy 98.457279 -224.060512)
			(xy 98.509053 -224.060512) (xy 98.560191 -224.068611) (xy 98.609431 -224.08461) (xy 98.655563 -224.108116)
			(xy 98.69745 -224.138548) (xy 98.73406 -224.175158) (xy 98.764492 -224.217045) (xy 98.787998 -224.263177)
			(xy 98.803997 -224.312417) (xy 98.812096 -224.363555) (xy 98.812604 -224.389442) (xy 99.093528 -224.389442)
			(xy 99.093935 -224.364105) (xy 99.101697 -224.314028) (xy 99.117029 -224.265728) (xy 99.13957 -224.220343)
			(xy 99.168789 -224.17894) (xy 99.203999 -224.142496) (xy 99.24437 -224.111867) (xy 99.288952 -224.087776)
			(xy 99.336695 -224.070789) (xy 99.361498 -224.065592) (xy 99.384358 -224.061274) (xy 99.589082 -223.706436)
			(xy 99.581462 -223.684338) (xy 99.572831 -223.657991) (xy 99.56351 -223.603344) (xy 99.56292 -223.575626)
			(xy 99.563428 -223.549719) (xy 99.571534 -223.498542) (xy 99.587546 -223.449263) (xy 99.611069 -223.403096)
			(xy 99.641525 -223.361177) (xy 99.678163 -223.324539) (xy 99.720082 -223.294083) (xy 99.766249 -223.27056)
			(xy 99.815528 -223.254548) (xy 99.866705 -223.246442) (xy 99.918519 -223.246442) (xy 99.969696 -223.254548)
			(xy 100.018975 -223.27056) (xy 100.065142 -223.294083) (xy 100.107061 -223.324539) (xy 100.143699 -223.361177)
			(xy 100.174155 -223.403096) (xy 100.197678 -223.449263) (xy 100.21369 -223.498542) (xy 100.221796 -223.549719)
			(xy 100.222304 -223.575626) (xy 100.221887 -223.600992) (xy 100.214134 -223.651127) (xy 100.198785 -223.69948)
			(xy 100.176203 -223.744908) (xy 100.146922 -223.786336) (xy 100.111634 -223.822783) (xy 100.071175 -223.853388)
			(xy 100.026501 -223.877427) (xy 99.978669 -223.894332) (xy 99.953826 -223.899476) (xy 99.930966 -223.903794)
			(xy 99.726242 -224.258632) (xy 99.734116 -224.280476) (xy 99.74269 -224.306896) (xy 99.75189 -224.36167)
			(xy 99.752404 -224.389442) (xy 100.033328 -224.389442) (xy 100.033836 -224.363555) (xy 100.041935 -224.312417)
			(xy 100.057934 -224.263177) (xy 100.08144 -224.217045) (xy 100.111872 -224.175158) (xy 100.148482 -224.138548)
			(xy 100.190369 -224.108116) (xy 100.236501 -224.08461) (xy 100.285741 -224.068611) (xy 100.336879 -224.060512)
			(xy 100.388653 -224.060512) (xy 100.439791 -224.068611) (xy 100.489031 -224.08461) (xy 100.535163 -224.108116)
			(xy 100.57705 -224.138548) (xy 100.61366 -224.175158) (xy 100.644092 -224.217045) (xy 100.667598 -224.263177)
			(xy 100.683597 -224.312417) (xy 100.691696 -224.363555) (xy 100.692204 -224.389442) (xy 100.973128 -224.389442)
			(xy 100.973535 -224.364105) (xy 100.981297 -224.314028) (xy 100.996629 -224.265728) (xy 101.01917 -224.220343)
			(xy 101.048389 -224.17894) (xy 101.083599 -224.142496) (xy 101.12397 -224.111867) (xy 101.168552 -224.087776)
			(xy 101.216295 -224.070789) (xy 101.241098 -224.065592) (xy 101.263958 -224.061274) (xy 101.468682 -223.706436)
			(xy 101.461062 -223.684338) (xy 101.452431 -223.657991) (xy 101.44311 -223.603344) (xy 101.44252 -223.575626)
			(xy 101.443028 -223.549719) (xy 101.451134 -223.498542) (xy 101.467146 -223.449263) (xy 101.490669 -223.403096)
			(xy 101.521125 -223.361177) (xy 101.557763 -223.324539) (xy 101.599682 -223.294083) (xy 101.645849 -223.27056)
			(xy 101.695128 -223.254548) (xy 101.746305 -223.246442) (xy 101.798119 -223.246442) (xy 101.849296 -223.254548)
			(xy 101.898575 -223.27056) (xy 101.944742 -223.294083) (xy 101.986661 -223.324539) (xy 102.023299 -223.361177)
			(xy 102.053755 -223.403096) (xy 102.077278 -223.449263) (xy 102.09329 -223.498542) (xy 102.101396 -223.549719)
			(xy 102.101904 -223.575626) (xy 102.101487 -223.600992) (xy 102.093734 -223.651127) (xy 102.078385 -223.69948)
			(xy 102.055803 -223.744908) (xy 102.026522 -223.786336) (xy 101.991234 -223.822783) (xy 101.950775 -223.853388)
			(xy 101.906101 -223.877427) (xy 101.858269 -223.894332) (xy 101.833426 -223.899476) (xy 101.810566 -223.903794)
			(xy 101.605842 -224.258632) (xy 101.613716 -224.280476) (xy 101.62229 -224.306896) (xy 101.63149 -224.36167)
			(xy 101.632004 -224.389442) (xy 101.912928 -224.389442) (xy 101.913436 -224.363555) (xy 101.921535 -224.312417)
			(xy 101.937534 -224.263177) (xy 101.96104 -224.217045) (xy 101.991472 -224.175158) (xy 102.028082 -224.138548)
			(xy 102.069969 -224.108116) (xy 102.116101 -224.08461) (xy 102.165341 -224.068611) (xy 102.216479 -224.060512)
			(xy 102.268253 -224.060512) (xy 102.319391 -224.068611) (xy 102.368631 -224.08461) (xy 102.414763 -224.108116)
			(xy 102.45665 -224.138548) (xy 102.49326 -224.175158) (xy 102.523692 -224.217045) (xy 102.547198 -224.263177)
			(xy 102.563197 -224.312417) (xy 102.571296 -224.363555) (xy 102.571804 -224.389442) (xy 102.852728 -224.389442)
			(xy 102.853135 -224.364105) (xy 102.860897 -224.314028) (xy 102.876229 -224.265728) (xy 102.89877 -224.220343)
			(xy 102.927989 -224.17894) (xy 102.963199 -224.142496) (xy 103.00357 -224.111867) (xy 103.048152 -224.087776)
			(xy 103.095895 -224.070789) (xy 103.120698 -224.065592) (xy 103.143558 -224.061274) (xy 103.348282 -223.706436)
			(xy 103.340662 -223.684338) (xy 103.332031 -223.657991) (xy 103.32271 -223.603344) (xy 103.32212 -223.575626)
			(xy 103.322628 -223.549719) (xy 103.330734 -223.498542) (xy 103.346746 -223.449263) (xy 103.370269 -223.403096)
			(xy 103.400725 -223.361177) (xy 103.437363 -223.324539) (xy 103.479282 -223.294083) (xy 103.525449 -223.27056)
			(xy 103.574728 -223.254548) (xy 103.625905 -223.246442) (xy 103.677719 -223.246442) (xy 103.728896 -223.254548)
			(xy 103.778175 -223.27056) (xy 103.824342 -223.294083) (xy 103.866261 -223.324539) (xy 103.902899 -223.361177)
			(xy 103.933355 -223.403096) (xy 103.956878 -223.449263) (xy 103.97289 -223.498542) (xy 103.980996 -223.549719)
			(xy 103.981504 -223.575626) (xy 103.981087 -223.600992) (xy 103.973334 -223.651127) (xy 103.957985 -223.69948)
			(xy 103.935403 -223.744908) (xy 103.906122 -223.786336) (xy 103.870834 -223.822783) (xy 103.830375 -223.853388)
			(xy 103.785701 -223.877427) (xy 103.737869 -223.894332) (xy 103.713026 -223.899476) (xy 103.690166 -223.903794)
			(xy 103.485442 -224.258632) (xy 103.493316 -224.280476) (xy 103.50189 -224.306896) (xy 103.51109 -224.36167)
			(xy 103.511604 -224.389442) (xy 103.792528 -224.389442) (xy 103.793036 -224.363555) (xy 103.801135 -224.312417)
			(xy 103.817134 -224.263177) (xy 103.84064 -224.217045) (xy 103.871072 -224.175158) (xy 103.907682 -224.138548)
			(xy 103.949569 -224.108116) (xy 103.995701 -224.08461) (xy 104.044941 -224.068611) (xy 104.096079 -224.060512)
			(xy 104.147853 -224.060512) (xy 104.198991 -224.068611) (xy 104.248231 -224.08461) (xy 104.294363 -224.108116)
			(xy 104.33625 -224.138548) (xy 104.37286 -224.175158) (xy 104.403292 -224.217045) (xy 104.426798 -224.263177)
			(xy 104.442797 -224.312417) (xy 104.450896 -224.363555) (xy 104.451404 -224.389442) (xy 104.732328 -224.389442)
			(xy 104.732735 -224.364105) (xy 104.740497 -224.314028) (xy 104.755829 -224.265728) (xy 104.77837 -224.220343)
			(xy 104.807589 -224.17894) (xy 104.842799 -224.142496) (xy 104.88317 -224.111867) (xy 104.927752 -224.087776)
			(xy 104.975495 -224.070789) (xy 105.000298 -224.065592) (xy 105.023158 -224.061274) (xy 105.227882 -223.706436)
			(xy 105.220262 -223.684338) (xy 105.211631 -223.657991) (xy 105.20231 -223.603344) (xy 105.20172 -223.575626)
			(xy 105.202228 -223.549719) (xy 105.210334 -223.498542) (xy 105.226346 -223.449263) (xy 105.249869 -223.403096)
			(xy 105.280325 -223.361177) (xy 105.316963 -223.324539) (xy 105.358882 -223.294083) (xy 105.405049 -223.27056)
			(xy 105.454328 -223.254548) (xy 105.505505 -223.246442) (xy 105.557319 -223.246442) (xy 105.608496 -223.254548)
			(xy 105.657775 -223.27056) (xy 105.703942 -223.294083) (xy 105.745861 -223.324539) (xy 105.782499 -223.361177)
			(xy 105.812955 -223.403096) (xy 105.836478 -223.449263) (xy 105.85249 -223.498542) (xy 105.860596 -223.549719)
			(xy 105.861104 -223.575626) (xy 105.860687 -223.600992) (xy 105.852934 -223.651127) (xy 105.837585 -223.69948)
			(xy 105.815003 -223.744908) (xy 105.785722 -223.786336) (xy 105.750434 -223.822783) (xy 105.709975 -223.853388)
			(xy 105.665301 -223.877427) (xy 105.617469 -223.894332) (xy 105.592626 -223.899476) (xy 105.569766 -223.903794)
			(xy 105.365042 -224.258632) (xy 105.372916 -224.280476) (xy 105.38149 -224.306896) (xy 105.39069 -224.36167)
			(xy 105.391204 -224.389442) (xy 105.672128 -224.389442) (xy 105.672636 -224.363555) (xy 105.680735 -224.312417)
			(xy 105.696734 -224.263177) (xy 105.72024 -224.217045) (xy 105.750672 -224.175158) (xy 105.787282 -224.138548)
			(xy 105.829169 -224.108116) (xy 105.875301 -224.08461) (xy 105.924541 -224.068611) (xy 105.975679 -224.060512)
			(xy 106.027453 -224.060512) (xy 106.078591 -224.068611) (xy 106.127831 -224.08461) (xy 106.173963 -224.108116)
			(xy 106.21585 -224.138548) (xy 106.25246 -224.175158) (xy 106.282892 -224.217045) (xy 106.306398 -224.263177)
			(xy 106.322397 -224.312417) (xy 106.330496 -224.363555) (xy 106.331004 -224.389442) (xy 106.611928 -224.389442)
			(xy 106.612335 -224.364105) (xy 106.620097 -224.314028) (xy 106.635429 -224.265728) (xy 106.65797 -224.220343)
			(xy 106.687189 -224.17894) (xy 106.722399 -224.142496) (xy 106.76277 -224.111867) (xy 106.807352 -224.087776)
			(xy 106.855095 -224.070789) (xy 106.879898 -224.065592) (xy 106.902758 -224.061274) (xy 107.107482 -223.706436)
			(xy 107.099862 -223.684338) (xy 107.091231 -223.657991) (xy 107.08191 -223.603344) (xy 107.08132 -223.575626)
			(xy 107.081828 -223.549719) (xy 107.089934 -223.498542) (xy 107.105946 -223.449263) (xy 107.129469 -223.403096)
			(xy 107.159925 -223.361177) (xy 107.196563 -223.324539) (xy 107.238482 -223.294083) (xy 107.284649 -223.27056)
			(xy 107.333928 -223.254548) (xy 107.385105 -223.246442) (xy 107.436919 -223.246442) (xy 107.488096 -223.254548)
			(xy 107.537375 -223.27056) (xy 107.583542 -223.294083) (xy 107.625461 -223.324539) (xy 107.662099 -223.361177)
			(xy 107.692555 -223.403096) (xy 107.716078 -223.449263) (xy 107.73209 -223.498542) (xy 107.740196 -223.549719)
			(xy 107.740704 -223.575626) (xy 107.740287 -223.600992) (xy 107.732534 -223.651127) (xy 107.717185 -223.69948)
			(xy 107.694603 -223.744908) (xy 107.665322 -223.786336) (xy 107.630034 -223.822783) (xy 107.589575 -223.853388)
			(xy 107.544901 -223.877427) (xy 107.497069 -223.894332) (xy 107.472226 -223.899476) (xy 107.449366 -223.903794)
			(xy 107.244642 -224.258632) (xy 107.252516 -224.280476) (xy 107.26109 -224.306896) (xy 107.27029 -224.36167)
			(xy 107.270804 -224.389442) (xy 107.551728 -224.389442) (xy 107.552236 -224.363555) (xy 107.560335 -224.312417)
			(xy 107.576334 -224.263177) (xy 107.59984 -224.217045) (xy 107.630272 -224.175158) (xy 107.666882 -224.138548)
			(xy 107.708769 -224.108116) (xy 107.754901 -224.08461) (xy 107.804141 -224.068611) (xy 107.855279 -224.060512)
			(xy 107.907053 -224.060512) (xy 107.958191 -224.068611) (xy 108.007431 -224.08461) (xy 108.053563 -224.108116)
			(xy 108.09545 -224.138548) (xy 108.13206 -224.175158) (xy 108.162492 -224.217045) (xy 108.185998 -224.263177)
			(xy 108.201997 -224.312417) (xy 108.210096 -224.363555) (xy 108.210604 -224.389442) (xy 108.491528 -224.389442)
			(xy 108.491935 -224.364105) (xy 108.499697 -224.314028) (xy 108.515029 -224.265728) (xy 108.53757 -224.220343)
			(xy 108.566789 -224.17894) (xy 108.601999 -224.142496) (xy 108.64237 -224.111867) (xy 108.686952 -224.087776)
			(xy 108.734695 -224.070789) (xy 108.759498 -224.065592) (xy 108.782358 -224.061274) (xy 108.987082 -223.706436)
			(xy 108.979462 -223.684338) (xy 108.970831 -223.657991) (xy 108.96151 -223.603344) (xy 108.96092 -223.575626)
			(xy 108.961428 -223.549719) (xy 108.969534 -223.498542) (xy 108.985546 -223.449263) (xy 109.009069 -223.403096)
			(xy 109.039525 -223.361177) (xy 109.076163 -223.324539) (xy 109.118082 -223.294083) (xy 109.164249 -223.27056)
			(xy 109.213528 -223.254548) (xy 109.264705 -223.246442) (xy 109.316519 -223.246442) (xy 109.367696 -223.254548)
			(xy 109.416975 -223.27056) (xy 109.463142 -223.294083) (xy 109.505061 -223.324539) (xy 109.541699 -223.361177)
			(xy 109.572155 -223.403096) (xy 109.595678 -223.449263) (xy 109.61169 -223.498542) (xy 109.619796 -223.549719)
			(xy 109.620304 -223.575626) (xy 109.619887 -223.600992) (xy 109.612134 -223.651127) (xy 109.596785 -223.69948)
			(xy 109.574203 -223.744908) (xy 109.544922 -223.786336) (xy 109.509634 -223.822783) (xy 109.469175 -223.853388)
			(xy 109.424501 -223.877427) (xy 109.376669 -223.894332) (xy 109.351826 -223.899476) (xy 109.328966 -223.903794)
			(xy 109.124242 -224.258632) (xy 109.132116 -224.280476) (xy 109.14069 -224.306896) (xy 109.14989 -224.36167)
			(xy 109.150404 -224.389442) (xy 109.431328 -224.389442) (xy 109.431836 -224.363555) (xy 109.439935 -224.312417)
			(xy 109.455934 -224.263177) (xy 109.47944 -224.217045) (xy 109.509872 -224.175158) (xy 109.546482 -224.138548)
			(xy 109.588369 -224.108116) (xy 109.634501 -224.08461) (xy 109.683741 -224.068611) (xy 109.734879 -224.060512)
			(xy 109.786653 -224.060512) (xy 109.837791 -224.068611) (xy 109.887031 -224.08461) (xy 109.933163 -224.108116)
			(xy 109.97505 -224.138548) (xy 110.01166 -224.175158) (xy 110.042092 -224.217045) (xy 110.065598 -224.263177)
			(xy 110.081597 -224.312417) (xy 110.089696 -224.363555) (xy 110.090204 -224.389442) (xy 110.371128 -224.389442)
			(xy 110.371535 -224.364105) (xy 110.379297 -224.314028) (xy 110.394629 -224.265728) (xy 110.41717 -224.220343)
			(xy 110.446389 -224.17894) (xy 110.481599 -224.142496) (xy 110.52197 -224.111867) (xy 110.566552 -224.087776)
			(xy 110.614295 -224.070789) (xy 110.639098 -224.065592) (xy 110.661958 -224.061274) (xy 110.866682 -223.706436)
			(xy 110.859062 -223.684338) (xy 110.850431 -223.657991) (xy 110.84111 -223.603344) (xy 110.84052 -223.575626)
			(xy 110.841028 -223.549719) (xy 110.849134 -223.498542) (xy 110.865146 -223.449263) (xy 110.888669 -223.403096)
			(xy 110.919125 -223.361177) (xy 110.955763 -223.324539) (xy 110.997682 -223.294083) (xy 111.043849 -223.27056)
			(xy 111.093128 -223.254548) (xy 111.144305 -223.246442) (xy 111.196119 -223.246442) (xy 111.247296 -223.254548)
			(xy 111.296575 -223.27056) (xy 111.342742 -223.294083) (xy 111.384661 -223.324539) (xy 111.421299 -223.361177)
			(xy 111.451755 -223.403096) (xy 111.475278 -223.449263) (xy 111.49129 -223.498542) (xy 111.499396 -223.549719)
			(xy 111.499904 -223.575626) (xy 111.499487 -223.600992) (xy 111.491734 -223.651127) (xy 111.476385 -223.69948)
			(xy 111.453803 -223.744908) (xy 111.424522 -223.786336) (xy 111.389234 -223.822783) (xy 111.348775 -223.853388)
			(xy 111.304101 -223.877427) (xy 111.256269 -223.894332) (xy 111.231426 -223.899476) (xy 111.208566 -223.903794)
			(xy 111.003842 -224.258632) (xy 111.011716 -224.280476) (xy 111.02029 -224.306896) (xy 111.02949 -224.36167)
			(xy 111.030004 -224.389442) (xy 111.310928 -224.389442) (xy 111.311436 -224.363555) (xy 111.319535 -224.312417)
			(xy 111.335534 -224.263177) (xy 111.35904 -224.217045) (xy 111.389472 -224.175158) (xy 111.426082 -224.138548)
			(xy 111.467969 -224.108116) (xy 111.514101 -224.08461) (xy 111.563341 -224.068611) (xy 111.614479 -224.060512)
			(xy 111.666253 -224.060512) (xy 111.717391 -224.068611) (xy 111.766631 -224.08461) (xy 111.812763 -224.108116)
			(xy 111.85465 -224.138548) (xy 111.89126 -224.175158) (xy 111.921692 -224.217045) (xy 111.945198 -224.263177)
			(xy 111.961197 -224.312417) (xy 111.969296 -224.363555) (xy 111.969804 -224.389442) (xy 112.250728 -224.389442)
			(xy 112.251135 -224.364105) (xy 112.258897 -224.314028) (xy 112.274229 -224.265728) (xy 112.29677 -224.220343)
			(xy 112.325989 -224.17894) (xy 112.361199 -224.142496) (xy 112.40157 -224.111867) (xy 112.446152 -224.087776)
			(xy 112.493895 -224.070789) (xy 112.518698 -224.065592) (xy 112.541558 -224.061274) (xy 112.746282 -223.706436)
			(xy 112.738662 -223.684338) (xy 112.730031 -223.657991) (xy 112.72071 -223.603344) (xy 112.72012 -223.575626)
			(xy 112.720628 -223.549719) (xy 112.728734 -223.498542) (xy 112.744746 -223.449263) (xy 112.768269 -223.403096)
			(xy 112.798725 -223.361177) (xy 112.835363 -223.324539) (xy 112.877282 -223.294083) (xy 112.923449 -223.27056)
			(xy 112.972728 -223.254548) (xy 113.023905 -223.246442) (xy 113.075719 -223.246442) (xy 113.126896 -223.254548)
			(xy 113.176175 -223.27056) (xy 113.222342 -223.294083) (xy 113.264261 -223.324539) (xy 113.300899 -223.361177)
			(xy 113.331355 -223.403096) (xy 113.354878 -223.449263) (xy 113.37089 -223.498542) (xy 113.378996 -223.549719)
			(xy 113.379504 -223.575626) (xy 113.379087 -223.600992) (xy 113.371334 -223.651127) (xy 113.355985 -223.69948)
			(xy 113.333403 -223.744908) (xy 113.304122 -223.786336) (xy 113.268834 -223.822783) (xy 113.228375 -223.853388)
			(xy 113.183701 -223.877427) (xy 113.135869 -223.894332) (xy 113.111026 -223.899476) (xy 113.088166 -223.903794)
			(xy 112.883442 -224.258632) (xy 112.891316 -224.280476) (xy 112.89989 -224.306896) (xy 112.90909 -224.36167)
			(xy 112.909604 -224.389442) (xy 113.190528 -224.389442) (xy 113.191036 -224.363555) (xy 113.199135 -224.312417)
			(xy 113.215134 -224.263177) (xy 113.23864 -224.217045) (xy 113.269072 -224.175158) (xy 113.305682 -224.138548)
			(xy 113.347569 -224.108116) (xy 113.393701 -224.08461) (xy 113.442941 -224.068611) (xy 113.494079 -224.060512)
			(xy 113.545853 -224.060512) (xy 113.596991 -224.068611) (xy 113.646231 -224.08461) (xy 113.692363 -224.108116)
			(xy 113.73425 -224.138548) (xy 113.77086 -224.175158) (xy 113.801292 -224.217045) (xy 113.824798 -224.263177)
			(xy 113.840797 -224.312417) (xy 113.848896 -224.363555) (xy 113.849404 -224.389442) (xy 114.130328 -224.389442)
			(xy 114.130735 -224.364105) (xy 114.138497 -224.314028) (xy 114.153829 -224.265728) (xy 114.17637 -224.220343)
			(xy 114.205589 -224.17894) (xy 114.240799 -224.142496) (xy 114.28117 -224.111867) (xy 114.325752 -224.087776)
			(xy 114.373495 -224.070789) (xy 114.398298 -224.065592) (xy 114.421158 -224.061274) (xy 114.626136 -223.706182)
			(xy 114.618516 -223.684084) (xy 114.609997 -223.657912) (xy 114.600803 -223.603651) (xy 114.600228 -223.576134)
			(xy 114.600228 -223.575626) (xy 114.600736 -223.549739) (xy 114.608835 -223.498601) (xy 114.624834 -223.449361)
			(xy 114.64834 -223.403229) (xy 114.678772 -223.361342) (xy 114.715382 -223.324732) (xy 114.757269 -223.2943)
			(xy 114.803401 -223.270794) (xy 114.852641 -223.254795) (xy 114.903779 -223.246696) (xy 114.955553 -223.246696)
			(xy 115.006691 -223.254795) (xy 115.055931 -223.270794) (xy 115.102063 -223.2943) (xy 115.14395 -223.324732)
			(xy 115.18056 -223.361342) (xy 115.210992 -223.403229) (xy 115.234498 -223.449361) (xy 115.250497 -223.498601)
			(xy 115.258596 -223.549739) (xy 115.259104 -223.575626) (xy 115.258687 -223.600992) (xy 115.250934 -223.651127)
			(xy 115.235585 -223.69948) (xy 115.213003 -223.744908) (xy 115.183722 -223.786336) (xy 115.148434 -223.822783)
			(xy 115.107975 -223.853388) (xy 115.063301 -223.877427) (xy 115.015469 -223.894332) (xy 114.990626 -223.899476)
			(xy 114.967766 -223.903794) (xy 114.763042 -224.258632) (xy 114.770916 -224.280476) (xy 114.77949 -224.306896)
			(xy 114.78869 -224.36167) (xy 114.789204 -224.389442) (xy 115.070128 -224.389442) (xy 115.070636 -224.363555)
			(xy 115.078735 -224.312417) (xy 115.094734 -224.263177) (xy 115.11824 -224.217045) (xy 115.148672 -224.175158)
			(xy 115.185282 -224.138548) (xy 115.227169 -224.108116) (xy 115.273301 -224.08461) (xy 115.322541 -224.068611)
			(xy 115.373679 -224.060512) (xy 115.425453 -224.060512) (xy 115.476591 -224.068611) (xy 115.525831 -224.08461)
			(xy 115.571963 -224.108116) (xy 115.61385 -224.138548) (xy 115.65046 -224.175158) (xy 115.680892 -224.217045)
			(xy 115.704398 -224.263177) (xy 115.720397 -224.312417) (xy 115.728496 -224.363555) (xy 115.729004 -224.389442)
			(xy 116.009928 -224.389442) (xy 116.010335 -224.364105) (xy 116.018097 -224.314028) (xy 116.033429 -224.265728)
			(xy 116.05597 -224.220343) (xy 116.085189 -224.17894) (xy 116.120399 -224.142496) (xy 116.16077 -224.111867)
			(xy 116.205352 -224.087776) (xy 116.253095 -224.070789) (xy 116.277898 -224.065592) (xy 116.300758 -224.061274)
			(xy 116.505482 -223.706436) (xy 116.497862 -223.684338) (xy 116.489231 -223.657991) (xy 116.47991 -223.603344)
			(xy 116.47932 -223.575626) (xy 116.479828 -223.549719) (xy 116.487934 -223.498542) (xy 116.503946 -223.449263)
			(xy 116.527469 -223.403096) (xy 116.557925 -223.361177) (xy 116.594563 -223.324539) (xy 116.636482 -223.294083)
			(xy 116.682649 -223.27056) (xy 116.731928 -223.254548) (xy 116.783105 -223.246442) (xy 116.834919 -223.246442)
			(xy 116.886096 -223.254548) (xy 116.935375 -223.27056) (xy 116.981542 -223.294083) (xy 117.023461 -223.324539)
			(xy 117.060099 -223.361177) (xy 117.090555 -223.403096) (xy 117.114078 -223.449263) (xy 117.13009 -223.498542)
			(xy 117.138196 -223.549719) (xy 117.138704 -223.575626) (xy 117.138287 -223.600992) (xy 117.130534 -223.651127)
			(xy 117.115185 -223.69948) (xy 117.092603 -223.744908) (xy 117.063322 -223.786336) (xy 117.028034 -223.822783)
			(xy 116.987575 -223.853388) (xy 116.942901 -223.877427) (xy 116.895069 -223.894332) (xy 116.870226 -223.899476)
			(xy 116.847366 -223.903794) (xy 116.642642 -224.258632) (xy 116.650516 -224.280476) (xy 116.65909 -224.306896)
			(xy 116.66829 -224.36167) (xy 116.668804 -224.389442) (xy 116.949728 -224.389442) (xy 116.950236 -224.363555)
			(xy 116.958335 -224.312417) (xy 116.974334 -224.263177) (xy 116.99784 -224.217045) (xy 117.028272 -224.175158)
			(xy 117.064882 -224.138548) (xy 117.106769 -224.108116) (xy 117.152901 -224.08461) (xy 117.202141 -224.068611)
			(xy 117.253279 -224.060512) (xy 117.305053 -224.060512) (xy 117.356191 -224.068611) (xy 117.405431 -224.08461)
			(xy 117.451563 -224.108116) (xy 117.49345 -224.138548) (xy 117.53006 -224.175158) (xy 117.560492 -224.217045)
			(xy 117.583998 -224.263177) (xy 117.599997 -224.312417) (xy 117.608096 -224.363555) (xy 117.608604 -224.389442)
			(xy 117.889528 -224.389442) (xy 117.889935 -224.364105) (xy 117.897697 -224.314028) (xy 117.913029 -224.265728)
			(xy 117.93557 -224.220343) (xy 117.964789 -224.17894) (xy 117.999999 -224.142496) (xy 118.04037 -224.111867)
			(xy 118.084952 -224.087776) (xy 118.132695 -224.070789) (xy 118.157498 -224.065592) (xy 118.180358 -224.061274)
			(xy 118.385082 -223.706436) (xy 118.377462 -223.684338) (xy 118.368831 -223.657991) (xy 118.35951 -223.603344)
			(xy 118.35892 -223.575626) (xy 118.359428 -223.549719) (xy 118.367534 -223.498542) (xy 118.383546 -223.449263)
			(xy 118.407069 -223.403096) (xy 118.437525 -223.361177) (xy 118.474163 -223.324539) (xy 118.516082 -223.294083)
			(xy 118.562249 -223.27056) (xy 118.611528 -223.254548) (xy 118.662705 -223.246442) (xy 118.714519 -223.246442)
			(xy 118.765696 -223.254548) (xy 118.814975 -223.27056) (xy 118.861142 -223.294083) (xy 118.903061 -223.324539)
			(xy 118.939699 -223.361177) (xy 118.970155 -223.403096) (xy 118.993678 -223.449263) (xy 119.00969 -223.498542)
			(xy 119.017796 -223.549719) (xy 119.018304 -223.575626) (xy 119.017887 -223.600992) (xy 119.010134 -223.651127)
			(xy 118.994785 -223.69948) (xy 118.972203 -223.744908) (xy 118.942922 -223.786336) (xy 118.907634 -223.822783)
			(xy 118.867175 -223.853388) (xy 118.822501 -223.877427) (xy 118.774669 -223.894332) (xy 118.749826 -223.899476)
			(xy 118.726966 -223.903794) (xy 118.522242 -224.258632) (xy 118.530116 -224.280476) (xy 118.53869 -224.306896)
			(xy 118.54789 -224.36167) (xy 118.548404 -224.389442) (xy 118.829328 -224.389442) (xy 118.829836 -224.363555)
			(xy 118.837935 -224.312417) (xy 118.853934 -224.263177) (xy 118.87744 -224.217045) (xy 118.907872 -224.175158)
			(xy 118.944482 -224.138548) (xy 118.986369 -224.108116) (xy 119.032501 -224.08461) (xy 119.081741 -224.068611)
			(xy 119.132879 -224.060512) (xy 119.184653 -224.060512) (xy 119.235791 -224.068611) (xy 119.285031 -224.08461)
			(xy 119.331163 -224.108116) (xy 119.37305 -224.138548) (xy 119.40966 -224.175158) (xy 119.440092 -224.217045)
			(xy 119.463598 -224.263177) (xy 119.479597 -224.312417) (xy 119.487696 -224.363555) (xy 119.488204 -224.389442)
			(xy 119.769128 -224.389442) (xy 119.769535 -224.364105) (xy 119.777297 -224.314028) (xy 119.792629 -224.265728)
			(xy 119.81517 -224.220343) (xy 119.844389 -224.17894) (xy 119.879599 -224.142496) (xy 119.91997 -224.111867)
			(xy 119.964552 -224.087776) (xy 120.012295 -224.070789) (xy 120.037098 -224.065592) (xy 120.059958 -224.061274)
			(xy 120.264682 -223.706436) (xy 120.257062 -223.684338) (xy 120.248431 -223.657991) (xy 120.23911 -223.603344)
			(xy 120.23852 -223.575626) (xy 120.239028 -223.549719) (xy 120.247134 -223.498542) (xy 120.263146 -223.449263)
			(xy 120.286669 -223.403096) (xy 120.317125 -223.361177) (xy 120.353763 -223.324539) (xy 120.395682 -223.294083)
			(xy 120.441849 -223.27056) (xy 120.491128 -223.254548) (xy 120.542305 -223.246442) (xy 120.594119 -223.246442)
			(xy 120.645296 -223.254548) (xy 120.694575 -223.27056) (xy 120.740742 -223.294083) (xy 120.782661 -223.324539)
			(xy 120.819299 -223.361177) (xy 120.849755 -223.403096) (xy 120.873278 -223.449263) (xy 120.88929 -223.498542)
			(xy 120.897396 -223.549719) (xy 120.897904 -223.575626) (xy 120.897487 -223.600992) (xy 120.889734 -223.651127)
			(xy 120.874385 -223.69948) (xy 120.851803 -223.744908) (xy 120.822522 -223.786336) (xy 120.787234 -223.822783)
			(xy 120.746775 -223.853388) (xy 120.702101 -223.877427) (xy 120.654269 -223.894332) (xy 120.629426 -223.899476)
			(xy 120.606566 -223.903794) (xy 120.401842 -224.258632) (xy 120.409716 -224.280476) (xy 120.41829 -224.306896)
			(xy 120.42749 -224.36167) (xy 120.428004 -224.389442) (xy 120.708928 -224.389442) (xy 120.709436 -224.363555)
			(xy 120.717535 -224.312417) (xy 120.733534 -224.263177) (xy 120.75704 -224.217045) (xy 120.787472 -224.175158)
			(xy 120.824082 -224.138548) (xy 120.865969 -224.108116) (xy 120.912101 -224.08461) (xy 120.961341 -224.068611)
			(xy 121.012479 -224.060512) (xy 121.064253 -224.060512) (xy 121.115391 -224.068611) (xy 121.164631 -224.08461)
			(xy 121.210763 -224.108116) (xy 121.25265 -224.138548) (xy 121.28926 -224.175158) (xy 121.319692 -224.217045)
			(xy 121.343198 -224.263177) (xy 121.359197 -224.312417) (xy 121.367296 -224.363555) (xy 121.367804 -224.389442)
			(xy 121.648728 -224.389442) (xy 121.649135 -224.364105) (xy 121.656897 -224.314028) (xy 121.672229 -224.265728)
			(xy 121.69477 -224.220343) (xy 121.723989 -224.17894) (xy 121.759199 -224.142496) (xy 121.79957 -224.111867)
			(xy 121.844152 -224.087776) (xy 121.891895 -224.070789) (xy 121.916698 -224.065592) (xy 121.939558 -224.061274)
			(xy 122.144282 -223.706436) (xy 122.136662 -223.684338) (xy 122.128031 -223.657991) (xy 122.11871 -223.603344)
			(xy 122.11812 -223.575626) (xy 122.118628 -223.549719) (xy 122.126734 -223.498542) (xy 122.142746 -223.449263)
			(xy 122.166269 -223.403096) (xy 122.196725 -223.361177) (xy 122.233363 -223.324539) (xy 122.275282 -223.294083)
			(xy 122.321449 -223.27056) (xy 122.370728 -223.254548) (xy 122.421905 -223.246442) (xy 122.473719 -223.246442)
			(xy 122.524896 -223.254548) (xy 122.574175 -223.27056) (xy 122.620342 -223.294083) (xy 122.662261 -223.324539)
			(xy 122.698899 -223.361177) (xy 122.729355 -223.403096) (xy 122.752878 -223.449263) (xy 122.76889 -223.498542)
			(xy 122.776996 -223.549719) (xy 122.777504 -223.575626) (xy 122.777087 -223.600992) (xy 122.769334 -223.651127)
			(xy 122.753985 -223.69948) (xy 122.731403 -223.744908) (xy 122.702122 -223.786336) (xy 122.666834 -223.822783)
			(xy 122.626375 -223.853388) (xy 122.581701 -223.877427) (xy 122.533869 -223.894332) (xy 122.509026 -223.899476)
			(xy 122.486166 -223.903794) (xy 122.281442 -224.258632) (xy 122.289316 -224.280476) (xy 122.29789 -224.306896)
			(xy 122.30709 -224.36167) (xy 122.307604 -224.389442) (xy 122.588528 -224.389442) (xy 122.589036 -224.363555)
			(xy 122.597135 -224.312417) (xy 122.613134 -224.263177) (xy 122.63664 -224.217045) (xy 122.667072 -224.175158)
			(xy 122.703682 -224.138548) (xy 122.745569 -224.108116) (xy 122.791701 -224.08461) (xy 122.840941 -224.068611)
			(xy 122.892079 -224.060512) (xy 122.943853 -224.060512) (xy 122.994991 -224.068611) (xy 123.044231 -224.08461)
			(xy 123.090363 -224.108116) (xy 123.13225 -224.138548) (xy 123.16886 -224.175158) (xy 123.199292 -224.217045)
			(xy 123.222798 -224.263177) (xy 123.238797 -224.312417) (xy 123.246896 -224.363555) (xy 123.247404 -224.389442)
			(xy 123.528328 -224.389442) (xy 123.528735 -224.364105) (xy 123.536497 -224.314028) (xy 123.551829 -224.265728)
			(xy 123.57437 -224.220343) (xy 123.603589 -224.17894) (xy 123.638799 -224.142496) (xy 123.67917 -224.111867)
			(xy 123.723752 -224.087776) (xy 123.771495 -224.070789) (xy 123.796298 -224.065592) (xy 123.819158 -224.061274)
			(xy 124.023882 -223.706436) (xy 124.016262 -223.684338) (xy 124.007631 -223.657991) (xy 123.99831 -223.603344)
			(xy 123.99772 -223.575626) (xy 123.998228 -223.549719) (xy 124.006334 -223.498542) (xy 124.022346 -223.449263)
			(xy 124.045869 -223.403096) (xy 124.076325 -223.361177) (xy 124.112963 -223.324539) (xy 124.154882 -223.294083)
			(xy 124.201049 -223.27056) (xy 124.250328 -223.254548) (xy 124.301505 -223.246442) (xy 124.353319 -223.246442)
			(xy 124.404496 -223.254548) (xy 124.453775 -223.27056) (xy 124.499942 -223.294083) (xy 124.541861 -223.324539)
			(xy 124.578499 -223.361177) (xy 124.608955 -223.403096) (xy 124.632478 -223.449263) (xy 124.64849 -223.498542)
			(xy 124.656596 -223.549719) (xy 124.657104 -223.575626) (xy 124.656687 -223.600992) (xy 124.648934 -223.651127)
			(xy 124.633585 -223.69948) (xy 124.611003 -223.744908) (xy 124.581722 -223.786336) (xy 124.546434 -223.822783)
			(xy 124.505975 -223.853388) (xy 124.461301 -223.877427) (xy 124.413469 -223.894332) (xy 124.388626 -223.899476)
			(xy 124.365766 -223.903794) (xy 124.161042 -224.258632) (xy 124.168916 -224.280476) (xy 124.17749 -224.306896)
			(xy 124.18669 -224.36167) (xy 124.187204 -224.389442) (xy 124.468128 -224.389442) (xy 124.468636 -224.363555)
			(xy 124.476735 -224.312417) (xy 124.492734 -224.263177) (xy 124.51624 -224.217045) (xy 124.546672 -224.175158)
			(xy 124.583282 -224.138548) (xy 124.625169 -224.108116) (xy 124.671301 -224.08461) (xy 124.720541 -224.068611)
			(xy 124.771679 -224.060512) (xy 124.823453 -224.060512) (xy 124.874591 -224.068611) (xy 124.923831 -224.08461)
			(xy 124.969963 -224.108116) (xy 125.01185 -224.138548) (xy 125.04846 -224.175158) (xy 125.078892 -224.217045)
			(xy 125.102398 -224.263177) (xy 125.118397 -224.312417) (xy 125.126496 -224.363555) (xy 125.127004 -224.389442)
			(xy 125.407928 -224.389442) (xy 125.408335 -224.364105) (xy 125.416097 -224.314028) (xy 125.431429 -224.265728)
			(xy 125.45397 -224.220343) (xy 125.483189 -224.17894) (xy 125.518399 -224.142496) (xy 125.55877 -224.111867)
			(xy 125.603352 -224.087776) (xy 125.651095 -224.070789) (xy 125.675898 -224.065592) (xy 125.698758 -224.061274)
			(xy 125.903482 -223.706436) (xy 125.895862 -223.684338) (xy 125.887231 -223.657991) (xy 125.87791 -223.603344)
			(xy 125.87732 -223.575626) (xy 125.877828 -223.549719) (xy 125.885934 -223.498542) (xy 125.901946 -223.449263)
			(xy 125.925469 -223.403096) (xy 125.955925 -223.361177) (xy 125.992563 -223.324539) (xy 126.034482 -223.294083)
			(xy 126.080649 -223.27056) (xy 126.129928 -223.254548) (xy 126.181105 -223.246442) (xy 126.232919 -223.246442)
			(xy 126.284096 -223.254548) (xy 126.333375 -223.27056) (xy 126.379542 -223.294083) (xy 126.421461 -223.324539)
			(xy 126.458099 -223.361177) (xy 126.488555 -223.403096) (xy 126.512078 -223.449263) (xy 126.52809 -223.498542)
			(xy 126.536196 -223.549719) (xy 126.536704 -223.575626) (xy 126.536287 -223.600992) (xy 126.528534 -223.651127)
			(xy 126.513185 -223.69948) (xy 126.490603 -223.744908) (xy 126.461322 -223.786336) (xy 126.426034 -223.822783)
			(xy 126.385575 -223.853388) (xy 126.340901 -223.877427) (xy 126.293069 -223.894332) (xy 126.268226 -223.899476)
			(xy 126.245366 -223.903794) (xy 126.040642 -224.258632) (xy 126.048516 -224.280476) (xy 126.05709 -224.306896)
			(xy 126.06629 -224.36167) (xy 126.066804 -224.389442) (xy 126.347728 -224.389442) (xy 126.348236 -224.363555)
			(xy 126.356335 -224.312417) (xy 126.372334 -224.263177) (xy 126.39584 -224.217045) (xy 126.426272 -224.175158)
			(xy 126.462882 -224.138548) (xy 126.504769 -224.108116) (xy 126.550901 -224.08461) (xy 126.600141 -224.068611)
			(xy 126.651279 -224.060512) (xy 126.703053 -224.060512) (xy 126.754191 -224.068611) (xy 126.803431 -224.08461)
			(xy 126.849563 -224.108116) (xy 126.89145 -224.138548) (xy 126.92806 -224.175158) (xy 126.958492 -224.217045)
			(xy 126.981998 -224.263177) (xy 126.997997 -224.312417) (xy 127.006096 -224.363555) (xy 127.006604 -224.389442)
			(xy 127.287528 -224.389442) (xy 127.287935 -224.364105) (xy 127.295697 -224.314028) (xy 127.311029 -224.265728)
			(xy 127.33357 -224.220343) (xy 127.362789 -224.17894) (xy 127.397999 -224.142496) (xy 127.43837 -224.111867)
			(xy 127.482952 -224.087776) (xy 127.530695 -224.070789) (xy 127.555498 -224.065592) (xy 127.578358 -224.061274)
			(xy 127.783082 -223.706436) (xy 127.775462 -223.684338) (xy 127.766831 -223.657991) (xy 127.75751 -223.603344)
			(xy 127.75692 -223.575626) (xy 127.757428 -223.549719) (xy 127.765534 -223.498542) (xy 127.781546 -223.449263)
			(xy 127.805069 -223.403096) (xy 127.835525 -223.361177) (xy 127.872163 -223.324539) (xy 127.914082 -223.294083)
			(xy 127.960249 -223.27056) (xy 128.009528 -223.254548) (xy 128.060705 -223.246442) (xy 128.112519 -223.246442)
			(xy 128.163696 -223.254548) (xy 128.212975 -223.27056) (xy 128.259142 -223.294083) (xy 128.301061 -223.324539)
			(xy 128.337699 -223.361177) (xy 128.368155 -223.403096) (xy 128.391678 -223.449263) (xy 128.40769 -223.498542)
			(xy 128.415796 -223.549719) (xy 128.416304 -223.575626) (xy 128.415887 -223.600992) (xy 128.408134 -223.651127)
			(xy 128.392785 -223.69948) (xy 128.370203 -223.744908) (xy 128.340922 -223.786336) (xy 128.305634 -223.822783)
			(xy 128.265175 -223.853388) (xy 128.220501 -223.877427) (xy 128.172669 -223.894332) (xy 128.147826 -223.899476)
			(xy 128.124966 -223.903794) (xy 127.920242 -224.258632) (xy 127.928116 -224.280476) (xy 127.93669 -224.306896)
			(xy 127.94589 -224.36167) (xy 127.946404 -224.389442) (xy 128.227328 -224.389442) (xy 128.227836 -224.363555)
			(xy 128.235935 -224.312417) (xy 128.251934 -224.263177) (xy 128.27544 -224.217045) (xy 128.305872 -224.175158)
			(xy 128.342482 -224.138548) (xy 128.384369 -224.108116) (xy 128.430501 -224.08461) (xy 128.479741 -224.068611)
			(xy 128.530879 -224.060512) (xy 128.582653 -224.060512) (xy 128.633791 -224.068611) (xy 128.683031 -224.08461)
			(xy 128.729163 -224.108116) (xy 128.77105 -224.138548) (xy 128.80766 -224.175158) (xy 128.838092 -224.217045)
			(xy 128.861598 -224.263177) (xy 128.877597 -224.312417) (xy 128.885696 -224.363555) (xy 128.886204 -224.389442)
			(xy 129.167128 -224.389442) (xy 129.167535 -224.364105) (xy 129.175297 -224.314028) (xy 129.190629 -224.265728)
			(xy 129.21317 -224.220343) (xy 129.242389 -224.17894) (xy 129.277599 -224.142496) (xy 129.31797 -224.111867)
			(xy 129.362552 -224.087776) (xy 129.410295 -224.070789) (xy 129.435098 -224.065592) (xy 129.457958 -224.061274)
			(xy 129.662682 -223.706436) (xy 129.655062 -223.684338) (xy 129.646431 -223.657991) (xy 129.63711 -223.603344)
			(xy 129.63652 -223.575626) (xy 129.637028 -223.549719) (xy 129.645134 -223.498542) (xy 129.661146 -223.449263)
			(xy 129.684669 -223.403096) (xy 129.715125 -223.361177) (xy 129.751763 -223.324539) (xy 129.793682 -223.294083)
			(xy 129.839849 -223.27056) (xy 129.889128 -223.254548) (xy 129.940305 -223.246442) (xy 129.992119 -223.246442)
			(xy 130.043296 -223.254548) (xy 130.092575 -223.27056) (xy 130.138742 -223.294083) (xy 130.180661 -223.324539)
			(xy 130.217299 -223.361177) (xy 130.247755 -223.403096) (xy 130.271278 -223.449263) (xy 130.28729 -223.498542)
			(xy 130.295396 -223.549719) (xy 130.295904 -223.575626) (xy 130.295487 -223.600992) (xy 130.287734 -223.651127)
			(xy 130.272385 -223.69948) (xy 130.249803 -223.744908) (xy 130.220522 -223.786336) (xy 130.185234 -223.822783)
			(xy 130.144775 -223.853388) (xy 130.100101 -223.877427) (xy 130.052269 -223.894332) (xy 130.027426 -223.899476)
			(xy 130.004566 -223.903794) (xy 129.799842 -224.258632) (xy 129.807716 -224.280476) (xy 129.81629 -224.306896)
			(xy 129.82549 -224.36167) (xy 129.826004 -224.389442) (xy 130.106928 -224.389442) (xy 130.107436 -224.363555)
			(xy 130.115535 -224.312417) (xy 130.131534 -224.263177) (xy 130.15504 -224.217045) (xy 130.185472 -224.175158)
			(xy 130.222082 -224.138548) (xy 130.263969 -224.108116) (xy 130.310101 -224.08461) (xy 130.359341 -224.068611)
			(xy 130.410479 -224.060512) (xy 130.462253 -224.060512) (xy 130.513391 -224.068611) (xy 130.562631 -224.08461)
			(xy 130.608763 -224.108116) (xy 130.65065 -224.138548) (xy 130.68726 -224.175158) (xy 130.717692 -224.217045)
			(xy 130.741198 -224.263177) (xy 130.757197 -224.312417) (xy 130.765296 -224.363555) (xy 130.765804 -224.389442)
			(xy 131.046728 -224.389442) (xy 131.047135 -224.364105) (xy 131.054897 -224.314028) (xy 131.070229 -224.265728)
			(xy 131.09277 -224.220343) (xy 131.121989 -224.17894) (xy 131.157199 -224.142496) (xy 131.19757 -224.111867)
			(xy 131.242152 -224.087776) (xy 131.289895 -224.070789) (xy 131.314698 -224.065592) (xy 131.337558 -224.061274)
			(xy 131.542282 -223.706182) (xy 131.534662 -223.684338) (xy 131.526017 -223.657995) (xy 131.516704 -223.603345)
			(xy 131.51612 -223.575626) (xy 131.516628 -223.549719) (xy 131.524734 -223.498542) (xy 131.540746 -223.449263)
			(xy 131.564269 -223.403096) (xy 131.594725 -223.361177) (xy 131.631363 -223.324539) (xy 131.673282 -223.294083)
			(xy 131.719449 -223.27056) (xy 131.768728 -223.254548) (xy 131.819905 -223.246442) (xy 131.871719 -223.246442)
			(xy 131.922896 -223.254548) (xy 131.972175 -223.27056) (xy 132.018342 -223.294083) (xy 132.060261 -223.324539)
			(xy 132.096899 -223.361177) (xy 132.127355 -223.403096) (xy 132.150878 -223.449263) (xy 132.16689 -223.498542)
			(xy 132.174996 -223.549719) (xy 132.175504 -223.575626) (xy 132.175003 -223.60097) (xy 132.167228 -223.651059)
			(xy 132.151879 -223.699368) (xy 132.12932 -223.74476) (xy 132.10008 -223.786165) (xy 132.064849 -223.822609)
			(xy 132.024457 -223.853232) (xy 131.979854 -223.877314) (xy 131.932092 -223.894288) (xy 131.90728 -223.899476)
			(xy 131.88442 -223.903794) (xy 131.679696 -224.258632) (xy 131.687316 -224.280476) (xy 131.695872 -224.306769)
			(xy 131.705065 -224.361289) (xy 131.705604 -224.388934) (xy 131.705604 -224.389442) (xy 131.986528 -224.389442)
			(xy 131.987036 -224.363555) (xy 131.995135 -224.312417) (xy 132.011134 -224.263177) (xy 132.03464 -224.217045)
			(xy 132.065072 -224.175158) (xy 132.101682 -224.138548) (xy 132.143569 -224.108116) (xy 132.189701 -224.08461)
			(xy 132.238941 -224.068611) (xy 132.290079 -224.060512) (xy 132.341853 -224.060512) (xy 132.392991 -224.068611)
			(xy 132.442231 -224.08461) (xy 132.488363 -224.108116) (xy 132.53025 -224.138548) (xy 132.56686 -224.175158)
			(xy 132.597292 -224.217045) (xy 132.620798 -224.263177) (xy 132.636797 -224.312417) (xy 132.644896 -224.363555)
			(xy 132.645404 -224.389442) (xy 132.926328 -224.389442) (xy 132.926735 -224.364105) (xy 132.934497 -224.314028)
			(xy 132.949829 -224.265728) (xy 132.97237 -224.220343) (xy 133.001589 -224.17894) (xy 133.036799 -224.142496)
			(xy 133.07717 -224.111867) (xy 133.121752 -224.087776) (xy 133.169495 -224.070789) (xy 133.194298 -224.065592)
			(xy 133.217158 -224.061274) (xy 133.422136 -223.705928) (xy 133.414516 -223.684084) (xy 133.405997 -223.657912)
			(xy 133.396803 -223.603651) (xy 133.396228 -223.576134) (xy 133.396228 -223.575626) (xy 133.396736 -223.549739)
			(xy 133.404835 -223.498601) (xy 133.420834 -223.449361) (xy 133.44434 -223.403229) (xy 133.474772 -223.361342)
			(xy 133.511382 -223.324732) (xy 133.553269 -223.2943) (xy 133.599401 -223.270794) (xy 133.648641 -223.254795)
			(xy 133.699779 -223.246696) (xy 133.751553 -223.246696) (xy 133.802691 -223.254795) (xy 133.851931 -223.270794)
			(xy 133.898063 -223.2943) (xy 133.93995 -223.324732) (xy 133.97656 -223.361342) (xy 134.006992 -223.403229)
			(xy 134.030498 -223.449361) (xy 134.046497 -223.498601) (xy 134.054596 -223.549739) (xy 134.055104 -223.575626)
			(xy 134.054603 -223.60097) (xy 134.046828 -223.651059) (xy 134.031479 -223.699368) (xy 134.00892 -223.74476)
			(xy 133.97968 -223.786165) (xy 133.944449 -223.822609) (xy 133.904057 -223.853232) (xy 133.859454 -223.877314)
			(xy 133.811692 -223.894288) (xy 133.78688 -223.899476) (xy 133.76402 -223.903794) (xy 133.559296 -224.258632)
			(xy 133.566916 -224.280476) (xy 133.575472 -224.306769) (xy 133.584665 -224.361289) (xy 133.585204 -224.388934)
			(xy 133.585204 -224.389442) (xy 133.866128 -224.389442) (xy 133.866636 -224.363555) (xy 133.874735 -224.312417)
			(xy 133.890734 -224.263177) (xy 133.91424 -224.217045) (xy 133.944672 -224.175158) (xy 133.981282 -224.138548)
			(xy 134.023169 -224.108116) (xy 134.069301 -224.08461) (xy 134.118541 -224.068611) (xy 134.169679 -224.060512)
			(xy 134.221453 -224.060512) (xy 134.272591 -224.068611) (xy 134.321831 -224.08461) (xy 134.367963 -224.108116)
			(xy 134.40985 -224.138548) (xy 134.44646 -224.175158) (xy 134.476892 -224.217045) (xy 134.500398 -224.263177)
			(xy 134.516397 -224.312417) (xy 134.524496 -224.363555) (xy 134.525004 -224.389442) (xy 337.635596 -224.389442)
			(xy 337.636029 -224.364106) (xy 337.64379 -224.314032) (xy 337.65912 -224.265734) (xy 337.681659 -224.22035)
			(xy 337.710875 -224.178949) (xy 337.746081 -224.142504) (xy 337.786448 -224.111874) (xy 337.831026 -224.087781)
			(xy 337.878765 -224.070791) (xy 337.903566 -224.065592) (xy 337.926426 -224.061274) (xy 338.13115 -223.706182)
			(xy 338.12353 -223.684338) (xy 338.114887 -223.657995) (xy 338.105572 -223.603345) (xy 338.104988 -223.575626)
			(xy 338.105496 -223.549719) (xy 338.113602 -223.498542) (xy 338.129614 -223.449263) (xy 338.153137 -223.403096)
			(xy 338.183593 -223.361177) (xy 338.220231 -223.324539) (xy 338.26215 -223.294083) (xy 338.308317 -223.27056)
			(xy 338.357596 -223.254548) (xy 338.408773 -223.246442) (xy 338.460587 -223.246442) (xy 338.511764 -223.254548)
			(xy 338.561043 -223.27056) (xy 338.60721 -223.294083) (xy 338.649129 -223.324539) (xy 338.685767 -223.361177)
			(xy 338.716223 -223.403096) (xy 338.739746 -223.449263) (xy 338.755758 -223.498542) (xy 338.763864 -223.549719)
			(xy 338.764372 -223.575626) (xy 338.763897 -223.600971) (xy 338.756121 -223.651063) (xy 338.740771 -223.699374)
			(xy 338.718208 -223.744767) (xy 338.688966 -223.786173) (xy 338.653731 -223.822617) (xy 338.613335 -223.853239)
			(xy 338.568728 -223.877319) (xy 338.520962 -223.89429) (xy 338.496148 -223.899476) (xy 338.473288 -223.903794)
			(xy 338.268564 -224.258632) (xy 338.276184 -224.280476) (xy 338.284739 -224.306769) (xy 338.293932 -224.361289)
			(xy 338.294472 -224.388934) (xy 338.294472 -224.389442) (xy 338.575396 -224.389442) (xy 338.575904 -224.363555)
			(xy 338.584003 -224.312417) (xy 338.600002 -224.263177) (xy 338.623508 -224.217045) (xy 338.65394 -224.175158)
			(xy 338.69055 -224.138548) (xy 338.732437 -224.108116) (xy 338.778569 -224.08461) (xy 338.827809 -224.068611)
			(xy 338.878947 -224.060512) (xy 338.930721 -224.060512) (xy 338.981859 -224.068611) (xy 339.031099 -224.08461)
			(xy 339.077231 -224.108116) (xy 339.119118 -224.138548) (xy 339.155728 -224.175158) (xy 339.18616 -224.217045)
			(xy 339.209666 -224.263177) (xy 339.225665 -224.312417) (xy 339.233764 -224.363555) (xy 339.234272 -224.389442)
			(xy 339.515196 -224.389442) (xy 339.515629 -224.364106) (xy 339.52339 -224.314032) (xy 339.53872 -224.265734)
			(xy 339.561259 -224.22035) (xy 339.590475 -224.178949) (xy 339.625681 -224.142504) (xy 339.666048 -224.111874)
			(xy 339.710626 -224.087781) (xy 339.758365 -224.070791) (xy 339.783166 -224.065592) (xy 339.806026 -224.061274)
			(xy 340.01075 -223.706182) (xy 340.00313 -223.684338) (xy 339.994487 -223.657995) (xy 339.985172 -223.603345)
			(xy 339.984588 -223.575626) (xy 339.985096 -223.549719) (xy 339.993202 -223.498542) (xy 340.009214 -223.449263)
			(xy 340.032737 -223.403096) (xy 340.063193 -223.361177) (xy 340.099831 -223.324539) (xy 340.14175 -223.294083)
			(xy 340.187917 -223.27056) (xy 340.237196 -223.254548) (xy 340.288373 -223.246442) (xy 340.340187 -223.246442)
			(xy 340.391364 -223.254548) (xy 340.440643 -223.27056) (xy 340.48681 -223.294083) (xy 340.528729 -223.324539)
			(xy 340.565367 -223.361177) (xy 340.595823 -223.403096) (xy 340.619346 -223.449263) (xy 340.635358 -223.498542)
			(xy 340.643464 -223.549719) (xy 340.643972 -223.575626) (xy 340.643497 -223.600971) (xy 340.635721 -223.651063)
			(xy 340.620371 -223.699374) (xy 340.597808 -223.744767) (xy 340.568566 -223.786173) (xy 340.533331 -223.822617)
			(xy 340.492935 -223.853239) (xy 340.448328 -223.877319) (xy 340.400562 -223.89429) (xy 340.375748 -223.899476)
			(xy 340.352888 -223.903794) (xy 340.148164 -224.258632) (xy 340.155784 -224.280476) (xy 340.164339 -224.306769)
			(xy 340.173532 -224.361289) (xy 340.174072 -224.388934) (xy 340.174072 -224.389442) (xy 340.454996 -224.389442)
			(xy 340.455504 -224.363555) (xy 340.463603 -224.312417) (xy 340.479602 -224.263177) (xy 340.503108 -224.217045)
			(xy 340.53354 -224.175158) (xy 340.57015 -224.138548) (xy 340.612037 -224.108116) (xy 340.658169 -224.08461)
			(xy 340.707409 -224.068611) (xy 340.758547 -224.060512) (xy 340.810321 -224.060512) (xy 340.861459 -224.068611)
			(xy 340.910699 -224.08461) (xy 340.956831 -224.108116) (xy 340.998718 -224.138548) (xy 341.035328 -224.175158)
			(xy 341.06576 -224.217045) (xy 341.089266 -224.263177) (xy 341.105265 -224.312417) (xy 341.113364 -224.363555)
			(xy 341.113872 -224.389442) (xy 341.394796 -224.389442) (xy 341.395229 -224.364106) (xy 341.40299 -224.314032)
			(xy 341.41832 -224.265734) (xy 341.440859 -224.22035) (xy 341.470075 -224.178949) (xy 341.505281 -224.142504)
			(xy 341.545648 -224.111874) (xy 341.590226 -224.087781) (xy 341.637965 -224.070791) (xy 341.662766 -224.065592)
			(xy 341.685626 -224.061274) (xy 341.89035 -223.706436) (xy 341.88273 -223.684338) (xy 341.874102 -223.657991)
			(xy 341.864779 -223.603344) (xy 341.864188 -223.575626) (xy 341.864696 -223.549719) (xy 341.872802 -223.498542)
			(xy 341.888814 -223.449263) (xy 341.912337 -223.403096) (xy 341.942793 -223.361177) (xy 341.979431 -223.324539)
			(xy 342.02135 -223.294083) (xy 342.067517 -223.27056) (xy 342.116796 -223.254548) (xy 342.167973 -223.246442)
			(xy 342.219787 -223.246442) (xy 342.270964 -223.254548) (xy 342.320243 -223.27056) (xy 342.36641 -223.294083)
			(xy 342.408329 -223.324539) (xy 342.444967 -223.361177) (xy 342.475423 -223.403096) (xy 342.498946 -223.449263)
			(xy 342.514958 -223.498542) (xy 342.523064 -223.549719) (xy 342.523572 -223.575626) (xy 342.523181 -223.600993)
			(xy 342.515428 -223.651131) (xy 342.500077 -223.699486) (xy 342.477492 -223.744915) (xy 342.448207 -223.786344)
			(xy 342.412916 -223.822791) (xy 342.372452 -223.853396) (xy 342.327774 -223.877433) (xy 342.279939 -223.894334)
			(xy 342.255094 -223.899476) (xy 342.232234 -223.903794) (xy 342.02751 -224.258632) (xy 342.035384 -224.280476)
			(xy 342.043957 -224.306897) (xy 342.053158 -224.36167) (xy 342.053672 -224.389442) (xy 342.334596 -224.389442)
			(xy 342.335104 -224.363555) (xy 342.343203 -224.312417) (xy 342.359202 -224.263177) (xy 342.382708 -224.217045)
			(xy 342.41314 -224.175158) (xy 342.44975 -224.138548) (xy 342.491637 -224.108116) (xy 342.537769 -224.08461)
			(xy 342.587009 -224.068611) (xy 342.638147 -224.060512) (xy 342.689921 -224.060512) (xy 342.741059 -224.068611)
			(xy 342.790299 -224.08461) (xy 342.836431 -224.108116) (xy 342.878318 -224.138548) (xy 342.914928 -224.175158)
			(xy 342.94536 -224.217045) (xy 342.968866 -224.263177) (xy 342.984865 -224.312417) (xy 342.992964 -224.363555)
			(xy 342.993472 -224.389442) (xy 343.274396 -224.389442) (xy 343.274829 -224.364106) (xy 343.28259 -224.314032)
			(xy 343.29792 -224.265734) (xy 343.320459 -224.22035) (xy 343.349675 -224.178949) (xy 343.384881 -224.142504)
			(xy 343.425248 -224.111874) (xy 343.469826 -224.087781) (xy 343.517565 -224.070791) (xy 343.542366 -224.065592)
			(xy 343.565226 -224.061274) (xy 343.76995 -223.706436) (xy 343.76233 -223.684338) (xy 343.753702 -223.657991)
			(xy 343.744379 -223.603344) (xy 343.743788 -223.575626) (xy 343.744296 -223.549719) (xy 343.752402 -223.498542)
			(xy 343.768414 -223.449263) (xy 343.791937 -223.403096) (xy 343.822393 -223.361177) (xy 343.859031 -223.324539)
			(xy 343.90095 -223.294083) (xy 343.947117 -223.27056) (xy 343.996396 -223.254548) (xy 344.047573 -223.246442)
			(xy 344.099387 -223.246442) (xy 344.150564 -223.254548) (xy 344.199843 -223.27056) (xy 344.24601 -223.294083)
			(xy 344.287929 -223.324539) (xy 344.324567 -223.361177) (xy 344.355023 -223.403096) (xy 344.378546 -223.449263)
			(xy 344.394558 -223.498542) (xy 344.402664 -223.549719) (xy 344.403172 -223.575626) (xy 344.402781 -223.600993)
			(xy 344.395028 -223.651131) (xy 344.379677 -223.699486) (xy 344.357092 -223.744915) (xy 344.327807 -223.786344)
			(xy 344.292516 -223.822791) (xy 344.252052 -223.853396) (xy 344.207374 -223.877433) (xy 344.159539 -223.894334)
			(xy 344.134694 -223.899476) (xy 344.111834 -223.903794) (xy 343.90711 -224.258632) (xy 343.914984 -224.280476)
			(xy 343.923557 -224.306897) (xy 343.932758 -224.36167) (xy 343.933272 -224.389442) (xy 344.214196 -224.389442)
			(xy 344.214704 -224.363555) (xy 344.222803 -224.312417) (xy 344.238802 -224.263177) (xy 344.262308 -224.217045)
			(xy 344.29274 -224.175158) (xy 344.32935 -224.138548) (xy 344.371237 -224.108116) (xy 344.417369 -224.08461)
			(xy 344.466609 -224.068611) (xy 344.517747 -224.060512) (xy 344.569521 -224.060512) (xy 344.620659 -224.068611)
			(xy 344.669899 -224.08461) (xy 344.716031 -224.108116) (xy 344.757918 -224.138548) (xy 344.794528 -224.175158)
			(xy 344.82496 -224.217045) (xy 344.848466 -224.263177) (xy 344.864465 -224.312417) (xy 344.872564 -224.363555)
			(xy 344.873072 -224.389442) (xy 345.153996 -224.389442) (xy 345.154429 -224.364106) (xy 345.16219 -224.314032)
			(xy 345.17752 -224.265734) (xy 345.200059 -224.22035) (xy 345.229275 -224.178949) (xy 345.264481 -224.142504)
			(xy 345.304848 -224.111874) (xy 345.349426 -224.087781) (xy 345.397165 -224.070791) (xy 345.421966 -224.065592)
			(xy 345.444826 -224.061274) (xy 345.64955 -223.706436) (xy 345.64193 -223.684338) (xy 345.633302 -223.657991)
			(xy 345.623979 -223.603344) (xy 345.623388 -223.575626) (xy 345.623896 -223.549719) (xy 345.632002 -223.498542)
			(xy 345.648014 -223.449263) (xy 345.671537 -223.403096) (xy 345.701993 -223.361177) (xy 345.738631 -223.324539)
			(xy 345.78055 -223.294083) (xy 345.826717 -223.27056) (xy 345.875996 -223.254548) (xy 345.927173 -223.246442)
			(xy 345.978987 -223.246442) (xy 346.030164 -223.254548) (xy 346.079443 -223.27056) (xy 346.12561 -223.294083)
			(xy 346.167529 -223.324539) (xy 346.204167 -223.361177) (xy 346.234623 -223.403096) (xy 346.258146 -223.449263)
			(xy 346.274158 -223.498542) (xy 346.282264 -223.549719) (xy 346.282772 -223.575626) (xy 346.282381 -223.600993)
			(xy 346.274628 -223.651131) (xy 346.259277 -223.699486) (xy 346.236692 -223.744915) (xy 346.207407 -223.786344)
			(xy 346.172116 -223.822791) (xy 346.131652 -223.853396) (xy 346.086974 -223.877433) (xy 346.039139 -223.894334)
			(xy 346.014294 -223.899476) (xy 345.991434 -223.903794) (xy 345.78671 -224.258632) (xy 345.794584 -224.280476)
			(xy 345.803157 -224.306897) (xy 345.812358 -224.36167) (xy 345.812872 -224.389442) (xy 346.093796 -224.389442)
			(xy 346.094304 -224.363555) (xy 346.102403 -224.312417) (xy 346.118402 -224.263177) (xy 346.141908 -224.217045)
			(xy 346.17234 -224.175158) (xy 346.20895 -224.138548) (xy 346.250837 -224.108116) (xy 346.296969 -224.08461)
			(xy 346.346209 -224.068611) (xy 346.397347 -224.060512) (xy 346.449121 -224.060512) (xy 346.500259 -224.068611)
			(xy 346.549499 -224.08461) (xy 346.595631 -224.108116) (xy 346.637518 -224.138548) (xy 346.674128 -224.175158)
			(xy 346.70456 -224.217045) (xy 346.728066 -224.263177) (xy 346.744065 -224.312417) (xy 346.752164 -224.363555)
			(xy 346.752672 -224.389442) (xy 347.033596 -224.389442) (xy 347.034029 -224.364106) (xy 347.04179 -224.314032)
			(xy 347.05712 -224.265734) (xy 347.079659 -224.22035) (xy 347.108875 -224.178949) (xy 347.144081 -224.142504)
			(xy 347.184448 -224.111874) (xy 347.229026 -224.087781) (xy 347.276765 -224.070791) (xy 347.301566 -224.065592)
			(xy 347.324426 -224.061274) (xy 347.52915 -223.706436) (xy 347.52153 -223.684338) (xy 347.512902 -223.657991)
			(xy 347.503579 -223.603344) (xy 347.502988 -223.575626) (xy 347.503496 -223.549719) (xy 347.511602 -223.498542)
			(xy 347.527614 -223.449263) (xy 347.551137 -223.403096) (xy 347.581593 -223.361177) (xy 347.618231 -223.324539)
			(xy 347.66015 -223.294083) (xy 347.706317 -223.27056) (xy 347.755596 -223.254548) (xy 347.806773 -223.246442)
			(xy 347.858587 -223.246442) (xy 347.909764 -223.254548) (xy 347.959043 -223.27056) (xy 348.00521 -223.294083)
			(xy 348.047129 -223.324539) (xy 348.083767 -223.361177) (xy 348.114223 -223.403096) (xy 348.137746 -223.449263)
			(xy 348.153758 -223.498542) (xy 348.161864 -223.549719) (xy 348.162372 -223.575626) (xy 348.161981 -223.600993)
			(xy 348.154228 -223.651131) (xy 348.138877 -223.699486) (xy 348.116292 -223.744915) (xy 348.087007 -223.786344)
			(xy 348.051716 -223.822791) (xy 348.011252 -223.853396) (xy 347.966574 -223.877433) (xy 347.918739 -223.894334)
			(xy 347.893894 -223.899476) (xy 347.871034 -223.903794) (xy 347.66631 -224.258632) (xy 347.674184 -224.280476)
			(xy 347.682757 -224.306897) (xy 347.691958 -224.36167) (xy 347.692472 -224.389442) (xy 347.973396 -224.389442)
			(xy 347.973904 -224.363555) (xy 347.982003 -224.312417) (xy 347.998002 -224.263177) (xy 348.021508 -224.217045)
			(xy 348.05194 -224.175158) (xy 348.08855 -224.138548) (xy 348.130437 -224.108116) (xy 348.176569 -224.08461)
			(xy 348.225809 -224.068611) (xy 348.276947 -224.060512) (xy 348.328721 -224.060512) (xy 348.379859 -224.068611)
			(xy 348.429099 -224.08461) (xy 348.475231 -224.108116) (xy 348.517118 -224.138548) (xy 348.553728 -224.175158)
			(xy 348.58416 -224.217045) (xy 348.607666 -224.263177) (xy 348.623665 -224.312417) (xy 348.631764 -224.363555)
			(xy 348.632272 -224.389442) (xy 348.913196 -224.389442) (xy 348.913629 -224.364106) (xy 348.92139 -224.314032)
			(xy 348.93672 -224.265734) (xy 348.959259 -224.22035) (xy 348.988475 -224.178949) (xy 349.023681 -224.142504)
			(xy 349.064048 -224.111874) (xy 349.108626 -224.087781) (xy 349.156365 -224.070791) (xy 349.181166 -224.065592)
			(xy 349.204026 -224.061274) (xy 349.40875 -223.706436) (xy 349.40113 -223.684338) (xy 349.392502 -223.657991)
			(xy 349.383179 -223.603344) (xy 349.382588 -223.575626) (xy 349.383096 -223.549719) (xy 349.391202 -223.498542)
			(xy 349.407214 -223.449263) (xy 349.430737 -223.403096) (xy 349.461193 -223.361177) (xy 349.497831 -223.324539)
			(xy 349.53975 -223.294083) (xy 349.585917 -223.27056) (xy 349.635196 -223.254548) (xy 349.686373 -223.246442)
			(xy 349.738187 -223.246442) (xy 349.789364 -223.254548) (xy 349.838643 -223.27056) (xy 349.88481 -223.294083)
			(xy 349.926729 -223.324539) (xy 349.963367 -223.361177) (xy 349.993823 -223.403096) (xy 350.017346 -223.449263)
			(xy 350.033358 -223.498542) (xy 350.041464 -223.549719) (xy 350.041972 -223.575626) (xy 350.041581 -223.600993)
			(xy 350.033828 -223.651131) (xy 350.018477 -223.699486) (xy 349.995892 -223.744915) (xy 349.966607 -223.786344)
			(xy 349.931316 -223.822791) (xy 349.890852 -223.853396) (xy 349.846174 -223.877433) (xy 349.798339 -223.894334)
			(xy 349.773494 -223.899476) (xy 349.750634 -223.903794) (xy 349.54591 -224.258632) (xy 349.553784 -224.280476)
			(xy 349.562357 -224.306897) (xy 349.571558 -224.36167) (xy 349.572072 -224.389442) (xy 349.852996 -224.389442)
			(xy 349.853504 -224.363555) (xy 349.861603 -224.312417) (xy 349.877602 -224.263177) (xy 349.901108 -224.217045)
			(xy 349.93154 -224.175158) (xy 349.96815 -224.138548) (xy 350.010037 -224.108116) (xy 350.056169 -224.08461)
			(xy 350.105409 -224.068611) (xy 350.156547 -224.060512) (xy 350.208321 -224.060512) (xy 350.259459 -224.068611)
			(xy 350.308699 -224.08461) (xy 350.354831 -224.108116) (xy 350.396718 -224.138548) (xy 350.433328 -224.175158)
			(xy 350.46376 -224.217045) (xy 350.487266 -224.263177) (xy 350.503265 -224.312417) (xy 350.511364 -224.363555)
			(xy 350.511872 -224.389442) (xy 350.792796 -224.389442) (xy 350.793229 -224.364106) (xy 350.80099 -224.314032)
			(xy 350.81632 -224.265734) (xy 350.838859 -224.22035) (xy 350.868075 -224.178949) (xy 350.903281 -224.142504)
			(xy 350.943648 -224.111874) (xy 350.988226 -224.087781) (xy 351.035965 -224.070791) (xy 351.060766 -224.065592)
			(xy 351.083626 -224.061274) (xy 351.28835 -223.706436) (xy 351.28073 -223.684338) (xy 351.272102 -223.657991)
			(xy 351.262779 -223.603344) (xy 351.262188 -223.575626) (xy 351.262696 -223.549719) (xy 351.270802 -223.498542)
			(xy 351.286814 -223.449263) (xy 351.310337 -223.403096) (xy 351.340793 -223.361177) (xy 351.377431 -223.324539)
			(xy 351.41935 -223.294083) (xy 351.465517 -223.27056) (xy 351.514796 -223.254548) (xy 351.565973 -223.246442)
			(xy 351.617787 -223.246442) (xy 351.668964 -223.254548) (xy 351.718243 -223.27056) (xy 351.76441 -223.294083)
			(xy 351.806329 -223.324539) (xy 351.842967 -223.361177) (xy 351.873423 -223.403096) (xy 351.896946 -223.449263)
			(xy 351.912958 -223.498542) (xy 351.921064 -223.549719) (xy 351.921572 -223.575626) (xy 351.921181 -223.600993)
			(xy 351.913428 -223.651131) (xy 351.898077 -223.699486) (xy 351.875492 -223.744915) (xy 351.846207 -223.786344)
			(xy 351.810916 -223.822791) (xy 351.770452 -223.853396) (xy 351.725774 -223.877433) (xy 351.677939 -223.894334)
			(xy 351.653094 -223.899476) (xy 351.630234 -223.903794) (xy 351.42551 -224.258632) (xy 351.433384 -224.280476)
			(xy 351.441957 -224.306897) (xy 351.451158 -224.36167) (xy 351.451672 -224.389442) (xy 351.732596 -224.389442)
			(xy 351.733104 -224.363555) (xy 351.741203 -224.312417) (xy 351.757202 -224.263177) (xy 351.780708 -224.217045)
			(xy 351.81114 -224.175158) (xy 351.84775 -224.138548) (xy 351.889637 -224.108116) (xy 351.935769 -224.08461)
			(xy 351.985009 -224.068611) (xy 352.036147 -224.060512) (xy 352.087921 -224.060512) (xy 352.139059 -224.068611)
			(xy 352.188299 -224.08461) (xy 352.234431 -224.108116) (xy 352.276318 -224.138548) (xy 352.312928 -224.175158)
			(xy 352.34336 -224.217045) (xy 352.366866 -224.263177) (xy 352.382865 -224.312417) (xy 352.390964 -224.363555)
			(xy 352.391472 -224.389442) (xy 352.672396 -224.389442) (xy 352.672829 -224.364106) (xy 352.68059 -224.314032)
			(xy 352.69592 -224.265734) (xy 352.718459 -224.22035) (xy 352.747675 -224.178949) (xy 352.782881 -224.142504)
			(xy 352.823248 -224.111874) (xy 352.867826 -224.087781) (xy 352.915565 -224.070791) (xy 352.940366 -224.065592)
			(xy 352.963226 -224.061274) (xy 353.16795 -223.706436) (xy 353.16033 -223.684338) (xy 353.151702 -223.657991)
			(xy 353.142379 -223.603344) (xy 353.141788 -223.575626) (xy 353.142296 -223.549719) (xy 353.150402 -223.498542)
			(xy 353.166414 -223.449263) (xy 353.189937 -223.403096) (xy 353.220393 -223.361177) (xy 353.257031 -223.324539)
			(xy 353.29895 -223.294083) (xy 353.345117 -223.27056) (xy 353.394396 -223.254548) (xy 353.445573 -223.246442)
			(xy 353.497387 -223.246442) (xy 353.548564 -223.254548) (xy 353.597843 -223.27056) (xy 353.64401 -223.294083)
			(xy 353.685929 -223.324539) (xy 353.722567 -223.361177) (xy 353.753023 -223.403096) (xy 353.776546 -223.449263)
			(xy 353.792558 -223.498542) (xy 353.800664 -223.549719) (xy 353.801172 -223.575626) (xy 353.800781 -223.600993)
			(xy 353.793028 -223.651131) (xy 353.777677 -223.699486) (xy 353.755092 -223.744915) (xy 353.725807 -223.786344)
			(xy 353.690516 -223.822791) (xy 353.650052 -223.853396) (xy 353.605374 -223.877433) (xy 353.557539 -223.894334)
			(xy 353.532694 -223.899476) (xy 353.509834 -223.903794) (xy 353.30511 -224.258632) (xy 353.312984 -224.280476)
			(xy 353.321557 -224.306897) (xy 353.330758 -224.36167) (xy 353.331272 -224.389442) (xy 353.612196 -224.389442)
			(xy 353.612704 -224.363555) (xy 353.620803 -224.312417) (xy 353.636802 -224.263177) (xy 353.660308 -224.217045)
			(xy 353.69074 -224.175158) (xy 353.72735 -224.138548) (xy 353.769237 -224.108116) (xy 353.815369 -224.08461)
			(xy 353.864609 -224.068611) (xy 353.915747 -224.060512) (xy 353.967521 -224.060512) (xy 354.018659 -224.068611)
			(xy 354.067899 -224.08461) (xy 354.114031 -224.108116) (xy 354.155918 -224.138548) (xy 354.192528 -224.175158)
			(xy 354.22296 -224.217045) (xy 354.246466 -224.263177) (xy 354.262465 -224.312417) (xy 354.270564 -224.363555)
			(xy 354.271072 -224.389442) (xy 354.551996 -224.389442) (xy 354.552429 -224.364106) (xy 354.56019 -224.314032)
			(xy 354.57552 -224.265734) (xy 354.598059 -224.22035) (xy 354.627275 -224.178949) (xy 354.662481 -224.142504)
			(xy 354.702848 -224.111874) (xy 354.747426 -224.087781) (xy 354.795165 -224.070791) (xy 354.819966 -224.065592)
			(xy 354.842826 -224.061274) (xy 355.04755 -223.706436) (xy 355.03993 -223.684338) (xy 355.031302 -223.657991)
			(xy 355.021979 -223.603344) (xy 355.021388 -223.575626) (xy 355.021896 -223.549719) (xy 355.030002 -223.498542)
			(xy 355.046014 -223.449263) (xy 355.069537 -223.403096) (xy 355.099993 -223.361177) (xy 355.136631 -223.324539)
			(xy 355.17855 -223.294083) (xy 355.224717 -223.27056) (xy 355.273996 -223.254548) (xy 355.325173 -223.246442)
			(xy 355.376987 -223.246442) (xy 355.428164 -223.254548) (xy 355.477443 -223.27056) (xy 355.52361 -223.294083)
			(xy 355.565529 -223.324539) (xy 355.602167 -223.361177) (xy 355.632623 -223.403096) (xy 355.656146 -223.449263)
			(xy 355.672158 -223.498542) (xy 355.680264 -223.549719) (xy 355.680772 -223.575626) (xy 355.680381 -223.600993)
			(xy 355.672628 -223.651131) (xy 355.657277 -223.699486) (xy 355.634692 -223.744915) (xy 355.605407 -223.786344)
			(xy 355.570116 -223.822791) (xy 355.529652 -223.853396) (xy 355.484974 -223.877433) (xy 355.437139 -223.894334)
			(xy 355.412294 -223.899476) (xy 355.389434 -223.903794) (xy 355.18471 -224.258632) (xy 355.192584 -224.280476)
			(xy 355.201157 -224.306897) (xy 355.210358 -224.36167) (xy 355.210872 -224.389442) (xy 355.491796 -224.389442)
			(xy 355.492304 -224.363555) (xy 355.500403 -224.312417) (xy 355.516402 -224.263177) (xy 355.539908 -224.217045)
			(xy 355.57034 -224.175158) (xy 355.60695 -224.138548) (xy 355.648837 -224.108116) (xy 355.694969 -224.08461)
			(xy 355.744209 -224.068611) (xy 355.795347 -224.060512) (xy 355.847121 -224.060512) (xy 355.898259 -224.068611)
			(xy 355.947499 -224.08461) (xy 355.993631 -224.108116) (xy 356.035518 -224.138548) (xy 356.072128 -224.175158)
			(xy 356.10256 -224.217045) (xy 356.126066 -224.263177) (xy 356.142065 -224.312417) (xy 356.150164 -224.363555)
			(xy 356.150672 -224.389442) (xy 356.431596 -224.389442) (xy 356.432029 -224.364106) (xy 356.43979 -224.314032)
			(xy 356.45512 -224.265734) (xy 356.477659 -224.22035) (xy 356.506875 -224.178949) (xy 356.542081 -224.142504)
			(xy 356.582448 -224.111874) (xy 356.627026 -224.087781) (xy 356.674765 -224.070791) (xy 356.699566 -224.065592)
			(xy 356.722426 -224.061274) (xy 356.92715 -223.706436) (xy 356.91953 -223.684338) (xy 356.910902 -223.657991)
			(xy 356.901579 -223.603344) (xy 356.900988 -223.575626) (xy 356.901496 -223.549719) (xy 356.909602 -223.498542)
			(xy 356.925614 -223.449263) (xy 356.949137 -223.403096) (xy 356.979593 -223.361177) (xy 357.016231 -223.324539)
			(xy 357.05815 -223.294083) (xy 357.104317 -223.27056) (xy 357.153596 -223.254548) (xy 357.204773 -223.246442)
			(xy 357.256587 -223.246442) (xy 357.307764 -223.254548) (xy 357.357043 -223.27056) (xy 357.40321 -223.294083)
			(xy 357.445129 -223.324539) (xy 357.481767 -223.361177) (xy 357.512223 -223.403096) (xy 357.535746 -223.449263)
			(xy 357.551758 -223.498542) (xy 357.559864 -223.549719) (xy 357.560372 -223.575626) (xy 357.559981 -223.600993)
			(xy 357.552228 -223.651131) (xy 357.536877 -223.699486) (xy 357.514292 -223.744915) (xy 357.485007 -223.786344)
			(xy 357.449716 -223.822791) (xy 357.409252 -223.853396) (xy 357.364574 -223.877433) (xy 357.316739 -223.894334)
			(xy 357.291894 -223.899476) (xy 357.269034 -223.903794) (xy 357.06431 -224.258632) (xy 357.072184 -224.280476)
			(xy 357.080757 -224.306897) (xy 357.089958 -224.36167) (xy 357.090472 -224.389442) (xy 357.371396 -224.389442)
			(xy 357.371904 -224.363555) (xy 357.380003 -224.312417) (xy 357.396002 -224.263177) (xy 357.419508 -224.217045)
			(xy 357.44994 -224.175158) (xy 357.48655 -224.138548) (xy 357.528437 -224.108116) (xy 357.574569 -224.08461)
			(xy 357.623809 -224.068611) (xy 357.674947 -224.060512) (xy 357.726721 -224.060512) (xy 357.777859 -224.068611)
			(xy 357.827099 -224.08461) (xy 357.873231 -224.108116) (xy 357.915118 -224.138548) (xy 357.951728 -224.175158)
			(xy 357.98216 -224.217045) (xy 358.005666 -224.263177) (xy 358.021665 -224.312417) (xy 358.029764 -224.363555)
			(xy 358.030272 -224.389442) (xy 358.311196 -224.389442) (xy 358.311629 -224.364106) (xy 358.31939 -224.314032)
			(xy 358.33472 -224.265734) (xy 358.357259 -224.22035) (xy 358.386475 -224.178949) (xy 358.421681 -224.142504)
			(xy 358.462048 -224.111874) (xy 358.506626 -224.087781) (xy 358.554365 -224.070791) (xy 358.579166 -224.065592)
			(xy 358.602026 -224.061274) (xy 358.80675 -223.706436) (xy 358.79913 -223.684338) (xy 358.790502 -223.657991)
			(xy 358.781179 -223.603344) (xy 358.780588 -223.575626) (xy 358.781096 -223.549719) (xy 358.789202 -223.498542)
			(xy 358.805214 -223.449263) (xy 358.828737 -223.403096) (xy 358.859193 -223.361177) (xy 358.895831 -223.324539)
			(xy 358.93775 -223.294083) (xy 358.983917 -223.27056) (xy 359.033196 -223.254548) (xy 359.084373 -223.246442)
			(xy 359.136187 -223.246442) (xy 359.187364 -223.254548) (xy 359.236643 -223.27056) (xy 359.28281 -223.294083)
			(xy 359.324729 -223.324539) (xy 359.361367 -223.361177) (xy 359.391823 -223.403096) (xy 359.415346 -223.449263)
			(xy 359.431358 -223.498542) (xy 359.439464 -223.549719) (xy 359.439972 -223.575626) (xy 359.439581 -223.600993)
			(xy 359.431828 -223.651131) (xy 359.416477 -223.699486) (xy 359.393892 -223.744915) (xy 359.364607 -223.786344)
			(xy 359.329316 -223.822791) (xy 359.288852 -223.853396) (xy 359.244174 -223.877433) (xy 359.196339 -223.894334)
			(xy 359.171494 -223.899476) (xy 359.148634 -223.903794) (xy 358.94391 -224.258632) (xy 358.951784 -224.280476)
			(xy 358.960357 -224.306897) (xy 358.969558 -224.36167) (xy 358.970072 -224.389442) (xy 359.250996 -224.389442)
			(xy 359.251504 -224.363555) (xy 359.259603 -224.312417) (xy 359.275602 -224.263177) (xy 359.299108 -224.217045)
			(xy 359.32954 -224.175158) (xy 359.36615 -224.138548) (xy 359.408037 -224.108116) (xy 359.454169 -224.08461)
			(xy 359.503409 -224.068611) (xy 359.554547 -224.060512) (xy 359.606321 -224.060512) (xy 359.657459 -224.068611)
			(xy 359.706699 -224.08461) (xy 359.752831 -224.108116) (xy 359.794718 -224.138548) (xy 359.831328 -224.175158)
			(xy 359.86176 -224.217045) (xy 359.885266 -224.263177) (xy 359.901265 -224.312417) (xy 359.909364 -224.363555)
			(xy 359.909872 -224.389442) (xy 360.190796 -224.389442) (xy 360.191229 -224.364106) (xy 360.19899 -224.314032)
			(xy 360.21432 -224.265734) (xy 360.236859 -224.22035) (xy 360.266075 -224.178949) (xy 360.301281 -224.142504)
			(xy 360.341648 -224.111874) (xy 360.386226 -224.087781) (xy 360.433965 -224.070791) (xy 360.458766 -224.065592)
			(xy 360.481626 -224.061274) (xy 360.68635 -223.706436) (xy 360.67873 -223.684338) (xy 360.670102 -223.657991)
			(xy 360.660779 -223.603344) (xy 360.660188 -223.575626) (xy 360.660696 -223.549719) (xy 360.668802 -223.498542)
			(xy 360.684814 -223.449263) (xy 360.708337 -223.403096) (xy 360.738793 -223.361177) (xy 360.775431 -223.324539)
			(xy 360.81735 -223.294083) (xy 360.863517 -223.27056) (xy 360.912796 -223.254548) (xy 360.963973 -223.246442)
			(xy 361.015787 -223.246442) (xy 361.066964 -223.254548) (xy 361.116243 -223.27056) (xy 361.16241 -223.294083)
			(xy 361.204329 -223.324539) (xy 361.240967 -223.361177) (xy 361.271423 -223.403096) (xy 361.294946 -223.449263)
			(xy 361.310958 -223.498542) (xy 361.319064 -223.549719) (xy 361.319572 -223.575626) (xy 361.319181 -223.600993)
			(xy 361.311428 -223.651131) (xy 361.296077 -223.699486) (xy 361.273492 -223.744915) (xy 361.244207 -223.786344)
			(xy 361.208916 -223.822791) (xy 361.168452 -223.853396) (xy 361.123774 -223.877433) (xy 361.075939 -223.894334)
			(xy 361.051094 -223.899476) (xy 361.028234 -223.903794) (xy 360.82351 -224.258632) (xy 360.831384 -224.280476)
			(xy 360.839957 -224.306897) (xy 360.849158 -224.36167) (xy 360.849672 -224.389442) (xy 361.130596 -224.389442)
			(xy 361.131104 -224.363555) (xy 361.139203 -224.312417) (xy 361.155202 -224.263177) (xy 361.178708 -224.217045)
			(xy 361.20914 -224.175158) (xy 361.24575 -224.138548) (xy 361.287637 -224.108116) (xy 361.333769 -224.08461)
			(xy 361.383009 -224.068611) (xy 361.434147 -224.060512) (xy 361.485921 -224.060512) (xy 361.537059 -224.068611)
			(xy 361.586299 -224.08461) (xy 361.632431 -224.108116) (xy 361.674318 -224.138548) (xy 361.710928 -224.175158)
			(xy 361.74136 -224.217045) (xy 361.764866 -224.263177) (xy 361.780865 -224.312417) (xy 361.788964 -224.363555)
			(xy 361.789472 -224.389442) (xy 362.070396 -224.389442) (xy 362.070829 -224.364106) (xy 362.07859 -224.314032)
			(xy 362.09392 -224.265734) (xy 362.116459 -224.22035) (xy 362.145675 -224.178949) (xy 362.180881 -224.142504)
			(xy 362.221248 -224.111874) (xy 362.265826 -224.087781) (xy 362.313565 -224.070791) (xy 362.338366 -224.065592)
			(xy 362.361226 -224.061274) (xy 362.566204 -223.706182) (xy 362.558584 -223.684084) (xy 362.550064 -223.657913)
			(xy 362.540871 -223.603651) (xy 362.540296 -223.576134) (xy 362.540296 -223.575626) (xy 362.540804 -223.549739)
			(xy 362.548903 -223.498601) (xy 362.564902 -223.449361) (xy 362.588408 -223.403229) (xy 362.61884 -223.361342)
			(xy 362.65545 -223.324732) (xy 362.697337 -223.2943) (xy 362.743469 -223.270794) (xy 362.792709 -223.254795)
			(xy 362.843847 -223.246696) (xy 362.895621 -223.246696) (xy 362.946759 -223.254795) (xy 362.995999 -223.270794)
			(xy 363.042131 -223.2943) (xy 363.084018 -223.324732) (xy 363.120628 -223.361342) (xy 363.15106 -223.403229)
			(xy 363.174566 -223.449361) (xy 363.190565 -223.498601) (xy 363.198664 -223.549739) (xy 363.199172 -223.575626)
			(xy 363.198781 -223.600993) (xy 363.191028 -223.651131) (xy 363.175677 -223.699486) (xy 363.153092 -223.744915)
			(xy 363.123807 -223.786344) (xy 363.088516 -223.822791) (xy 363.048052 -223.853396) (xy 363.003374 -223.877433)
			(xy 362.955539 -223.894334) (xy 362.930694 -223.899476) (xy 362.907834 -223.903794) (xy 362.70311 -224.258632)
			(xy 362.710984 -224.280476) (xy 362.719557 -224.306897) (xy 362.728758 -224.36167) (xy 362.729272 -224.389442)
			(xy 363.010196 -224.389442) (xy 363.010704 -224.363555) (xy 363.018803 -224.312417) (xy 363.034802 -224.263177)
			(xy 363.058308 -224.217045) (xy 363.08874 -224.175158) (xy 363.12535 -224.138548) (xy 363.167237 -224.108116)
			(xy 363.213369 -224.08461) (xy 363.262609 -224.068611) (xy 363.313747 -224.060512) (xy 363.365521 -224.060512)
			(xy 363.416659 -224.068611) (xy 363.465899 -224.08461) (xy 363.512031 -224.108116) (xy 363.553918 -224.138548)
			(xy 363.590528 -224.175158) (xy 363.62096 -224.217045) (xy 363.644466 -224.263177) (xy 363.660465 -224.312417)
			(xy 363.668564 -224.363555) (xy 363.669072 -224.389442) (xy 363.949996 -224.389442) (xy 363.950429 -224.364106)
			(xy 363.95819 -224.314032) (xy 363.97352 -224.265734) (xy 363.996059 -224.22035) (xy 364.025275 -224.178949)
			(xy 364.060481 -224.142504) (xy 364.100848 -224.111874) (xy 364.145426 -224.087781) (xy 364.193165 -224.070791)
			(xy 364.217966 -224.065592) (xy 364.240826 -224.061274) (xy 364.44555 -223.706436) (xy 364.43793 -223.684338)
			(xy 364.429302 -223.657991) (xy 364.419979 -223.603344) (xy 364.419388 -223.575626) (xy 364.419896 -223.549719)
			(xy 364.428002 -223.498542) (xy 364.444014 -223.449263) (xy 364.467537 -223.403096) (xy 364.497993 -223.361177)
			(xy 364.534631 -223.324539) (xy 364.57655 -223.294083) (xy 364.622717 -223.27056) (xy 364.671996 -223.254548)
			(xy 364.723173 -223.246442) (xy 364.774987 -223.246442) (xy 364.826164 -223.254548) (xy 364.875443 -223.27056)
			(xy 364.92161 -223.294083) (xy 364.963529 -223.324539) (xy 365.000167 -223.361177) (xy 365.030623 -223.403096)
			(xy 365.054146 -223.449263) (xy 365.070158 -223.498542) (xy 365.078264 -223.549719) (xy 365.078772 -223.575626)
			(xy 365.078381 -223.600993) (xy 365.070628 -223.651131) (xy 365.055277 -223.699486) (xy 365.032692 -223.744915)
			(xy 365.003407 -223.786344) (xy 364.968116 -223.822791) (xy 364.927652 -223.853396) (xy 364.882974 -223.877433)
			(xy 364.835139 -223.894334) (xy 364.810294 -223.899476) (xy 364.787434 -223.903794) (xy 364.58271 -224.258632)
			(xy 364.590584 -224.280476) (xy 364.599157 -224.306897) (xy 364.608358 -224.36167) (xy 364.608872 -224.389442)
			(xy 364.889796 -224.389442) (xy 364.890304 -224.363555) (xy 364.898403 -224.312417) (xy 364.914402 -224.263177)
			(xy 364.937908 -224.217045) (xy 364.96834 -224.175158) (xy 365.00495 -224.138548) (xy 365.046837 -224.108116)
			(xy 365.092969 -224.08461) (xy 365.142209 -224.068611) (xy 365.193347 -224.060512) (xy 365.245121 -224.060512)
			(xy 365.296259 -224.068611) (xy 365.345499 -224.08461) (xy 365.391631 -224.108116) (xy 365.433518 -224.138548)
			(xy 365.470128 -224.175158) (xy 365.50056 -224.217045) (xy 365.524066 -224.263177) (xy 365.540065 -224.312417)
			(xy 365.548164 -224.363555) (xy 365.548672 -224.389442) (xy 365.829596 -224.389442) (xy 365.830029 -224.364106)
			(xy 365.83779 -224.314032) (xy 365.85312 -224.265734) (xy 365.875659 -224.22035) (xy 365.904875 -224.178949)
			(xy 365.940081 -224.142504) (xy 365.980448 -224.111874) (xy 366.025026 -224.087781) (xy 366.072765 -224.070791)
			(xy 366.097566 -224.065592) (xy 366.120426 -224.061274) (xy 366.32515 -223.706436) (xy 366.31753 -223.684338)
			(xy 366.308902 -223.657991) (xy 366.299579 -223.603344) (xy 366.298988 -223.575626) (xy 366.299496 -223.549719)
			(xy 366.307602 -223.498542) (xy 366.323614 -223.449263) (xy 366.347137 -223.403096) (xy 366.377593 -223.361177)
			(xy 366.414231 -223.324539) (xy 366.45615 -223.294083) (xy 366.502317 -223.27056) (xy 366.551596 -223.254548)
			(xy 366.602773 -223.246442) (xy 366.654587 -223.246442) (xy 366.705764 -223.254548) (xy 366.755043 -223.27056)
			(xy 366.80121 -223.294083) (xy 366.843129 -223.324539) (xy 366.879767 -223.361177) (xy 366.910223 -223.403096)
			(xy 366.933746 -223.449263) (xy 366.949758 -223.498542) (xy 366.957864 -223.549719) (xy 366.958372 -223.575626)
			(xy 366.957981 -223.600993) (xy 366.950228 -223.651131) (xy 366.934877 -223.699486) (xy 366.912292 -223.744915)
			(xy 366.883007 -223.786344) (xy 366.847716 -223.822791) (xy 366.807252 -223.853396) (xy 366.762574 -223.877433)
			(xy 366.714739 -223.894334) (xy 366.689894 -223.899476) (xy 366.667034 -223.903794) (xy 366.46231 -224.258632)
			(xy 366.470184 -224.280476) (xy 366.478757 -224.306897) (xy 366.487958 -224.36167) (xy 366.488472 -224.389442)
			(xy 366.769396 -224.389442) (xy 366.769904 -224.363555) (xy 366.778003 -224.312417) (xy 366.794002 -224.263177)
			(xy 366.817508 -224.217045) (xy 366.84794 -224.175158) (xy 366.88455 -224.138548) (xy 366.926437 -224.108116)
			(xy 366.972569 -224.08461) (xy 367.021809 -224.068611) (xy 367.072947 -224.060512) (xy 367.124721 -224.060512)
			(xy 367.175859 -224.068611) (xy 367.225099 -224.08461) (xy 367.271231 -224.108116) (xy 367.313118 -224.138548)
			(xy 367.349728 -224.175158) (xy 367.38016 -224.217045) (xy 367.403666 -224.263177) (xy 367.419665 -224.312417)
			(xy 367.427764 -224.363555) (xy 367.428272 -224.389442) (xy 367.709196 -224.389442) (xy 367.709629 -224.364106)
			(xy 367.71739 -224.314032) (xy 367.73272 -224.265734) (xy 367.755259 -224.22035) (xy 367.784475 -224.178949)
			(xy 367.819681 -224.142504) (xy 367.860048 -224.111874) (xy 367.904626 -224.087781) (xy 367.952365 -224.070791)
			(xy 367.977166 -224.065592) (xy 368.000026 -224.061274) (xy 368.20475 -223.706436) (xy 368.19713 -223.684338)
			(xy 368.188502 -223.657991) (xy 368.179179 -223.603344) (xy 368.178588 -223.575626) (xy 368.179096 -223.549719)
			(xy 368.187202 -223.498542) (xy 368.203214 -223.449263) (xy 368.226737 -223.403096) (xy 368.257193 -223.361177)
			(xy 368.293831 -223.324539) (xy 368.33575 -223.294083) (xy 368.381917 -223.27056) (xy 368.431196 -223.254548)
			(xy 368.482373 -223.246442) (xy 368.534187 -223.246442) (xy 368.585364 -223.254548) (xy 368.634643 -223.27056)
			(xy 368.68081 -223.294083) (xy 368.722729 -223.324539) (xy 368.759367 -223.361177) (xy 368.789823 -223.403096)
			(xy 368.813346 -223.449263) (xy 368.829358 -223.498542) (xy 368.837464 -223.549719) (xy 368.837972 -223.575626)
			(xy 368.837581 -223.600993) (xy 368.829828 -223.651131) (xy 368.814477 -223.699486) (xy 368.791892 -223.744915)
			(xy 368.762607 -223.786344) (xy 368.727316 -223.822791) (xy 368.686852 -223.853396) (xy 368.642174 -223.877433)
			(xy 368.594339 -223.894334) (xy 368.569494 -223.899476) (xy 368.546634 -223.903794) (xy 368.34191 -224.258632)
			(xy 368.349784 -224.280476) (xy 368.358357 -224.306897) (xy 368.367558 -224.36167) (xy 368.368072 -224.389442)
			(xy 368.648996 -224.389442) (xy 368.649504 -224.363555) (xy 368.657603 -224.312417) (xy 368.673602 -224.263177)
			(xy 368.697108 -224.217045) (xy 368.72754 -224.175158) (xy 368.76415 -224.138548) (xy 368.806037 -224.108116)
			(xy 368.852169 -224.08461) (xy 368.901409 -224.068611) (xy 368.952547 -224.060512) (xy 369.004321 -224.060512)
			(xy 369.055459 -224.068611) (xy 369.104699 -224.08461) (xy 369.150831 -224.108116) (xy 369.192718 -224.138548)
			(xy 369.229328 -224.175158) (xy 369.25976 -224.217045) (xy 369.283266 -224.263177) (xy 369.299265 -224.312417)
			(xy 369.307364 -224.363555) (xy 369.307872 -224.389442) (xy 369.588796 -224.389442) (xy 369.589229 -224.364106)
			(xy 369.59699 -224.314032) (xy 369.61232 -224.265734) (xy 369.634859 -224.22035) (xy 369.664075 -224.178949)
			(xy 369.699281 -224.142504) (xy 369.739648 -224.111874) (xy 369.784226 -224.087781) (xy 369.831965 -224.070791)
			(xy 369.856766 -224.065592) (xy 369.879626 -224.061274) (xy 370.08435 -223.706436) (xy 370.07673 -223.684338)
			(xy 370.068102 -223.657991) (xy 370.058779 -223.603344) (xy 370.058188 -223.575626) (xy 370.058696 -223.549719)
			(xy 370.066802 -223.498542) (xy 370.082814 -223.449263) (xy 370.106337 -223.403096) (xy 370.136793 -223.361177)
			(xy 370.173431 -223.324539) (xy 370.21535 -223.294083) (xy 370.261517 -223.27056) (xy 370.310796 -223.254548)
			(xy 370.361973 -223.246442) (xy 370.413787 -223.246442) (xy 370.464964 -223.254548) (xy 370.514243 -223.27056)
			(xy 370.56041 -223.294083) (xy 370.602329 -223.324539) (xy 370.638967 -223.361177) (xy 370.669423 -223.403096)
			(xy 370.692946 -223.449263) (xy 370.708958 -223.498542) (xy 370.717064 -223.549719) (xy 370.717572 -223.575626)
			(xy 370.717181 -223.600993) (xy 370.709428 -223.651131) (xy 370.694077 -223.699486) (xy 370.671492 -223.744915)
			(xy 370.642207 -223.786344) (xy 370.606916 -223.822791) (xy 370.566452 -223.853396) (xy 370.521774 -223.877433)
			(xy 370.473939 -223.894334) (xy 370.449094 -223.899476) (xy 370.426234 -223.903794) (xy 370.22151 -224.258632)
			(xy 370.229384 -224.280476) (xy 370.237957 -224.306897) (xy 370.247158 -224.36167) (xy 370.247672 -224.389442)
			(xy 370.528596 -224.389442) (xy 370.529104 -224.363555) (xy 370.537203 -224.312417) (xy 370.553202 -224.263177)
			(xy 370.576708 -224.217045) (xy 370.60714 -224.175158) (xy 370.64375 -224.138548) (xy 370.685637 -224.108116)
			(xy 370.731769 -224.08461) (xy 370.781009 -224.068611) (xy 370.832147 -224.060512) (xy 370.883921 -224.060512)
			(xy 370.935059 -224.068611) (xy 370.984299 -224.08461) (xy 371.030431 -224.108116) (xy 371.072318 -224.138548)
			(xy 371.108928 -224.175158) (xy 371.13936 -224.217045) (xy 371.162866 -224.263177) (xy 371.178865 -224.312417)
			(xy 371.186964 -224.363555) (xy 371.187472 -224.389442) (xy 371.468396 -224.389442) (xy 371.468829 -224.364106)
			(xy 371.47659 -224.314032) (xy 371.49192 -224.265734) (xy 371.514459 -224.22035) (xy 371.543675 -224.178949)
			(xy 371.578881 -224.142504) (xy 371.619248 -224.111874) (xy 371.663826 -224.087781) (xy 371.711565 -224.070791)
			(xy 371.736366 -224.065592) (xy 371.759226 -224.061274) (xy 371.96395 -223.706436) (xy 371.95633 -223.684338)
			(xy 371.947702 -223.657991) (xy 371.938379 -223.603344) (xy 371.937788 -223.575626) (xy 371.938296 -223.549719)
			(xy 371.946402 -223.498542) (xy 371.962414 -223.449263) (xy 371.985937 -223.403096) (xy 372.016393 -223.361177)
			(xy 372.053031 -223.324539) (xy 372.09495 -223.294083) (xy 372.141117 -223.27056) (xy 372.190396 -223.254548)
			(xy 372.241573 -223.246442) (xy 372.293387 -223.246442) (xy 372.344564 -223.254548) (xy 372.393843 -223.27056)
			(xy 372.44001 -223.294083) (xy 372.481929 -223.324539) (xy 372.518567 -223.361177) (xy 372.549023 -223.403096)
			(xy 372.572546 -223.449263) (xy 372.588558 -223.498542) (xy 372.596664 -223.549719) (xy 372.597172 -223.575626)
			(xy 372.596781 -223.600993) (xy 372.589028 -223.651131) (xy 372.573677 -223.699486) (xy 372.551092 -223.744915)
			(xy 372.521807 -223.786344) (xy 372.486516 -223.822791) (xy 372.446052 -223.853396) (xy 372.401374 -223.877433)
			(xy 372.353539 -223.894334) (xy 372.328694 -223.899476) (xy 372.305834 -223.903794) (xy 372.10111 -224.258632)
			(xy 372.108984 -224.280476) (xy 372.117557 -224.306897) (xy 372.126758 -224.36167) (xy 372.127272 -224.389442)
			(xy 372.408196 -224.389442) (xy 372.408704 -224.363555) (xy 372.416803 -224.312417) (xy 372.432802 -224.263177)
			(xy 372.456308 -224.217045) (xy 372.48674 -224.175158) (xy 372.52335 -224.138548) (xy 372.565237 -224.108116)
			(xy 372.611369 -224.08461) (xy 372.660609 -224.068611) (xy 372.711747 -224.060512) (xy 372.763521 -224.060512)
			(xy 372.814659 -224.068611) (xy 372.863899 -224.08461) (xy 372.910031 -224.108116) (xy 372.951918 -224.138548)
			(xy 372.988528 -224.175158) (xy 373.01896 -224.217045) (xy 373.042466 -224.263177) (xy 373.058465 -224.312417)
			(xy 373.066564 -224.363555) (xy 373.067072 -224.389442) (xy 373.347996 -224.389442) (xy 373.348429 -224.364106)
			(xy 373.35619 -224.314032) (xy 373.37152 -224.265734) (xy 373.394059 -224.22035) (xy 373.423275 -224.178949)
			(xy 373.458481 -224.142504) (xy 373.498848 -224.111874) (xy 373.543426 -224.087781) (xy 373.591165 -224.070791)
			(xy 373.615966 -224.065592) (xy 373.638826 -224.061274) (xy 373.84355 -223.706436) (xy 373.83593 -223.684338)
			(xy 373.827302 -223.657991) (xy 373.817979 -223.603344) (xy 373.817388 -223.575626) (xy 373.817896 -223.549719)
			(xy 373.826002 -223.498542) (xy 373.842014 -223.449263) (xy 373.865537 -223.403096) (xy 373.895993 -223.361177)
			(xy 373.932631 -223.324539) (xy 373.97455 -223.294083) (xy 374.020717 -223.27056) (xy 374.069996 -223.254548)
			(xy 374.121173 -223.246442) (xy 374.172987 -223.246442) (xy 374.224164 -223.254548) (xy 374.273443 -223.27056)
			(xy 374.31961 -223.294083) (xy 374.361529 -223.324539) (xy 374.398167 -223.361177) (xy 374.428623 -223.403096)
			(xy 374.452146 -223.449263) (xy 374.468158 -223.498542) (xy 374.476264 -223.549719) (xy 374.476772 -223.575626)
			(xy 374.476381 -223.600993) (xy 374.468628 -223.651131) (xy 374.453277 -223.699486) (xy 374.430692 -223.744915)
			(xy 374.401407 -223.786344) (xy 374.366116 -223.822791) (xy 374.325652 -223.853396) (xy 374.280974 -223.877433)
			(xy 374.233139 -223.894334) (xy 374.208294 -223.899476) (xy 374.185434 -223.903794) (xy 373.98071 -224.258632)
			(xy 373.988584 -224.280476) (xy 373.997157 -224.306897) (xy 374.006358 -224.36167) (xy 374.006872 -224.389442)
			(xy 374.287796 -224.389442) (xy 374.288304 -224.363555) (xy 374.296403 -224.312417) (xy 374.312402 -224.263177)
			(xy 374.335908 -224.217045) (xy 374.36634 -224.175158) (xy 374.40295 -224.138548) (xy 374.444837 -224.108116)
			(xy 374.490969 -224.08461) (xy 374.540209 -224.068611) (xy 374.591347 -224.060512) (xy 374.643121 -224.060512)
			(xy 374.694259 -224.068611) (xy 374.743499 -224.08461) (xy 374.789631 -224.108116) (xy 374.831518 -224.138548)
			(xy 374.868128 -224.175158) (xy 374.89856 -224.217045) (xy 374.922066 -224.263177) (xy 374.938065 -224.312417)
			(xy 374.946164 -224.363555) (xy 374.946672 -224.389442) (xy 375.227596 -224.389442) (xy 375.228029 -224.364106)
			(xy 375.23579 -224.314032) (xy 375.25112 -224.265734) (xy 375.273659 -224.22035) (xy 375.302875 -224.178949)
			(xy 375.338081 -224.142504) (xy 375.378448 -224.111874) (xy 375.423026 -224.087781) (xy 375.470765 -224.070791)
			(xy 375.495566 -224.065592) (xy 375.518426 -224.061274) (xy 375.72315 -223.706436) (xy 375.71553 -223.684338)
			(xy 375.706902 -223.657991) (xy 375.697579 -223.603344) (xy 375.696988 -223.575626) (xy 375.697496 -223.549719)
			(xy 375.705602 -223.498542) (xy 375.721614 -223.449263) (xy 375.745137 -223.403096) (xy 375.775593 -223.361177)
			(xy 375.812231 -223.324539) (xy 375.85415 -223.294083) (xy 375.900317 -223.27056) (xy 375.949596 -223.254548)
			(xy 376.000773 -223.246442) (xy 376.052587 -223.246442) (xy 376.103764 -223.254548) (xy 376.153043 -223.27056)
			(xy 376.19921 -223.294083) (xy 376.241129 -223.324539) (xy 376.277767 -223.361177) (xy 376.308223 -223.403096)
			(xy 376.331746 -223.449263) (xy 376.347758 -223.498542) (xy 376.355864 -223.549719) (xy 376.356372 -223.575626)
			(xy 376.355981 -223.600993) (xy 376.348228 -223.651131) (xy 376.332877 -223.699486) (xy 376.310292 -223.744915)
			(xy 376.281007 -223.786344) (xy 376.245716 -223.822791) (xy 376.205252 -223.853396) (xy 376.160574 -223.877433)
			(xy 376.112739 -223.894334) (xy 376.087894 -223.899476) (xy 376.065034 -223.903794) (xy 375.86031 -224.258632)
			(xy 375.868184 -224.280476) (xy 375.876757 -224.306897) (xy 375.885958 -224.36167) (xy 375.886472 -224.389442)
			(xy 376.167396 -224.389442) (xy 376.167904 -224.363555) (xy 376.176003 -224.312417) (xy 376.192002 -224.263177)
			(xy 376.215508 -224.217045) (xy 376.24594 -224.175158) (xy 376.28255 -224.138548) (xy 376.324437 -224.108116)
			(xy 376.370569 -224.08461) (xy 376.419809 -224.068611) (xy 376.470947 -224.060512) (xy 376.522721 -224.060512)
			(xy 376.573859 -224.068611) (xy 376.623099 -224.08461) (xy 376.669231 -224.108116) (xy 376.711118 -224.138548)
			(xy 376.747728 -224.175158) (xy 376.77816 -224.217045) (xy 376.801666 -224.263177) (xy 376.817665 -224.312417)
			(xy 376.825764 -224.363555) (xy 376.826272 -224.389442) (xy 377.107196 -224.389442) (xy 377.107629 -224.364106)
			(xy 377.11539 -224.314032) (xy 377.13072 -224.265734) (xy 377.153259 -224.22035) (xy 377.182475 -224.178949)
			(xy 377.217681 -224.142504) (xy 377.258048 -224.111874) (xy 377.302626 -224.087781) (xy 377.350365 -224.070791)
			(xy 377.375166 -224.065592) (xy 377.398026 -224.061274) (xy 377.60275 -223.706436) (xy 377.59513 -223.684338)
			(xy 377.586502 -223.657991) (xy 377.577179 -223.603344) (xy 377.576588 -223.575626) (xy 377.577096 -223.549719)
			(xy 377.585202 -223.498542) (xy 377.601214 -223.449263) (xy 377.624737 -223.403096) (xy 377.655193 -223.361177)
			(xy 377.691831 -223.324539) (xy 377.73375 -223.294083) (xy 377.779917 -223.27056) (xy 377.829196 -223.254548)
			(xy 377.880373 -223.246442) (xy 377.932187 -223.246442) (xy 377.983364 -223.254548) (xy 378.032643 -223.27056)
			(xy 378.07881 -223.294083) (xy 378.120729 -223.324539) (xy 378.157367 -223.361177) (xy 378.187823 -223.403096)
			(xy 378.211346 -223.449263) (xy 378.227358 -223.498542) (xy 378.235464 -223.549719) (xy 378.235972 -223.575626)
			(xy 378.235581 -223.600993) (xy 378.227828 -223.651131) (xy 378.212477 -223.699486) (xy 378.189892 -223.744915)
			(xy 378.160607 -223.786344) (xy 378.125316 -223.822791) (xy 378.084852 -223.853396) (xy 378.040174 -223.877433)
			(xy 377.992339 -223.894334) (xy 377.967494 -223.899476) (xy 377.944634 -223.903794) (xy 377.73991 -224.258632)
			(xy 377.747784 -224.280476) (xy 377.756357 -224.306897) (xy 377.765558 -224.36167) (xy 377.766072 -224.389442)
			(xy 378.046996 -224.389442) (xy 378.047504 -224.363555) (xy 378.055603 -224.312417) (xy 378.071602 -224.263177)
			(xy 378.095108 -224.217045) (xy 378.12554 -224.175158) (xy 378.16215 -224.138548) (xy 378.204037 -224.108116)
			(xy 378.250169 -224.08461) (xy 378.299409 -224.068611) (xy 378.350547 -224.060512) (xy 378.402321 -224.060512)
			(xy 378.453459 -224.068611) (xy 378.502699 -224.08461) (xy 378.548831 -224.108116) (xy 378.590718 -224.138548)
			(xy 378.627328 -224.175158) (xy 378.65776 -224.217045) (xy 378.681266 -224.263177) (xy 378.697265 -224.312417)
			(xy 378.705364 -224.363555) (xy 378.705872 -224.389442) (xy 378.986796 -224.389442) (xy 378.987229 -224.364106)
			(xy 378.99499 -224.314032) (xy 379.01032 -224.265734) (xy 379.032859 -224.22035) (xy 379.062075 -224.178949)
			(xy 379.097281 -224.142504) (xy 379.137648 -224.111874) (xy 379.182226 -224.087781) (xy 379.229965 -224.070791)
			(xy 379.254766 -224.065592) (xy 379.277626 -224.061274) (xy 379.48235 -223.706182) (xy 379.47473 -223.684338)
			(xy 379.466087 -223.657995) (xy 379.456772 -223.603345) (xy 379.456188 -223.575626) (xy 379.456696 -223.549719)
			(xy 379.464802 -223.498542) (xy 379.480814 -223.449263) (xy 379.504337 -223.403096) (xy 379.534793 -223.361177)
			(xy 379.571431 -223.324539) (xy 379.61335 -223.294083) (xy 379.659517 -223.27056) (xy 379.708796 -223.254548)
			(xy 379.759973 -223.246442) (xy 379.811787 -223.246442) (xy 379.862964 -223.254548) (xy 379.912243 -223.27056)
			(xy 379.95841 -223.294083) (xy 380.000329 -223.324539) (xy 380.036967 -223.361177) (xy 380.067423 -223.403096)
			(xy 380.090946 -223.449263) (xy 380.106958 -223.498542) (xy 380.115064 -223.549719) (xy 380.115572 -223.575626)
			(xy 380.115097 -223.600971) (xy 380.107321 -223.651063) (xy 380.091971 -223.699374) (xy 380.069408 -223.744767)
			(xy 380.040166 -223.786173) (xy 380.004931 -223.822617) (xy 379.964535 -223.853239) (xy 379.919928 -223.877319)
			(xy 379.872162 -223.89429) (xy 379.847348 -223.899476) (xy 379.824488 -223.903794) (xy 379.619764 -224.258632)
			(xy 379.627384 -224.280476) (xy 379.635939 -224.306769) (xy 379.645132 -224.361289) (xy 379.645672 -224.388934)
			(xy 379.645672 -224.389442) (xy 379.926596 -224.389442) (xy 379.927104 -224.363555) (xy 379.935203 -224.312417)
			(xy 379.951202 -224.263177) (xy 379.974708 -224.217045) (xy 380.00514 -224.175158) (xy 380.04175 -224.138548)
			(xy 380.083637 -224.108116) (xy 380.129769 -224.08461) (xy 380.179009 -224.068611) (xy 380.230147 -224.060512)
			(xy 380.281921 -224.060512) (xy 380.333059 -224.068611) (xy 380.382299 -224.08461) (xy 380.428431 -224.108116)
			(xy 380.470318 -224.138548) (xy 380.506928 -224.175158) (xy 380.53736 -224.217045) (xy 380.560866 -224.263177)
			(xy 380.576865 -224.312417) (xy 380.584964 -224.363555) (xy 380.585472 -224.389442) (xy 380.866396 -224.389442)
			(xy 380.866829 -224.364106) (xy 380.87459 -224.314032) (xy 380.88992 -224.265734) (xy 380.912459 -224.22035)
			(xy 380.941675 -224.178949) (xy 380.976881 -224.142504) (xy 381.017248 -224.111874) (xy 381.061826 -224.087781)
			(xy 381.109565 -224.070791) (xy 381.134366 -224.065592) (xy 381.157226 -224.061274) (xy 381.362204 -223.705928)
			(xy 381.354584 -223.684084) (xy 381.346064 -223.657913) (xy 381.336871 -223.603651) (xy 381.336296 -223.576134)
			(xy 381.336296 -223.575626) (xy 381.336804 -223.549739) (xy 381.344903 -223.498601) (xy 381.360902 -223.449361)
			(xy 381.384408 -223.403229) (xy 381.41484 -223.361342) (xy 381.45145 -223.324732) (xy 381.493337 -223.2943)
			(xy 381.539469 -223.270794) (xy 381.588709 -223.254795) (xy 381.639847 -223.246696) (xy 381.691621 -223.246696)
			(xy 381.742759 -223.254795) (xy 381.791999 -223.270794) (xy 381.838131 -223.2943) (xy 381.880018 -223.324732)
			(xy 381.916628 -223.361342) (xy 381.94706 -223.403229) (xy 381.970566 -223.449361) (xy 381.986565 -223.498601)
			(xy 381.994664 -223.549739) (xy 381.995172 -223.575626) (xy 381.994697 -223.600971) (xy 381.986921 -223.651063)
			(xy 381.971571 -223.699374) (xy 381.949008 -223.744767) (xy 381.919766 -223.786173) (xy 381.884531 -223.822617)
			(xy 381.844135 -223.853239) (xy 381.799528 -223.877319) (xy 381.751762 -223.89429) (xy 381.726948 -223.899476)
			(xy 381.704088 -223.903794) (xy 381.499364 -224.258632) (xy 381.506984 -224.280476) (xy 381.515539 -224.306769)
			(xy 381.524732 -224.361289) (xy 381.525272 -224.388934) (xy 381.525272 -224.389442) (xy 381.806196 -224.389442)
			(xy 381.806704 -224.363555) (xy 381.814803 -224.312417) (xy 381.830802 -224.263177) (xy 381.854308 -224.217045)
			(xy 381.88474 -224.175158) (xy 381.92135 -224.138548) (xy 381.963237 -224.108116) (xy 382.009369 -224.08461)
			(xy 382.058609 -224.068611) (xy 382.109747 -224.060512) (xy 382.161521 -224.060512) (xy 382.212659 -224.068611)
			(xy 382.261899 -224.08461) (xy 382.308031 -224.108116) (xy 382.349918 -224.138548) (xy 382.386528 -224.175158)
			(xy 382.41696 -224.217045) (xy 382.440466 -224.263177) (xy 382.456465 -224.312417) (xy 382.464564 -224.363555)
			(xy 382.465072 -224.389442) (xy 382.464539 -224.41715) (xy 382.455342 -224.471795) (xy 382.446784 -224.498154)
			(xy 382.439164 -224.519998) (xy 382.644142 -224.87509) (xy 382.667002 -224.879408) (xy 382.691815 -224.884555)
			(xy 382.739557 -224.901547) (xy 382.784137 -224.925644) (xy 382.824504 -224.95628) (xy 382.859707 -224.992732)
			(xy 382.888918 -225.034142) (xy 382.911448 -225.079534) (xy 382.926766 -225.12784) (xy 382.934512 -225.17792)
			(xy 382.934972 -225.203258) (xy 382.934464 -225.229145) (xy 382.926365 -225.280283) (xy 382.910366 -225.329523)
			(xy 382.88686 -225.375655) (xy 382.856428 -225.417542) (xy 382.819818 -225.454152) (xy 382.777931 -225.484584)
			(xy 382.731799 -225.50809) (xy 382.682559 -225.524089) (xy 382.631421 -225.532188) (xy 382.579647 -225.532188)
			(xy 382.528509 -225.524089) (xy 382.479269 -225.50809) (xy 382.433137 -225.484584) (xy 382.39125 -225.454152)
			(xy 382.35464 -225.417542) (xy 382.324208 -225.375655) (xy 382.300702 -225.329523) (xy 382.284703 -225.280283)
			(xy 382.276604 -225.229145) (xy 382.276096 -225.203258) (xy 382.276096 -225.20275) (xy 382.276653 -225.175107)
			(xy 382.285844 -225.120589) (xy 382.294384 -225.094292) (xy 382.302004 -225.072448) (xy 382.09728 -224.71761)
			(xy 382.07442 -224.713292) (xy 382.049591 -224.708158) (xy 382.001812 -224.691199) (xy 381.957192 -224.667122)
			(xy 381.916786 -224.636498) (xy 381.881546 -224.600046) (xy 381.852303 -224.558629) (xy 381.829748 -224.513222)
			(xy 381.814412 -224.464896) (xy 381.806657 -224.414792) (xy 381.806196 -224.389442) (xy 381.525272 -224.389442)
			(xy 381.524764 -224.415329) (xy 381.516665 -224.466467) (xy 381.500666 -224.515707) (xy 381.47716 -224.561839)
			(xy 381.446728 -224.603726) (xy 381.410118 -224.640336) (xy 381.368231 -224.670768) (xy 381.322099 -224.694274)
			(xy 381.272859 -224.710273) (xy 381.221721 -224.718372) (xy 381.169947 -224.718372) (xy 381.118809 -224.710273)
			(xy 381.069569 -224.694274) (xy 381.023437 -224.670768) (xy 380.98155 -224.640336) (xy 380.94494 -224.603726)
			(xy 380.914508 -224.561839) (xy 380.891002 -224.515707) (xy 380.875003 -224.466467) (xy 380.866904 -224.415329)
			(xy 380.866396 -224.389442) (xy 380.585472 -224.389442) (xy 380.584925 -224.417149) (xy 380.575741 -224.471796)
			(xy 380.567184 -224.498154) (xy 380.55931 -224.520252) (xy 380.764288 -224.87509) (xy 380.787148 -224.879408)
			(xy 380.811971 -224.884565) (xy 380.859751 -224.90152) (xy 380.904371 -224.925592) (xy 380.944778 -224.956214)
			(xy 380.980019 -224.992662) (xy 381.009263 -225.034077) (xy 381.031819 -225.079482) (xy 381.047156 -225.127806)
			(xy 381.054911 -225.177908) (xy 381.055372 -225.203258) (xy 381.054864 -225.229165) (xy 381.046758 -225.280342)
			(xy 381.030746 -225.329621) (xy 381.007223 -225.375788) (xy 380.976767 -225.417707) (xy 380.940129 -225.454345)
			(xy 380.89821 -225.484801) (xy 380.852043 -225.508324) (xy 380.802764 -225.524336) (xy 380.751587 -225.532442)
			(xy 380.699773 -225.532442) (xy 380.648596 -225.524336) (xy 380.599317 -225.508324) (xy 380.55315 -225.484801)
			(xy 380.511231 -225.454345) (xy 380.474593 -225.417707) (xy 380.444137 -225.375788) (xy 380.420614 -225.329621)
			(xy 380.404602 -225.280342) (xy 380.396496 -225.229165) (xy 380.395988 -225.203258) (xy 380.396597 -225.175541)
			(xy 380.40591 -225.120895) (xy 380.41453 -225.094546) (xy 380.422404 -225.072448) (xy 380.217426 -224.71761)
			(xy 380.194566 -224.713292) (xy 380.169748 -224.708169) (xy 380.122005 -224.691172) (xy 380.077426 -224.667071)
			(xy 380.03706 -224.636431) (xy 380.001857 -224.599976) (xy 379.972648 -224.558564) (xy 379.950119 -224.51317)
			(xy 379.934801 -224.464863) (xy 379.927055 -224.414781) (xy 379.926596 -224.389442) (xy 379.645672 -224.389442)
			(xy 379.645164 -224.415329) (xy 379.637065 -224.466467) (xy 379.621066 -224.515707) (xy 379.59756 -224.561839)
			(xy 379.567128 -224.603726) (xy 379.530518 -224.640336) (xy 379.488631 -224.670768) (xy 379.442499 -224.694274)
			(xy 379.393259 -224.710273) (xy 379.342121 -224.718372) (xy 379.290347 -224.718372) (xy 379.239209 -224.710273)
			(xy 379.189969 -224.694274) (xy 379.143837 -224.670768) (xy 379.10195 -224.640336) (xy 379.06534 -224.603726)
			(xy 379.034908 -224.561839) (xy 379.011402 -224.515707) (xy 378.995403 -224.466467) (xy 378.987304 -224.415329)
			(xy 378.986796 -224.389442) (xy 378.705872 -224.389442) (xy 378.705325 -224.417149) (xy 378.696141 -224.471796)
			(xy 378.687584 -224.498154) (xy 378.67971 -224.520252) (xy 378.884688 -224.87509) (xy 378.907548 -224.879408)
			(xy 378.932371 -224.884565) (xy 378.980151 -224.90152) (xy 379.024771 -224.925592) (xy 379.065178 -224.956214)
			(xy 379.100419 -224.992662) (xy 379.129663 -225.034077) (xy 379.152219 -225.079482) (xy 379.167556 -225.127806)
			(xy 379.175311 -225.177908) (xy 379.175772 -225.203258) (xy 379.175264 -225.229165) (xy 379.167158 -225.280342)
			(xy 379.151146 -225.329621) (xy 379.127623 -225.375788) (xy 379.097167 -225.417707) (xy 379.060529 -225.454345)
			(xy 379.01861 -225.484801) (xy 378.972443 -225.508324) (xy 378.923164 -225.524336) (xy 378.871987 -225.532442)
			(xy 378.820173 -225.532442) (xy 378.768996 -225.524336) (xy 378.719717 -225.508324) (xy 378.67355 -225.484801)
			(xy 378.631631 -225.454345) (xy 378.594993 -225.417707) (xy 378.564537 -225.375788) (xy 378.541014 -225.329621)
			(xy 378.525002 -225.280342) (xy 378.516896 -225.229165) (xy 378.516388 -225.203258) (xy 378.516997 -225.175541)
			(xy 378.52631 -225.120895) (xy 378.53493 -225.094546) (xy 378.542804 -225.072448) (xy 378.337826 -224.71761)
			(xy 378.314966 -224.713292) (xy 378.290148 -224.708169) (xy 378.242405 -224.691172) (xy 378.197826 -224.667071)
			(xy 378.15746 -224.636431) (xy 378.122257 -224.599976) (xy 378.093048 -224.558564) (xy 378.070519 -224.51317)
			(xy 378.055201 -224.464863) (xy 378.047455 -224.414781) (xy 378.046996 -224.389442) (xy 377.766072 -224.389442)
			(xy 377.765564 -224.415329) (xy 377.757465 -224.466467) (xy 377.741466 -224.515707) (xy 377.71796 -224.561839)
			(xy 377.687528 -224.603726) (xy 377.650918 -224.640336) (xy 377.609031 -224.670768) (xy 377.562899 -224.694274)
			(xy 377.513659 -224.710273) (xy 377.462521 -224.718372) (xy 377.410747 -224.718372) (xy 377.359609 -224.710273)
			(xy 377.310369 -224.694274) (xy 377.264237 -224.670768) (xy 377.22235 -224.640336) (xy 377.18574 -224.603726)
			(xy 377.155308 -224.561839) (xy 377.131802 -224.515707) (xy 377.115803 -224.466467) (xy 377.107704 -224.415329)
			(xy 377.107196 -224.389442) (xy 376.826272 -224.389442) (xy 376.825725 -224.417149) (xy 376.816541 -224.471796)
			(xy 376.807984 -224.498154) (xy 376.80011 -224.520252) (xy 377.005088 -224.87509) (xy 377.027948 -224.879408)
			(xy 377.052771 -224.884565) (xy 377.100551 -224.90152) (xy 377.145171 -224.925592) (xy 377.185578 -224.956214)
			(xy 377.220819 -224.992662) (xy 377.250063 -225.034077) (xy 377.272619 -225.079482) (xy 377.287956 -225.127806)
			(xy 377.295711 -225.177908) (xy 377.296172 -225.203258) (xy 377.295664 -225.229165) (xy 377.287558 -225.280342)
			(xy 377.271546 -225.329621) (xy 377.248023 -225.375788) (xy 377.217567 -225.417707) (xy 377.180929 -225.454345)
			(xy 377.13901 -225.484801) (xy 377.092843 -225.508324) (xy 377.043564 -225.524336) (xy 376.992387 -225.532442)
			(xy 376.940573 -225.532442) (xy 376.889396 -225.524336) (xy 376.840117 -225.508324) (xy 376.79395 -225.484801)
			(xy 376.752031 -225.454345) (xy 376.715393 -225.417707) (xy 376.684937 -225.375788) (xy 376.661414 -225.329621)
			(xy 376.645402 -225.280342) (xy 376.637296 -225.229165) (xy 376.636788 -225.203258) (xy 376.637397 -225.175541)
			(xy 376.64671 -225.120895) (xy 376.65533 -225.094546) (xy 376.663204 -225.072448) (xy 376.458226 -224.71761)
			(xy 376.435366 -224.713292) (xy 376.410548 -224.708169) (xy 376.362805 -224.691172) (xy 376.318226 -224.667071)
			(xy 376.27786 -224.636431) (xy 376.242657 -224.599976) (xy 376.213448 -224.558564) (xy 376.190919 -224.51317)
			(xy 376.175601 -224.464863) (xy 376.167855 -224.414781) (xy 376.167396 -224.389442) (xy 375.886472 -224.389442)
			(xy 375.885964 -224.415329) (xy 375.877865 -224.466467) (xy 375.861866 -224.515707) (xy 375.83836 -224.561839)
			(xy 375.807928 -224.603726) (xy 375.771318 -224.640336) (xy 375.729431 -224.670768) (xy 375.683299 -224.694274)
			(xy 375.634059 -224.710273) (xy 375.582921 -224.718372) (xy 375.531147 -224.718372) (xy 375.480009 -224.710273)
			(xy 375.430769 -224.694274) (xy 375.384637 -224.670768) (xy 375.34275 -224.640336) (xy 375.30614 -224.603726)
			(xy 375.275708 -224.561839) (xy 375.252202 -224.515707) (xy 375.236203 -224.466467) (xy 375.228104 -224.415329)
			(xy 375.227596 -224.389442) (xy 374.946672 -224.389442) (xy 374.946125 -224.417149) (xy 374.936941 -224.471796)
			(xy 374.928384 -224.498154) (xy 374.92051 -224.520252) (xy 375.125488 -224.87509) (xy 375.148348 -224.879408)
			(xy 375.173171 -224.884565) (xy 375.220951 -224.90152) (xy 375.265571 -224.925592) (xy 375.305978 -224.956214)
			(xy 375.341219 -224.992662) (xy 375.370463 -225.034077) (xy 375.393019 -225.079482) (xy 375.408356 -225.127806)
			(xy 375.416111 -225.177908) (xy 375.416572 -225.203258) (xy 375.416064 -225.229165) (xy 375.407958 -225.280342)
			(xy 375.391946 -225.329621) (xy 375.368423 -225.375788) (xy 375.337967 -225.417707) (xy 375.301329 -225.454345)
			(xy 375.25941 -225.484801) (xy 375.213243 -225.508324) (xy 375.163964 -225.524336) (xy 375.112787 -225.532442)
			(xy 375.060973 -225.532442) (xy 375.009796 -225.524336) (xy 374.960517 -225.508324) (xy 374.91435 -225.484801)
			(xy 374.872431 -225.454345) (xy 374.835793 -225.417707) (xy 374.805337 -225.375788) (xy 374.781814 -225.329621)
			(xy 374.765802 -225.280342) (xy 374.757696 -225.229165) (xy 374.757188 -225.203258) (xy 374.757797 -225.175541)
			(xy 374.76711 -225.120895) (xy 374.77573 -225.094546) (xy 374.783604 -225.072448) (xy 374.578626 -224.71761)
			(xy 374.555766 -224.713292) (xy 374.530948 -224.708169) (xy 374.483205 -224.691172) (xy 374.438626 -224.667071)
			(xy 374.39826 -224.636431) (xy 374.363057 -224.599976) (xy 374.333848 -224.558564) (xy 374.311319 -224.51317)
			(xy 374.296001 -224.464863) (xy 374.288255 -224.414781) (xy 374.287796 -224.389442) (xy 374.006872 -224.389442)
			(xy 374.006364 -224.415329) (xy 373.998265 -224.466467) (xy 373.982266 -224.515707) (xy 373.95876 -224.561839)
			(xy 373.928328 -224.603726) (xy 373.891718 -224.640336) (xy 373.849831 -224.670768) (xy 373.803699 -224.694274)
			(xy 373.754459 -224.710273) (xy 373.703321 -224.718372) (xy 373.651547 -224.718372) (xy 373.600409 -224.710273)
			(xy 373.551169 -224.694274) (xy 373.505037 -224.670768) (xy 373.46315 -224.640336) (xy 373.42654 -224.603726)
			(xy 373.396108 -224.561839) (xy 373.372602 -224.515707) (xy 373.356603 -224.466467) (xy 373.348504 -224.415329)
			(xy 373.347996 -224.389442) (xy 373.067072 -224.389442) (xy 373.066525 -224.417149) (xy 373.057341 -224.471796)
			(xy 373.048784 -224.498154) (xy 373.04091 -224.520252) (xy 373.245888 -224.87509) (xy 373.268748 -224.879408)
			(xy 373.293571 -224.884565) (xy 373.341351 -224.90152) (xy 373.385971 -224.925592) (xy 373.426378 -224.956214)
			(xy 373.461619 -224.992662) (xy 373.490863 -225.034077) (xy 373.513419 -225.079482) (xy 373.528756 -225.127806)
			(xy 373.536511 -225.177908) (xy 373.536972 -225.203258) (xy 373.536464 -225.229165) (xy 373.528358 -225.280342)
			(xy 373.512346 -225.329621) (xy 373.488823 -225.375788) (xy 373.458367 -225.417707) (xy 373.421729 -225.454345)
			(xy 373.37981 -225.484801) (xy 373.333643 -225.508324) (xy 373.284364 -225.524336) (xy 373.233187 -225.532442)
			(xy 373.181373 -225.532442) (xy 373.130196 -225.524336) (xy 373.080917 -225.508324) (xy 373.03475 -225.484801)
			(xy 372.992831 -225.454345) (xy 372.956193 -225.417707) (xy 372.925737 -225.375788) (xy 372.902214 -225.329621)
			(xy 372.886202 -225.280342) (xy 372.878096 -225.229165) (xy 372.877588 -225.203258) (xy 372.878197 -225.175541)
			(xy 372.88751 -225.120895) (xy 372.89613 -225.094546) (xy 372.904004 -225.072448) (xy 372.699026 -224.71761)
			(xy 372.676166 -224.713292) (xy 372.651348 -224.708169) (xy 372.603605 -224.691172) (xy 372.559026 -224.667071)
			(xy 372.51866 -224.636431) (xy 372.483457 -224.599976) (xy 372.454248 -224.558564) (xy 372.431719 -224.51317)
			(xy 372.416401 -224.464863) (xy 372.408655 -224.414781) (xy 372.408196 -224.389442) (xy 372.127272 -224.389442)
			(xy 372.126764 -224.415329) (xy 372.118665 -224.466467) (xy 372.102666 -224.515707) (xy 372.07916 -224.561839)
			(xy 372.048728 -224.603726) (xy 372.012118 -224.640336) (xy 371.970231 -224.670768) (xy 371.924099 -224.694274)
			(xy 371.874859 -224.710273) (xy 371.823721 -224.718372) (xy 371.771947 -224.718372) (xy 371.720809 -224.710273)
			(xy 371.671569 -224.694274) (xy 371.625437 -224.670768) (xy 371.58355 -224.640336) (xy 371.54694 -224.603726)
			(xy 371.516508 -224.561839) (xy 371.493002 -224.515707) (xy 371.477003 -224.466467) (xy 371.468904 -224.415329)
			(xy 371.468396 -224.389442) (xy 371.187472 -224.389442) (xy 371.186925 -224.417149) (xy 371.177741 -224.471796)
			(xy 371.169184 -224.498154) (xy 371.16131 -224.520252) (xy 371.366288 -224.87509) (xy 371.389148 -224.879408)
			(xy 371.413971 -224.884565) (xy 371.461751 -224.90152) (xy 371.506371 -224.925592) (xy 371.546778 -224.956214)
			(xy 371.582019 -224.992662) (xy 371.611263 -225.034077) (xy 371.633819 -225.079482) (xy 371.649156 -225.127806)
			(xy 371.656911 -225.177908) (xy 371.657372 -225.203258) (xy 371.656864 -225.229165) (xy 371.648758 -225.280342)
			(xy 371.632746 -225.329621) (xy 371.609223 -225.375788) (xy 371.578767 -225.417707) (xy 371.542129 -225.454345)
			(xy 371.50021 -225.484801) (xy 371.454043 -225.508324) (xy 371.404764 -225.524336) (xy 371.353587 -225.532442)
			(xy 371.301773 -225.532442) (xy 371.250596 -225.524336) (xy 371.201317 -225.508324) (xy 371.15515 -225.484801)
			(xy 371.113231 -225.454345) (xy 371.076593 -225.417707) (xy 371.046137 -225.375788) (xy 371.022614 -225.329621)
			(xy 371.006602 -225.280342) (xy 370.998496 -225.229165) (xy 370.997988 -225.203258) (xy 370.998597 -225.175541)
			(xy 371.00791 -225.120895) (xy 371.01653 -225.094546) (xy 371.024404 -225.072448) (xy 370.819426 -224.71761)
			(xy 370.796566 -224.713292) (xy 370.771748 -224.708169) (xy 370.724005 -224.691172) (xy 370.679426 -224.667071)
			(xy 370.63906 -224.636431) (xy 370.603857 -224.599976) (xy 370.574648 -224.558564) (xy 370.552119 -224.51317)
			(xy 370.536801 -224.464863) (xy 370.529055 -224.414781) (xy 370.528596 -224.389442) (xy 370.247672 -224.389442)
			(xy 370.247164 -224.415329) (xy 370.239065 -224.466467) (xy 370.223066 -224.515707) (xy 370.19956 -224.561839)
			(xy 370.169128 -224.603726) (xy 370.132518 -224.640336) (xy 370.090631 -224.670768) (xy 370.044499 -224.694274)
			(xy 369.995259 -224.710273) (xy 369.944121 -224.718372) (xy 369.892347 -224.718372) (xy 369.841209 -224.710273)
			(xy 369.791969 -224.694274) (xy 369.745837 -224.670768) (xy 369.70395 -224.640336) (xy 369.66734 -224.603726)
			(xy 369.636908 -224.561839) (xy 369.613402 -224.515707) (xy 369.597403 -224.466467) (xy 369.589304 -224.415329)
			(xy 369.588796 -224.389442) (xy 369.307872 -224.389442) (xy 369.307325 -224.417149) (xy 369.298141 -224.471796)
			(xy 369.289584 -224.498154) (xy 369.28171 -224.520252) (xy 369.486688 -224.87509) (xy 369.509548 -224.879408)
			(xy 369.534371 -224.884565) (xy 369.582151 -224.90152) (xy 369.626771 -224.925592) (xy 369.667178 -224.956214)
			(xy 369.702419 -224.992662) (xy 369.731663 -225.034077) (xy 369.754219 -225.079482) (xy 369.769556 -225.127806)
			(xy 369.777311 -225.177908) (xy 369.777772 -225.203258) (xy 369.777264 -225.229165) (xy 369.769158 -225.280342)
			(xy 369.753146 -225.329621) (xy 369.729623 -225.375788) (xy 369.699167 -225.417707) (xy 369.662529 -225.454345)
			(xy 369.62061 -225.484801) (xy 369.574443 -225.508324) (xy 369.525164 -225.524336) (xy 369.473987 -225.532442)
			(xy 369.422173 -225.532442) (xy 369.370996 -225.524336) (xy 369.321717 -225.508324) (xy 369.27555 -225.484801)
			(xy 369.233631 -225.454345) (xy 369.196993 -225.417707) (xy 369.166537 -225.375788) (xy 369.143014 -225.329621)
			(xy 369.127002 -225.280342) (xy 369.118896 -225.229165) (xy 369.118388 -225.203258) (xy 369.118997 -225.175541)
			(xy 369.12831 -225.120895) (xy 369.13693 -225.094546) (xy 369.144804 -225.072448) (xy 368.939826 -224.71761)
			(xy 368.916966 -224.713292) (xy 368.892148 -224.708169) (xy 368.844405 -224.691172) (xy 368.799826 -224.667071)
			(xy 368.75946 -224.636431) (xy 368.724257 -224.599976) (xy 368.695048 -224.558564) (xy 368.672519 -224.51317)
			(xy 368.657201 -224.464863) (xy 368.649455 -224.414781) (xy 368.648996 -224.389442) (xy 368.368072 -224.389442)
			(xy 368.367564 -224.415329) (xy 368.359465 -224.466467) (xy 368.343466 -224.515707) (xy 368.31996 -224.561839)
			(xy 368.289528 -224.603726) (xy 368.252918 -224.640336) (xy 368.211031 -224.670768) (xy 368.164899 -224.694274)
			(xy 368.115659 -224.710273) (xy 368.064521 -224.718372) (xy 368.012747 -224.718372) (xy 367.961609 -224.710273)
			(xy 367.912369 -224.694274) (xy 367.866237 -224.670768) (xy 367.82435 -224.640336) (xy 367.78774 -224.603726)
			(xy 367.757308 -224.561839) (xy 367.733802 -224.515707) (xy 367.717803 -224.466467) (xy 367.709704 -224.415329)
			(xy 367.709196 -224.389442) (xy 367.428272 -224.389442) (xy 367.427725 -224.417149) (xy 367.418541 -224.471796)
			(xy 367.409984 -224.498154) (xy 367.40211 -224.520252) (xy 367.607088 -224.87509) (xy 367.629948 -224.879408)
			(xy 367.654771 -224.884565) (xy 367.702551 -224.90152) (xy 367.747171 -224.925592) (xy 367.787578 -224.956214)
			(xy 367.822819 -224.992662) (xy 367.852063 -225.034077) (xy 367.874619 -225.079482) (xy 367.889956 -225.127806)
			(xy 367.897711 -225.177908) (xy 367.898172 -225.203258) (xy 367.897664 -225.229165) (xy 367.889558 -225.280342)
			(xy 367.873546 -225.329621) (xy 367.850023 -225.375788) (xy 367.819567 -225.417707) (xy 367.782929 -225.454345)
			(xy 367.74101 -225.484801) (xy 367.694843 -225.508324) (xy 367.645564 -225.524336) (xy 367.594387 -225.532442)
			(xy 367.542573 -225.532442) (xy 367.491396 -225.524336) (xy 367.442117 -225.508324) (xy 367.39595 -225.484801)
			(xy 367.354031 -225.454345) (xy 367.317393 -225.417707) (xy 367.286937 -225.375788) (xy 367.263414 -225.329621)
			(xy 367.247402 -225.280342) (xy 367.239296 -225.229165) (xy 367.238788 -225.203258) (xy 367.239397 -225.175541)
			(xy 367.24871 -225.120895) (xy 367.25733 -225.094546) (xy 367.265204 -225.072448) (xy 367.060226 -224.71761)
			(xy 367.037366 -224.713292) (xy 367.012548 -224.708169) (xy 366.964805 -224.691172) (xy 366.920226 -224.667071)
			(xy 366.87986 -224.636431) (xy 366.844657 -224.599976) (xy 366.815448 -224.558564) (xy 366.792919 -224.51317)
			(xy 366.777601 -224.464863) (xy 366.769855 -224.414781) (xy 366.769396 -224.389442) (xy 366.488472 -224.389442)
			(xy 366.487964 -224.415329) (xy 366.479865 -224.466467) (xy 366.463866 -224.515707) (xy 366.44036 -224.561839)
			(xy 366.409928 -224.603726) (xy 366.373318 -224.640336) (xy 366.331431 -224.670768) (xy 366.285299 -224.694274)
			(xy 366.236059 -224.710273) (xy 366.184921 -224.718372) (xy 366.133147 -224.718372) (xy 366.082009 -224.710273)
			(xy 366.032769 -224.694274) (xy 365.986637 -224.670768) (xy 365.94475 -224.640336) (xy 365.90814 -224.603726)
			(xy 365.877708 -224.561839) (xy 365.854202 -224.515707) (xy 365.838203 -224.466467) (xy 365.830104 -224.415329)
			(xy 365.829596 -224.389442) (xy 365.548672 -224.389442) (xy 365.548125 -224.417149) (xy 365.538941 -224.471796)
			(xy 365.530384 -224.498154) (xy 365.52251 -224.520252) (xy 365.727488 -224.87509) (xy 365.750348 -224.879408)
			(xy 365.775171 -224.884565) (xy 365.822951 -224.90152) (xy 365.867571 -224.925592) (xy 365.907978 -224.956214)
			(xy 365.943219 -224.992662) (xy 365.972463 -225.034077) (xy 365.995019 -225.079482) (xy 366.010356 -225.127806)
			(xy 366.018111 -225.177908) (xy 366.018572 -225.203258) (xy 366.018064 -225.229165) (xy 366.009958 -225.280342)
			(xy 365.993946 -225.329621) (xy 365.970423 -225.375788) (xy 365.939967 -225.417707) (xy 365.903329 -225.454345)
			(xy 365.86141 -225.484801) (xy 365.815243 -225.508324) (xy 365.765964 -225.524336) (xy 365.714787 -225.532442)
			(xy 365.662973 -225.532442) (xy 365.611796 -225.524336) (xy 365.562517 -225.508324) (xy 365.51635 -225.484801)
			(xy 365.474431 -225.454345) (xy 365.437793 -225.417707) (xy 365.407337 -225.375788) (xy 365.383814 -225.329621)
			(xy 365.367802 -225.280342) (xy 365.359696 -225.229165) (xy 365.359188 -225.203258) (xy 365.359797 -225.175541)
			(xy 365.36911 -225.120895) (xy 365.37773 -225.094546) (xy 365.385604 -225.072448) (xy 365.180626 -224.71761)
			(xy 365.157766 -224.713292) (xy 365.132948 -224.708169) (xy 365.085205 -224.691172) (xy 365.040626 -224.667071)
			(xy 365.00026 -224.636431) (xy 364.965057 -224.599976) (xy 364.935848 -224.558564) (xy 364.913319 -224.51317)
			(xy 364.898001 -224.464863) (xy 364.890255 -224.414781) (xy 364.889796 -224.389442) (xy 364.608872 -224.389442)
			(xy 364.608364 -224.415329) (xy 364.600265 -224.466467) (xy 364.584266 -224.515707) (xy 364.56076 -224.561839)
			(xy 364.530328 -224.603726) (xy 364.493718 -224.640336) (xy 364.451831 -224.670768) (xy 364.405699 -224.694274)
			(xy 364.356459 -224.710273) (xy 364.305321 -224.718372) (xy 364.253547 -224.718372) (xy 364.202409 -224.710273)
			(xy 364.153169 -224.694274) (xy 364.107037 -224.670768) (xy 364.06515 -224.640336) (xy 364.02854 -224.603726)
			(xy 363.998108 -224.561839) (xy 363.974602 -224.515707) (xy 363.958603 -224.466467) (xy 363.950504 -224.415329)
			(xy 363.949996 -224.389442) (xy 363.669072 -224.389442) (xy 363.668525 -224.417149) (xy 363.659341 -224.471796)
			(xy 363.650784 -224.498154) (xy 363.64291 -224.520252) (xy 363.847888 -224.87509) (xy 363.870748 -224.879408)
			(xy 363.895571 -224.884565) (xy 363.943351 -224.90152) (xy 363.987971 -224.925592) (xy 364.028378 -224.956214)
			(xy 364.063619 -224.992662) (xy 364.092863 -225.034077) (xy 364.115419 -225.079482) (xy 364.130756 -225.127806)
			(xy 364.138511 -225.177908) (xy 364.138972 -225.203258) (xy 364.138464 -225.229165) (xy 364.130358 -225.280342)
			(xy 364.114346 -225.329621) (xy 364.090823 -225.375788) (xy 364.060367 -225.417707) (xy 364.023729 -225.454345)
			(xy 363.98181 -225.484801) (xy 363.935643 -225.508324) (xy 363.886364 -225.524336) (xy 363.835187 -225.532442)
			(xy 363.783373 -225.532442) (xy 363.732196 -225.524336) (xy 363.682917 -225.508324) (xy 363.63675 -225.484801)
			(xy 363.594831 -225.454345) (xy 363.558193 -225.417707) (xy 363.527737 -225.375788) (xy 363.504214 -225.329621)
			(xy 363.488202 -225.280342) (xy 363.480096 -225.229165) (xy 363.479588 -225.203258) (xy 363.480197 -225.175541)
			(xy 363.48951 -225.120895) (xy 363.49813 -225.094546) (xy 363.506004 -225.072448) (xy 363.301026 -224.71761)
			(xy 363.278166 -224.713292) (xy 363.253348 -224.708169) (xy 363.205605 -224.691172) (xy 363.161026 -224.667071)
			(xy 363.12066 -224.636431) (xy 363.085457 -224.599976) (xy 363.056248 -224.558564) (xy 363.033719 -224.51317)
			(xy 363.018401 -224.464863) (xy 363.010655 -224.414781) (xy 363.010196 -224.389442) (xy 362.729272 -224.389442)
			(xy 362.728764 -224.415329) (xy 362.720665 -224.466467) (xy 362.704666 -224.515707) (xy 362.68116 -224.561839)
			(xy 362.650728 -224.603726) (xy 362.614118 -224.640336) (xy 362.572231 -224.670768) (xy 362.526099 -224.694274)
			(xy 362.476859 -224.710273) (xy 362.425721 -224.718372) (xy 362.373947 -224.718372) (xy 362.322809 -224.710273)
			(xy 362.273569 -224.694274) (xy 362.227437 -224.670768) (xy 362.18555 -224.640336) (xy 362.14894 -224.603726)
			(xy 362.118508 -224.561839) (xy 362.095002 -224.515707) (xy 362.079003 -224.466467) (xy 362.070904 -224.415329)
			(xy 362.070396 -224.389442) (xy 361.789472 -224.389442) (xy 361.788925 -224.417149) (xy 361.779741 -224.471796)
			(xy 361.771184 -224.498154) (xy 361.76331 -224.520252) (xy 361.968288 -224.87509) (xy 361.991148 -224.879408)
			(xy 362.015971 -224.884565) (xy 362.063751 -224.90152) (xy 362.108371 -224.925592) (xy 362.148778 -224.956214)
			(xy 362.184019 -224.992662) (xy 362.213263 -225.034077) (xy 362.235819 -225.079482) (xy 362.251156 -225.127806)
			(xy 362.258911 -225.177908) (xy 362.259372 -225.203258) (xy 362.258864 -225.229165) (xy 362.250758 -225.280342)
			(xy 362.234746 -225.329621) (xy 362.211223 -225.375788) (xy 362.180767 -225.417707) (xy 362.144129 -225.454345)
			(xy 362.10221 -225.484801) (xy 362.056043 -225.508324) (xy 362.006764 -225.524336) (xy 361.955587 -225.532442)
			(xy 361.903773 -225.532442) (xy 361.852596 -225.524336) (xy 361.803317 -225.508324) (xy 361.75715 -225.484801)
			(xy 361.715231 -225.454345) (xy 361.678593 -225.417707) (xy 361.648137 -225.375788) (xy 361.624614 -225.329621)
			(xy 361.608602 -225.280342) (xy 361.600496 -225.229165) (xy 361.599988 -225.203258) (xy 361.600597 -225.175541)
			(xy 361.60991 -225.120895) (xy 361.61853 -225.094546) (xy 361.626404 -225.072448) (xy 361.421426 -224.71761)
			(xy 361.398566 -224.713292) (xy 361.373748 -224.708169) (xy 361.326005 -224.691172) (xy 361.281426 -224.667071)
			(xy 361.24106 -224.636431) (xy 361.205857 -224.599976) (xy 361.176648 -224.558564) (xy 361.154119 -224.51317)
			(xy 361.138801 -224.464863) (xy 361.131055 -224.414781) (xy 361.130596 -224.389442) (xy 360.849672 -224.389442)
			(xy 360.849164 -224.415329) (xy 360.841065 -224.466467) (xy 360.825066 -224.515707) (xy 360.80156 -224.561839)
			(xy 360.771128 -224.603726) (xy 360.734518 -224.640336) (xy 360.692631 -224.670768) (xy 360.646499 -224.694274)
			(xy 360.597259 -224.710273) (xy 360.546121 -224.718372) (xy 360.494347 -224.718372) (xy 360.443209 -224.710273)
			(xy 360.393969 -224.694274) (xy 360.347837 -224.670768) (xy 360.30595 -224.640336) (xy 360.26934 -224.603726)
			(xy 360.238908 -224.561839) (xy 360.215402 -224.515707) (xy 360.199403 -224.466467) (xy 360.191304 -224.415329)
			(xy 360.190796 -224.389442) (xy 359.909872 -224.389442) (xy 359.909325 -224.417149) (xy 359.900141 -224.471796)
			(xy 359.891584 -224.498154) (xy 359.88371 -224.520252) (xy 360.088688 -224.87509) (xy 360.111548 -224.879408)
			(xy 360.136371 -224.884565) (xy 360.184151 -224.90152) (xy 360.228771 -224.925592) (xy 360.269178 -224.956214)
			(xy 360.304419 -224.992662) (xy 360.333663 -225.034077) (xy 360.356219 -225.079482) (xy 360.371556 -225.127806)
			(xy 360.379311 -225.177908) (xy 360.379772 -225.203258) (xy 360.379264 -225.229165) (xy 360.371158 -225.280342)
			(xy 360.355146 -225.329621) (xy 360.331623 -225.375788) (xy 360.301167 -225.417707) (xy 360.264529 -225.454345)
			(xy 360.22261 -225.484801) (xy 360.176443 -225.508324) (xy 360.127164 -225.524336) (xy 360.075987 -225.532442)
			(xy 360.024173 -225.532442) (xy 359.972996 -225.524336) (xy 359.923717 -225.508324) (xy 359.87755 -225.484801)
			(xy 359.835631 -225.454345) (xy 359.798993 -225.417707) (xy 359.768537 -225.375788) (xy 359.745014 -225.329621)
			(xy 359.729002 -225.280342) (xy 359.720896 -225.229165) (xy 359.720388 -225.203258) (xy 359.720997 -225.175541)
			(xy 359.73031 -225.120895) (xy 359.73893 -225.094546) (xy 359.746804 -225.072448) (xy 359.541826 -224.71761)
			(xy 359.518966 -224.713292) (xy 359.494148 -224.708169) (xy 359.446405 -224.691172) (xy 359.401826 -224.667071)
			(xy 359.36146 -224.636431) (xy 359.326257 -224.599976) (xy 359.297048 -224.558564) (xy 359.274519 -224.51317)
			(xy 359.259201 -224.464863) (xy 359.251455 -224.414781) (xy 359.250996 -224.389442) (xy 358.970072 -224.389442)
			(xy 358.969564 -224.415329) (xy 358.961465 -224.466467) (xy 358.945466 -224.515707) (xy 358.92196 -224.561839)
			(xy 358.891528 -224.603726) (xy 358.854918 -224.640336) (xy 358.813031 -224.670768) (xy 358.766899 -224.694274)
			(xy 358.717659 -224.710273) (xy 358.666521 -224.718372) (xy 358.614747 -224.718372) (xy 358.563609 -224.710273)
			(xy 358.514369 -224.694274) (xy 358.468237 -224.670768) (xy 358.42635 -224.640336) (xy 358.38974 -224.603726)
			(xy 358.359308 -224.561839) (xy 358.335802 -224.515707) (xy 358.319803 -224.466467) (xy 358.311704 -224.415329)
			(xy 358.311196 -224.389442) (xy 358.030272 -224.389442) (xy 358.029725 -224.417149) (xy 358.020541 -224.471796)
			(xy 358.011984 -224.498154) (xy 358.00411 -224.520252) (xy 358.209088 -224.87509) (xy 358.231948 -224.879408)
			(xy 358.256771 -224.884565) (xy 358.304551 -224.90152) (xy 358.349171 -224.925592) (xy 358.389578 -224.956214)
			(xy 358.424819 -224.992662) (xy 358.454063 -225.034077) (xy 358.476619 -225.079482) (xy 358.491956 -225.127806)
			(xy 358.499711 -225.177908) (xy 358.500172 -225.203258) (xy 358.499664 -225.229165) (xy 358.491558 -225.280342)
			(xy 358.475546 -225.329621) (xy 358.452023 -225.375788) (xy 358.421567 -225.417707) (xy 358.384929 -225.454345)
			(xy 358.34301 -225.484801) (xy 358.296843 -225.508324) (xy 358.247564 -225.524336) (xy 358.196387 -225.532442)
			(xy 358.144573 -225.532442) (xy 358.093396 -225.524336) (xy 358.044117 -225.508324) (xy 357.99795 -225.484801)
			(xy 357.956031 -225.454345) (xy 357.919393 -225.417707) (xy 357.888937 -225.375788) (xy 357.865414 -225.329621)
			(xy 357.849402 -225.280342) (xy 357.841296 -225.229165) (xy 357.840788 -225.203258) (xy 357.841397 -225.175541)
			(xy 357.85071 -225.120895) (xy 357.85933 -225.094546) (xy 357.867204 -225.072448) (xy 357.662226 -224.71761)
			(xy 357.639366 -224.713292) (xy 357.614548 -224.708169) (xy 357.566805 -224.691172) (xy 357.522226 -224.667071)
			(xy 357.48186 -224.636431) (xy 357.446657 -224.599976) (xy 357.417448 -224.558564) (xy 357.394919 -224.51317)
			(xy 357.379601 -224.464863) (xy 357.371855 -224.414781) (xy 357.371396 -224.389442) (xy 357.090472 -224.389442)
			(xy 357.089964 -224.415329) (xy 357.081865 -224.466467) (xy 357.065866 -224.515707) (xy 357.04236 -224.561839)
			(xy 357.011928 -224.603726) (xy 356.975318 -224.640336) (xy 356.933431 -224.670768) (xy 356.887299 -224.694274)
			(xy 356.838059 -224.710273) (xy 356.786921 -224.718372) (xy 356.735147 -224.718372) (xy 356.684009 -224.710273)
			(xy 356.634769 -224.694274) (xy 356.588637 -224.670768) (xy 356.54675 -224.640336) (xy 356.51014 -224.603726)
			(xy 356.479708 -224.561839) (xy 356.456202 -224.515707) (xy 356.440203 -224.466467) (xy 356.432104 -224.415329)
			(xy 356.431596 -224.389442) (xy 356.150672 -224.389442) (xy 356.150125 -224.417149) (xy 356.140941 -224.471796)
			(xy 356.132384 -224.498154) (xy 356.12451 -224.520252) (xy 356.329488 -224.87509) (xy 356.352348 -224.879408)
			(xy 356.377171 -224.884565) (xy 356.424951 -224.90152) (xy 356.469571 -224.925592) (xy 356.509978 -224.956214)
			(xy 356.545219 -224.992662) (xy 356.574463 -225.034077) (xy 356.597019 -225.079482) (xy 356.612356 -225.127806)
			(xy 356.620111 -225.177908) (xy 356.620572 -225.203258) (xy 356.620064 -225.229165) (xy 356.611958 -225.280342)
			(xy 356.595946 -225.329621) (xy 356.572423 -225.375788) (xy 356.541967 -225.417707) (xy 356.505329 -225.454345)
			(xy 356.46341 -225.484801) (xy 356.417243 -225.508324) (xy 356.367964 -225.524336) (xy 356.316787 -225.532442)
			(xy 356.264973 -225.532442) (xy 356.213796 -225.524336) (xy 356.164517 -225.508324) (xy 356.11835 -225.484801)
			(xy 356.076431 -225.454345) (xy 356.039793 -225.417707) (xy 356.009337 -225.375788) (xy 355.985814 -225.329621)
			(xy 355.969802 -225.280342) (xy 355.961696 -225.229165) (xy 355.961188 -225.203258) (xy 355.961797 -225.175541)
			(xy 355.97111 -225.120895) (xy 355.97973 -225.094546) (xy 355.987604 -225.072448) (xy 355.782626 -224.71761)
			(xy 355.759766 -224.713292) (xy 355.734948 -224.708169) (xy 355.687205 -224.691172) (xy 355.642626 -224.667071)
			(xy 355.60226 -224.636431) (xy 355.567057 -224.599976) (xy 355.537848 -224.558564) (xy 355.515319 -224.51317)
			(xy 355.500001 -224.464863) (xy 355.492255 -224.414781) (xy 355.491796 -224.389442) (xy 355.210872 -224.389442)
			(xy 355.210364 -224.415329) (xy 355.202265 -224.466467) (xy 355.186266 -224.515707) (xy 355.16276 -224.561839)
			(xy 355.132328 -224.603726) (xy 355.095718 -224.640336) (xy 355.053831 -224.670768) (xy 355.007699 -224.694274)
			(xy 354.958459 -224.710273) (xy 354.907321 -224.718372) (xy 354.855547 -224.718372) (xy 354.804409 -224.710273)
			(xy 354.755169 -224.694274) (xy 354.709037 -224.670768) (xy 354.66715 -224.640336) (xy 354.63054 -224.603726)
			(xy 354.600108 -224.561839) (xy 354.576602 -224.515707) (xy 354.560603 -224.466467) (xy 354.552504 -224.415329)
			(xy 354.551996 -224.389442) (xy 354.271072 -224.389442) (xy 354.270525 -224.417149) (xy 354.261341 -224.471796)
			(xy 354.252784 -224.498154) (xy 354.24491 -224.520252) (xy 354.449888 -224.87509) (xy 354.472748 -224.879408)
			(xy 354.497571 -224.884565) (xy 354.545351 -224.90152) (xy 354.589971 -224.925592) (xy 354.630378 -224.956214)
			(xy 354.665619 -224.992662) (xy 354.694863 -225.034077) (xy 354.717419 -225.079482) (xy 354.732756 -225.127806)
			(xy 354.740511 -225.177908) (xy 354.740972 -225.203258) (xy 354.740464 -225.229165) (xy 354.732358 -225.280342)
			(xy 354.716346 -225.329621) (xy 354.692823 -225.375788) (xy 354.662367 -225.417707) (xy 354.625729 -225.454345)
			(xy 354.58381 -225.484801) (xy 354.537643 -225.508324) (xy 354.488364 -225.524336) (xy 354.437187 -225.532442)
			(xy 354.385373 -225.532442) (xy 354.334196 -225.524336) (xy 354.284917 -225.508324) (xy 354.23875 -225.484801)
			(xy 354.196831 -225.454345) (xy 354.160193 -225.417707) (xy 354.129737 -225.375788) (xy 354.106214 -225.329621)
			(xy 354.090202 -225.280342) (xy 354.082096 -225.229165) (xy 354.081588 -225.203258) (xy 354.082197 -225.175541)
			(xy 354.09151 -225.120895) (xy 354.10013 -225.094546) (xy 354.108004 -225.072448) (xy 353.903026 -224.71761)
			(xy 353.880166 -224.713292) (xy 353.855348 -224.708169) (xy 353.807605 -224.691172) (xy 353.763026 -224.667071)
			(xy 353.72266 -224.636431) (xy 353.687457 -224.599976) (xy 353.658248 -224.558564) (xy 353.635719 -224.51317)
			(xy 353.620401 -224.464863) (xy 353.612655 -224.414781) (xy 353.612196 -224.389442) (xy 353.331272 -224.389442)
			(xy 353.330764 -224.415329) (xy 353.322665 -224.466467) (xy 353.306666 -224.515707) (xy 353.28316 -224.561839)
			(xy 353.252728 -224.603726) (xy 353.216118 -224.640336) (xy 353.174231 -224.670768) (xy 353.128099 -224.694274)
			(xy 353.078859 -224.710273) (xy 353.027721 -224.718372) (xy 352.975947 -224.718372) (xy 352.924809 -224.710273)
			(xy 352.875569 -224.694274) (xy 352.829437 -224.670768) (xy 352.78755 -224.640336) (xy 352.75094 -224.603726)
			(xy 352.720508 -224.561839) (xy 352.697002 -224.515707) (xy 352.681003 -224.466467) (xy 352.672904 -224.415329)
			(xy 352.672396 -224.389442) (xy 352.391472 -224.389442) (xy 352.390925 -224.417149) (xy 352.381741 -224.471796)
			(xy 352.373184 -224.498154) (xy 352.36531 -224.520252) (xy 352.570288 -224.87509) (xy 352.593148 -224.879408)
			(xy 352.617971 -224.884565) (xy 352.665751 -224.90152) (xy 352.710371 -224.925592) (xy 352.750778 -224.956214)
			(xy 352.786019 -224.992662) (xy 352.815263 -225.034077) (xy 352.837819 -225.079482) (xy 352.853156 -225.127806)
			(xy 352.860911 -225.177908) (xy 352.861372 -225.203258) (xy 352.860864 -225.229165) (xy 352.852758 -225.280342)
			(xy 352.836746 -225.329621) (xy 352.813223 -225.375788) (xy 352.782767 -225.417707) (xy 352.746129 -225.454345)
			(xy 352.70421 -225.484801) (xy 352.658043 -225.508324) (xy 352.608764 -225.524336) (xy 352.557587 -225.532442)
			(xy 352.505773 -225.532442) (xy 352.454596 -225.524336) (xy 352.405317 -225.508324) (xy 352.35915 -225.484801)
			(xy 352.317231 -225.454345) (xy 352.280593 -225.417707) (xy 352.250137 -225.375788) (xy 352.226614 -225.329621)
			(xy 352.210602 -225.280342) (xy 352.202496 -225.229165) (xy 352.201988 -225.203258) (xy 352.202597 -225.175541)
			(xy 352.21191 -225.120895) (xy 352.22053 -225.094546) (xy 352.228404 -225.072448) (xy 352.023426 -224.71761)
			(xy 352.000566 -224.713292) (xy 351.975748 -224.708169) (xy 351.928005 -224.691172) (xy 351.883426 -224.667071)
			(xy 351.84306 -224.636431) (xy 351.807857 -224.599976) (xy 351.778648 -224.558564) (xy 351.756119 -224.51317)
			(xy 351.740801 -224.464863) (xy 351.733055 -224.414781) (xy 351.732596 -224.389442) (xy 351.451672 -224.389442)
			(xy 351.451164 -224.415329) (xy 351.443065 -224.466467) (xy 351.427066 -224.515707) (xy 351.40356 -224.561839)
			(xy 351.373128 -224.603726) (xy 351.336518 -224.640336) (xy 351.294631 -224.670768) (xy 351.248499 -224.694274)
			(xy 351.199259 -224.710273) (xy 351.148121 -224.718372) (xy 351.096347 -224.718372) (xy 351.045209 -224.710273)
			(xy 350.995969 -224.694274) (xy 350.949837 -224.670768) (xy 350.90795 -224.640336) (xy 350.87134 -224.603726)
			(xy 350.840908 -224.561839) (xy 350.817402 -224.515707) (xy 350.801403 -224.466467) (xy 350.793304 -224.415329)
			(xy 350.792796 -224.389442) (xy 350.511872 -224.389442) (xy 350.511325 -224.417149) (xy 350.502141 -224.471796)
			(xy 350.493584 -224.498154) (xy 350.48571 -224.520252) (xy 350.690688 -224.87509) (xy 350.713548 -224.879408)
			(xy 350.738371 -224.884565) (xy 350.786151 -224.90152) (xy 350.830771 -224.925592) (xy 350.871178 -224.956214)
			(xy 350.906419 -224.992662) (xy 350.935663 -225.034077) (xy 350.958219 -225.079482) (xy 350.973556 -225.127806)
			(xy 350.981311 -225.177908) (xy 350.981772 -225.203258) (xy 350.981264 -225.229165) (xy 350.973158 -225.280342)
			(xy 350.957146 -225.329621) (xy 350.933623 -225.375788) (xy 350.903167 -225.417707) (xy 350.866529 -225.454345)
			(xy 350.82461 -225.484801) (xy 350.778443 -225.508324) (xy 350.729164 -225.524336) (xy 350.677987 -225.532442)
			(xy 350.626173 -225.532442) (xy 350.574996 -225.524336) (xy 350.525717 -225.508324) (xy 350.47955 -225.484801)
			(xy 350.437631 -225.454345) (xy 350.400993 -225.417707) (xy 350.370537 -225.375788) (xy 350.347014 -225.329621)
			(xy 350.331002 -225.280342) (xy 350.322896 -225.229165) (xy 350.322388 -225.203258) (xy 350.322997 -225.175541)
			(xy 350.33231 -225.120895) (xy 350.34093 -225.094546) (xy 350.348804 -225.072448) (xy 350.143826 -224.71761)
			(xy 350.120966 -224.713292) (xy 350.096148 -224.708169) (xy 350.048405 -224.691172) (xy 350.003826 -224.667071)
			(xy 349.96346 -224.636431) (xy 349.928257 -224.599976) (xy 349.899048 -224.558564) (xy 349.876519 -224.51317)
			(xy 349.861201 -224.464863) (xy 349.853455 -224.414781) (xy 349.852996 -224.389442) (xy 349.572072 -224.389442)
			(xy 349.571564 -224.415329) (xy 349.563465 -224.466467) (xy 349.547466 -224.515707) (xy 349.52396 -224.561839)
			(xy 349.493528 -224.603726) (xy 349.456918 -224.640336) (xy 349.415031 -224.670768) (xy 349.368899 -224.694274)
			(xy 349.319659 -224.710273) (xy 349.268521 -224.718372) (xy 349.216747 -224.718372) (xy 349.165609 -224.710273)
			(xy 349.116369 -224.694274) (xy 349.070237 -224.670768) (xy 349.02835 -224.640336) (xy 348.99174 -224.603726)
			(xy 348.961308 -224.561839) (xy 348.937802 -224.515707) (xy 348.921803 -224.466467) (xy 348.913704 -224.415329)
			(xy 348.913196 -224.389442) (xy 348.632272 -224.389442) (xy 348.631725 -224.417149) (xy 348.622541 -224.471796)
			(xy 348.613984 -224.498154) (xy 348.60611 -224.520252) (xy 348.811088 -224.87509) (xy 348.833948 -224.879408)
			(xy 348.858771 -224.884565) (xy 348.906551 -224.90152) (xy 348.951171 -224.925592) (xy 348.991578 -224.956214)
			(xy 349.026819 -224.992662) (xy 349.056063 -225.034077) (xy 349.078619 -225.079482) (xy 349.093956 -225.127806)
			(xy 349.101711 -225.177908) (xy 349.102172 -225.203258) (xy 349.101664 -225.229165) (xy 349.093558 -225.280342)
			(xy 349.077546 -225.329621) (xy 349.054023 -225.375788) (xy 349.023567 -225.417707) (xy 348.986929 -225.454345)
			(xy 348.94501 -225.484801) (xy 348.898843 -225.508324) (xy 348.849564 -225.524336) (xy 348.798387 -225.532442)
			(xy 348.746573 -225.532442) (xy 348.695396 -225.524336) (xy 348.646117 -225.508324) (xy 348.59995 -225.484801)
			(xy 348.558031 -225.454345) (xy 348.521393 -225.417707) (xy 348.490937 -225.375788) (xy 348.467414 -225.329621)
			(xy 348.451402 -225.280342) (xy 348.443296 -225.229165) (xy 348.442788 -225.203258) (xy 348.443397 -225.175541)
			(xy 348.45271 -225.120895) (xy 348.46133 -225.094546) (xy 348.469204 -225.072448) (xy 348.264226 -224.71761)
			(xy 348.241366 -224.713292) (xy 348.216548 -224.708169) (xy 348.168805 -224.691172) (xy 348.124226 -224.667071)
			(xy 348.08386 -224.636431) (xy 348.048657 -224.599976) (xy 348.019448 -224.558564) (xy 347.996919 -224.51317)
			(xy 347.981601 -224.464863) (xy 347.973855 -224.414781) (xy 347.973396 -224.389442) (xy 347.692472 -224.389442)
			(xy 347.691964 -224.415329) (xy 347.683865 -224.466467) (xy 347.667866 -224.515707) (xy 347.64436 -224.561839)
			(xy 347.613928 -224.603726) (xy 347.577318 -224.640336) (xy 347.535431 -224.670768) (xy 347.489299 -224.694274)
			(xy 347.440059 -224.710273) (xy 347.388921 -224.718372) (xy 347.337147 -224.718372) (xy 347.286009 -224.710273)
			(xy 347.236769 -224.694274) (xy 347.190637 -224.670768) (xy 347.14875 -224.640336) (xy 347.11214 -224.603726)
			(xy 347.081708 -224.561839) (xy 347.058202 -224.515707) (xy 347.042203 -224.466467) (xy 347.034104 -224.415329)
			(xy 347.033596 -224.389442) (xy 346.752672 -224.389442) (xy 346.752125 -224.417149) (xy 346.742941 -224.471796)
			(xy 346.734384 -224.498154) (xy 346.72651 -224.520252) (xy 346.931488 -224.87509) (xy 346.954348 -224.879408)
			(xy 346.979171 -224.884565) (xy 347.026951 -224.90152) (xy 347.071571 -224.925592) (xy 347.111978 -224.956214)
			(xy 347.147219 -224.992662) (xy 347.176463 -225.034077) (xy 347.199019 -225.079482) (xy 347.214356 -225.127806)
			(xy 347.222111 -225.177908) (xy 347.222572 -225.203258) (xy 347.222064 -225.229165) (xy 347.213958 -225.280342)
			(xy 347.197946 -225.329621) (xy 347.174423 -225.375788) (xy 347.143967 -225.417707) (xy 347.107329 -225.454345)
			(xy 347.06541 -225.484801) (xy 347.019243 -225.508324) (xy 346.969964 -225.524336) (xy 346.918787 -225.532442)
			(xy 346.866973 -225.532442) (xy 346.815796 -225.524336) (xy 346.766517 -225.508324) (xy 346.72035 -225.484801)
			(xy 346.678431 -225.454345) (xy 346.641793 -225.417707) (xy 346.611337 -225.375788) (xy 346.587814 -225.329621)
			(xy 346.571802 -225.280342) (xy 346.563696 -225.229165) (xy 346.563188 -225.203258) (xy 346.563797 -225.175541)
			(xy 346.57311 -225.120895) (xy 346.58173 -225.094546) (xy 346.589604 -225.072448) (xy 346.384626 -224.71761)
			(xy 346.361766 -224.713292) (xy 346.336948 -224.708169) (xy 346.289205 -224.691172) (xy 346.244626 -224.667071)
			(xy 346.20426 -224.636431) (xy 346.169057 -224.599976) (xy 346.139848 -224.558564) (xy 346.117319 -224.51317)
			(xy 346.102001 -224.464863) (xy 346.094255 -224.414781) (xy 346.093796 -224.389442) (xy 345.812872 -224.389442)
			(xy 345.812364 -224.415329) (xy 345.804265 -224.466467) (xy 345.788266 -224.515707) (xy 345.76476 -224.561839)
			(xy 345.734328 -224.603726) (xy 345.697718 -224.640336) (xy 345.655831 -224.670768) (xy 345.609699 -224.694274)
			(xy 345.560459 -224.710273) (xy 345.509321 -224.718372) (xy 345.457547 -224.718372) (xy 345.406409 -224.710273)
			(xy 345.357169 -224.694274) (xy 345.311037 -224.670768) (xy 345.26915 -224.640336) (xy 345.23254 -224.603726)
			(xy 345.202108 -224.561839) (xy 345.178602 -224.515707) (xy 345.162603 -224.466467) (xy 345.154504 -224.415329)
			(xy 345.153996 -224.389442) (xy 344.873072 -224.389442) (xy 344.872525 -224.417149) (xy 344.863341 -224.471796)
			(xy 344.854784 -224.498154) (xy 344.84691 -224.520252) (xy 345.051888 -224.87509) (xy 345.074748 -224.879408)
			(xy 345.099571 -224.884565) (xy 345.147351 -224.90152) (xy 345.191971 -224.925592) (xy 345.232378 -224.956214)
			(xy 345.267619 -224.992662) (xy 345.296863 -225.034077) (xy 345.319419 -225.079482) (xy 345.334756 -225.127806)
			(xy 345.342511 -225.177908) (xy 345.342972 -225.203258) (xy 345.342464 -225.229165) (xy 345.334358 -225.280342)
			(xy 345.318346 -225.329621) (xy 345.294823 -225.375788) (xy 345.264367 -225.417707) (xy 345.227729 -225.454345)
			(xy 345.18581 -225.484801) (xy 345.139643 -225.508324) (xy 345.090364 -225.524336) (xy 345.039187 -225.532442)
			(xy 344.987373 -225.532442) (xy 344.936196 -225.524336) (xy 344.886917 -225.508324) (xy 344.84075 -225.484801)
			(xy 344.798831 -225.454345) (xy 344.762193 -225.417707) (xy 344.731737 -225.375788) (xy 344.708214 -225.329621)
			(xy 344.692202 -225.280342) (xy 344.684096 -225.229165) (xy 344.683588 -225.203258) (xy 344.684197 -225.175541)
			(xy 344.69351 -225.120895) (xy 344.70213 -225.094546) (xy 344.710004 -225.072448) (xy 344.505026 -224.71761)
			(xy 344.482166 -224.713292) (xy 344.457348 -224.708169) (xy 344.409605 -224.691172) (xy 344.365026 -224.667071)
			(xy 344.32466 -224.636431) (xy 344.289457 -224.599976) (xy 344.260248 -224.558564) (xy 344.237719 -224.51317)
			(xy 344.222401 -224.464863) (xy 344.214655 -224.414781) (xy 344.214196 -224.389442) (xy 343.933272 -224.389442)
			(xy 343.932764 -224.415329) (xy 343.924665 -224.466467) (xy 343.908666 -224.515707) (xy 343.88516 -224.561839)
			(xy 343.854728 -224.603726) (xy 343.818118 -224.640336) (xy 343.776231 -224.670768) (xy 343.730099 -224.694274)
			(xy 343.680859 -224.710273) (xy 343.629721 -224.718372) (xy 343.577947 -224.718372) (xy 343.526809 -224.710273)
			(xy 343.477569 -224.694274) (xy 343.431437 -224.670768) (xy 343.38955 -224.640336) (xy 343.35294 -224.603726)
			(xy 343.322508 -224.561839) (xy 343.299002 -224.515707) (xy 343.283003 -224.466467) (xy 343.274904 -224.415329)
			(xy 343.274396 -224.389442) (xy 342.993472 -224.389442) (xy 342.992925 -224.417149) (xy 342.983741 -224.471796)
			(xy 342.975184 -224.498154) (xy 342.96731 -224.520252) (xy 343.172288 -224.87509) (xy 343.195148 -224.879408)
			(xy 343.219971 -224.884565) (xy 343.267751 -224.90152) (xy 343.312371 -224.925592) (xy 343.352778 -224.956214)
			(xy 343.388019 -224.992662) (xy 343.417263 -225.034077) (xy 343.439819 -225.079482) (xy 343.455156 -225.127806)
			(xy 343.462911 -225.177908) (xy 343.463372 -225.203258) (xy 343.462864 -225.229165) (xy 343.454758 -225.280342)
			(xy 343.438746 -225.329621) (xy 343.415223 -225.375788) (xy 343.384767 -225.417707) (xy 343.348129 -225.454345)
			(xy 343.30621 -225.484801) (xy 343.260043 -225.508324) (xy 343.210764 -225.524336) (xy 343.159587 -225.532442)
			(xy 343.107773 -225.532442) (xy 343.056596 -225.524336) (xy 343.007317 -225.508324) (xy 342.96115 -225.484801)
			(xy 342.919231 -225.454345) (xy 342.882593 -225.417707) (xy 342.852137 -225.375788) (xy 342.828614 -225.329621)
			(xy 342.812602 -225.280342) (xy 342.804496 -225.229165) (xy 342.803988 -225.203258) (xy 342.804597 -225.175541)
			(xy 342.81391 -225.120895) (xy 342.82253 -225.094546) (xy 342.830404 -225.072448) (xy 342.625426 -224.71761)
			(xy 342.602566 -224.713292) (xy 342.577748 -224.708169) (xy 342.530005 -224.691172) (xy 342.485426 -224.667071)
			(xy 342.44506 -224.636431) (xy 342.409857 -224.599976) (xy 342.380648 -224.558564) (xy 342.358119 -224.51317)
			(xy 342.342801 -224.464863) (xy 342.335055 -224.414781) (xy 342.334596 -224.389442) (xy 342.053672 -224.389442)
			(xy 342.053164 -224.415329) (xy 342.045065 -224.466467) (xy 342.029066 -224.515707) (xy 342.00556 -224.561839)
			(xy 341.975128 -224.603726) (xy 341.938518 -224.640336) (xy 341.896631 -224.670768) (xy 341.850499 -224.694274)
			(xy 341.801259 -224.710273) (xy 341.750121 -224.718372) (xy 341.698347 -224.718372) (xy 341.647209 -224.710273)
			(xy 341.597969 -224.694274) (xy 341.551837 -224.670768) (xy 341.50995 -224.640336) (xy 341.47334 -224.603726)
			(xy 341.442908 -224.561839) (xy 341.419402 -224.515707) (xy 341.403403 -224.466467) (xy 341.395304 -224.415329)
			(xy 341.394796 -224.389442) (xy 341.113872 -224.389442) (xy 341.113872 -224.38995) (xy 341.113311 -224.417593)
			(xy 341.104122 -224.472111) (xy 341.095584 -224.498408) (xy 341.087964 -224.520252) (xy 341.292688 -224.87509)
			(xy 341.315548 -224.879408) (xy 341.340371 -224.884565) (xy 341.388151 -224.90152) (xy 341.432771 -224.925592)
			(xy 341.473178 -224.956214) (xy 341.508419 -224.992662) (xy 341.537663 -225.034077) (xy 341.560219 -225.079482)
			(xy 341.575556 -225.127806) (xy 341.583311 -225.177908) (xy 341.583772 -225.203258) (xy 341.583264 -225.229165)
			(xy 341.575158 -225.280342) (xy 341.559146 -225.329621) (xy 341.535623 -225.375788) (xy 341.505167 -225.417707)
			(xy 341.468529 -225.454345) (xy 341.42661 -225.484801) (xy 341.380443 -225.508324) (xy 341.331164 -225.524336)
			(xy 341.279987 -225.532442) (xy 341.228173 -225.532442) (xy 341.176996 -225.524336) (xy 341.127717 -225.508324)
			(xy 341.08155 -225.484801) (xy 341.039631 -225.454345) (xy 341.002993 -225.417707) (xy 340.972537 -225.375788)
			(xy 340.949014 -225.329621) (xy 340.933002 -225.280342) (xy 340.924896 -225.229165) (xy 340.924388 -225.203258)
			(xy 340.924388 -225.20275) (xy 340.924995 -225.175096) (xy 340.93432 -225.120578) (xy 340.94293 -225.094292)
			(xy 340.95055 -225.072448) (xy 340.745826 -224.71761) (xy 340.722966 -224.713292) (xy 340.698148 -224.708169)
			(xy 340.650405 -224.691172) (xy 340.605826 -224.667071) (xy 340.56546 -224.636431) (xy 340.530257 -224.599976)
			(xy 340.501048 -224.558564) (xy 340.478519 -224.51317) (xy 340.463201 -224.464863) (xy 340.455455 -224.414781)
			(xy 340.454996 -224.389442) (xy 340.174072 -224.389442) (xy 340.173564 -224.415329) (xy 340.165465 -224.466467)
			(xy 340.149466 -224.515707) (xy 340.12596 -224.561839) (xy 340.095528 -224.603726) (xy 340.058918 -224.640336)
			(xy 340.017031 -224.670768) (xy 339.970899 -224.694274) (xy 339.921659 -224.710273) (xy 339.870521 -224.718372)
			(xy 339.818747 -224.718372) (xy 339.767609 -224.710273) (xy 339.718369 -224.694274) (xy 339.672237 -224.670768)
			(xy 339.63035 -224.640336) (xy 339.59374 -224.603726) (xy 339.563308 -224.561839) (xy 339.539802 -224.515707)
			(xy 339.523803 -224.466467) (xy 339.515704 -224.415329) (xy 339.515196 -224.389442) (xy 339.234272 -224.389442)
			(xy 339.234272 -224.38995) (xy 339.233711 -224.417593) (xy 339.224522 -224.472111) (xy 339.215984 -224.498408)
			(xy 339.208364 -224.520252) (xy 339.413088 -224.87509) (xy 339.435948 -224.879408) (xy 339.460771 -224.884565)
			(xy 339.508551 -224.90152) (xy 339.553171 -224.925592) (xy 339.593578 -224.956214) (xy 339.628819 -224.992662)
			(xy 339.658063 -225.034077) (xy 339.680619 -225.079482) (xy 339.695956 -225.127806) (xy 339.703711 -225.177908)
			(xy 339.704172 -225.203258) (xy 339.703664 -225.229165) (xy 339.695558 -225.280342) (xy 339.679546 -225.329621)
			(xy 339.656023 -225.375788) (xy 339.625567 -225.417707) (xy 339.588929 -225.454345) (xy 339.54701 -225.484801)
			(xy 339.500843 -225.508324) (xy 339.451564 -225.524336) (xy 339.400387 -225.532442) (xy 339.348573 -225.532442)
			(xy 339.297396 -225.524336) (xy 339.248117 -225.508324) (xy 339.20195 -225.484801) (xy 339.160031 -225.454345)
			(xy 339.123393 -225.417707) (xy 339.092937 -225.375788) (xy 339.069414 -225.329621) (xy 339.053402 -225.280342)
			(xy 339.045296 -225.229165) (xy 339.044788 -225.203258) (xy 339.044788 -225.20275) (xy 339.045395 -225.175096)
			(xy 339.05472 -225.120578) (xy 339.06333 -225.094292) (xy 339.07095 -225.072448) (xy 338.866226 -224.71761)
			(xy 338.843366 -224.713292) (xy 338.818548 -224.708169) (xy 338.770805 -224.691172) (xy 338.726226 -224.667071)
			(xy 338.68586 -224.636431) (xy 338.650657 -224.599976) (xy 338.621448 -224.558564) (xy 338.598919 -224.51317)
			(xy 338.583601 -224.464863) (xy 338.575855 -224.414781) (xy 338.575396 -224.389442) (xy 338.294472 -224.389442)
			(xy 338.293964 -224.415329) (xy 338.285865 -224.466467) (xy 338.269866 -224.515707) (xy 338.24636 -224.561839)
			(xy 338.215928 -224.603726) (xy 338.179318 -224.640336) (xy 338.137431 -224.670768) (xy 338.091299 -224.694274)
			(xy 338.042059 -224.710273) (xy 337.990921 -224.718372) (xy 337.939147 -224.718372) (xy 337.888009 -224.710273)
			(xy 337.838769 -224.694274) (xy 337.792637 -224.670768) (xy 337.75075 -224.640336) (xy 337.71414 -224.603726)
			(xy 337.683708 -224.561839) (xy 337.660202 -224.515707) (xy 337.644203 -224.466467) (xy 337.636104 -224.415329)
			(xy 337.635596 -224.389442) (xy 134.525004 -224.389442) (xy 134.524474 -224.41715) (xy 134.515275 -224.471796)
			(xy 134.506716 -224.498154) (xy 134.499096 -224.519998) (xy 134.704074 -224.87509) (xy 134.726934 -224.879408)
			(xy 134.751752 -224.884531) (xy 134.799495 -224.901528) (xy 134.844074 -224.925629) (xy 134.88444 -224.956269)
			(xy 134.919643 -224.992724) (xy 134.948852 -225.034136) (xy 134.971381 -225.07953) (xy 134.986699 -225.127837)
			(xy 134.994445 -225.177919) (xy 134.994904 -225.203258) (xy 134.994396 -225.229145) (xy 134.986297 -225.280283)
			(xy 134.970298 -225.329523) (xy 134.946792 -225.375655) (xy 134.91636 -225.417542) (xy 134.87975 -225.454152)
			(xy 134.837863 -225.484584) (xy 134.791731 -225.50809) (xy 134.742491 -225.524089) (xy 134.691353 -225.532188)
			(xy 134.639579 -225.532188) (xy 134.588441 -225.524089) (xy 134.539201 -225.50809) (xy 134.493069 -225.484584)
			(xy 134.451182 -225.454152) (xy 134.414572 -225.417542) (xy 134.38414 -225.375655) (xy 134.360634 -225.329523)
			(xy 134.344635 -225.280283) (xy 134.336536 -225.229145) (xy 134.336028 -225.203258) (xy 134.336028 -225.20275)
			(xy 134.336589 -225.175107) (xy 134.345778 -225.120589) (xy 134.354316 -225.094292) (xy 134.361936 -225.072448)
			(xy 134.157212 -224.71761) (xy 134.134352 -224.713292) (xy 134.109529 -224.708135) (xy 134.061749 -224.69118)
			(xy 134.017129 -224.667108) (xy 133.976722 -224.636486) (xy 133.941481 -224.600038) (xy 133.912237 -224.558623)
			(xy 133.889681 -224.513218) (xy 133.874344 -224.464894) (xy 133.866589 -224.414792) (xy 133.866128 -224.389442)
			(xy 133.585204 -224.389442) (xy 133.584696 -224.415329) (xy 133.576597 -224.466467) (xy 133.560598 -224.515707)
			(xy 133.537092 -224.561839) (xy 133.50666 -224.603726) (xy 133.47005 -224.640336) (xy 133.428163 -224.670768)
			(xy 133.382031 -224.694274) (xy 133.332791 -224.710273) (xy 133.281653 -224.718372) (xy 133.229879 -224.718372)
			(xy 133.178741 -224.710273) (xy 133.129501 -224.694274) (xy 133.083369 -224.670768) (xy 133.041482 -224.640336)
			(xy 133.004872 -224.603726) (xy 132.97444 -224.561839) (xy 132.950934 -224.515707) (xy 132.934935 -224.466467)
			(xy 132.926836 -224.415329) (xy 132.926328 -224.389442) (xy 132.645404 -224.389442) (xy 132.64486 -224.417149)
			(xy 132.635674 -224.471796) (xy 132.627116 -224.498154) (xy 132.619242 -224.520252) (xy 132.82422 -224.87509)
			(xy 132.84708 -224.879408) (xy 132.871909 -224.884542) (xy 132.919688 -224.901501) (xy 132.964308 -224.925578)
			(xy 133.004714 -224.956202) (xy 133.039954 -224.992654) (xy 133.069197 -225.034071) (xy 133.091752 -225.079478)
			(xy 133.107088 -225.127804) (xy 133.114843 -225.177908) (xy 133.115304 -225.203258) (xy 133.114796 -225.229165)
			(xy 133.10669 -225.280342) (xy 133.090678 -225.329621) (xy 133.067155 -225.375788) (xy 133.036699 -225.417707)
			(xy 133.000061 -225.454345) (xy 132.958142 -225.484801) (xy 132.911975 -225.508324) (xy 132.862696 -225.524336)
			(xy 132.811519 -225.532442) (xy 132.759705 -225.532442) (xy 132.708528 -225.524336) (xy 132.659249 -225.508324)
			(xy 132.613082 -225.484801) (xy 132.571163 -225.454345) (xy 132.534525 -225.417707) (xy 132.504069 -225.375788)
			(xy 132.480546 -225.329621) (xy 132.464534 -225.280342) (xy 132.456428 -225.229165) (xy 132.45592 -225.203258)
			(xy 132.456527 -225.175541) (xy 132.465842 -225.120895) (xy 132.474462 -225.094546) (xy 132.482336 -225.072448)
			(xy 132.277358 -224.71761) (xy 132.254498 -224.713292) (xy 132.229685 -224.708145) (xy 132.181943 -224.691153)
			(xy 132.137363 -224.667056) (xy 132.096996 -224.63642) (xy 132.061793 -224.599968) (xy 132.032582 -224.558558)
			(xy 132.010052 -224.513166) (xy 131.994734 -224.46486) (xy 131.986988 -224.41478) (xy 131.986528 -224.389442)
			(xy 131.705604 -224.389442) (xy 131.705096 -224.415329) (xy 131.696997 -224.466467) (xy 131.680998 -224.515707)
			(xy 131.657492 -224.561839) (xy 131.62706 -224.603726) (xy 131.59045 -224.640336) (xy 131.548563 -224.670768)
			(xy 131.502431 -224.694274) (xy 131.453191 -224.710273) (xy 131.402053 -224.718372) (xy 131.350279 -224.718372)
			(xy 131.299141 -224.710273) (xy 131.249901 -224.694274) (xy 131.203769 -224.670768) (xy 131.161882 -224.640336)
			(xy 131.125272 -224.603726) (xy 131.09484 -224.561839) (xy 131.071334 -224.515707) (xy 131.055335 -224.466467)
			(xy 131.047236 -224.415329) (xy 131.046728 -224.389442) (xy 130.765804 -224.389442) (xy 130.76526 -224.417149)
			(xy 130.756074 -224.471796) (xy 130.747516 -224.498154) (xy 130.739642 -224.520252) (xy 130.94462 -224.87509)
			(xy 130.96748 -224.879408) (xy 130.992309 -224.884542) (xy 131.040088 -224.901501) (xy 131.084708 -224.925578)
			(xy 131.125114 -224.956202) (xy 131.160354 -224.992654) (xy 131.189597 -225.034071) (xy 131.212152 -225.079478)
			(xy 131.227488 -225.127804) (xy 131.235243 -225.177908) (xy 131.235704 -225.203258) (xy 131.235196 -225.229165)
			(xy 131.22709 -225.280342) (xy 131.211078 -225.329621) (xy 131.187555 -225.375788) (xy 131.157099 -225.417707)
			(xy 131.120461 -225.454345) (xy 131.078542 -225.484801) (xy 131.032375 -225.508324) (xy 130.983096 -225.524336)
			(xy 130.931919 -225.532442) (xy 130.880105 -225.532442) (xy 130.828928 -225.524336) (xy 130.779649 -225.508324)
			(xy 130.733482 -225.484801) (xy 130.691563 -225.454345) (xy 130.654925 -225.417707) (xy 130.624469 -225.375788)
			(xy 130.600946 -225.329621) (xy 130.584934 -225.280342) (xy 130.576828 -225.229165) (xy 130.57632 -225.203258)
			(xy 130.576927 -225.175541) (xy 130.586242 -225.120895) (xy 130.594862 -225.094546) (xy 130.602736 -225.072448)
			(xy 130.397758 -224.71761) (xy 130.374898 -224.713292) (xy 130.350085 -224.708145) (xy 130.302343 -224.691153)
			(xy 130.257763 -224.667056) (xy 130.217396 -224.63642) (xy 130.182193 -224.599968) (xy 130.152982 -224.558558)
			(xy 130.130452 -224.513166) (xy 130.115134 -224.46486) (xy 130.107388 -224.41478) (xy 130.106928 -224.389442)
			(xy 129.826004 -224.389442) (xy 129.825496 -224.415329) (xy 129.817397 -224.466467) (xy 129.801398 -224.515707)
			(xy 129.777892 -224.561839) (xy 129.74746 -224.603726) (xy 129.71085 -224.640336) (xy 129.668963 -224.670768)
			(xy 129.622831 -224.694274) (xy 129.573591 -224.710273) (xy 129.522453 -224.718372) (xy 129.470679 -224.718372)
			(xy 129.419541 -224.710273) (xy 129.370301 -224.694274) (xy 129.324169 -224.670768) (xy 129.282282 -224.640336)
			(xy 129.245672 -224.603726) (xy 129.21524 -224.561839) (xy 129.191734 -224.515707) (xy 129.175735 -224.466467)
			(xy 129.167636 -224.415329) (xy 129.167128 -224.389442) (xy 128.886204 -224.389442) (xy 128.88566 -224.417149)
			(xy 128.876474 -224.471796) (xy 128.867916 -224.498154) (xy 128.860042 -224.520252) (xy 129.06502 -224.87509)
			(xy 129.08788 -224.879408) (xy 129.112709 -224.884542) (xy 129.160488 -224.901501) (xy 129.205108 -224.925578)
			(xy 129.245514 -224.956202) (xy 129.280754 -224.992654) (xy 129.309997 -225.034071) (xy 129.332552 -225.079478)
			(xy 129.347888 -225.127804) (xy 129.355643 -225.177908) (xy 129.356104 -225.203258) (xy 129.355596 -225.229165)
			(xy 129.34749 -225.280342) (xy 129.331478 -225.329621) (xy 129.307955 -225.375788) (xy 129.277499 -225.417707)
			(xy 129.240861 -225.454345) (xy 129.198942 -225.484801) (xy 129.152775 -225.508324) (xy 129.103496 -225.524336)
			(xy 129.052319 -225.532442) (xy 129.000505 -225.532442) (xy 128.949328 -225.524336) (xy 128.900049 -225.508324)
			(xy 128.853882 -225.484801) (xy 128.811963 -225.454345) (xy 128.775325 -225.417707) (xy 128.744869 -225.375788)
			(xy 128.721346 -225.329621) (xy 128.705334 -225.280342) (xy 128.697228 -225.229165) (xy 128.69672 -225.203258)
			(xy 128.697327 -225.175541) (xy 128.706642 -225.120895) (xy 128.715262 -225.094546) (xy 128.723136 -225.072448)
			(xy 128.518158 -224.71761) (xy 128.495298 -224.713292) (xy 128.470485 -224.708145) (xy 128.422743 -224.691153)
			(xy 128.378163 -224.667056) (xy 128.337796 -224.63642) (xy 128.302593 -224.599968) (xy 128.273382 -224.558558)
			(xy 128.250852 -224.513166) (xy 128.235534 -224.46486) (xy 128.227788 -224.41478) (xy 128.227328 -224.389442)
			(xy 127.946404 -224.389442) (xy 127.945896 -224.415329) (xy 127.937797 -224.466467) (xy 127.921798 -224.515707)
			(xy 127.898292 -224.561839) (xy 127.86786 -224.603726) (xy 127.83125 -224.640336) (xy 127.789363 -224.670768)
			(xy 127.743231 -224.694274) (xy 127.693991 -224.710273) (xy 127.642853 -224.718372) (xy 127.591079 -224.718372)
			(xy 127.539941 -224.710273) (xy 127.490701 -224.694274) (xy 127.444569 -224.670768) (xy 127.402682 -224.640336)
			(xy 127.366072 -224.603726) (xy 127.33564 -224.561839) (xy 127.312134 -224.515707) (xy 127.296135 -224.466467)
			(xy 127.288036 -224.415329) (xy 127.287528 -224.389442) (xy 127.006604 -224.389442) (xy 127.00606 -224.417149)
			(xy 126.996874 -224.471796) (xy 126.988316 -224.498154) (xy 126.980442 -224.520252) (xy 127.18542 -224.87509)
			(xy 127.20828 -224.879408) (xy 127.233109 -224.884542) (xy 127.280888 -224.901501) (xy 127.325508 -224.925578)
			(xy 127.365914 -224.956202) (xy 127.401154 -224.992654) (xy 127.430397 -225.034071) (xy 127.452952 -225.079478)
			(xy 127.468288 -225.127804) (xy 127.476043 -225.177908) (xy 127.476504 -225.203258) (xy 127.475996 -225.229165)
			(xy 127.46789 -225.280342) (xy 127.451878 -225.329621) (xy 127.428355 -225.375788) (xy 127.397899 -225.417707)
			(xy 127.361261 -225.454345) (xy 127.319342 -225.484801) (xy 127.273175 -225.508324) (xy 127.223896 -225.524336)
			(xy 127.172719 -225.532442) (xy 127.120905 -225.532442) (xy 127.069728 -225.524336) (xy 127.020449 -225.508324)
			(xy 126.974282 -225.484801) (xy 126.932363 -225.454345) (xy 126.895725 -225.417707) (xy 126.865269 -225.375788)
			(xy 126.841746 -225.329621) (xy 126.825734 -225.280342) (xy 126.817628 -225.229165) (xy 126.81712 -225.203258)
			(xy 126.817727 -225.175541) (xy 126.827042 -225.120895) (xy 126.835662 -225.094546) (xy 126.843536 -225.072448)
			(xy 126.638558 -224.71761) (xy 126.615698 -224.713292) (xy 126.590885 -224.708145) (xy 126.543143 -224.691153)
			(xy 126.498563 -224.667056) (xy 126.458196 -224.63642) (xy 126.422993 -224.599968) (xy 126.393782 -224.558558)
			(xy 126.371252 -224.513166) (xy 126.355934 -224.46486) (xy 126.348188 -224.41478) (xy 126.347728 -224.389442)
			(xy 126.066804 -224.389442) (xy 126.066296 -224.415329) (xy 126.058197 -224.466467) (xy 126.042198 -224.515707)
			(xy 126.018692 -224.561839) (xy 125.98826 -224.603726) (xy 125.95165 -224.640336) (xy 125.909763 -224.670768)
			(xy 125.863631 -224.694274) (xy 125.814391 -224.710273) (xy 125.763253 -224.718372) (xy 125.711479 -224.718372)
			(xy 125.660341 -224.710273) (xy 125.611101 -224.694274) (xy 125.564969 -224.670768) (xy 125.523082 -224.640336)
			(xy 125.486472 -224.603726) (xy 125.45604 -224.561839) (xy 125.432534 -224.515707) (xy 125.416535 -224.466467)
			(xy 125.408436 -224.415329) (xy 125.407928 -224.389442) (xy 125.127004 -224.389442) (xy 125.12646 -224.417149)
			(xy 125.117274 -224.471796) (xy 125.108716 -224.498154) (xy 125.100842 -224.520252) (xy 125.30582 -224.87509)
			(xy 125.32868 -224.879408) (xy 125.353509 -224.884542) (xy 125.401288 -224.901501) (xy 125.445908 -224.925578)
			(xy 125.486314 -224.956202) (xy 125.521554 -224.992654) (xy 125.550797 -225.034071) (xy 125.573352 -225.079478)
			(xy 125.588688 -225.127804) (xy 125.596443 -225.177908) (xy 125.596904 -225.203258) (xy 125.596396 -225.229165)
			(xy 125.58829 -225.280342) (xy 125.572278 -225.329621) (xy 125.548755 -225.375788) (xy 125.518299 -225.417707)
			(xy 125.481661 -225.454345) (xy 125.439742 -225.484801) (xy 125.393575 -225.508324) (xy 125.344296 -225.524336)
			(xy 125.293119 -225.532442) (xy 125.241305 -225.532442) (xy 125.190128 -225.524336) (xy 125.140849 -225.508324)
			(xy 125.094682 -225.484801) (xy 125.052763 -225.454345) (xy 125.016125 -225.417707) (xy 124.985669 -225.375788)
			(xy 124.962146 -225.329621) (xy 124.946134 -225.280342) (xy 124.938028 -225.229165) (xy 124.93752 -225.203258)
			(xy 124.938127 -225.175541) (xy 124.947442 -225.120895) (xy 124.956062 -225.094546) (xy 124.963936 -225.072448)
			(xy 124.758958 -224.71761) (xy 124.736098 -224.713292) (xy 124.711285 -224.708145) (xy 124.663543 -224.691153)
			(xy 124.618963 -224.667056) (xy 124.578596 -224.63642) (xy 124.543393 -224.599968) (xy 124.514182 -224.558558)
			(xy 124.491652 -224.513166) (xy 124.476334 -224.46486) (xy 124.468588 -224.41478) (xy 124.468128 -224.389442)
			(xy 124.187204 -224.389442) (xy 124.186696 -224.415329) (xy 124.178597 -224.466467) (xy 124.162598 -224.515707)
			(xy 124.139092 -224.561839) (xy 124.10866 -224.603726) (xy 124.07205 -224.640336) (xy 124.030163 -224.670768)
			(xy 123.984031 -224.694274) (xy 123.934791 -224.710273) (xy 123.883653 -224.718372) (xy 123.831879 -224.718372)
			(xy 123.780741 -224.710273) (xy 123.731501 -224.694274) (xy 123.685369 -224.670768) (xy 123.643482 -224.640336)
			(xy 123.606872 -224.603726) (xy 123.57644 -224.561839) (xy 123.552934 -224.515707) (xy 123.536935 -224.466467)
			(xy 123.528836 -224.415329) (xy 123.528328 -224.389442) (xy 123.247404 -224.389442) (xy 123.24686 -224.417149)
			(xy 123.237674 -224.471796) (xy 123.229116 -224.498154) (xy 123.221242 -224.520252) (xy 123.42622 -224.87509)
			(xy 123.44908 -224.879408) (xy 123.473909 -224.884542) (xy 123.521688 -224.901501) (xy 123.566308 -224.925578)
			(xy 123.606714 -224.956202) (xy 123.641954 -224.992654) (xy 123.671197 -225.034071) (xy 123.693752 -225.079478)
			(xy 123.709088 -225.127804) (xy 123.716843 -225.177908) (xy 123.717304 -225.203258) (xy 123.716796 -225.229165)
			(xy 123.70869 -225.280342) (xy 123.692678 -225.329621) (xy 123.669155 -225.375788) (xy 123.638699 -225.417707)
			(xy 123.602061 -225.454345) (xy 123.560142 -225.484801) (xy 123.513975 -225.508324) (xy 123.464696 -225.524336)
			(xy 123.413519 -225.532442) (xy 123.361705 -225.532442) (xy 123.310528 -225.524336) (xy 123.261249 -225.508324)
			(xy 123.215082 -225.484801) (xy 123.173163 -225.454345) (xy 123.136525 -225.417707) (xy 123.106069 -225.375788)
			(xy 123.082546 -225.329621) (xy 123.066534 -225.280342) (xy 123.058428 -225.229165) (xy 123.05792 -225.203258)
			(xy 123.058527 -225.175541) (xy 123.067842 -225.120895) (xy 123.076462 -225.094546) (xy 123.084336 -225.072448)
			(xy 122.879358 -224.71761) (xy 122.856498 -224.713292) (xy 122.831685 -224.708145) (xy 122.783943 -224.691153)
			(xy 122.739363 -224.667056) (xy 122.698996 -224.63642) (xy 122.663793 -224.599968) (xy 122.634582 -224.558558)
			(xy 122.612052 -224.513166) (xy 122.596734 -224.46486) (xy 122.588988 -224.41478) (xy 122.588528 -224.389442)
			(xy 122.307604 -224.389442) (xy 122.307096 -224.415329) (xy 122.298997 -224.466467) (xy 122.282998 -224.515707)
			(xy 122.259492 -224.561839) (xy 122.22906 -224.603726) (xy 122.19245 -224.640336) (xy 122.150563 -224.670768)
			(xy 122.104431 -224.694274) (xy 122.055191 -224.710273) (xy 122.004053 -224.718372) (xy 121.952279 -224.718372)
			(xy 121.901141 -224.710273) (xy 121.851901 -224.694274) (xy 121.805769 -224.670768) (xy 121.763882 -224.640336)
			(xy 121.727272 -224.603726) (xy 121.69684 -224.561839) (xy 121.673334 -224.515707) (xy 121.657335 -224.466467)
			(xy 121.649236 -224.415329) (xy 121.648728 -224.389442) (xy 121.367804 -224.389442) (xy 121.36726 -224.417149)
			(xy 121.358074 -224.471796) (xy 121.349516 -224.498154) (xy 121.341642 -224.520252) (xy 121.54662 -224.87509)
			(xy 121.56948 -224.879408) (xy 121.594309 -224.884542) (xy 121.642088 -224.901501) (xy 121.686708 -224.925578)
			(xy 121.727114 -224.956202) (xy 121.762354 -224.992654) (xy 121.791597 -225.034071) (xy 121.814152 -225.079478)
			(xy 121.829488 -225.127804) (xy 121.837243 -225.177908) (xy 121.837704 -225.203258) (xy 121.837196 -225.229165)
			(xy 121.82909 -225.280342) (xy 121.813078 -225.329621) (xy 121.789555 -225.375788) (xy 121.759099 -225.417707)
			(xy 121.722461 -225.454345) (xy 121.680542 -225.484801) (xy 121.634375 -225.508324) (xy 121.585096 -225.524336)
			(xy 121.533919 -225.532442) (xy 121.482105 -225.532442) (xy 121.430928 -225.524336) (xy 121.381649 -225.508324)
			(xy 121.335482 -225.484801) (xy 121.293563 -225.454345) (xy 121.256925 -225.417707) (xy 121.226469 -225.375788)
			(xy 121.202946 -225.329621) (xy 121.186934 -225.280342) (xy 121.178828 -225.229165) (xy 121.17832 -225.203258)
			(xy 121.178927 -225.175541) (xy 121.188242 -225.120895) (xy 121.196862 -225.094546) (xy 121.204736 -225.072448)
			(xy 120.999758 -224.71761) (xy 120.976898 -224.713292) (xy 120.952085 -224.708145) (xy 120.904343 -224.691153)
			(xy 120.859763 -224.667056) (xy 120.819396 -224.63642) (xy 120.784193 -224.599968) (xy 120.754982 -224.558558)
			(xy 120.732452 -224.513166) (xy 120.717134 -224.46486) (xy 120.709388 -224.41478) (xy 120.708928 -224.389442)
			(xy 120.428004 -224.389442) (xy 120.427496 -224.415329) (xy 120.419397 -224.466467) (xy 120.403398 -224.515707)
			(xy 120.379892 -224.561839) (xy 120.34946 -224.603726) (xy 120.31285 -224.640336) (xy 120.270963 -224.670768)
			(xy 120.224831 -224.694274) (xy 120.175591 -224.710273) (xy 120.124453 -224.718372) (xy 120.072679 -224.718372)
			(xy 120.021541 -224.710273) (xy 119.972301 -224.694274) (xy 119.926169 -224.670768) (xy 119.884282 -224.640336)
			(xy 119.847672 -224.603726) (xy 119.81724 -224.561839) (xy 119.793734 -224.515707) (xy 119.777735 -224.466467)
			(xy 119.769636 -224.415329) (xy 119.769128 -224.389442) (xy 119.488204 -224.389442) (xy 119.48766 -224.417149)
			(xy 119.478474 -224.471796) (xy 119.469916 -224.498154) (xy 119.462042 -224.520252) (xy 119.66702 -224.87509)
			(xy 119.68988 -224.879408) (xy 119.714709 -224.884542) (xy 119.762488 -224.901501) (xy 119.807108 -224.925578)
			(xy 119.847514 -224.956202) (xy 119.882754 -224.992654) (xy 119.911997 -225.034071) (xy 119.934552 -225.079478)
			(xy 119.949888 -225.127804) (xy 119.957643 -225.177908) (xy 119.958104 -225.203258) (xy 119.957596 -225.229165)
			(xy 119.94949 -225.280342) (xy 119.933478 -225.329621) (xy 119.909955 -225.375788) (xy 119.879499 -225.417707)
			(xy 119.842861 -225.454345) (xy 119.800942 -225.484801) (xy 119.754775 -225.508324) (xy 119.705496 -225.524336)
			(xy 119.654319 -225.532442) (xy 119.602505 -225.532442) (xy 119.551328 -225.524336) (xy 119.502049 -225.508324)
			(xy 119.455882 -225.484801) (xy 119.413963 -225.454345) (xy 119.377325 -225.417707) (xy 119.346869 -225.375788)
			(xy 119.323346 -225.329621) (xy 119.307334 -225.280342) (xy 119.299228 -225.229165) (xy 119.29872 -225.203258)
			(xy 119.299327 -225.175541) (xy 119.308642 -225.120895) (xy 119.317262 -225.094546) (xy 119.325136 -225.072448)
			(xy 119.120158 -224.71761) (xy 119.097298 -224.713292) (xy 119.072485 -224.708145) (xy 119.024743 -224.691153)
			(xy 118.980163 -224.667056) (xy 118.939796 -224.63642) (xy 118.904593 -224.599968) (xy 118.875382 -224.558558)
			(xy 118.852852 -224.513166) (xy 118.837534 -224.46486) (xy 118.829788 -224.41478) (xy 118.829328 -224.389442)
			(xy 118.548404 -224.389442) (xy 118.547896 -224.415329) (xy 118.539797 -224.466467) (xy 118.523798 -224.515707)
			(xy 118.500292 -224.561839) (xy 118.46986 -224.603726) (xy 118.43325 -224.640336) (xy 118.391363 -224.670768)
			(xy 118.345231 -224.694274) (xy 118.295991 -224.710273) (xy 118.244853 -224.718372) (xy 118.193079 -224.718372)
			(xy 118.141941 -224.710273) (xy 118.092701 -224.694274) (xy 118.046569 -224.670768) (xy 118.004682 -224.640336)
			(xy 117.968072 -224.603726) (xy 117.93764 -224.561839) (xy 117.914134 -224.515707) (xy 117.898135 -224.466467)
			(xy 117.890036 -224.415329) (xy 117.889528 -224.389442) (xy 117.608604 -224.389442) (xy 117.60806 -224.417149)
			(xy 117.598874 -224.471796) (xy 117.590316 -224.498154) (xy 117.582442 -224.520252) (xy 117.78742 -224.87509)
			(xy 117.81028 -224.879408) (xy 117.835109 -224.884542) (xy 117.882888 -224.901501) (xy 117.927508 -224.925578)
			(xy 117.967914 -224.956202) (xy 118.003154 -224.992654) (xy 118.032397 -225.034071) (xy 118.054952 -225.079478)
			(xy 118.070288 -225.127804) (xy 118.078043 -225.177908) (xy 118.078504 -225.203258) (xy 118.077996 -225.229165)
			(xy 118.06989 -225.280342) (xy 118.053878 -225.329621) (xy 118.030355 -225.375788) (xy 117.999899 -225.417707)
			(xy 117.963261 -225.454345) (xy 117.921342 -225.484801) (xy 117.875175 -225.508324) (xy 117.825896 -225.524336)
			(xy 117.774719 -225.532442) (xy 117.722905 -225.532442) (xy 117.671728 -225.524336) (xy 117.622449 -225.508324)
			(xy 117.576282 -225.484801) (xy 117.534363 -225.454345) (xy 117.497725 -225.417707) (xy 117.467269 -225.375788)
			(xy 117.443746 -225.329621) (xy 117.427734 -225.280342) (xy 117.419628 -225.229165) (xy 117.41912 -225.203258)
			(xy 117.419727 -225.175541) (xy 117.429042 -225.120895) (xy 117.437662 -225.094546) (xy 117.445536 -225.072448)
			(xy 117.240558 -224.71761) (xy 117.217698 -224.713292) (xy 117.192885 -224.708145) (xy 117.145143 -224.691153)
			(xy 117.100563 -224.667056) (xy 117.060196 -224.63642) (xy 117.024993 -224.599968) (xy 116.995782 -224.558558)
			(xy 116.973252 -224.513166) (xy 116.957934 -224.46486) (xy 116.950188 -224.41478) (xy 116.949728 -224.389442)
			(xy 116.668804 -224.389442) (xy 116.668296 -224.415329) (xy 116.660197 -224.466467) (xy 116.644198 -224.515707)
			(xy 116.620692 -224.561839) (xy 116.59026 -224.603726) (xy 116.55365 -224.640336) (xy 116.511763 -224.670768)
			(xy 116.465631 -224.694274) (xy 116.416391 -224.710273) (xy 116.365253 -224.718372) (xy 116.313479 -224.718372)
			(xy 116.262341 -224.710273) (xy 116.213101 -224.694274) (xy 116.166969 -224.670768) (xy 116.125082 -224.640336)
			(xy 116.088472 -224.603726) (xy 116.05804 -224.561839) (xy 116.034534 -224.515707) (xy 116.018535 -224.466467)
			(xy 116.010436 -224.415329) (xy 116.009928 -224.389442) (xy 115.729004 -224.389442) (xy 115.72846 -224.417149)
			(xy 115.719274 -224.471796) (xy 115.710716 -224.498154) (xy 115.702842 -224.520252) (xy 115.90782 -224.87509)
			(xy 115.93068 -224.879408) (xy 115.955509 -224.884542) (xy 116.003288 -224.901501) (xy 116.047908 -224.925578)
			(xy 116.088314 -224.956202) (xy 116.123554 -224.992654) (xy 116.152797 -225.034071) (xy 116.175352 -225.079478)
			(xy 116.190688 -225.127804) (xy 116.198443 -225.177908) (xy 116.198904 -225.203258) (xy 116.198396 -225.229165)
			(xy 116.19029 -225.280342) (xy 116.174278 -225.329621) (xy 116.150755 -225.375788) (xy 116.120299 -225.417707)
			(xy 116.083661 -225.454345) (xy 116.041742 -225.484801) (xy 115.995575 -225.508324) (xy 115.946296 -225.524336)
			(xy 115.895119 -225.532442) (xy 115.843305 -225.532442) (xy 115.792128 -225.524336) (xy 115.742849 -225.508324)
			(xy 115.696682 -225.484801) (xy 115.654763 -225.454345) (xy 115.618125 -225.417707) (xy 115.587669 -225.375788)
			(xy 115.564146 -225.329621) (xy 115.548134 -225.280342) (xy 115.540028 -225.229165) (xy 115.53952 -225.203258)
			(xy 115.540127 -225.175541) (xy 115.549442 -225.120895) (xy 115.558062 -225.094546) (xy 115.565936 -225.072448)
			(xy 115.360958 -224.71761) (xy 115.338098 -224.713292) (xy 115.313285 -224.708145) (xy 115.265543 -224.691153)
			(xy 115.220963 -224.667056) (xy 115.180596 -224.63642) (xy 115.145393 -224.599968) (xy 115.116182 -224.558558)
			(xy 115.093652 -224.513166) (xy 115.078334 -224.46486) (xy 115.070588 -224.41478) (xy 115.070128 -224.389442)
			(xy 114.789204 -224.389442) (xy 114.788696 -224.415329) (xy 114.780597 -224.466467) (xy 114.764598 -224.515707)
			(xy 114.741092 -224.561839) (xy 114.71066 -224.603726) (xy 114.67405 -224.640336) (xy 114.632163 -224.670768)
			(xy 114.586031 -224.694274) (xy 114.536791 -224.710273) (xy 114.485653 -224.718372) (xy 114.433879 -224.718372)
			(xy 114.382741 -224.710273) (xy 114.333501 -224.694274) (xy 114.287369 -224.670768) (xy 114.245482 -224.640336)
			(xy 114.208872 -224.603726) (xy 114.17844 -224.561839) (xy 114.154934 -224.515707) (xy 114.138935 -224.466467)
			(xy 114.130836 -224.415329) (xy 114.130328 -224.389442) (xy 113.849404 -224.389442) (xy 113.84886 -224.417149)
			(xy 113.839674 -224.471796) (xy 113.831116 -224.498154) (xy 113.823242 -224.520252) (xy 114.02822 -224.87509)
			(xy 114.05108 -224.879408) (xy 114.075909 -224.884542) (xy 114.123688 -224.901501) (xy 114.168308 -224.925578)
			(xy 114.208714 -224.956202) (xy 114.243954 -224.992654) (xy 114.273197 -225.034071) (xy 114.295752 -225.079478)
			(xy 114.311088 -225.127804) (xy 114.318843 -225.177908) (xy 114.319304 -225.203258) (xy 114.318796 -225.229165)
			(xy 114.31069 -225.280342) (xy 114.294678 -225.329621) (xy 114.271155 -225.375788) (xy 114.240699 -225.417707)
			(xy 114.204061 -225.454345) (xy 114.162142 -225.484801) (xy 114.115975 -225.508324) (xy 114.066696 -225.524336)
			(xy 114.015519 -225.532442) (xy 113.963705 -225.532442) (xy 113.912528 -225.524336) (xy 113.863249 -225.508324)
			(xy 113.817082 -225.484801) (xy 113.775163 -225.454345) (xy 113.738525 -225.417707) (xy 113.708069 -225.375788)
			(xy 113.684546 -225.329621) (xy 113.668534 -225.280342) (xy 113.660428 -225.229165) (xy 113.65992 -225.203258)
			(xy 113.660527 -225.175541) (xy 113.669842 -225.120895) (xy 113.678462 -225.094546) (xy 113.686336 -225.072448)
			(xy 113.481358 -224.71761) (xy 113.458498 -224.713292) (xy 113.433685 -224.708145) (xy 113.385943 -224.691153)
			(xy 113.341363 -224.667056) (xy 113.300996 -224.63642) (xy 113.265793 -224.599968) (xy 113.236582 -224.558558)
			(xy 113.214052 -224.513166) (xy 113.198734 -224.46486) (xy 113.190988 -224.41478) (xy 113.190528 -224.389442)
			(xy 112.909604 -224.389442) (xy 112.909096 -224.415329) (xy 112.900997 -224.466467) (xy 112.884998 -224.515707)
			(xy 112.861492 -224.561839) (xy 112.83106 -224.603726) (xy 112.79445 -224.640336) (xy 112.752563 -224.670768)
			(xy 112.706431 -224.694274) (xy 112.657191 -224.710273) (xy 112.606053 -224.718372) (xy 112.554279 -224.718372)
			(xy 112.503141 -224.710273) (xy 112.453901 -224.694274) (xy 112.407769 -224.670768) (xy 112.365882 -224.640336)
			(xy 112.329272 -224.603726) (xy 112.29884 -224.561839) (xy 112.275334 -224.515707) (xy 112.259335 -224.466467)
			(xy 112.251236 -224.415329) (xy 112.250728 -224.389442) (xy 111.969804 -224.389442) (xy 111.96926 -224.417149)
			(xy 111.960074 -224.471796) (xy 111.951516 -224.498154) (xy 111.943642 -224.520252) (xy 112.14862 -224.87509)
			(xy 112.17148 -224.879408) (xy 112.196309 -224.884542) (xy 112.244088 -224.901501) (xy 112.288708 -224.925578)
			(xy 112.329114 -224.956202) (xy 112.364354 -224.992654) (xy 112.393597 -225.034071) (xy 112.416152 -225.079478)
			(xy 112.431488 -225.127804) (xy 112.439243 -225.177908) (xy 112.439704 -225.203258) (xy 112.439196 -225.229165)
			(xy 112.43109 -225.280342) (xy 112.415078 -225.329621) (xy 112.391555 -225.375788) (xy 112.361099 -225.417707)
			(xy 112.324461 -225.454345) (xy 112.282542 -225.484801) (xy 112.236375 -225.508324) (xy 112.187096 -225.524336)
			(xy 112.135919 -225.532442) (xy 112.084105 -225.532442) (xy 112.032928 -225.524336) (xy 111.983649 -225.508324)
			(xy 111.937482 -225.484801) (xy 111.895563 -225.454345) (xy 111.858925 -225.417707) (xy 111.828469 -225.375788)
			(xy 111.804946 -225.329621) (xy 111.788934 -225.280342) (xy 111.780828 -225.229165) (xy 111.78032 -225.203258)
			(xy 111.780927 -225.175541) (xy 111.790242 -225.120895) (xy 111.798862 -225.094546) (xy 111.806736 -225.072448)
			(xy 111.601758 -224.71761) (xy 111.578898 -224.713292) (xy 111.554085 -224.708145) (xy 111.506343 -224.691153)
			(xy 111.461763 -224.667056) (xy 111.421396 -224.63642) (xy 111.386193 -224.599968) (xy 111.356982 -224.558558)
			(xy 111.334452 -224.513166) (xy 111.319134 -224.46486) (xy 111.311388 -224.41478) (xy 111.310928 -224.389442)
			(xy 111.030004 -224.389442) (xy 111.029496 -224.415329) (xy 111.021397 -224.466467) (xy 111.005398 -224.515707)
			(xy 110.981892 -224.561839) (xy 110.95146 -224.603726) (xy 110.91485 -224.640336) (xy 110.872963 -224.670768)
			(xy 110.826831 -224.694274) (xy 110.777591 -224.710273) (xy 110.726453 -224.718372) (xy 110.674679 -224.718372)
			(xy 110.623541 -224.710273) (xy 110.574301 -224.694274) (xy 110.528169 -224.670768) (xy 110.486282 -224.640336)
			(xy 110.449672 -224.603726) (xy 110.41924 -224.561839) (xy 110.395734 -224.515707) (xy 110.379735 -224.466467)
			(xy 110.371636 -224.415329) (xy 110.371128 -224.389442) (xy 110.090204 -224.389442) (xy 110.08966 -224.417149)
			(xy 110.080474 -224.471796) (xy 110.071916 -224.498154) (xy 110.064042 -224.520252) (xy 110.26902 -224.87509)
			(xy 110.29188 -224.879408) (xy 110.316709 -224.884542) (xy 110.364488 -224.901501) (xy 110.409108 -224.925578)
			(xy 110.449514 -224.956202) (xy 110.484754 -224.992654) (xy 110.513997 -225.034071) (xy 110.536552 -225.079478)
			(xy 110.551888 -225.127804) (xy 110.559643 -225.177908) (xy 110.560104 -225.203258) (xy 110.559596 -225.229165)
			(xy 110.55149 -225.280342) (xy 110.535478 -225.329621) (xy 110.511955 -225.375788) (xy 110.481499 -225.417707)
			(xy 110.444861 -225.454345) (xy 110.402942 -225.484801) (xy 110.356775 -225.508324) (xy 110.307496 -225.524336)
			(xy 110.256319 -225.532442) (xy 110.204505 -225.532442) (xy 110.153328 -225.524336) (xy 110.104049 -225.508324)
			(xy 110.057882 -225.484801) (xy 110.015963 -225.454345) (xy 109.979325 -225.417707) (xy 109.948869 -225.375788)
			(xy 109.925346 -225.329621) (xy 109.909334 -225.280342) (xy 109.901228 -225.229165) (xy 109.90072 -225.203258)
			(xy 109.901327 -225.175541) (xy 109.910642 -225.120895) (xy 109.919262 -225.094546) (xy 109.927136 -225.072448)
			(xy 109.722158 -224.71761) (xy 109.699298 -224.713292) (xy 109.674485 -224.708145) (xy 109.626743 -224.691153)
			(xy 109.582163 -224.667056) (xy 109.541796 -224.63642) (xy 109.506593 -224.599968) (xy 109.477382 -224.558558)
			(xy 109.454852 -224.513166) (xy 109.439534 -224.46486) (xy 109.431788 -224.41478) (xy 109.431328 -224.389442)
			(xy 109.150404 -224.389442) (xy 109.149896 -224.415329) (xy 109.141797 -224.466467) (xy 109.125798 -224.515707)
			(xy 109.102292 -224.561839) (xy 109.07186 -224.603726) (xy 109.03525 -224.640336) (xy 108.993363 -224.670768)
			(xy 108.947231 -224.694274) (xy 108.897991 -224.710273) (xy 108.846853 -224.718372) (xy 108.795079 -224.718372)
			(xy 108.743941 -224.710273) (xy 108.694701 -224.694274) (xy 108.648569 -224.670768) (xy 108.606682 -224.640336)
			(xy 108.570072 -224.603726) (xy 108.53964 -224.561839) (xy 108.516134 -224.515707) (xy 108.500135 -224.466467)
			(xy 108.492036 -224.415329) (xy 108.491528 -224.389442) (xy 108.210604 -224.389442) (xy 108.21006 -224.417149)
			(xy 108.200874 -224.471796) (xy 108.192316 -224.498154) (xy 108.184442 -224.520252) (xy 108.38942 -224.87509)
			(xy 108.41228 -224.879408) (xy 108.437109 -224.884542) (xy 108.484888 -224.901501) (xy 108.529508 -224.925578)
			(xy 108.569914 -224.956202) (xy 108.605154 -224.992654) (xy 108.634397 -225.034071) (xy 108.656952 -225.079478)
			(xy 108.672288 -225.127804) (xy 108.680043 -225.177908) (xy 108.680504 -225.203258) (xy 108.679996 -225.229165)
			(xy 108.67189 -225.280342) (xy 108.655878 -225.329621) (xy 108.632355 -225.375788) (xy 108.601899 -225.417707)
			(xy 108.565261 -225.454345) (xy 108.523342 -225.484801) (xy 108.477175 -225.508324) (xy 108.427896 -225.524336)
			(xy 108.376719 -225.532442) (xy 108.324905 -225.532442) (xy 108.273728 -225.524336) (xy 108.224449 -225.508324)
			(xy 108.178282 -225.484801) (xy 108.136363 -225.454345) (xy 108.099725 -225.417707) (xy 108.069269 -225.375788)
			(xy 108.045746 -225.329621) (xy 108.029734 -225.280342) (xy 108.021628 -225.229165) (xy 108.02112 -225.203258)
			(xy 108.021727 -225.175541) (xy 108.031042 -225.120895) (xy 108.039662 -225.094546) (xy 108.047536 -225.072448)
			(xy 107.842558 -224.71761) (xy 107.819698 -224.713292) (xy 107.794885 -224.708145) (xy 107.747143 -224.691153)
			(xy 107.702563 -224.667056) (xy 107.662196 -224.63642) (xy 107.626993 -224.599968) (xy 107.597782 -224.558558)
			(xy 107.575252 -224.513166) (xy 107.559934 -224.46486) (xy 107.552188 -224.41478) (xy 107.551728 -224.389442)
			(xy 107.270804 -224.389442) (xy 107.270296 -224.415329) (xy 107.262197 -224.466467) (xy 107.246198 -224.515707)
			(xy 107.222692 -224.561839) (xy 107.19226 -224.603726) (xy 107.15565 -224.640336) (xy 107.113763 -224.670768)
			(xy 107.067631 -224.694274) (xy 107.018391 -224.710273) (xy 106.967253 -224.718372) (xy 106.915479 -224.718372)
			(xy 106.864341 -224.710273) (xy 106.815101 -224.694274) (xy 106.768969 -224.670768) (xy 106.727082 -224.640336)
			(xy 106.690472 -224.603726) (xy 106.66004 -224.561839) (xy 106.636534 -224.515707) (xy 106.620535 -224.466467)
			(xy 106.612436 -224.415329) (xy 106.611928 -224.389442) (xy 106.331004 -224.389442) (xy 106.33046 -224.417149)
			(xy 106.321274 -224.471796) (xy 106.312716 -224.498154) (xy 106.304842 -224.520252) (xy 106.50982 -224.87509)
			(xy 106.53268 -224.879408) (xy 106.557509 -224.884542) (xy 106.605288 -224.901501) (xy 106.649908 -224.925578)
			(xy 106.690314 -224.956202) (xy 106.725554 -224.992654) (xy 106.754797 -225.034071) (xy 106.777352 -225.079478)
			(xy 106.792688 -225.127804) (xy 106.800443 -225.177908) (xy 106.800904 -225.203258) (xy 106.800396 -225.229165)
			(xy 106.79229 -225.280342) (xy 106.776278 -225.329621) (xy 106.752755 -225.375788) (xy 106.722299 -225.417707)
			(xy 106.685661 -225.454345) (xy 106.643742 -225.484801) (xy 106.597575 -225.508324) (xy 106.548296 -225.524336)
			(xy 106.497119 -225.532442) (xy 106.445305 -225.532442) (xy 106.394128 -225.524336) (xy 106.344849 -225.508324)
			(xy 106.298682 -225.484801) (xy 106.256763 -225.454345) (xy 106.220125 -225.417707) (xy 106.189669 -225.375788)
			(xy 106.166146 -225.329621) (xy 106.150134 -225.280342) (xy 106.142028 -225.229165) (xy 106.14152 -225.203258)
			(xy 106.142127 -225.175541) (xy 106.151442 -225.120895) (xy 106.160062 -225.094546) (xy 106.167936 -225.072448)
			(xy 105.962958 -224.71761) (xy 105.940098 -224.713292) (xy 105.915285 -224.708145) (xy 105.867543 -224.691153)
			(xy 105.822963 -224.667056) (xy 105.782596 -224.63642) (xy 105.747393 -224.599968) (xy 105.718182 -224.558558)
			(xy 105.695652 -224.513166) (xy 105.680334 -224.46486) (xy 105.672588 -224.41478) (xy 105.672128 -224.389442)
			(xy 105.391204 -224.389442) (xy 105.390696 -224.415329) (xy 105.382597 -224.466467) (xy 105.366598 -224.515707)
			(xy 105.343092 -224.561839) (xy 105.31266 -224.603726) (xy 105.27605 -224.640336) (xy 105.234163 -224.670768)
			(xy 105.188031 -224.694274) (xy 105.138791 -224.710273) (xy 105.087653 -224.718372) (xy 105.035879 -224.718372)
			(xy 104.984741 -224.710273) (xy 104.935501 -224.694274) (xy 104.889369 -224.670768) (xy 104.847482 -224.640336)
			(xy 104.810872 -224.603726) (xy 104.78044 -224.561839) (xy 104.756934 -224.515707) (xy 104.740935 -224.466467)
			(xy 104.732836 -224.415329) (xy 104.732328 -224.389442) (xy 104.451404 -224.389442) (xy 104.45086 -224.417149)
			(xy 104.441674 -224.471796) (xy 104.433116 -224.498154) (xy 104.425242 -224.520252) (xy 104.63022 -224.87509)
			(xy 104.65308 -224.879408) (xy 104.677909 -224.884542) (xy 104.725688 -224.901501) (xy 104.770308 -224.925578)
			(xy 104.810714 -224.956202) (xy 104.845954 -224.992654) (xy 104.875197 -225.034071) (xy 104.897752 -225.079478)
			(xy 104.913088 -225.127804) (xy 104.920843 -225.177908) (xy 104.921304 -225.203258) (xy 104.920796 -225.229165)
			(xy 104.91269 -225.280342) (xy 104.896678 -225.329621) (xy 104.873155 -225.375788) (xy 104.842699 -225.417707)
			(xy 104.806061 -225.454345) (xy 104.764142 -225.484801) (xy 104.717975 -225.508324) (xy 104.668696 -225.524336)
			(xy 104.617519 -225.532442) (xy 104.565705 -225.532442) (xy 104.514528 -225.524336) (xy 104.465249 -225.508324)
			(xy 104.419082 -225.484801) (xy 104.377163 -225.454345) (xy 104.340525 -225.417707) (xy 104.310069 -225.375788)
			(xy 104.286546 -225.329621) (xy 104.270534 -225.280342) (xy 104.262428 -225.229165) (xy 104.26192 -225.203258)
			(xy 104.262527 -225.175541) (xy 104.271842 -225.120895) (xy 104.280462 -225.094546) (xy 104.288336 -225.072448)
			(xy 104.083358 -224.71761) (xy 104.060498 -224.713292) (xy 104.035685 -224.708145) (xy 103.987943 -224.691153)
			(xy 103.943363 -224.667056) (xy 103.902996 -224.63642) (xy 103.867793 -224.599968) (xy 103.838582 -224.558558)
			(xy 103.816052 -224.513166) (xy 103.800734 -224.46486) (xy 103.792988 -224.41478) (xy 103.792528 -224.389442)
			(xy 103.511604 -224.389442) (xy 103.511096 -224.415329) (xy 103.502997 -224.466467) (xy 103.486998 -224.515707)
			(xy 103.463492 -224.561839) (xy 103.43306 -224.603726) (xy 103.39645 -224.640336) (xy 103.354563 -224.670768)
			(xy 103.308431 -224.694274) (xy 103.259191 -224.710273) (xy 103.208053 -224.718372) (xy 103.156279 -224.718372)
			(xy 103.105141 -224.710273) (xy 103.055901 -224.694274) (xy 103.009769 -224.670768) (xy 102.967882 -224.640336)
			(xy 102.931272 -224.603726) (xy 102.90084 -224.561839) (xy 102.877334 -224.515707) (xy 102.861335 -224.466467)
			(xy 102.853236 -224.415329) (xy 102.852728 -224.389442) (xy 102.571804 -224.389442) (xy 102.57126 -224.417149)
			(xy 102.562074 -224.471796) (xy 102.553516 -224.498154) (xy 102.545642 -224.520252) (xy 102.75062 -224.87509)
			(xy 102.77348 -224.879408) (xy 102.798309 -224.884542) (xy 102.846088 -224.901501) (xy 102.890708 -224.925578)
			(xy 102.931114 -224.956202) (xy 102.966354 -224.992654) (xy 102.995597 -225.034071) (xy 103.018152 -225.079478)
			(xy 103.033488 -225.127804) (xy 103.041243 -225.177908) (xy 103.041704 -225.203258) (xy 103.041196 -225.229165)
			(xy 103.03309 -225.280342) (xy 103.017078 -225.329621) (xy 102.993555 -225.375788) (xy 102.963099 -225.417707)
			(xy 102.926461 -225.454345) (xy 102.884542 -225.484801) (xy 102.838375 -225.508324) (xy 102.789096 -225.524336)
			(xy 102.737919 -225.532442) (xy 102.686105 -225.532442) (xy 102.634928 -225.524336) (xy 102.585649 -225.508324)
			(xy 102.539482 -225.484801) (xy 102.497563 -225.454345) (xy 102.460925 -225.417707) (xy 102.430469 -225.375788)
			(xy 102.406946 -225.329621) (xy 102.390934 -225.280342) (xy 102.382828 -225.229165) (xy 102.38232 -225.203258)
			(xy 102.382927 -225.175541) (xy 102.392242 -225.120895) (xy 102.400862 -225.094546) (xy 102.408736 -225.072448)
			(xy 102.203758 -224.71761) (xy 102.180898 -224.713292) (xy 102.156085 -224.708145) (xy 102.108343 -224.691153)
			(xy 102.063763 -224.667056) (xy 102.023396 -224.63642) (xy 101.988193 -224.599968) (xy 101.958982 -224.558558)
			(xy 101.936452 -224.513166) (xy 101.921134 -224.46486) (xy 101.913388 -224.41478) (xy 101.912928 -224.389442)
			(xy 101.632004 -224.389442) (xy 101.631496 -224.415329) (xy 101.623397 -224.466467) (xy 101.607398 -224.515707)
			(xy 101.583892 -224.561839) (xy 101.55346 -224.603726) (xy 101.51685 -224.640336) (xy 101.474963 -224.670768)
			(xy 101.428831 -224.694274) (xy 101.379591 -224.710273) (xy 101.328453 -224.718372) (xy 101.276679 -224.718372)
			(xy 101.225541 -224.710273) (xy 101.176301 -224.694274) (xy 101.130169 -224.670768) (xy 101.088282 -224.640336)
			(xy 101.051672 -224.603726) (xy 101.02124 -224.561839) (xy 100.997734 -224.515707) (xy 100.981735 -224.466467)
			(xy 100.973636 -224.415329) (xy 100.973128 -224.389442) (xy 100.692204 -224.389442) (xy 100.69166 -224.417149)
			(xy 100.682474 -224.471796) (xy 100.673916 -224.498154) (xy 100.666042 -224.520252) (xy 100.87102 -224.87509)
			(xy 100.89388 -224.879408) (xy 100.918709 -224.884542) (xy 100.966488 -224.901501) (xy 101.011108 -224.925578)
			(xy 101.051514 -224.956202) (xy 101.086754 -224.992654) (xy 101.115997 -225.034071) (xy 101.138552 -225.079478)
			(xy 101.153888 -225.127804) (xy 101.161643 -225.177908) (xy 101.162104 -225.203258) (xy 101.161596 -225.229165)
			(xy 101.15349 -225.280342) (xy 101.137478 -225.329621) (xy 101.113955 -225.375788) (xy 101.083499 -225.417707)
			(xy 101.046861 -225.454345) (xy 101.004942 -225.484801) (xy 100.958775 -225.508324) (xy 100.909496 -225.524336)
			(xy 100.858319 -225.532442) (xy 100.806505 -225.532442) (xy 100.755328 -225.524336) (xy 100.706049 -225.508324)
			(xy 100.659882 -225.484801) (xy 100.617963 -225.454345) (xy 100.581325 -225.417707) (xy 100.550869 -225.375788)
			(xy 100.527346 -225.329621) (xy 100.511334 -225.280342) (xy 100.503228 -225.229165) (xy 100.50272 -225.203258)
			(xy 100.503327 -225.175541) (xy 100.512642 -225.120895) (xy 100.521262 -225.094546) (xy 100.529136 -225.072448)
			(xy 100.324158 -224.71761) (xy 100.301298 -224.713292) (xy 100.276485 -224.708145) (xy 100.228743 -224.691153)
			(xy 100.184163 -224.667056) (xy 100.143796 -224.63642) (xy 100.108593 -224.599968) (xy 100.079382 -224.558558)
			(xy 100.056852 -224.513166) (xy 100.041534 -224.46486) (xy 100.033788 -224.41478) (xy 100.033328 -224.389442)
			(xy 99.752404 -224.389442) (xy 99.751896 -224.415329) (xy 99.743797 -224.466467) (xy 99.727798 -224.515707)
			(xy 99.704292 -224.561839) (xy 99.67386 -224.603726) (xy 99.63725 -224.640336) (xy 99.595363 -224.670768)
			(xy 99.549231 -224.694274) (xy 99.499991 -224.710273) (xy 99.448853 -224.718372) (xy 99.397079 -224.718372)
			(xy 99.345941 -224.710273) (xy 99.296701 -224.694274) (xy 99.250569 -224.670768) (xy 99.208682 -224.640336)
			(xy 99.172072 -224.603726) (xy 99.14164 -224.561839) (xy 99.118134 -224.515707) (xy 99.102135 -224.466467)
			(xy 99.094036 -224.415329) (xy 99.093528 -224.389442) (xy 98.812604 -224.389442) (xy 98.81206 -224.417149)
			(xy 98.802874 -224.471796) (xy 98.794316 -224.498154) (xy 98.786442 -224.520252) (xy 98.99142 -224.87509)
			(xy 99.01428 -224.879408) (xy 99.039109 -224.884542) (xy 99.086888 -224.901501) (xy 99.131508 -224.925578)
			(xy 99.171914 -224.956202) (xy 99.207154 -224.992654) (xy 99.236397 -225.034071) (xy 99.258952 -225.079478)
			(xy 99.274288 -225.127804) (xy 99.282043 -225.177908) (xy 99.282504 -225.203258) (xy 99.281996 -225.229165)
			(xy 99.27389 -225.280342) (xy 99.257878 -225.329621) (xy 99.234355 -225.375788) (xy 99.203899 -225.417707)
			(xy 99.167261 -225.454345) (xy 99.125342 -225.484801) (xy 99.079175 -225.508324) (xy 99.029896 -225.524336)
			(xy 98.978719 -225.532442) (xy 98.926905 -225.532442) (xy 98.875728 -225.524336) (xy 98.826449 -225.508324)
			(xy 98.780282 -225.484801) (xy 98.738363 -225.454345) (xy 98.701725 -225.417707) (xy 98.671269 -225.375788)
			(xy 98.647746 -225.329621) (xy 98.631734 -225.280342) (xy 98.623628 -225.229165) (xy 98.62312 -225.203258)
			(xy 98.623727 -225.175541) (xy 98.633042 -225.120895) (xy 98.641662 -225.094546) (xy 98.649536 -225.072448)
			(xy 98.444558 -224.71761) (xy 98.421698 -224.713292) (xy 98.396885 -224.708145) (xy 98.349143 -224.691153)
			(xy 98.304563 -224.667056) (xy 98.264196 -224.63642) (xy 98.228993 -224.599968) (xy 98.199782 -224.558558)
			(xy 98.177252 -224.513166) (xy 98.161934 -224.46486) (xy 98.154188 -224.41478) (xy 98.153728 -224.389442)
			(xy 97.872804 -224.389442) (xy 97.872296 -224.415329) (xy 97.864197 -224.466467) (xy 97.848198 -224.515707)
			(xy 97.824692 -224.561839) (xy 97.79426 -224.603726) (xy 97.75765 -224.640336) (xy 97.715763 -224.670768)
			(xy 97.669631 -224.694274) (xy 97.620391 -224.710273) (xy 97.569253 -224.718372) (xy 97.517479 -224.718372)
			(xy 97.466341 -224.710273) (xy 97.417101 -224.694274) (xy 97.370969 -224.670768) (xy 97.329082 -224.640336)
			(xy 97.292472 -224.603726) (xy 97.26204 -224.561839) (xy 97.238534 -224.515707) (xy 97.222535 -224.466467)
			(xy 97.214436 -224.415329) (xy 97.213928 -224.389442) (xy 96.933004 -224.389442) (xy 96.93246 -224.417149)
			(xy 96.923274 -224.471796) (xy 96.914716 -224.498154) (xy 96.906842 -224.520252) (xy 97.11182 -224.87509)
			(xy 97.13468 -224.879408) (xy 97.159509 -224.884542) (xy 97.207288 -224.901501) (xy 97.251908 -224.925578)
			(xy 97.292314 -224.956202) (xy 97.327554 -224.992654) (xy 97.356797 -225.034071) (xy 97.379352 -225.079478)
			(xy 97.394688 -225.127804) (xy 97.402443 -225.177908) (xy 97.402904 -225.203258) (xy 97.402396 -225.229165)
			(xy 97.39429 -225.280342) (xy 97.378278 -225.329621) (xy 97.354755 -225.375788) (xy 97.324299 -225.417707)
			(xy 97.287661 -225.454345) (xy 97.245742 -225.484801) (xy 97.199575 -225.508324) (xy 97.150296 -225.524336)
			(xy 97.099119 -225.532442) (xy 97.047305 -225.532442) (xy 96.996128 -225.524336) (xy 96.946849 -225.508324)
			(xy 96.900682 -225.484801) (xy 96.858763 -225.454345) (xy 96.822125 -225.417707) (xy 96.791669 -225.375788)
			(xy 96.768146 -225.329621) (xy 96.752134 -225.280342) (xy 96.744028 -225.229165) (xy 96.74352 -225.203258)
			(xy 96.744127 -225.175541) (xy 96.753442 -225.120895) (xy 96.762062 -225.094546) (xy 96.769936 -225.072448)
			(xy 96.564958 -224.71761) (xy 96.542098 -224.713292) (xy 96.517285 -224.708145) (xy 96.469543 -224.691153)
			(xy 96.424963 -224.667056) (xy 96.384596 -224.63642) (xy 96.349393 -224.599968) (xy 96.320182 -224.558558)
			(xy 96.297652 -224.513166) (xy 96.282334 -224.46486) (xy 96.274588 -224.41478) (xy 96.274128 -224.389442)
			(xy 95.993204 -224.389442) (xy 95.992696 -224.415329) (xy 95.984597 -224.466467) (xy 95.968598 -224.515707)
			(xy 95.945092 -224.561839) (xy 95.91466 -224.603726) (xy 95.87805 -224.640336) (xy 95.836163 -224.670768)
			(xy 95.790031 -224.694274) (xy 95.740791 -224.710273) (xy 95.689653 -224.718372) (xy 95.637879 -224.718372)
			(xy 95.586741 -224.710273) (xy 95.537501 -224.694274) (xy 95.491369 -224.670768) (xy 95.449482 -224.640336)
			(xy 95.412872 -224.603726) (xy 95.38244 -224.561839) (xy 95.358934 -224.515707) (xy 95.342935 -224.466467)
			(xy 95.334836 -224.415329) (xy 95.334328 -224.389442) (xy 95.053404 -224.389442) (xy 95.05286 -224.417149)
			(xy 95.043674 -224.471796) (xy 95.035116 -224.498154) (xy 95.027242 -224.520252) (xy 95.23222 -224.87509)
			(xy 95.25508 -224.879408) (xy 95.279909 -224.884542) (xy 95.327688 -224.901501) (xy 95.372308 -224.925578)
			(xy 95.412714 -224.956202) (xy 95.447954 -224.992654) (xy 95.477197 -225.034071) (xy 95.499752 -225.079478)
			(xy 95.515088 -225.127804) (xy 95.522843 -225.177908) (xy 95.523304 -225.203258) (xy 95.522796 -225.229165)
			(xy 95.51469 -225.280342) (xy 95.498678 -225.329621) (xy 95.475155 -225.375788) (xy 95.444699 -225.417707)
			(xy 95.408061 -225.454345) (xy 95.366142 -225.484801) (xy 95.319975 -225.508324) (xy 95.270696 -225.524336)
			(xy 95.219519 -225.532442) (xy 95.167705 -225.532442) (xy 95.116528 -225.524336) (xy 95.067249 -225.508324)
			(xy 95.021082 -225.484801) (xy 94.979163 -225.454345) (xy 94.942525 -225.417707) (xy 94.912069 -225.375788)
			(xy 94.888546 -225.329621) (xy 94.872534 -225.280342) (xy 94.864428 -225.229165) (xy 94.86392 -225.203258)
			(xy 94.864527 -225.175541) (xy 94.873842 -225.120895) (xy 94.882462 -225.094546) (xy 94.890336 -225.072448)
			(xy 94.685358 -224.71761) (xy 94.662498 -224.713292) (xy 94.637685 -224.708145) (xy 94.589943 -224.691153)
			(xy 94.545363 -224.667056) (xy 94.504996 -224.63642) (xy 94.469793 -224.599968) (xy 94.440582 -224.558558)
			(xy 94.418052 -224.513166) (xy 94.402734 -224.46486) (xy 94.394988 -224.41478) (xy 94.394528 -224.389442)
			(xy 94.113604 -224.389442) (xy 94.113096 -224.415329) (xy 94.104997 -224.466467) (xy 94.088998 -224.515707)
			(xy 94.065492 -224.561839) (xy 94.03506 -224.603726) (xy 93.99845 -224.640336) (xy 93.956563 -224.670768)
			(xy 93.910431 -224.694274) (xy 93.861191 -224.710273) (xy 93.810053 -224.718372) (xy 93.758279 -224.718372)
			(xy 93.707141 -224.710273) (xy 93.657901 -224.694274) (xy 93.611769 -224.670768) (xy 93.569882 -224.640336)
			(xy 93.533272 -224.603726) (xy 93.50284 -224.561839) (xy 93.479334 -224.515707) (xy 93.463335 -224.466467)
			(xy 93.455236 -224.415329) (xy 93.454728 -224.389442) (xy 93.173804 -224.389442) (xy 93.173804 -224.38995)
			(xy 93.173247 -224.417593) (xy 93.164056 -224.472111) (xy 93.155516 -224.498408) (xy 93.147896 -224.520252)
			(xy 93.35262 -224.87509) (xy 93.37548 -224.879408) (xy 93.400309 -224.884542) (xy 93.448088 -224.901501)
			(xy 93.492708 -224.925578) (xy 93.533114 -224.956202) (xy 93.568354 -224.992654) (xy 93.597597 -225.034071)
			(xy 93.620152 -225.079478) (xy 93.635488 -225.127804) (xy 93.643243 -225.177908) (xy 93.643704 -225.203258)
			(xy 93.643196 -225.229165) (xy 93.63509 -225.280342) (xy 93.619078 -225.329621) (xy 93.595555 -225.375788)
			(xy 93.565099 -225.417707) (xy 93.528461 -225.454345) (xy 93.486542 -225.484801) (xy 93.440375 -225.508324)
			(xy 93.391096 -225.524336) (xy 93.339919 -225.532442) (xy 93.288105 -225.532442) (xy 93.236928 -225.524336)
			(xy 93.187649 -225.508324) (xy 93.141482 -225.484801) (xy 93.099563 -225.454345) (xy 93.062925 -225.417707)
			(xy 93.032469 -225.375788) (xy 93.008946 -225.329621) (xy 92.992934 -225.280342) (xy 92.984828 -225.229165)
			(xy 92.98432 -225.203258) (xy 92.98432 -225.20275) (xy 92.98493 -225.175096) (xy 92.994253 -225.120579)
			(xy 93.002862 -225.094292) (xy 93.010482 -225.072448) (xy 92.805758 -224.71761) (xy 92.782898 -224.713292)
			(xy 92.758085 -224.708145) (xy 92.710343 -224.691153) (xy 92.665763 -224.667056) (xy 92.625396 -224.63642)
			(xy 92.590193 -224.599968) (xy 92.560982 -224.558558) (xy 92.538452 -224.513166) (xy 92.523134 -224.46486)
			(xy 92.515388 -224.41478) (xy 92.514928 -224.389442) (xy 92.234004 -224.389442) (xy 92.233496 -224.415329)
			(xy 92.225397 -224.466467) (xy 92.209398 -224.515707) (xy 92.185892 -224.561839) (xy 92.15546 -224.603726)
			(xy 92.11885 -224.640336) (xy 92.076963 -224.670768) (xy 92.030831 -224.694274) (xy 91.981591 -224.710273)
			(xy 91.930453 -224.718372) (xy 91.878679 -224.718372) (xy 91.827541 -224.710273) (xy 91.778301 -224.694274)
			(xy 91.732169 -224.670768) (xy 91.690282 -224.640336) (xy 91.653672 -224.603726) (xy 91.62324 -224.561839)
			(xy 91.599734 -224.515707) (xy 91.583735 -224.466467) (xy 91.575636 -224.415329) (xy 91.575128 -224.389442)
			(xy 91.294204 -224.389442) (xy 91.294204 -224.38995) (xy 91.293647 -224.417593) (xy 91.284456 -224.472111)
			(xy 91.275916 -224.498408) (xy 91.268296 -224.520252) (xy 91.47302 -224.87509) (xy 91.49588 -224.879408)
			(xy 91.520709 -224.884542) (xy 91.568488 -224.901501) (xy 91.613108 -224.925578) (xy 91.653514 -224.956202)
			(xy 91.688754 -224.992654) (xy 91.717997 -225.034071) (xy 91.740552 -225.079478) (xy 91.755888 -225.127804)
			(xy 91.763643 -225.177908) (xy 91.764104 -225.203258) (xy 91.763596 -225.229165) (xy 91.75549 -225.280342)
			(xy 91.739478 -225.329621) (xy 91.715955 -225.375788) (xy 91.685499 -225.417707) (xy 91.648861 -225.454345)
			(xy 91.606942 -225.484801) (xy 91.560775 -225.508324) (xy 91.511496 -225.524336) (xy 91.460319 -225.532442)
			(xy 91.408505 -225.532442) (xy 91.357328 -225.524336) (xy 91.308049 -225.508324) (xy 91.261882 -225.484801)
			(xy 91.219963 -225.454345) (xy 91.183325 -225.417707) (xy 91.152869 -225.375788) (xy 91.129346 -225.329621)
			(xy 91.113334 -225.280342) (xy 91.105228 -225.229165) (xy 91.10472 -225.203258) (xy 91.10472 -225.20275)
			(xy 91.10533 -225.175096) (xy 91.114653 -225.120579) (xy 91.123262 -225.094292) (xy 91.130882 -225.072448)
			(xy 90.926158 -224.71761) (xy 90.903298 -224.713292) (xy 90.878485 -224.708145) (xy 90.830743 -224.691153)
			(xy 90.786163 -224.667056) (xy 90.745796 -224.63642) (xy 90.710593 -224.599968) (xy 90.681382 -224.558558)
			(xy 90.658852 -224.513166) (xy 90.643534 -224.46486) (xy 90.635788 -224.41478) (xy 90.635328 -224.389442)
			(xy 90.354404 -224.389442) (xy 90.353896 -224.415329) (xy 90.345797 -224.466467) (xy 90.329798 -224.515707)
			(xy 90.306292 -224.561839) (xy 90.27586 -224.603726) (xy 90.23925 -224.640336) (xy 90.197363 -224.670768)
			(xy 90.151231 -224.694274) (xy 90.101991 -224.710273) (xy 90.050853 -224.718372) (xy 89.999079 -224.718372)
			(xy 89.947941 -224.710273) (xy 89.898701 -224.694274) (xy 89.852569 -224.670768) (xy 89.810682 -224.640336)
			(xy 89.774072 -224.603726) (xy 89.74364 -224.561839) (xy 89.720134 -224.515707) (xy 89.704135 -224.466467)
			(xy 89.696036 -224.415329) (xy 89.695528 -224.389442) (xy 2.509012 -224.389442) (xy 2.509012 -247.620536)
			(xy 228.175312 -247.620536) (xy 228.175312 -246.756936) (xy 228.175798 -246.729685) (xy 228.183554 -246.675737)
			(xy 228.198909 -246.623442) (xy 228.221551 -246.573865) (xy 228.251017 -246.528015) (xy 228.286708 -246.486824)
			(xy 228.327899 -246.451133) (xy 228.373749 -246.421667) (xy 228.423326 -246.399025) (xy 228.475621 -246.38367)
			(xy 228.529569 -246.375914) (xy 228.584071 -246.375914) (xy 228.638019 -246.38367) (xy 228.690314 -246.399025)
			(xy 228.739891 -246.421667) (xy 228.785741 -246.451133) (xy 228.826932 -246.486824) (xy 228.862623 -246.528015)
			(xy 228.892089 -246.573865) (xy 228.914731 -246.623442) (xy 228.930086 -246.675737) (xy 228.937842 -246.729685)
			(xy 228.938328 -246.756936) (xy 228.938328 -247.620536) (xy 228.937842 -247.647787) (xy 228.930086 -247.701735)
			(xy 228.914731 -247.75403) (xy 228.892089 -247.803607) (xy 228.862623 -247.849457) (xy 228.826932 -247.890648)
			(xy 228.785741 -247.926339) (xy 228.739891 -247.955805) (xy 228.690314 -247.978447) (xy 228.638019 -247.993802)
			(xy 228.584071 -248.001558) (xy 228.529569 -248.001558) (xy 228.475621 -247.993802) (xy 228.423326 -247.978447)
			(xy 228.373749 -247.955805) (xy 228.327899 -247.926339) (xy 228.286708 -247.890648) (xy 228.251017 -247.849457)
			(xy 228.221551 -247.803607) (xy 228.198909 -247.75403) (xy 228.183554 -247.701735) (xy 228.175798 -247.647787)
			(xy 228.175312 -247.620536) (xy 2.509012 -247.620536) (xy 2.509012 -251.76988) (xy 75.695566 -251.76988)
			(xy 75.699547 -251.63686) (xy 75.711476 -251.504315) (xy 75.731311 -251.372722) (xy 75.75898 -251.24255)
			(xy 75.794384 -251.114265) (xy 75.837397 -250.988328) (xy 75.887864 -250.865189) (xy 75.945605 -250.745288)
			(xy 76.010414 -250.629055) (xy 76.082058 -250.516905) (xy 76.16028 -250.409241) (xy 76.244801 -250.306448)
			(xy 76.335319 -250.208893) (xy 76.431508 -250.116927) (xy 76.533026 -250.030877) (xy 76.639507 -249.951053)
			(xy 76.750572 -249.87774) (xy 76.865823 -249.8112) (xy 76.984847 -249.751671) (xy 77.107218 -249.699367)
			(xy 77.232497 -249.654475) (xy 77.360238 -249.617156) (xy 77.489981 -249.587543) (xy 77.621263 -249.565742)
			(xy 77.753614 -249.551832) (xy 77.88656 -249.545861) (xy 78.019625 -249.547852) (xy 78.152333 -249.557797)
			(xy 78.284209 -249.575661) (xy 78.41478 -249.601379) (xy 78.54358 -249.63486) (xy 78.670146 -249.675984)
			(xy 78.794027 -249.724604) (xy 78.914778 -249.780545) (xy 79.031968 -249.843607) (xy 79.145177 -249.913565)
			(xy 79.253999 -249.990169) (xy 79.358045 -250.073143) (xy 79.456943 -250.162191) (xy 79.550338 -250.256994)
			(xy 79.637896 -250.357212) (xy 79.719305 -250.462488) (xy 79.794271 -250.572444) (xy 79.862528 -250.686686)
			(xy 79.92383 -250.804806) (xy 79.977959 -250.926381) (xy 80.02472 -251.050975) (xy 80.063946 -251.178143)
			(xy 80.095496 -251.307429) (xy 80.119259 -251.43837) (xy 80.135148 -251.570498) (xy 80.143106 -251.70334)
			(xy 80.143604 -251.76988) (xy 143.715496 -251.76988) (xy 143.719477 -251.63686) (xy 143.731406 -251.504315)
			(xy 143.751241 -251.372722) (xy 143.77891 -251.24255) (xy 143.814314 -251.114265) (xy 143.857327 -250.988328)
			(xy 143.907794 -250.865189) (xy 143.965535 -250.745288) (xy 144.030344 -250.629055) (xy 144.101988 -250.516905)
			(xy 144.18021 -250.409241) (xy 144.264731 -250.306448) (xy 144.355249 -250.208893) (xy 144.451438 -250.116927)
			(xy 144.552956 -250.030877) (xy 144.659437 -249.951053) (xy 144.770502 -249.87774) (xy 144.885753 -249.8112)
			(xy 145.004777 -249.751671) (xy 145.127148 -249.699367) (xy 145.252427 -249.654475) (xy 145.380168 -249.617156)
			(xy 145.509911 -249.587543) (xy 145.641193 -249.565742) (xy 145.773544 -249.551832) (xy 145.90649 -249.545861)
			(xy 146.039555 -249.547852) (xy 146.172263 -249.557797) (xy 146.304139 -249.575661) (xy 146.43471 -249.601379)
			(xy 146.56351 -249.63486) (xy 146.690076 -249.675984) (xy 146.813957 -249.724604) (xy 146.934708 -249.780545)
			(xy 147.051898 -249.843607) (xy 147.165107 -249.913565) (xy 147.273929 -249.990169) (xy 147.377975 -250.073143)
			(xy 147.476873 -250.162191) (xy 147.570268 -250.256994) (xy 147.657826 -250.357212) (xy 147.739235 -250.462488)
			(xy 147.814201 -250.572444) (xy 147.882458 -250.686686) (xy 147.94376 -250.804806) (xy 147.997889 -250.926381)
			(xy 148.04465 -251.050975) (xy 148.083876 -251.178143) (xy 148.115426 -251.307429) (xy 148.139189 -251.43837)
			(xy 148.155078 -251.570498) (xy 148.163036 -251.70334) (xy 148.163534 -251.76988) (xy 323.635634 -251.76988)
			(xy 323.639615 -251.63686) (xy 323.651544 -251.504315) (xy 323.671379 -251.372722) (xy 323.699048 -251.24255)
			(xy 323.734452 -251.114265) (xy 323.777465 -250.988328) (xy 323.827932 -250.865189) (xy 323.885673 -250.745288)
			(xy 323.950482 -250.629055) (xy 324.022126 -250.516905) (xy 324.100348 -250.409241) (xy 324.184869 -250.306448)
			(xy 324.275387 -250.208893) (xy 324.371576 -250.116927) (xy 324.473094 -250.030877) (xy 324.579575 -249.951053)
			(xy 324.69064 -249.87774) (xy 324.805891 -249.8112) (xy 324.924915 -249.751671) (xy 325.047286 -249.699367)
			(xy 325.172565 -249.654475) (xy 325.300306 -249.617156) (xy 325.430049 -249.587543) (xy 325.561331 -249.565742)
			(xy 325.693682 -249.551832) (xy 325.826628 -249.545861) (xy 325.959693 -249.547852) (xy 326.092401 -249.557797)
			(xy 326.224277 -249.575661) (xy 326.354848 -249.601379) (xy 326.483648 -249.63486) (xy 326.610214 -249.675984)
			(xy 326.734095 -249.724604) (xy 326.854846 -249.780545) (xy 326.972036 -249.843607) (xy 327.085245 -249.913565)
			(xy 327.194067 -249.990169) (xy 327.298113 -250.073143) (xy 327.397011 -250.162191) (xy 327.490406 -250.256994)
			(xy 327.577964 -250.357212) (xy 327.659373 -250.462488) (xy 327.734339 -250.572444) (xy 327.802596 -250.686686)
			(xy 327.863898 -250.804806) (xy 327.918027 -250.926381) (xy 327.964788 -251.050975) (xy 328.004014 -251.178143)
			(xy 328.035564 -251.307429) (xy 328.059327 -251.43837) (xy 328.075216 -251.570498) (xy 328.083174 -251.70334)
			(xy 328.083672 -251.76988) (xy 391.655564 -251.76988) (xy 391.659545 -251.63686) (xy 391.671474 -251.504315)
			(xy 391.691309 -251.372722) (xy 391.718978 -251.24255) (xy 391.754382 -251.114265) (xy 391.797395 -250.988328)
			(xy 391.847862 -250.865189) (xy 391.905603 -250.745288) (xy 391.970412 -250.629055) (xy 392.042056 -250.516905)
			(xy 392.120278 -250.409241) (xy 392.204799 -250.306448) (xy 392.295317 -250.208893) (xy 392.391506 -250.116927)
			(xy 392.493024 -250.030877) (xy 392.599505 -249.951053) (xy 392.71057 -249.87774) (xy 392.825821 -249.8112)
			(xy 392.944845 -249.751671) (xy 393.067216 -249.699367) (xy 393.192495 -249.654475) (xy 393.320236 -249.617156)
			(xy 393.449979 -249.587543) (xy 393.581261 -249.565742) (xy 393.713612 -249.551832) (xy 393.846558 -249.545861)
			(xy 393.979623 -249.547852) (xy 394.112331 -249.557797) (xy 394.244207 -249.575661) (xy 394.374778 -249.601379)
			(xy 394.503578 -249.63486) (xy 394.630144 -249.675984) (xy 394.754025 -249.724604) (xy 394.874776 -249.780545)
			(xy 394.991966 -249.843607) (xy 395.105175 -249.913565) (xy 395.213997 -249.990169) (xy 395.318043 -250.073143)
			(xy 395.416941 -250.162191) (xy 395.510336 -250.256994) (xy 395.597894 -250.357212) (xy 395.679303 -250.462488)
			(xy 395.754269 -250.572444) (xy 395.822526 -250.686686) (xy 395.883828 -250.804806) (xy 395.937957 -250.926381)
			(xy 395.984718 -251.050975) (xy 396.023944 -251.178143) (xy 396.055494 -251.307429) (xy 396.079257 -251.43837)
			(xy 396.095146 -251.570498) (xy 396.103104 -251.70334) (xy 396.103602 -251.76988) (xy 396.103104 -251.83642)
			(xy 396.095146 -251.969262) (xy 396.079257 -252.10139) (xy 396.055494 -252.232331) (xy 396.023944 -252.361617)
			(xy 395.984718 -252.488785) (xy 395.937957 -252.613379) (xy 395.883828 -252.734954) (xy 395.822526 -252.853074)
			(xy 395.754269 -252.967316) (xy 395.679303 -253.077272) (xy 395.597894 -253.182548) (xy 395.510336 -253.282766)
			(xy 395.416941 -253.377569) (xy 395.318043 -253.466617) (xy 395.213997 -253.549591) (xy 395.105175 -253.626195)
			(xy 394.991966 -253.696153) (xy 394.874776 -253.759215) (xy 394.754025 -253.815156) (xy 394.630144 -253.863776)
			(xy 394.503578 -253.9049) (xy 394.374778 -253.938381) (xy 394.244207 -253.964099) (xy 394.112331 -253.981963)
			(xy 393.979623 -253.991908) (xy 393.846558 -253.993899) (xy 393.713612 -253.987928) (xy 393.581261 -253.974018)
			(xy 393.449979 -253.952217) (xy 393.320236 -253.922604) (xy 393.192495 -253.885285) (xy 393.067216 -253.840393)
			(xy 392.944845 -253.788089) (xy 392.825821 -253.72856) (xy 392.71057 -253.66202) (xy 392.599505 -253.588707)
			(xy 392.493024 -253.508883) (xy 392.391506 -253.422833) (xy 392.295317 -253.330867) (xy 392.204799 -253.233312)
			(xy 392.120278 -253.130519) (xy 392.042056 -253.022855) (xy 391.970412 -252.910705) (xy 391.905603 -252.794472)
			(xy 391.847862 -252.674571) (xy 391.797395 -252.551432) (xy 391.754382 -252.425495) (xy 391.718978 -252.29721)
			(xy 391.691309 -252.167038) (xy 391.671474 -252.035445) (xy 391.659545 -251.9029) (xy 391.655564 -251.76988)
			(xy 328.083672 -251.76988) (xy 328.083174 -251.83642) (xy 328.075216 -251.969262) (xy 328.059327 -252.10139)
			(xy 328.035564 -252.232331) (xy 328.004014 -252.361617) (xy 327.964788 -252.488785) (xy 327.918027 -252.613379)
			(xy 327.863898 -252.734954) (xy 327.802596 -252.853074) (xy 327.734339 -252.967316) (xy 327.659373 -253.077272)
			(xy 327.577964 -253.182548) (xy 327.490406 -253.282766) (xy 327.397011 -253.377569) (xy 327.298113 -253.466617)
			(xy 327.194067 -253.549591) (xy 327.085245 -253.626195) (xy 326.972036 -253.696153) (xy 326.854846 -253.759215)
			(xy 326.734095 -253.815156) (xy 326.610214 -253.863776) (xy 326.483648 -253.9049) (xy 326.354848 -253.938381)
			(xy 326.224277 -253.964099) (xy 326.092401 -253.981963) (xy 325.959693 -253.991908) (xy 325.826628 -253.993899)
			(xy 325.693682 -253.987928) (xy 325.561331 -253.974018) (xy 325.430049 -253.952217) (xy 325.300306 -253.922604)
			(xy 325.172565 -253.885285) (xy 325.047286 -253.840393) (xy 324.924915 -253.788089) (xy 324.805891 -253.72856)
			(xy 324.69064 -253.66202) (xy 324.579575 -253.588707) (xy 324.473094 -253.508883) (xy 324.371576 -253.422833)
			(xy 324.275387 -253.330867) (xy 324.184869 -253.233312) (xy 324.100348 -253.130519) (xy 324.022126 -253.022855)
			(xy 323.950482 -252.910705) (xy 323.885673 -252.794472) (xy 323.827932 -252.674571) (xy 323.777465 -252.551432)
			(xy 323.734452 -252.425495) (xy 323.699048 -252.29721) (xy 323.671379 -252.167038) (xy 323.651544 -252.035445)
			(xy 323.639615 -251.9029) (xy 323.635634 -251.76988) (xy 148.163534 -251.76988) (xy 148.163036 -251.83642)
			(xy 148.155078 -251.969262) (xy 148.139189 -252.10139) (xy 148.115426 -252.232331) (xy 148.083876 -252.361617)
			(xy 148.04465 -252.488785) (xy 147.997889 -252.613379) (xy 147.94376 -252.734954) (xy 147.882458 -252.853074)
			(xy 147.814201 -252.967316) (xy 147.739235 -253.077272) (xy 147.657826 -253.182548) (xy 147.570268 -253.282766)
			(xy 147.476873 -253.377569) (xy 147.377975 -253.466617) (xy 147.273929 -253.549591) (xy 147.165107 -253.626195)
			(xy 147.051898 -253.696153) (xy 146.934708 -253.759215) (xy 146.813957 -253.815156) (xy 146.690076 -253.863776)
			(xy 146.56351 -253.9049) (xy 146.43471 -253.938381) (xy 146.304139 -253.964099) (xy 146.172263 -253.981963)
			(xy 146.039555 -253.991908) (xy 145.90649 -253.993899) (xy 145.773544 -253.987928) (xy 145.641193 -253.974018)
			(xy 145.509911 -253.952217) (xy 145.380168 -253.922604) (xy 145.252427 -253.885285) (xy 145.127148 -253.840393)
			(xy 145.004777 -253.788089) (xy 144.885753 -253.72856) (xy 144.770502 -253.66202) (xy 144.659437 -253.588707)
			(xy 144.552956 -253.508883) (xy 144.451438 -253.422833) (xy 144.355249 -253.330867) (xy 144.264731 -253.233312)
			(xy 144.18021 -253.130519) (xy 144.101988 -253.022855) (xy 144.030344 -252.910705) (xy 143.965535 -252.794472)
			(xy 143.907794 -252.674571) (xy 143.857327 -252.551432) (xy 143.814314 -252.425495) (xy 143.77891 -252.29721)
			(xy 143.751241 -252.167038) (xy 143.731406 -252.035445) (xy 143.719477 -251.9029) (xy 143.715496 -251.76988)
			(xy 80.143604 -251.76988) (xy 80.143106 -251.83642) (xy 80.135148 -251.969262) (xy 80.119259 -252.10139)
			(xy 80.095496 -252.232331) (xy 80.063946 -252.361617) (xy 80.02472 -252.488785) (xy 79.977959 -252.613379)
			(xy 79.92383 -252.734954) (xy 79.862528 -252.853074) (xy 79.794271 -252.967316) (xy 79.719305 -253.077272)
			(xy 79.637896 -253.182548) (xy 79.550338 -253.282766) (xy 79.456943 -253.377569) (xy 79.358045 -253.466617)
			(xy 79.253999 -253.549591) (xy 79.145177 -253.626195) (xy 79.031968 -253.696153) (xy 78.914778 -253.759215)
			(xy 78.794027 -253.815156) (xy 78.670146 -253.863776) (xy 78.54358 -253.9049) (xy 78.41478 -253.938381)
			(xy 78.284209 -253.964099) (xy 78.152333 -253.981963) (xy 78.019625 -253.991908) (xy 77.88656 -253.993899)
			(xy 77.753614 -253.987928) (xy 77.621263 -253.974018) (xy 77.489981 -253.952217) (xy 77.360238 -253.922604)
			(xy 77.232497 -253.885285) (xy 77.107218 -253.840393) (xy 76.984847 -253.788089) (xy 76.865823 -253.72856)
			(xy 76.750572 -253.66202) (xy 76.639507 -253.588707) (xy 76.533026 -253.508883) (xy 76.431508 -253.422833)
			(xy 76.335319 -253.330867) (xy 76.244801 -253.233312) (xy 76.16028 -253.130519) (xy 76.082058 -253.022855)
			(xy 76.010414 -252.910705) (xy 75.945605 -252.794472) (xy 75.887864 -252.674571) (xy 75.837397 -252.551432)
			(xy 75.794384 -252.425495) (xy 75.75898 -252.29721) (xy 75.731311 -252.167038) (xy 75.711476 -252.035445)
			(xy 75.699547 -251.9029) (xy 75.695566 -251.76988) (xy 2.509012 -251.76988) (xy 2.509012 -273.453098)
			(xy 108.601256 -273.453098) (xy 108.601764 -273.427211) (xy 108.609863 -273.376073) (xy 108.625862 -273.326833)
			(xy 108.649368 -273.280701) (xy 108.6798 -273.238814) (xy 108.71641 -273.202204) (xy 108.758297 -273.171772)
			(xy 108.804429 -273.148266) (xy 108.853669 -273.132267) (xy 108.904807 -273.124168) (xy 108.956581 -273.124168)
			(xy 109.007719 -273.132267) (xy 109.056959 -273.148266) (xy 109.103091 -273.171772) (xy 109.144978 -273.202204)
			(xy 109.181588 -273.238814) (xy 109.21202 -273.280701) (xy 109.235526 -273.326833) (xy 109.251525 -273.376073)
			(xy 109.259624 -273.427211) (xy 109.260132 -273.453098) (xy 356.541324 -273.453098) (xy 356.541832 -273.427211)
			(xy 356.549931 -273.376073) (xy 356.56593 -273.326833) (xy 356.589436 -273.280701) (xy 356.619868 -273.238814)
			(xy 356.656478 -273.202204) (xy 356.698365 -273.171772) (xy 356.744497 -273.148266) (xy 356.793737 -273.132267)
			(xy 356.844875 -273.124168) (xy 356.896649 -273.124168) (xy 356.947787 -273.132267) (xy 356.997027 -273.148266)
			(xy 357.043159 -273.171772) (xy 357.085046 -273.202204) (xy 357.121656 -273.238814) (xy 357.152088 -273.280701)
			(xy 357.175594 -273.326833) (xy 357.191593 -273.376073) (xy 357.199692 -273.427211) (xy 357.2002 -273.453098)
			(xy 357.19967 -273.480806) (xy 357.190475 -273.535453) (xy 357.181912 -273.56181) (xy 357.174292 -273.583654)
			(xy 357.37927 -273.938746) (xy 357.40213 -273.943064) (xy 357.426938 -273.948232) (xy 357.474677 -273.965225)
			(xy 357.519254 -273.989322) (xy 357.559619 -274.019956) (xy 357.594821 -274.056405) (xy 357.624032 -274.097811)
			(xy 357.646564 -274.143199) (xy 357.661886 -274.191501) (xy 357.669637 -274.241577) (xy 357.6701 -274.266914)
			(xy 357.669592 -274.292801) (xy 357.661493 -274.343939) (xy 357.645494 -274.393179) (xy 357.621988 -274.439311)
			(xy 357.591556 -274.481198) (xy 357.554946 -274.517808) (xy 357.513059 -274.54824) (xy 357.466927 -274.571746)
			(xy 357.417687 -274.587745) (xy 357.366549 -274.595844) (xy 357.314775 -274.595844) (xy 357.263637 -274.587745)
			(xy 357.214397 -274.571746) (xy 357.168265 -274.54824) (xy 357.126378 -274.517808) (xy 357.089768 -274.481198)
			(xy 357.059336 -274.439311) (xy 357.03583 -274.393179) (xy 357.019831 -274.343939) (xy 357.011732 -274.292801)
			(xy 357.011224 -274.266914) (xy 357.011756 -274.239206) (xy 357.020949 -274.184559) (xy 357.029512 -274.158202)
			(xy 357.037386 -274.136104) (xy 356.832408 -273.781266) (xy 356.809548 -273.776948) (xy 356.784736 -273.771741)
			(xy 356.73696 -273.75479) (xy 356.692344 -273.730722) (xy 356.651938 -273.700106) (xy 356.616698 -273.663665)
			(xy 356.587453 -273.622257) (xy 356.564893 -273.576859) (xy 356.549551 -273.528542) (xy 356.541789 -273.478445)
			(xy 356.541324 -273.453098) (xy 109.260132 -273.453098) (xy 109.259601 -273.480806) (xy 109.250407 -273.535453)
			(xy 109.241844 -273.56181) (xy 109.234224 -273.583654) (xy 109.439202 -273.938746) (xy 109.462062 -273.943064)
			(xy 109.486859 -273.948281) (xy 109.534598 -273.965264) (xy 109.579176 -273.989353) (xy 109.619543 -274.019979)
			(xy 109.654747 -274.056422) (xy 109.683961 -274.097824) (xy 109.706494 -274.143208) (xy 109.721817 -274.191505)
			(xy 109.729569 -274.241579) (xy 109.730032 -274.266914) (xy 351.372424 -274.266914) (xy 351.372932 -274.241027)
			(xy 351.381031 -274.189889) (xy 351.39703 -274.140649) (xy 351.420536 -274.094517) (xy 351.450968 -274.05263)
			(xy 351.487578 -274.01602) (xy 351.529465 -273.985588) (xy 351.575597 -273.962082) (xy 351.624837 -273.946083)
			(xy 351.675975 -273.937984) (xy 351.727749 -273.937984) (xy 351.778887 -273.946083) (xy 351.828127 -273.962082)
			(xy 351.874259 -273.985588) (xy 351.916146 -274.01602) (xy 351.952756 -274.05263) (xy 351.983188 -274.094517)
			(xy 352.006694 -274.140649) (xy 352.022693 -274.189889) (xy 352.030792 -274.241027) (xy 352.0313 -274.266914)
			(xy 352.0313 -274.267422) (xy 352.030713 -274.294938) (xy 352.021525 -274.349199) (xy 352.013012 -274.375372)
			(xy 352.005392 -274.397216) (xy 352.210624 -274.752562) (xy 352.233484 -274.75688) (xy 352.258307 -274.762037)
			(xy 352.306085 -274.778995) (xy 352.350703 -274.80307) (xy 352.391108 -274.833692) (xy 352.426348 -274.87014)
			(xy 352.455591 -274.911554) (xy 352.478148 -274.956958) (xy 352.493487 -275.00528) (xy 352.501245 -275.055381)
			(xy 352.501708 -275.08073) (xy 352.5012 -275.106637) (xy 352.493094 -275.157814) (xy 352.477082 -275.207093)
			(xy 352.453559 -275.25326) (xy 352.423103 -275.295179) (xy 352.386465 -275.331817) (xy 352.344546 -275.362273)
			(xy 352.298379 -275.385796) (xy 352.2491 -275.401808) (xy 352.197923 -275.409914) (xy 352.146109 -275.409914)
			(xy 352.094932 -275.401808) (xy 352.045653 -275.385796) (xy 351.999486 -275.362273) (xy 351.957567 -275.331817)
			(xy 351.920929 -275.295179) (xy 351.890473 -275.25326) (xy 351.86695 -275.207093) (xy 351.850938 -275.157814)
			(xy 351.842832 -275.106637) (xy 351.842324 -275.08073) (xy 351.842924 -275.053013) (xy 351.852243 -274.998366)
			(xy 351.860866 -274.972018) (xy 351.86874 -274.94992) (xy 351.663762 -274.595082) (xy 351.640902 -274.590764)
			(xy 351.616074 -274.585582) (xy 351.568269 -274.568647) (xy 351.523622 -274.544591) (xy 351.483185 -274.513981)
			(xy 351.447913 -274.47754) (xy 351.418638 -274.436127) (xy 351.39605 -274.390718) (xy 351.380683 -274.342387)
			(xy 351.372898 -274.292272) (xy 351.372424 -274.266914) (xy 109.730032 -274.266914) (xy 109.729524 -274.292801)
			(xy 109.721425 -274.343939) (xy 109.705426 -274.393179) (xy 109.68192 -274.439311) (xy 109.651488 -274.481198)
			(xy 109.614878 -274.517808) (xy 109.572991 -274.54824) (xy 109.526859 -274.571746) (xy 109.477619 -274.587745)
			(xy 109.426481 -274.595844) (xy 109.374707 -274.595844) (xy 109.323569 -274.587745) (xy 109.274329 -274.571746)
			(xy 109.228197 -274.54824) (xy 109.18631 -274.517808) (xy 109.1497 -274.481198) (xy 109.119268 -274.439311)
			(xy 109.095762 -274.393179) (xy 109.079763 -274.343939) (xy 109.071664 -274.292801) (xy 109.071156 -274.266914)
			(xy 109.071691 -274.239206) (xy 109.080883 -274.184559) (xy 109.089444 -274.158202) (xy 109.097318 -274.136104)
			(xy 108.89234 -273.781266) (xy 108.86948 -273.776948) (xy 108.844673 -273.771718) (xy 108.796897 -273.754771)
			(xy 108.75228 -273.730708) (xy 108.711874 -273.700095) (xy 108.676632 -273.663656) (xy 108.647386 -273.622251)
			(xy 108.624826 -273.576855) (xy 108.609484 -273.528539) (xy 108.601721 -273.478444) (xy 108.601256 -273.453098)
			(xy 2.509012 -273.453098) (xy 2.509012 -274.266914) (xy 103.432356 -274.266914) (xy 103.432864 -274.241027)
			(xy 103.440963 -274.189889) (xy 103.456962 -274.140649) (xy 103.480468 -274.094517) (xy 103.5109 -274.05263)
			(xy 103.54751 -274.01602) (xy 103.589397 -273.985588) (xy 103.635529 -273.962082) (xy 103.684769 -273.946083)
			(xy 103.735907 -273.937984) (xy 103.787681 -273.937984) (xy 103.838819 -273.946083) (xy 103.888059 -273.962082)
			(xy 103.934191 -273.985588) (xy 103.976078 -274.01602) (xy 104.012688 -274.05263) (xy 104.04312 -274.094517)
			(xy 104.066626 -274.140649) (xy 104.082625 -274.189889) (xy 104.090724 -274.241027) (xy 104.091232 -274.266914)
			(xy 104.091232 -274.267422) (xy 104.090643 -274.294938) (xy 104.081456 -274.349199) (xy 104.072944 -274.375372)
			(xy 104.065324 -274.397216) (xy 104.270556 -274.752562) (xy 104.293416 -274.75688) (xy 104.318228 -274.762086)
			(xy 104.366006 -274.779035) (xy 104.410625 -274.803101) (xy 104.451032 -274.833715) (xy 104.486274 -274.870157)
			(xy 104.515519 -274.911566) (xy 104.538078 -274.956966) (xy 104.553418 -275.005285) (xy 104.561177 -275.055382)
			(xy 104.56164 -275.08073) (xy 104.561132 -275.106637) (xy 104.553026 -275.157814) (xy 104.537014 -275.207093)
			(xy 104.513491 -275.25326) (xy 104.483035 -275.295179) (xy 104.446397 -275.331817) (xy 104.404478 -275.362273)
			(xy 104.358311 -275.385796) (xy 104.309032 -275.401808) (xy 104.257855 -275.409914) (xy 104.206041 -275.409914)
			(xy 104.154864 -275.401808) (xy 104.105585 -275.385796) (xy 104.059418 -275.362273) (xy 104.017499 -275.331817)
			(xy 103.980861 -275.295179) (xy 103.950405 -275.25326) (xy 103.926882 -275.207093) (xy 103.91087 -275.157814)
			(xy 103.902764 -275.106637) (xy 103.902256 -275.08073) (xy 103.902854 -275.053013) (xy 103.912174 -274.998366)
			(xy 103.920798 -274.972018) (xy 103.928672 -274.94992) (xy 103.723694 -274.595082) (xy 103.700834 -274.590764)
			(xy 103.676011 -274.585559) (xy 103.628206 -274.568629) (xy 103.583558 -274.544577) (xy 103.543121 -274.51397)
			(xy 103.507847 -274.477532) (xy 103.478571 -274.436121) (xy 103.455983 -274.390715) (xy 103.440615 -274.342385)
			(xy 103.43283 -274.292271) (xy 103.432356 -274.266914) (xy 2.509012 -274.266914) (xy 2.509012 -275.10659)
			(xy 102.023373 -275.10659) (xy 102.023373 -275.05481) (xy 102.031474 -275.003669) (xy 102.047476 -274.954425)
			(xy 102.070985 -274.90829) (xy 102.101423 -274.866402) (xy 102.138039 -274.829791) (xy 102.179931 -274.79936)
			(xy 102.226069 -274.775858) (xy 102.275316 -274.759863) (xy 102.326458 -274.75177) (xy 102.352348 -274.751292)
			(xy 102.377861 -274.751741) (xy 102.428277 -274.759608) (xy 102.476879 -274.775148) (xy 102.522507 -274.79799)
			(xy 102.564072 -274.827588) (xy 102.600581 -274.863235) (xy 102.616254 -274.883372) (xy 103.028242 -274.883372)
			(xy 103.043883 -274.86321) (xy 103.0804 -274.827569) (xy 103.121973 -274.797979) (xy 103.167607 -274.775148)
			(xy 103.216215 -274.75962) (xy 103.266634 -274.751765) (xy 103.292148 -274.751292) (xy 103.318035 -274.751743)
			(xy 103.369171 -274.759849) (xy 103.41841 -274.775854) (xy 103.464539 -274.799364) (xy 103.506423 -274.8298)
			(xy 103.543031 -274.866413) (xy 103.573461 -274.908302) (xy 103.596964 -274.954434) (xy 103.612962 -275.003675)
			(xy 103.62106 -275.054813) (xy 103.62106 -275.106587) (xy 103.612962 -275.157725) (xy 103.596964 -275.206966)
			(xy 103.573461 -275.253098) (xy 103.543031 -275.294987) (xy 103.506423 -275.3316) (xy 103.464539 -275.362036)
			(xy 103.41841 -275.385546) (xy 103.369171 -275.401551) (xy 103.318035 -275.409657) (xy 103.292148 -275.410168)
			(xy 103.266637 -275.409665) (xy 103.216223 -275.401811) (xy 103.167621 -275.386283) (xy 103.121992 -275.363452)
			(xy 103.080426 -275.333862) (xy 103.043916 -275.298222) (xy 103.028242 -275.278088) (xy 102.616254 -275.278088)
			(xy 102.600546 -275.298195) (xy 102.564044 -275.333841) (xy 102.522486 -275.363438) (xy 102.476864 -275.386279)
			(xy 102.428268 -275.401819) (xy 102.377858 -275.409687) (xy 102.352348 -275.410168) (xy 102.326458 -275.40963)
			(xy 102.275316 -275.401537) (xy 102.226069 -275.385542) (xy 102.179931 -275.36204) (xy 102.138039 -275.331609)
			(xy 102.101423 -275.294998) (xy 102.070985 -275.25311) (xy 102.047476 -275.206975) (xy 102.031474 -275.157731)
			(xy 102.023373 -275.10659) (xy 2.509012 -275.10659) (xy 2.509012 -276.708616) (xy 102.022656 -276.708616)
			(xy 102.023189 -276.683284) (xy 102.030938 -276.633215) (xy 102.046256 -276.584922) (xy 102.068781 -276.53954)
			(xy 102.097985 -276.498139) (xy 102.133179 -276.461694) (xy 102.173534 -276.431062) (xy 102.218101 -276.406964)
			(xy 102.265829 -276.389968) (xy 102.290626 -276.384766) (xy 102.313486 -276.380448) (xy 102.518464 -276.025356)
			(xy 102.510844 -276.003512) (xy 102.502285 -275.977153) (xy 102.493085 -275.922508) (xy 102.492556 -275.8948)
			(xy 102.493064 -275.868913) (xy 102.501163 -275.817775) (xy 102.517162 -275.768535) (xy 102.540668 -275.722403)
			(xy 102.5711 -275.680516) (xy 102.60771 -275.643906) (xy 102.649597 -275.613474) (xy 102.695729 -275.589968)
			(xy 102.744969 -275.573969) (xy 102.796107 -275.56587) (xy 102.847881 -275.56587) (xy 102.899019 -275.573969)
			(xy 102.948259 -275.589968) (xy 102.994391 -275.613474) (xy 103.036278 -275.643906) (xy 103.072888 -275.680516)
			(xy 103.10332 -275.722403) (xy 103.126826 -275.768535) (xy 103.142825 -275.817775) (xy 103.150924 -275.868913)
			(xy 103.151432 -275.8948) (xy 104.372156 -275.8948) (xy 104.372675 -275.869467) (xy 104.380426 -275.819398)
			(xy 104.395746 -275.771105) (xy 104.418273 -275.725723) (xy 104.447479 -275.684322) (xy 104.482674 -275.647877)
			(xy 104.523031 -275.617245) (xy 104.567599 -275.593147) (xy 104.615329 -275.576152) (xy 104.640126 -275.57095)
			(xy 104.662986 -275.566632) (xy 104.868218 -275.211286) (xy 104.860598 -275.189188) (xy 104.851972 -275.162906)
			(xy 104.842659 -275.108385) (xy 104.842056 -275.08073) (xy 104.842564 -275.054823) (xy 104.85067 -275.003646)
			(xy 104.866682 -274.954367) (xy 104.890205 -274.9082) (xy 104.920661 -274.866281) (xy 104.957299 -274.829643)
			(xy 104.999218 -274.799187) (xy 105.045385 -274.775664) (xy 105.094664 -274.759652) (xy 105.145841 -274.751546)
			(xy 105.197655 -274.751546) (xy 105.248832 -274.759652) (xy 105.298111 -274.775664) (xy 105.344278 -274.799187)
			(xy 105.386197 -274.829643) (xy 105.422835 -274.866281) (xy 105.453291 -274.9082) (xy 105.476814 -274.954367)
			(xy 105.492826 -275.003646) (xy 105.500932 -275.054823) (xy 105.50144 -275.08073) (xy 107.661456 -275.08073)
			(xy 107.661964 -275.054823) (xy 107.67007 -275.003646) (xy 107.686082 -274.954367) (xy 107.709605 -274.9082)
			(xy 107.740061 -274.866281) (xy 107.776699 -274.829643) (xy 107.818618 -274.799187) (xy 107.864785 -274.775664)
			(xy 107.914064 -274.759652) (xy 107.965241 -274.751546) (xy 108.017055 -274.751546) (xy 108.068232 -274.759652)
			(xy 108.117511 -274.775664) (xy 108.163678 -274.799187) (xy 108.205597 -274.829643) (xy 108.242235 -274.866281)
			(xy 108.272691 -274.9082) (xy 108.296214 -274.954367) (xy 108.312226 -275.003646) (xy 108.320332 -275.054823)
			(xy 108.32084 -275.08073) (xy 108.320273 -275.106588) (xy 349.963473 -275.106588) (xy 349.963473 -275.054812)
			(xy 349.971573 -275.003674) (xy 349.987573 -274.954432) (xy 350.011079 -274.9083) (xy 350.041513 -274.866413)
			(xy 350.078125 -274.829803) (xy 350.120014 -274.799371) (xy 350.166147 -274.775867) (xy 350.215389 -274.759869)
			(xy 350.266528 -274.751772) (xy 350.292416 -274.751292) (xy 350.317928 -274.751764) (xy 350.368343 -274.759627)
			(xy 350.416945 -274.775162) (xy 350.462573 -274.797999) (xy 350.504138 -274.827593) (xy 350.540648 -274.863237)
			(xy 350.556322 -274.883372) (xy 350.96831 -274.883372) (xy 350.98397 -274.863226) (xy 351.020483 -274.827584)
			(xy 351.062052 -274.797992) (xy 351.107683 -274.775158) (xy 351.156287 -274.759626) (xy 351.206703 -274.751768)
			(xy 351.232216 -274.751292) (xy 351.258105 -274.751741) (xy 351.309245 -274.759843) (xy 351.358488 -274.775845)
			(xy 351.404622 -274.799353) (xy 351.44651 -274.829789) (xy 351.483122 -274.866402) (xy 351.513555 -274.908292)
			(xy 351.537061 -274.954427) (xy 351.553061 -275.003671) (xy 351.56116 -275.054811) (xy 351.56116 -275.106589)
			(xy 351.553061 -275.157729) (xy 351.537061 -275.206973) (xy 351.513555 -275.253108) (xy 351.483122 -275.294998)
			(xy 351.44651 -275.331611) (xy 351.404622 -275.362047) (xy 351.358488 -275.385555) (xy 351.309245 -275.401557)
			(xy 351.258105 -275.409659) (xy 351.232216 -275.410168) (xy 351.206704 -275.409689) (xy 351.156289 -275.401829)
			(xy 351.107687 -275.386297) (xy 351.062058 -275.363461) (xy 351.020493 -275.333868) (xy 350.983983 -275.298224)
			(xy 350.96831 -275.278088) (xy 350.556322 -275.278088) (xy 350.540633 -275.29821) (xy 350.504126 -275.333856)
			(xy 350.462565 -275.363451) (xy 350.416939 -275.386289) (xy 350.36834 -275.401826) (xy 350.317927 -275.409689)
			(xy 350.292416 -275.410168) (xy 350.266528 -275.409628) (xy 350.215389 -275.401531) (xy 350.166147 -275.385533)
			(xy 350.120014 -275.362029) (xy 350.078125 -275.331597) (xy 350.041513 -275.294987) (xy 350.011079 -275.2531)
			(xy 349.987573 -275.206968) (xy 349.971573 -275.157726) (xy 349.963473 -275.106588) (xy 108.320273 -275.106588)
			(xy 108.320232 -275.108447) (xy 108.310918 -275.163093) (xy 108.302298 -275.189442) (xy 108.294424 -275.21154)
			(xy 108.499656 -275.566632) (xy 108.522516 -275.57095) (xy 108.547321 -275.576185) (xy 108.595097 -275.593131)
			(xy 108.639715 -275.617194) (xy 108.680121 -275.647805) (xy 108.715363 -275.684244) (xy 108.744609 -275.725649)
			(xy 108.767169 -275.771044) (xy 108.782512 -275.819359) (xy 108.790275 -275.869454) (xy 108.79074 -275.8948)
			(xy 108.790232 -275.920707) (xy 108.782126 -275.971884) (xy 108.766114 -276.021163) (xy 108.742591 -276.06733)
			(xy 108.712135 -276.109249) (xy 108.675497 -276.145887) (xy 108.633578 -276.176343) (xy 108.587411 -276.199866)
			(xy 108.538132 -276.215878) (xy 108.486955 -276.223984) (xy 108.435141 -276.223984) (xy 108.383964 -276.215878)
			(xy 108.334685 -276.199866) (xy 108.288518 -276.176343) (xy 108.246599 -276.145887) (xy 108.209961 -276.109249)
			(xy 108.179505 -276.06733) (xy 108.155982 -276.021163) (xy 108.13997 -275.971884) (xy 108.131864 -275.920707)
			(xy 108.131356 -275.8948) (xy 108.131947 -275.867082) (xy 108.141272 -275.812436) (xy 108.149898 -275.786088)
			(xy 108.157772 -275.76399) (xy 107.95254 -275.408898) (xy 107.92968 -275.40458) (xy 107.904858 -275.399414)
			(xy 107.857077 -275.382462) (xy 107.812456 -275.358392) (xy 107.772048 -275.327773) (xy 107.736806 -275.291325)
			(xy 107.707562 -275.249911) (xy 107.685006 -275.204506) (xy 107.66967 -275.156182) (xy 107.661916 -275.10608)
			(xy 107.661456 -275.08073) (xy 105.50144 -275.08073) (xy 105.500998 -275.106094) (xy 105.493245 -275.156227)
			(xy 105.477898 -275.204578) (xy 105.455318 -275.250004) (xy 105.42604 -275.291431) (xy 105.390756 -275.327878)
			(xy 105.350301 -275.358484) (xy 105.305631 -275.382526) (xy 105.257803 -275.399433) (xy 105.232962 -275.40458)
			(xy 105.209848 -275.408898) (xy 105.00487 -275.76399) (xy 105.012744 -275.786088) (xy 105.021303 -275.812447)
			(xy 105.030503 -275.867092) (xy 105.031032 -275.8948) (xy 105.030524 -275.920687) (xy 105.030521 -275.920707)
			(xy 106.252016 -275.920707) (xy 106.252016 -275.868893) (xy 106.260122 -275.817717) (xy 106.276133 -275.768439)
			(xy 106.299656 -275.722272) (xy 106.330111 -275.680353) (xy 106.366749 -275.643715) (xy 106.408667 -275.613259)
			(xy 106.454833 -275.589735) (xy 106.504111 -275.573723) (xy 106.555287 -275.565617) (xy 106.581194 -275.565108)
			(xy 106.606706 -275.56559) (xy 106.65712 -275.57345) (xy 106.705722 -275.588983) (xy 106.75135 -275.611818)
			(xy 106.792916 -275.64141) (xy 106.829426 -275.677053) (xy 106.8451 -275.697188) (xy 107.257088 -275.697188)
			(xy 107.272765 -275.677056) (xy 107.309275 -275.641412) (xy 107.350839 -275.611819) (xy 107.396467 -275.588982)
			(xy 107.445068 -275.573448) (xy 107.495482 -275.565586) (xy 107.520994 -275.565108) (xy 107.546904 -275.565589)
			(xy 107.598085 -275.573695) (xy 107.647369 -275.589707) (xy 107.693541 -275.613232) (xy 107.735464 -275.64369)
			(xy 107.772106 -275.680332) (xy 107.802565 -275.722254) (xy 107.826091 -275.768426) (xy 107.842104 -275.817709)
			(xy 107.85021 -275.86889) (xy 107.85021 -275.92071) (xy 107.842104 -275.971891) (xy 107.826091 -276.021174)
			(xy 107.802565 -276.067346) (xy 107.772106 -276.109268) (xy 107.735464 -276.14591) (xy 107.693541 -276.176368)
			(xy 107.647369 -276.199893) (xy 107.598085 -276.215905) (xy 107.546904 -276.224011) (xy 107.520994 -276.224492)
			(xy 107.495482 -276.224019) (xy 107.445067 -276.216157) (xy 107.396465 -276.200622) (xy 107.350837 -276.177785)
			(xy 107.309271 -276.148192) (xy 107.272762 -276.112547) (xy 107.257088 -276.092412) (xy 106.8451 -276.092412)
			(xy 106.82943 -276.11255) (xy 106.792919 -276.148193) (xy 106.751353 -276.177786) (xy 106.705724 -276.200622)
			(xy 106.657121 -276.216155) (xy 106.606706 -276.224015) (xy 106.581194 -276.224492) (xy 106.555287 -276.223983)
			(xy 106.504111 -276.215877) (xy 106.454833 -276.199865) (xy 106.408667 -276.176341) (xy 106.366749 -276.145885)
			(xy 106.330111 -276.109247) (xy 106.299656 -276.067328) (xy 106.276133 -276.021161) (xy 106.260122 -275.971883)
			(xy 106.252016 -275.920707) (xy 105.030521 -275.920707) (xy 105.022425 -275.971825) (xy 105.006426 -276.021065)
			(xy 104.98292 -276.067197) (xy 104.952488 -276.109084) (xy 104.915878 -276.145694) (xy 104.873991 -276.176126)
			(xy 104.827859 -276.199632) (xy 104.778619 -276.215631) (xy 104.727481 -276.22373) (xy 104.675707 -276.22373)
			(xy 104.624569 -276.215631) (xy 104.575329 -276.199632) (xy 104.529197 -276.176126) (xy 104.48731 -276.145694)
			(xy 104.4507 -276.109084) (xy 104.420268 -276.067197) (xy 104.396762 -276.021065) (xy 104.380763 -275.971825)
			(xy 104.372664 -275.920687) (xy 104.372156 -275.8948) (xy 103.151432 -275.8948) (xy 103.150966 -275.920146)
			(xy 103.143192 -275.97024) (xy 103.127843 -276.018553) (xy 103.105281 -276.063948) (xy 103.076038 -276.105356)
			(xy 103.040801 -276.1418) (xy 103.000402 -276.172421) (xy 102.955792 -276.196499) (xy 102.908023 -276.213466)
			(xy 102.883208 -276.21865) (xy 102.860348 -276.222968) (xy 102.65537 -276.577806) (xy 102.663244 -276.599904)
			(xy 102.671807 -276.626262) (xy 102.681004 -276.680908) (xy 102.681532 -276.708616) (xy 102.962456 -276.708616)
			(xy 102.962964 -276.682709) (xy 102.97107 -276.631532) (xy 102.987082 -276.582253) (xy 103.010605 -276.536086)
			(xy 103.041061 -276.494167) (xy 103.077699 -276.457529) (xy 103.119618 -276.427073) (xy 103.165785 -276.40355)
			(xy 103.215064 -276.387538) (xy 103.266241 -276.379432) (xy 103.318055 -276.379432) (xy 103.369232 -276.387538)
			(xy 103.418511 -276.40355) (xy 103.464678 -276.427073) (xy 103.506597 -276.457529) (xy 103.543235 -276.494167)
			(xy 103.573691 -276.536086) (xy 103.597214 -276.582253) (xy 103.613226 -276.631532) (xy 103.621332 -276.682709)
			(xy 103.62184 -276.708616) (xy 103.621308 -276.734511) (xy 103.902706 -276.734511) (xy 103.902706 -276.682689)
			(xy 103.910813 -276.631506) (xy 103.926828 -276.582222) (xy 103.950356 -276.53605) (xy 103.980818 -276.494128)
			(xy 104.017464 -276.457487) (xy 104.059391 -276.427031) (xy 104.105566 -276.40351) (xy 104.154853 -276.387502)
			(xy 104.206037 -276.379402) (xy 104.231948 -276.378924) (xy 104.257462 -276.37936) (xy 104.307879 -276.387228)
			(xy 104.356482 -276.40277) (xy 104.40211 -276.425614) (xy 104.443674 -276.455215) (xy 104.480182 -276.490865)
			(xy 104.495854 -276.511004) (xy 104.907842 -276.511004) (xy 104.923492 -276.490849) (xy 104.960006 -276.455206)
			(xy 105.001577 -276.425615) (xy 105.04721 -276.402782) (xy 105.095816 -276.387253) (xy 105.146235 -276.379398)
			(xy 105.171748 -276.378924) (xy 105.197654 -276.379404) (xy 105.248828 -276.387515) (xy 105.298102 -276.403532)
			(xy 105.344265 -276.427059) (xy 105.38618 -276.457517) (xy 105.422814 -276.494157) (xy 105.453266 -276.536076)
			(xy 105.476786 -276.582242) (xy 105.492796 -276.631519) (xy 105.5009 -276.682694) (xy 105.5009 -276.734506)
			(xy 105.492796 -276.785681) (xy 105.476786 -276.834958) (xy 105.453266 -276.881124) (xy 105.422814 -276.923043)
			(xy 105.38618 -276.959683) (xy 105.344265 -276.990141) (xy 105.298102 -277.013668) (xy 105.248828 -277.029685)
			(xy 105.197654 -277.037796) (xy 105.171748 -277.038308) (xy 105.146238 -277.037789) (xy 105.095825 -277.029936)
			(xy 105.047224 -277.01441) (xy 105.001596 -276.991582) (xy 104.960029 -276.961996) (xy 104.923517 -276.92636)
			(xy 104.907842 -276.906228) (xy 104.495854 -276.906228) (xy 104.480157 -276.926344) (xy 104.443651 -276.961988)
			(xy 104.40209 -276.991583) (xy 104.356467 -277.014422) (xy 104.307869 -277.029961) (xy 104.257458 -277.037827)
			(xy 104.231948 -277.038308) (xy 104.206037 -277.037798) (xy 104.154853 -277.029698) (xy 104.105566 -277.01369)
			(xy 104.059391 -276.990169) (xy 104.017464 -276.959713) (xy 103.980818 -276.923072) (xy 103.950356 -276.88115)
			(xy 103.926828 -276.834978) (xy 103.910813 -276.785694) (xy 103.902706 -276.734511) (xy 103.621308 -276.734511)
			(xy 103.621269 -276.736398) (xy 103.611945 -276.791174) (xy 103.603298 -276.817582) (xy 103.595424 -276.839426)
			(xy 103.800402 -277.194264) (xy 103.823262 -277.198582) (xy 103.848063 -277.203782) (xy 103.895803 -277.220766)
			(xy 103.940382 -277.244857) (xy 103.98075 -277.275485) (xy 104.015954 -277.311931) (xy 104.045167 -277.353334)
			(xy 104.067699 -277.398721) (xy 104.083021 -277.44702) (xy 104.09077 -277.497096) (xy 104.091232 -277.522432)
			(xy 106.251756 -277.522432) (xy 106.252213 -277.497097) (xy 106.259974 -277.447026) (xy 106.275303 -277.39873)
			(xy 106.297839 -277.353349) (xy 106.327053 -277.311948) (xy 106.362255 -277.275504) (xy 106.402618 -277.244873)
			(xy 106.447192 -277.220777) (xy 106.494926 -277.203783) (xy 106.519726 -277.198582) (xy 106.542586 -277.194264)
			(xy 106.747818 -276.838918) (xy 106.740198 -276.817074) (xy 106.731593 -276.790786) (xy 106.722266 -276.736269)
			(xy 106.721656 -276.708616) (xy 106.722164 -276.682709) (xy 106.73027 -276.631532) (xy 106.746282 -276.582253)
			(xy 106.769805 -276.536086) (xy 106.800261 -276.494167) (xy 106.836899 -276.457529) (xy 106.878818 -276.427073)
			(xy 106.924985 -276.40355) (xy 106.974264 -276.387538) (xy 107.025441 -276.379432) (xy 107.077255 -276.379432)
			(xy 107.128432 -276.387538) (xy 107.177711 -276.40355) (xy 107.223878 -276.427073) (xy 107.265797 -276.457529)
			(xy 107.302435 -276.494167) (xy 107.332891 -276.536086) (xy 107.356414 -276.582253) (xy 107.372426 -276.631532)
			(xy 107.380532 -276.682709) (xy 107.38104 -276.708616) (xy 108.601256 -276.708616) (xy 108.601789 -276.683284)
			(xy 108.609538 -276.633215) (xy 108.624856 -276.584922) (xy 108.647381 -276.53954) (xy 108.676585 -276.498139)
			(xy 108.711779 -276.461694) (xy 108.752134 -276.431062) (xy 108.796701 -276.406964) (xy 108.844429 -276.389968)
			(xy 108.869226 -276.384766) (xy 108.892086 -276.380448) (xy 109.097064 -276.02561) (xy 109.08919 -276.003766)
			(xy 109.080545 -275.977358) (xy 109.071224 -275.922582) (xy 109.070648 -275.8948) (xy 109.071156 -275.868893)
			(xy 109.079262 -275.817716) (xy 109.095274 -275.768437) (xy 109.118797 -275.72227) (xy 109.149253 -275.680351)
			(xy 109.185891 -275.643713) (xy 109.22781 -275.613257) (xy 109.273977 -275.589734) (xy 109.323256 -275.573722)
			(xy 109.374433 -275.565616) (xy 109.426247 -275.565616) (xy 109.477424 -275.573722) (xy 109.526703 -275.589734)
			(xy 109.57287 -275.613257) (xy 109.614789 -275.643713) (xy 109.651427 -275.680351) (xy 109.681883 -275.72227)
			(xy 109.705406 -275.768437) (xy 109.721418 -275.817716) (xy 109.729524 -275.868893) (xy 109.730032 -275.8948)
			(xy 109.729566 -275.920146) (xy 109.721792 -275.97024) (xy 109.706443 -276.018553) (xy 109.683881 -276.063948)
			(xy 109.654638 -276.105356) (xy 109.619401 -276.1418) (xy 109.579002 -276.172421) (xy 109.534392 -276.196499)
			(xy 109.486623 -276.213466) (xy 109.461808 -276.21865) (xy 109.438948 -276.222968) (xy 109.23397 -276.577806)
			(xy 109.241844 -276.599904) (xy 109.250407 -276.626262) (xy 109.259604 -276.680908) (xy 109.260132 -276.708616)
			(xy 349.962724 -276.708616) (xy 349.963202 -276.683281) (xy 349.970953 -276.633207) (xy 349.986274 -276.584909)
			(xy 350.008806 -276.539525) (xy 350.038016 -276.498122) (xy 350.073218 -276.461676) (xy 350.113581 -276.431046)
			(xy 350.158157 -276.406953) (xy 350.205894 -276.389964) (xy 350.230694 -276.384766) (xy 350.253554 -276.380448)
			(xy 350.458532 -276.025356) (xy 350.450912 -276.003512) (xy 350.442352 -275.977154) (xy 350.433153 -275.922508)
			(xy 350.432624 -275.8948) (xy 350.433132 -275.868913) (xy 350.441231 -275.817775) (xy 350.45723 -275.768535)
			(xy 350.480736 -275.722403) (xy 350.511168 -275.680516) (xy 350.547778 -275.643906) (xy 350.589665 -275.613474)
			(xy 350.635797 -275.589968) (xy 350.685037 -275.573969) (xy 350.736175 -275.56587) (xy 350.787949 -275.56587)
			(xy 350.839087 -275.573969) (xy 350.888327 -275.589968) (xy 350.934459 -275.613474) (xy 350.976346 -275.643906)
			(xy 351.012956 -275.680516) (xy 351.043388 -275.722403) (xy 351.066894 -275.768535) (xy 351.082893 -275.817775)
			(xy 351.090992 -275.868913) (xy 351.0915 -275.8948) (xy 352.312224 -275.8948) (xy 352.312688 -275.869465)
			(xy 352.320441 -275.81939) (xy 352.335764 -275.771092) (xy 352.358298 -275.725707) (xy 352.38751 -275.684304)
			(xy 352.422713 -275.647859) (xy 352.463078 -275.617229) (xy 352.507655 -275.593136) (xy 352.555393 -275.576148)
			(xy 352.580194 -275.57095) (xy 352.603054 -275.566632) (xy 352.808286 -275.211286) (xy 352.800666 -275.189188)
			(xy 352.792042 -275.162906) (xy 352.782727 -275.108385) (xy 352.782124 -275.08073) (xy 352.782632 -275.054823)
			(xy 352.790738 -275.003646) (xy 352.80675 -274.954367) (xy 352.830273 -274.9082) (xy 352.860729 -274.866281)
			(xy 352.897367 -274.829643) (xy 352.939286 -274.799187) (xy 352.985453 -274.775664) (xy 353.034732 -274.759652)
			(xy 353.085909 -274.751546) (xy 353.137723 -274.751546) (xy 353.1889 -274.759652) (xy 353.238179 -274.775664)
			(xy 353.284346 -274.799187) (xy 353.326265 -274.829643) (xy 353.362903 -274.866281) (xy 353.393359 -274.9082)
			(xy 353.416882 -274.954367) (xy 353.432894 -275.003646) (xy 353.441 -275.054823) (xy 353.441508 -275.08073)
			(xy 355.601524 -275.08073) (xy 355.602032 -275.054823) (xy 355.610138 -275.003646) (xy 355.62615 -274.954367)
			(xy 355.649673 -274.9082) (xy 355.680129 -274.866281) (xy 355.716767 -274.829643) (xy 355.758686 -274.799187)
			(xy 355.804853 -274.775664) (xy 355.854132 -274.759652) (xy 355.905309 -274.751546) (xy 355.957123 -274.751546)
			(xy 356.0083 -274.759652) (xy 356.057579 -274.775664) (xy 356.103746 -274.799187) (xy 356.145665 -274.829643)
			(xy 356.182303 -274.866281) (xy 356.212759 -274.9082) (xy 356.236282 -274.954367) (xy 356.252294 -275.003646)
			(xy 356.2604 -275.054823) (xy 356.260908 -275.08073) (xy 356.260296 -275.108446) (xy 356.250985 -275.163093)
			(xy 356.242366 -275.189442) (xy 356.234492 -275.21154) (xy 356.439724 -275.566632) (xy 356.462584 -275.57095)
			(xy 356.4874 -275.576135) (xy 356.535176 -275.593092) (xy 356.579792 -275.617163) (xy 356.620197 -275.647782)
			(xy 356.655436 -275.684226) (xy 356.684681 -275.725636) (xy 356.707239 -275.771036) (xy 356.722581 -275.819355)
			(xy 356.730343 -275.869452) (xy 356.730808 -275.8948) (xy 356.7303 -275.920707) (xy 356.722194 -275.971884)
			(xy 356.706182 -276.021163) (xy 356.682659 -276.06733) (xy 356.652203 -276.109249) (xy 356.615565 -276.145887)
			(xy 356.573646 -276.176343) (xy 356.527479 -276.199866) (xy 356.4782 -276.215878) (xy 356.427023 -276.223984)
			(xy 356.375209 -276.223984) (xy 356.324032 -276.215878) (xy 356.274753 -276.199866) (xy 356.228586 -276.176343)
			(xy 356.186667 -276.145887) (xy 356.150029 -276.109249) (xy 356.119573 -276.06733) (xy 356.09605 -276.021163)
			(xy 356.080038 -275.971884) (xy 356.071932 -275.920707) (xy 356.071424 -275.8948) (xy 356.072017 -275.867083)
			(xy 356.081341 -275.812436) (xy 356.089966 -275.786088) (xy 356.09784 -275.76399) (xy 355.892608 -275.408898)
			(xy 355.869748 -275.40458) (xy 355.844921 -275.399437) (xy 355.79714 -275.382481) (xy 355.75252 -275.358407)
			(xy 355.712113 -275.327784) (xy 355.676872 -275.291334) (xy 355.647629 -275.249917) (xy 355.625073 -275.20451)
			(xy 355.609738 -275.156184) (xy 355.601984 -275.10608) (xy 355.601524 -275.08073) (xy 353.441508 -275.08073)
			(xy 353.441092 -275.106096) (xy 353.433338 -275.156231) (xy 353.417989 -275.204584) (xy 353.395406 -275.250011)
			(xy 353.366125 -275.291439) (xy 353.330837 -275.327886) (xy 353.290378 -275.358492) (xy 353.245704 -275.382531)
			(xy 353.197873 -275.399435) (xy 353.17303 -275.40458) (xy 353.149916 -275.408898) (xy 352.944938 -275.76399)
			(xy 352.952812 -275.786088) (xy 352.96137 -275.812447) (xy 352.97057 -275.867092) (xy 352.9711 -275.8948)
			(xy 352.970592 -275.920687) (xy 352.970589 -275.920705) (xy 354.192116 -275.920705) (xy 354.192116 -275.868895)
			(xy 354.200221 -275.817722) (xy 354.21623 -275.768446) (xy 354.23975 -275.722282) (xy 354.270202 -275.680364)
			(xy 354.306835 -275.643726) (xy 354.348749 -275.61327) (xy 354.394911 -275.589745) (xy 354.444185 -275.57373)
			(xy 354.495357 -275.565619) (xy 354.521262 -275.565108) (xy 354.546773 -275.565613) (xy 354.597186 -275.573468)
			(xy 354.645788 -275.588996) (xy 354.691416 -275.611827) (xy 354.732982 -275.641416) (xy 354.769494 -275.677055)
			(xy 354.785168 -275.697188) (xy 355.197156 -275.697188) (xy 355.212852 -275.677071) (xy 355.249357 -275.641427)
			(xy 355.290918 -275.611831) (xy 355.336542 -275.588992) (xy 355.38514 -275.573454) (xy 355.435551 -275.565588)
			(xy 355.461062 -275.565108) (xy 355.486973 -275.565587) (xy 355.538159 -275.573688) (xy 355.587447 -275.589698)
			(xy 355.633623 -275.613221) (xy 355.67555 -275.643679) (xy 355.712197 -275.680321) (xy 355.742659 -275.722245)
			(xy 355.766188 -275.768418) (xy 355.782203 -275.817704) (xy 355.79031 -275.868889) (xy 355.79031 -275.920711)
			(xy 355.782203 -275.971896) (xy 355.766188 -276.021182) (xy 355.742659 -276.067355) (xy 355.712197 -276.109279)
			(xy 355.67555 -276.145921) (xy 355.633623 -276.176379) (xy 355.587447 -276.199902) (xy 355.538159 -276.215912)
			(xy 355.486973 -276.224013) (xy 355.461062 -276.224492) (xy 355.435549 -276.224043) (xy 355.385133 -276.216176)
			(xy 355.336531 -276.200636) (xy 355.290902 -276.177795) (xy 355.249337 -276.148197) (xy 355.212829 -276.112549)
			(xy 355.197156 -276.092412) (xy 354.785168 -276.092412) (xy 354.769516 -276.112565) (xy 354.733002 -276.148208)
			(xy 354.691432 -276.177799) (xy 354.645799 -276.200632) (xy 354.597193 -276.216162) (xy 354.546775 -276.224017)
			(xy 354.521262 -276.224492) (xy 354.495357 -276.223981) (xy 354.444185 -276.21587) (xy 354.394911 -276.199855)
			(xy 354.348749 -276.17633) (xy 354.306835 -276.145874) (xy 354.270202 -276.109236) (xy 354.23975 -276.067318)
			(xy 354.21623 -276.021154) (xy 354.200221 -275.971878) (xy 354.192116 -275.920705) (xy 352.970589 -275.920705)
			(xy 352.962493 -275.971825) (xy 352.946494 -276.021065) (xy 352.922988 -276.067197) (xy 352.892556 -276.109084)
			(xy 352.855946 -276.145694) (xy 352.814059 -276.176126) (xy 352.767927 -276.199632) (xy 352.718687 -276.215631)
			(xy 352.667549 -276.22373) (xy 352.615775 -276.22373) (xy 352.564637 -276.215631) (xy 352.515397 -276.199632)
			(xy 352.469265 -276.176126) (xy 352.427378 -276.145694) (xy 352.390768 -276.109084) (xy 352.360336 -276.067197)
			(xy 352.33683 -276.021065) (xy 352.320831 -275.971825) (xy 352.312732 -275.920687) (xy 352.312224 -275.8948)
			(xy 351.0915 -275.8948) (xy 351.090979 -275.920144) (xy 351.083207 -275.970232) (xy 351.067862 -276.018541)
			(xy 351.045306 -276.063932) (xy 351.016069 -276.105338) (xy 350.98084 -276.141782) (xy 350.940449 -276.172406)
			(xy 350.895848 -276.196488) (xy 350.848087 -276.213462) (xy 350.823276 -276.21865) (xy 350.800416 -276.222968)
			(xy 350.595438 -276.577806) (xy 350.603312 -276.599904) (xy 350.611874 -276.626262) (xy 350.621072 -276.680908)
			(xy 350.6216 -276.708616) (xy 350.902524 -276.708616) (xy 350.903032 -276.682709) (xy 350.911138 -276.631532)
			(xy 350.92715 -276.582253) (xy 350.950673 -276.536086) (xy 350.981129 -276.494167) (xy 351.017767 -276.457529)
			(xy 351.059686 -276.427073) (xy 351.105853 -276.40355) (xy 351.155132 -276.387538) (xy 351.206309 -276.379432)
			(xy 351.258123 -276.379432) (xy 351.3093 -276.387538) (xy 351.358579 -276.40355) (xy 351.404746 -276.427073)
			(xy 351.446665 -276.457529) (xy 351.483303 -276.494167) (xy 351.513759 -276.536086) (xy 351.537282 -276.582253)
			(xy 351.553294 -276.631532) (xy 351.5614 -276.682709) (xy 351.561908 -276.708616) (xy 351.561377 -276.734509)
			(xy 351.842805 -276.734509) (xy 351.842805 -276.682691) (xy 351.850912 -276.631511) (xy 351.866925 -276.582229)
			(xy 351.89045 -276.53606) (xy 351.920909 -276.494139) (xy 351.957551 -276.457499) (xy 351.999473 -276.427042)
			(xy 352.045644 -276.403519) (xy 352.094927 -276.387508) (xy 352.146107 -276.379404) (xy 352.172016 -276.378924)
			(xy 352.197529 -276.379383) (xy 352.247945 -276.387247) (xy 352.296547 -276.402784) (xy 352.342175 -276.425624)
			(xy 352.38374 -276.45522) (xy 352.420249 -276.490867) (xy 352.435922 -276.511004) (xy 352.84791 -276.511004)
			(xy 352.863579 -276.490865) (xy 352.900089 -276.455221) (xy 352.941656 -276.425628) (xy 352.987285 -276.402792)
			(xy 353.035888 -276.387259) (xy 353.086304 -276.3794) (xy 353.111816 -276.378924) (xy 353.137724 -276.379401)
			(xy 353.188901 -276.387509) (xy 353.23818 -276.403523) (xy 353.284347 -276.427048) (xy 353.326266 -276.457506)
			(xy 353.362904 -276.494146) (xy 353.39336 -276.536066) (xy 353.416883 -276.582235) (xy 353.432895 -276.631514)
			(xy 353.441 -276.682692) (xy 353.441 -276.734508) (xy 353.432895 -276.785686) (xy 353.416883 -276.834965)
			(xy 353.39336 -276.881134) (xy 353.362904 -276.923054) (xy 353.326266 -276.959694) (xy 353.284347 -276.990152)
			(xy 353.23818 -277.013677) (xy 353.188901 -277.029691) (xy 353.137724 -277.037799) (xy 353.111816 -277.038308)
			(xy 353.086305 -277.037813) (xy 353.035891 -277.029955) (xy 352.98729 -277.014424) (xy 352.941662 -276.991591)
			(xy 352.900096 -276.962001) (xy 352.863585 -276.926361) (xy 352.84791 -276.906228) (xy 352.435922 -276.906228)
			(xy 352.420244 -276.926359) (xy 352.383734 -276.962002) (xy 352.342169 -276.991595) (xy 352.296542 -277.014432)
			(xy 352.247941 -277.029967) (xy 352.197528 -277.03783) (xy 352.172016 -277.038308) (xy 352.146107 -277.037796)
			(xy 352.094927 -277.029692) (xy 352.045644 -277.013681) (xy 351.999473 -276.990158) (xy 351.957551 -276.959701)
			(xy 351.920909 -276.923061) (xy 351.89045 -276.88114) (xy 351.866925 -276.834971) (xy 351.850912 -276.785689)
			(xy 351.842805 -276.734509) (xy 351.561377 -276.734509) (xy 351.561338 -276.736398) (xy 351.552014 -276.791174)
			(xy 351.543366 -276.817582) (xy 351.535492 -276.839426) (xy 351.74047 -277.194264) (xy 351.76333 -277.198582)
			(xy 351.788142 -277.203733) (xy 351.835882 -277.220727) (xy 351.88046 -277.244826) (xy 351.920825 -277.275462)
			(xy 351.956028 -277.311913) (xy 351.985239 -277.353322) (xy 352.007769 -277.398712) (xy 352.02309 -277.447016)
			(xy 352.030838 -277.497095) (xy 352.0313 -277.522432) (xy 354.191824 -277.522432) (xy 354.192226 -277.497095)
			(xy 354.199989 -277.447018) (xy 354.215322 -277.398718) (xy 354.237864 -277.353333) (xy 354.267084 -277.31193)
			(xy 354.302294 -277.275486) (xy 354.342666 -277.244857) (xy 354.387248 -277.220766) (xy 354.434991 -277.203779)
			(xy 354.459794 -277.198582) (xy 354.482654 -277.194264) (xy 354.687886 -276.838918) (xy 354.680266 -276.817074)
			(xy 354.671663 -276.790785) (xy 354.662334 -276.736269) (xy 354.661724 -276.708616) (xy 354.662232 -276.682709)
			(xy 354.670338 -276.631532) (xy 354.68635 -276.582253) (xy 354.709873 -276.536086) (xy 354.740329 -276.494167)
			(xy 354.776967 -276.457529) (xy 354.818886 -276.427073) (xy 354.865053 -276.40355) (xy 354.914332 -276.387538)
			(xy 354.965509 -276.379432) (xy 355.017323 -276.379432) (xy 355.0685 -276.387538) (xy 355.117779 -276.40355)
			(xy 355.163946 -276.427073) (xy 355.205865 -276.457529) (xy 355.242503 -276.494167) (xy 355.272959 -276.536086)
			(xy 355.296482 -276.582253) (xy 355.312494 -276.631532) (xy 355.3206 -276.682709) (xy 355.321108 -276.708616)
			(xy 356.541324 -276.708616) (xy 356.541802 -276.683281) (xy 356.549553 -276.633207) (xy 356.564874 -276.584909)
			(xy 356.587406 -276.539525) (xy 356.616616 -276.498122) (xy 356.651818 -276.461676) (xy 356.692181 -276.431046)
			(xy 356.736757 -276.406953) (xy 356.784494 -276.389964) (xy 356.809294 -276.384766) (xy 356.832154 -276.380448)
			(xy 357.037132 -276.02561) (xy 357.029258 -276.003766) (xy 357.020612 -275.977358) (xy 357.011292 -275.922582)
			(xy 357.010716 -275.8948) (xy 357.011224 -275.868893) (xy 357.01933 -275.817716) (xy 357.035342 -275.768437)
			(xy 357.058865 -275.72227) (xy 357.089321 -275.680351) (xy 357.125959 -275.643713) (xy 357.167878 -275.613257)
			(xy 357.214045 -275.589734) (xy 357.263324 -275.573722) (xy 357.314501 -275.565616) (xy 357.366315 -275.565616)
			(xy 357.417492 -275.573722) (xy 357.466771 -275.589734) (xy 357.512938 -275.613257) (xy 357.554857 -275.643713)
			(xy 357.591495 -275.680351) (xy 357.621951 -275.72227) (xy 357.645474 -275.768437) (xy 357.661486 -275.817716)
			(xy 357.669592 -275.868893) (xy 357.6701 -275.8948) (xy 357.669579 -275.920144) (xy 357.661807 -275.970232)
			(xy 357.646462 -276.018541) (xy 357.623906 -276.063932) (xy 357.594669 -276.105338) (xy 357.55944 -276.141782)
			(xy 357.519049 -276.172406) (xy 357.474448 -276.196488) (xy 357.426687 -276.213462) (xy 357.401876 -276.21865)
			(xy 357.379016 -276.222968) (xy 357.174038 -276.577806) (xy 357.181912 -276.599904) (xy 357.190474 -276.626262)
			(xy 357.199672 -276.680908) (xy 357.2002 -276.708616) (xy 357.199692 -276.734503) (xy 357.191593 -276.785641)
			(xy 357.175594 -276.834881) (xy 357.152088 -276.881013) (xy 357.121656 -276.9229) (xy 357.085046 -276.95951)
			(xy 357.043159 -276.989942) (xy 356.997027 -277.013448) (xy 356.947787 -277.029447) (xy 356.896649 -277.037546)
			(xy 356.844875 -277.037546) (xy 356.793737 -277.029447) (xy 356.744497 -277.013448) (xy 356.698365 -276.989942)
			(xy 356.656478 -276.95951) (xy 356.619868 -276.9229) (xy 356.589436 -276.881013) (xy 356.56593 -276.834881)
			(xy 356.549931 -276.785641) (xy 356.541832 -276.734503) (xy 356.541324 -276.708616) (xy 355.321108 -276.708616)
			(xy 355.320641 -276.73399) (xy 355.312871 -276.784141) (xy 355.297501 -276.832506) (xy 355.274895 -276.877942)
			(xy 355.245588 -276.919373) (xy 355.210273 -276.955819) (xy 355.169787 -276.986418) (xy 355.125087 -277.010445)
			(xy 355.07723 -277.027332) (xy 355.052376 -277.032466) (xy 355.029516 -277.036784) (xy 354.824538 -277.391622)
			(xy 354.832412 -277.41372) (xy 354.840977 -277.440077) (xy 354.850173 -277.494724) (xy 354.8507 -277.522432)
			(xy 355.131624 -277.522432) (xy 355.132132 -277.496545) (xy 355.140231 -277.445407) (xy 355.15623 -277.396167)
			(xy 355.179736 -277.350035) (xy 355.210168 -277.308148) (xy 355.246778 -277.271538) (xy 355.288665 -277.241106)
			(xy 355.334797 -277.2176) (xy 355.384037 -277.201601) (xy 355.435175 -277.193502) (xy 355.486949 -277.193502)
			(xy 355.538087 -277.201601) (xy 355.587327 -277.2176) (xy 355.633459 -277.241106) (xy 355.675346 -277.271538)
			(xy 355.711956 -277.308148) (xy 355.742388 -277.350035) (xy 355.765894 -277.396167) (xy 355.781893 -277.445407)
			(xy 355.789992 -277.496545) (xy 355.7905 -277.522432) (xy 355.7905 -277.52294) (xy 355.789963 -277.548303)
			(xy 356.071748 -277.548303) (xy 356.071748 -277.496497) (xy 356.079852 -277.445329) (xy 356.09586 -277.396058)
			(xy 356.119377 -277.349898) (xy 356.149826 -277.307985) (xy 356.186456 -277.271351) (xy 356.228366 -277.240897)
			(xy 356.274523 -277.217374) (xy 356.323792 -277.201361) (xy 356.374959 -277.193251) (xy 356.400862 -277.19274)
			(xy 356.426374 -277.193232) (xy 356.476788 -277.201088) (xy 356.52539 -277.216618) (xy 356.571019 -277.239452)
			(xy 356.612585 -277.269043) (xy 356.649095 -277.304685) (xy 356.664768 -277.32482) (xy 357.076756 -277.32482)
			(xy 357.09246 -277.30471) (xy 357.128963 -277.269063) (xy 357.170522 -277.239467) (xy 357.216144 -277.216626)
			(xy 357.264741 -277.201087) (xy 357.315152 -277.19322) (xy 357.340662 -277.19274) (xy 357.366576 -277.193155)
			(xy 357.417766 -277.201257) (xy 357.467059 -277.217268) (xy 357.51324 -277.240794) (xy 357.555171 -277.271254)
			(xy 357.591821 -277.3079) (xy 357.622286 -277.349828) (xy 357.645817 -277.396006) (xy 357.661834 -277.445297)
			(xy 357.669942 -277.496486) (xy 357.669942 -277.548314) (xy 357.661834 -277.599503) (xy 357.645817 -277.648794)
			(xy 357.622286 -277.694972) (xy 357.591821 -277.7369) (xy 357.555171 -277.773546) (xy 357.51324 -277.804006)
			(xy 357.467059 -277.827532) (xy 357.417766 -277.843543) (xy 357.366576 -277.851645) (xy 357.340662 -277.852124)
			(xy 357.31515 -277.851662) (xy 357.264735 -277.843796) (xy 357.216133 -277.828258) (xy 357.170505 -277.805419)
			(xy 357.12894 -277.775824) (xy 357.09243 -277.74018) (xy 357.076756 -277.720044) (xy 356.664768 -277.720044)
			(xy 356.649125 -277.740204) (xy 356.612608 -277.775845) (xy 356.571036 -277.805434) (xy 356.525401 -277.828266)
			(xy 356.476795 -277.843795) (xy 356.426376 -277.85165) (xy 356.400862 -277.852124) (xy 356.374959 -277.851549)
			(xy 356.323792 -277.843439) (xy 356.274523 -277.827426) (xy 356.228366 -277.803903) (xy 356.186456 -277.773449)
			(xy 356.149826 -277.736815) (xy 356.119377 -277.694902) (xy 356.09586 -277.648742) (xy 356.079852 -277.599471)
			(xy 356.071748 -277.548303) (xy 355.789963 -277.548303) (xy 355.789917 -277.550456) (xy 355.780726 -277.604717)
			(xy 355.772212 -277.63089) (xy 355.764592 -277.652988) (xy 355.969824 -278.008334) (xy 355.992684 -278.012652)
			(xy 356.017501 -278.017836) (xy 356.065277 -278.034792) (xy 356.109893 -278.058863) (xy 356.150297 -278.089482)
			(xy 356.185537 -278.125927) (xy 356.214781 -278.167338) (xy 356.23734 -278.212738) (xy 356.252681 -278.261056)
			(xy 356.260443 -278.311154) (xy 356.260908 -278.336502) (xy 356.2604 -278.362409) (xy 356.252294 -278.413586)
			(xy 356.236282 -278.462865) (xy 356.212759 -278.509032) (xy 356.182303 -278.550951) (xy 356.145665 -278.587589)
			(xy 356.103746 -278.618045) (xy 356.057579 -278.641568) (xy 356.0083 -278.65758) (xy 355.957123 -278.665686)
			(xy 355.905309 -278.665686) (xy 355.854132 -278.65758) (xy 355.804853 -278.641568) (xy 355.758686 -278.618045)
			(xy 355.716767 -278.587589) (xy 355.680129 -278.550951) (xy 355.649673 -278.509032) (xy 355.62615 -278.462865)
			(xy 355.610138 -278.413586) (xy 355.602032 -278.362409) (xy 355.601524 -278.336502) (xy 355.602117 -278.308785)
			(xy 355.611441 -278.254138) (xy 355.620066 -278.22779) (xy 355.62794 -278.205692) (xy 355.422962 -277.8506)
			(xy 355.399848 -277.846282) (xy 355.375022 -277.841137) (xy 355.327241 -277.824181) (xy 355.282621 -277.800107)
			(xy 355.242213 -277.769484) (xy 355.206972 -277.733035) (xy 355.177729 -277.691618) (xy 355.155174 -277.646211)
			(xy 355.139838 -277.597886) (xy 355.132084 -277.547782) (xy 355.131624 -277.522432) (xy 354.8507 -277.522432)
			(xy 354.850192 -277.548319) (xy 354.842093 -277.599457) (xy 354.826094 -277.648697) (xy 354.802588 -277.694829)
			(xy 354.772156 -277.736716) (xy 354.735546 -277.773326) (xy 354.693659 -277.803758) (xy 354.647527 -277.827264)
			(xy 354.598287 -277.843263) (xy 354.547149 -277.851362) (xy 354.495375 -277.851362) (xy 354.444237 -277.843263)
			(xy 354.394997 -277.827264) (xy 354.348865 -277.803758) (xy 354.306978 -277.773326) (xy 354.270368 -277.736716)
			(xy 354.239936 -277.694829) (xy 354.21643 -277.648697) (xy 354.200431 -277.599457) (xy 354.192332 -277.548319)
			(xy 354.191824 -277.522432) (xy 352.0313 -277.522432) (xy 352.030792 -277.548319) (xy 352.022693 -277.599457)
			(xy 352.006694 -277.648697) (xy 351.983188 -277.694829) (xy 351.952756 -277.736716) (xy 351.916146 -277.773326)
			(xy 351.874259 -277.803758) (xy 351.828127 -277.827264) (xy 351.778887 -277.843263) (xy 351.727749 -277.851362)
			(xy 351.675975 -277.851362) (xy 351.624837 -277.843263) (xy 351.575597 -277.827264) (xy 351.529465 -277.803758)
			(xy 351.487578 -277.773326) (xy 351.450968 -277.736716) (xy 351.420536 -277.694829) (xy 351.39703 -277.648697)
			(xy 351.381031 -277.599457) (xy 351.372932 -277.548319) (xy 351.372424 -277.522432) (xy 351.37296 -277.494724)
			(xy 351.382151 -277.440077) (xy 351.390712 -277.41372) (xy 351.398586 -277.391622) (xy 351.193608 -277.036784)
			(xy 351.170748 -277.032466) (xy 351.145918 -277.027336) (xy 351.098136 -277.010379) (xy 351.053515 -276.986304)
			(xy 351.013107 -276.955679) (xy 350.977866 -276.919227) (xy 350.948624 -276.877808) (xy 350.926069 -276.8324)
			(xy 350.910735 -276.784072) (xy 350.902983 -276.733967) (xy 350.902524 -276.708616) (xy 350.6216 -276.708616)
			(xy 350.621092 -276.734503) (xy 350.612993 -276.785641) (xy 350.596994 -276.834881) (xy 350.573488 -276.881013)
			(xy 350.543056 -276.9229) (xy 350.506446 -276.95951) (xy 350.464559 -276.989942) (xy 350.418427 -277.013448)
			(xy 350.369187 -277.029447) (xy 350.318049 -277.037546) (xy 350.266275 -277.037546) (xy 350.215137 -277.029447)
			(xy 350.165897 -277.013448) (xy 350.119765 -276.989942) (xy 350.077878 -276.95951) (xy 350.041268 -276.9229)
			(xy 350.010836 -276.881013) (xy 349.98733 -276.834881) (xy 349.971331 -276.785641) (xy 349.963232 -276.734503)
			(xy 349.962724 -276.708616) (xy 109.260132 -276.708616) (xy 109.259624 -276.734503) (xy 109.251525 -276.785641)
			(xy 109.235526 -276.834881) (xy 109.21202 -276.881013) (xy 109.181588 -276.9229) (xy 109.144978 -276.95951)
			(xy 109.103091 -276.989942) (xy 109.056959 -277.013448) (xy 109.007719 -277.029447) (xy 108.956581 -277.037546)
			(xy 108.904807 -277.037546) (xy 108.853669 -277.029447) (xy 108.804429 -277.013448) (xy 108.758297 -276.989942)
			(xy 108.71641 -276.95951) (xy 108.6798 -276.9229) (xy 108.649368 -276.881013) (xy 108.625862 -276.834881)
			(xy 108.609863 -276.785641) (xy 108.601764 -276.734503) (xy 108.601256 -276.708616) (xy 107.38104 -276.708616)
			(xy 107.380628 -276.733993) (xy 107.372856 -276.784149) (xy 107.357482 -276.832518) (xy 107.334871 -276.877958)
			(xy 107.305557 -276.91939) (xy 107.270234 -276.955836) (xy 107.229739 -276.986433) (xy 107.18503 -277.010456)
			(xy 107.137166 -277.027337) (xy 107.112308 -277.032466) (xy 107.089448 -277.036784) (xy 106.88447 -277.391622)
			(xy 106.892344 -277.41372) (xy 106.90091 -277.440076) (xy 106.910105 -277.494723) (xy 106.910632 -277.522432)
			(xy 107.191556 -277.522432) (xy 107.192064 -277.496545) (xy 107.200163 -277.445407) (xy 107.216162 -277.396167)
			(xy 107.239668 -277.350035) (xy 107.2701 -277.308148) (xy 107.30671 -277.271538) (xy 107.348597 -277.241106)
			(xy 107.394729 -277.2176) (xy 107.443969 -277.201601) (xy 107.495107 -277.193502) (xy 107.546881 -277.193502)
			(xy 107.598019 -277.201601) (xy 107.647259 -277.2176) (xy 107.693391 -277.241106) (xy 107.735278 -277.271538)
			(xy 107.771888 -277.308148) (xy 107.80232 -277.350035) (xy 107.825826 -277.396167) (xy 107.841825 -277.445407)
			(xy 107.849924 -277.496545) (xy 107.850432 -277.522432) (xy 107.850432 -277.52294) (xy 107.849894 -277.548305)
			(xy 108.131648 -277.548305) (xy 108.131648 -277.496495) (xy 108.139753 -277.445324) (xy 108.155763 -277.396051)
			(xy 108.179283 -277.349889) (xy 108.209735 -277.307974) (xy 108.24637 -277.271339) (xy 108.288284 -277.240886)
			(xy 108.334445 -277.217365) (xy 108.383718 -277.201354) (xy 108.43489 -277.193249) (xy 108.460794 -277.19274)
			(xy 108.486306 -277.193209) (xy 108.536722 -277.20107) (xy 108.585325 -277.216605) (xy 108.630953 -277.239442)
			(xy 108.672518 -277.269037) (xy 108.709027 -277.304684) (xy 108.7247 -277.32482) (xy 109.136688 -277.32482)
			(xy 109.152374 -277.304695) (xy 109.18888 -277.269049) (xy 109.230443 -277.239454) (xy 109.276069 -277.216616)
			(xy 109.324669 -277.20108) (xy 109.375083 -277.193218) (xy 109.400594 -277.19274) (xy 109.426506 -277.193157)
			(xy 109.477693 -277.201263) (xy 109.526981 -277.217277) (xy 109.573157 -277.240805) (xy 109.615085 -277.271266)
			(xy 109.65173 -277.307911) (xy 109.682192 -277.349838) (xy 109.70572 -277.396013) (xy 109.721735 -277.445301)
			(xy 109.729842 -277.496488) (xy 109.729842 -277.548312) (xy 109.721735 -277.599499) (xy 109.70572 -277.648787)
			(xy 109.682192 -277.694962) (xy 109.65173 -277.736889) (xy 109.615085 -277.773534) (xy 109.573157 -277.803995)
			(xy 109.526981 -277.827523) (xy 109.477693 -277.843537) (xy 109.426506 -277.851643) (xy 109.400594 -277.852124)
			(xy 109.375083 -277.851639) (xy 109.324669 -277.843778) (xy 109.276068 -277.828245) (xy 109.230439 -277.80541)
			(xy 109.188874 -277.775819) (xy 109.152362 -277.740178) (xy 109.136688 -277.720044) (xy 108.7247 -277.720044)
			(xy 108.709039 -277.740189) (xy 108.672525 -277.77583) (xy 108.630957 -277.805422) (xy 108.585326 -277.828256)
			(xy 108.536723 -277.843788) (xy 108.486307 -277.851647) (xy 108.460794 -277.852124) (xy 108.43489 -277.851551)
			(xy 108.383718 -277.843446) (xy 108.334445 -277.827435) (xy 108.288284 -277.803914) (xy 108.24637 -277.773461)
			(xy 108.209735 -277.736826) (xy 108.179283 -277.694911) (xy 108.155763 -277.648749) (xy 108.139753 -277.599476)
			(xy 108.131648 -277.548305) (xy 107.849894 -277.548305) (xy 107.849848 -277.550456) (xy 107.840658 -277.604717)
			(xy 107.832144 -277.63089) (xy 107.824524 -277.652988) (xy 108.029756 -278.008334) (xy 108.052616 -278.012652)
			(xy 108.077422 -278.017885) (xy 108.125198 -278.034831) (xy 108.169815 -278.058894) (xy 108.210222 -278.089506)
			(xy 108.245463 -278.125945) (xy 108.27471 -278.16735) (xy 108.29727 -278.212746) (xy 108.312612 -278.261061)
			(xy 108.320375 -278.311156) (xy 108.32084 -278.336502) (xy 108.320332 -278.362409) (xy 108.312226 -278.413586)
			(xy 108.296214 -278.462865) (xy 108.272691 -278.509032) (xy 108.242235 -278.550951) (xy 108.205597 -278.587589)
			(xy 108.163678 -278.618045) (xy 108.117511 -278.641568) (xy 108.068232 -278.65758) (xy 108.017055 -278.665686)
			(xy 107.965241 -278.665686) (xy 107.914064 -278.65758) (xy 107.864785 -278.641568) (xy 107.818618 -278.618045)
			(xy 107.776699 -278.587589) (xy 107.740061 -278.550951) (xy 107.709605 -278.509032) (xy 107.686082 -278.462865)
			(xy 107.67007 -278.413586) (xy 107.661964 -278.362409) (xy 107.661456 -278.336502) (xy 107.662047 -278.308784)
			(xy 107.671372 -278.254138) (xy 107.679998 -278.22779) (xy 107.687872 -278.205692) (xy 107.482894 -277.8506)
			(xy 107.45978 -277.846282) (xy 107.434959 -277.841114) (xy 107.387178 -277.824162) (xy 107.342557 -277.800093)
			(xy 107.302149 -277.769473) (xy 107.266907 -277.733026) (xy 107.237663 -277.691612) (xy 107.215107 -277.646207)
			(xy 107.199771 -277.597884) (xy 107.192016 -277.547781) (xy 107.191556 -277.522432) (xy 106.910632 -277.522432)
			(xy 106.910124 -277.548319) (xy 106.902025 -277.599457) (xy 106.886026 -277.648697) (xy 106.86252 -277.694829)
			(xy 106.832088 -277.736716) (xy 106.795478 -277.773326) (xy 106.753591 -277.803758) (xy 106.707459 -277.827264)
			(xy 106.658219 -277.843263) (xy 106.607081 -277.851362) (xy 106.555307 -277.851362) (xy 106.504169 -277.843263)
			(xy 106.454929 -277.827264) (xy 106.408797 -277.803758) (xy 106.36691 -277.773326) (xy 106.3303 -277.736716)
			(xy 106.299868 -277.694829) (xy 106.276362 -277.648697) (xy 106.260363 -277.599457) (xy 106.252264 -277.548319)
			(xy 106.251756 -277.522432) (xy 104.091232 -277.522432) (xy 104.090724 -277.548319) (xy 104.082625 -277.599457)
			(xy 104.066626 -277.648697) (xy 104.04312 -277.694829) (xy 104.012688 -277.736716) (xy 103.976078 -277.773326)
			(xy 103.934191 -277.803758) (xy 103.888059 -277.827264) (xy 103.838819 -277.843263) (xy 103.787681 -277.851362)
			(xy 103.735907 -277.851362) (xy 103.684769 -277.843263) (xy 103.635529 -277.827264) (xy 103.589397 -277.803758)
			(xy 103.54751 -277.773326) (xy 103.5109 -277.736716) (xy 103.480468 -277.694829) (xy 103.456962 -277.648697)
			(xy 103.440963 -277.599457) (xy 103.432864 -277.548319) (xy 103.432356 -277.522432) (xy 103.432895 -277.494724)
			(xy 103.442084 -277.440078) (xy 103.450644 -277.41372) (xy 103.458518 -277.391622) (xy 103.25354 -277.036784)
			(xy 103.23068 -277.032466) (xy 103.205855 -277.027313) (xy 103.158073 -277.01036) (xy 103.113452 -276.986289)
			(xy 103.073043 -276.955668) (xy 103.037801 -276.919219) (xy 103.008557 -276.877803) (xy 102.986002 -276.832396)
			(xy 102.970667 -276.78407) (xy 102.962915 -276.733966) (xy 102.962456 -276.708616) (xy 102.681532 -276.708616)
			(xy 102.681024 -276.734503) (xy 102.672925 -276.785641) (xy 102.656926 -276.834881) (xy 102.63342 -276.881013)
			(xy 102.602988 -276.9229) (xy 102.566378 -276.95951) (xy 102.524491 -276.989942) (xy 102.478359 -277.013448)
			(xy 102.429119 -277.029447) (xy 102.377981 -277.037546) (xy 102.326207 -277.037546) (xy 102.275069 -277.029447)
			(xy 102.225829 -277.013448) (xy 102.179697 -276.989942) (xy 102.13781 -276.95951) (xy 102.1012 -276.9229)
			(xy 102.070768 -276.881013) (xy 102.047262 -276.834881) (xy 102.031263 -276.785641) (xy 102.023164 -276.734503)
			(xy 102.022656 -276.708616) (xy 2.509012 -276.708616) (xy 2.509012 -279.150318) (xy 101.552756 -279.150318)
			(xy 101.553264 -279.124431) (xy 101.561363 -279.073293) (xy 101.577362 -279.024053) (xy 101.600868 -278.977921)
			(xy 101.6313 -278.936034) (xy 101.66791 -278.899424) (xy 101.709797 -278.868992) (xy 101.755929 -278.845486)
			(xy 101.805169 -278.829487) (xy 101.856307 -278.821388) (xy 101.908081 -278.821388) (xy 101.959219 -278.829487)
			(xy 102.008459 -278.845486) (xy 102.054591 -278.868992) (xy 102.096478 -278.899424) (xy 102.133088 -278.936034)
			(xy 102.16352 -278.977921) (xy 102.187026 -279.024053) (xy 102.203025 -279.073293) (xy 102.211124 -279.124431)
			(xy 102.211632 -279.150318) (xy 102.211632 -279.150826) (xy 102.21109 -279.176186) (xy 102.493088 -279.176186)
			(xy 102.493088 -279.124414) (xy 102.501186 -279.07328) (xy 102.517184 -279.024043) (xy 102.540688 -278.977914)
			(xy 102.571118 -278.93603) (xy 102.607725 -278.899422) (xy 102.649609 -278.868991) (xy 102.695737 -278.845487)
			(xy 102.744975 -278.829488) (xy 102.796108 -278.821388) (xy 102.821994 -278.82088) (xy 102.847505 -278.821372)
			(xy 102.897919 -278.829232) (xy 102.94652 -278.844763) (xy 102.992148 -278.867597) (xy 103.033714 -278.897186)
			(xy 103.070226 -278.932826) (xy 103.0859 -278.95296) (xy 103.497888 -278.95296) (xy 103.513557 -278.932822)
			(xy 103.550069 -278.89718) (xy 103.591636 -278.867588) (xy 103.637265 -278.844752) (xy 103.685867 -278.829219)
			(xy 103.736282 -278.821357) (xy 103.761794 -278.82088) (xy 103.787685 -278.821325) (xy 103.83883 -278.829425)
			(xy 103.888078 -278.845425) (xy 103.934217 -278.868934) (xy 103.97611 -278.89937) (xy 104.012726 -278.935985)
			(xy 104.043163 -278.977878) (xy 104.066672 -279.024016) (xy 104.082674 -279.073264) (xy 104.090775 -279.124409)
			(xy 104.090775 -279.150318) (xy 349.492824 -279.150318) (xy 349.493332 -279.124431) (xy 349.501431 -279.073293)
			(xy 349.51743 -279.024053) (xy 349.540936 -278.977921) (xy 349.571368 -278.936034) (xy 349.607978 -278.899424)
			(xy 349.649865 -278.868992) (xy 349.695997 -278.845486) (xy 349.745237 -278.829487) (xy 349.796375 -278.821388)
			(xy 349.848149 -278.821388) (xy 349.899287 -278.829487) (xy 349.948527 -278.845486) (xy 349.994659 -278.868992)
			(xy 350.036546 -278.899424) (xy 350.073156 -278.936034) (xy 350.103588 -278.977921) (xy 350.127094 -279.024053)
			(xy 350.143093 -279.073293) (xy 350.151192 -279.124431) (xy 350.1517 -279.150318) (xy 350.1517 -279.150826)
			(xy 350.15116 -279.176184) (xy 350.433187 -279.176184) (xy 350.433187 -279.124416) (xy 350.441285 -279.073285)
			(xy 350.457281 -279.02405) (xy 350.480782 -278.977924) (xy 350.511209 -278.936041) (xy 350.547812 -278.899433)
			(xy 350.589691 -278.869002) (xy 350.635815 -278.845496) (xy 350.685048 -278.829494) (xy 350.736178 -278.82139)
			(xy 350.762062 -278.82088) (xy 350.787572 -278.821396) (xy 350.837985 -278.82925) (xy 350.886585 -278.844777)
			(xy 350.932214 -278.867606) (xy 350.97378 -278.897192) (xy 351.010293 -278.932828) (xy 351.025968 -278.95296)
			(xy 351.437956 -278.95296) (xy 351.453644 -278.932837) (xy 351.490152 -278.897194) (xy 351.531715 -278.8676)
			(xy 351.57734 -278.844762) (xy 351.625939 -278.829225) (xy 351.676351 -278.82136) (xy 351.701862 -278.82088)
			(xy 351.727755 -278.821322) (xy 351.778904 -278.829418) (xy 351.828156 -278.845416) (xy 351.874299 -278.868923)
			(xy 351.916197 -278.899359) (xy 351.952817 -278.935974) (xy 351.983257 -278.977868) (xy 352.006769 -279.024009)
			(xy 352.022773 -279.073259) (xy 352.030875 -279.124407) (xy 352.030875 -279.176193) (xy 352.022773 -279.227341)
			(xy 352.006769 -279.276591) (xy 351.983257 -279.322732) (xy 351.952817 -279.364626) (xy 351.916197 -279.401241)
			(xy 351.874299 -279.431677) (xy 351.828156 -279.455184) (xy 351.778904 -279.471182) (xy 351.727755 -279.479278)
			(xy 351.701862 -279.479756) (xy 351.676348 -279.47932) (xy 351.625931 -279.471453) (xy 351.577328 -279.455912)
			(xy 351.531699 -279.433068) (xy 351.490135 -279.403466) (xy 351.453628 -279.367815) (xy 351.437956 -279.347676)
			(xy 351.025968 -279.347676) (xy 351.010307 -279.367822) (xy 350.973795 -279.403466) (xy 350.932228 -279.433059)
			(xy 350.886597 -279.455894) (xy 350.837992 -279.471425) (xy 350.787575 -279.479281) (xy 350.762062 -279.479756)
			(xy 350.736178 -279.47921) (xy 350.685048 -279.471106) (xy 350.635815 -279.455104) (xy 350.589691 -279.431598)
			(xy 350.547812 -279.401167) (xy 350.511209 -279.364559) (xy 350.480782 -279.322676) (xy 350.457281 -279.27655)
			(xy 350.441285 -279.227315) (xy 350.433187 -279.176184) (xy 350.15116 -279.176184) (xy 350.151114 -279.178342)
			(xy 350.141925 -279.232603) (xy 350.133412 -279.258776) (xy 350.125792 -279.28062) (xy 350.331024 -279.635966)
			(xy 350.353884 -279.640284) (xy 350.378708 -279.645438) (xy 350.426486 -279.662396) (xy 350.471104 -279.68647)
			(xy 350.511509 -279.717093) (xy 350.546749 -279.753542) (xy 350.575992 -279.794956) (xy 350.598549 -279.84036)
			(xy 350.613887 -279.888683) (xy 350.621645 -279.938785) (xy 350.622108 -279.964134) (xy 350.6216 -279.990041)
			(xy 350.613494 -280.041218) (xy 350.597482 -280.090497) (xy 350.573959 -280.136664) (xy 350.543503 -280.178583)
			(xy 350.506865 -280.215221) (xy 350.464946 -280.245677) (xy 350.418779 -280.2692) (xy 350.3695 -280.285212)
			(xy 350.318323 -280.293318) (xy 350.266509 -280.293318) (xy 350.215332 -280.285212) (xy 350.166053 -280.2692)
			(xy 350.119886 -280.245677) (xy 350.077967 -280.215221) (xy 350.041329 -280.178583) (xy 350.010873 -280.136664)
			(xy 349.98735 -280.090497) (xy 349.971338 -280.041218) (xy 349.963232 -279.990041) (xy 349.962724 -279.964134)
			(xy 349.963325 -279.936417) (xy 349.972644 -279.88177) (xy 349.981266 -279.855422) (xy 349.98914 -279.833324)
			(xy 349.784162 -279.478486) (xy 349.761302 -279.474168) (xy 349.736475 -279.468982) (xy 349.688671 -279.452048)
			(xy 349.644023 -279.427992) (xy 349.603586 -279.397383) (xy 349.568314 -279.360942) (xy 349.539039 -279.319529)
			(xy 349.516451 -279.274121) (xy 349.501083 -279.22579) (xy 349.493299 -279.175676) (xy 349.492824 -279.150318)
			(xy 104.090775 -279.150318) (xy 104.090775 -279.176191) (xy 104.082674 -279.227336) (xy 104.066672 -279.276584)
			(xy 104.043163 -279.322722) (xy 104.012726 -279.364615) (xy 103.97611 -279.40123) (xy 103.934217 -279.431666)
			(xy 103.888078 -279.455175) (xy 103.83883 -279.471175) (xy 103.787685 -279.479275) (xy 103.761794 -279.479756)
			(xy 103.736281 -279.479297) (xy 103.685865 -279.471435) (xy 103.637262 -279.455898) (xy 103.591633 -279.433058)
			(xy 103.550069 -279.403461) (xy 103.51356 -279.367813) (xy 103.497888 -279.347676) (xy 103.0859 -279.347676)
			(xy 103.07022 -279.367806) (xy 103.033713 -279.403452) (xy 102.992149 -279.433046) (xy 102.946521 -279.455884)
			(xy 102.89792 -279.471418) (xy 102.847506 -279.479279) (xy 102.821994 -279.479756) (xy 102.796108 -279.479212)
			(xy 102.744975 -279.471112) (xy 102.695737 -279.455113) (xy 102.649609 -279.431609) (xy 102.607725 -279.401178)
			(xy 102.571118 -279.36457) (xy 102.540688 -279.322686) (xy 102.517184 -279.276557) (xy 102.501186 -279.22732)
			(xy 102.493088 -279.176186) (xy 102.21109 -279.176186) (xy 102.211044 -279.178342) (xy 102.201856 -279.232603)
			(xy 102.193344 -279.258776) (xy 102.185724 -279.28062) (xy 102.390956 -279.635966) (xy 102.413816 -279.640284)
			(xy 102.438629 -279.645487) (xy 102.486407 -279.662435) (xy 102.531027 -279.686501) (xy 102.571434 -279.717117)
			(xy 102.606676 -279.753559) (xy 102.635921 -279.794969) (xy 102.658479 -279.840369) (xy 102.673819 -279.888688)
			(xy 102.681577 -279.938786) (xy 102.68204 -279.964134) (xy 102.681532 -279.990041) (xy 102.673426 -280.041218)
			(xy 102.657414 -280.090497) (xy 102.633891 -280.136664) (xy 102.603435 -280.178583) (xy 102.566797 -280.215221)
			(xy 102.524878 -280.245677) (xy 102.478711 -280.2692) (xy 102.429432 -280.285212) (xy 102.378255 -280.293318)
			(xy 102.326441 -280.293318) (xy 102.275264 -280.285212) (xy 102.225985 -280.2692) (xy 102.179818 -280.245677)
			(xy 102.137899 -280.215221) (xy 102.101261 -280.178583) (xy 102.070805 -280.136664) (xy 102.047282 -280.090497)
			(xy 102.03127 -280.041218) (xy 102.023164 -279.990041) (xy 102.022656 -279.964134) (xy 102.023255 -279.936417)
			(xy 102.032575 -279.88177) (xy 102.041198 -279.855422) (xy 102.049072 -279.833324) (xy 101.844094 -279.478486)
			(xy 101.821234 -279.474168) (xy 101.796412 -279.468959) (xy 101.748608 -279.452029) (xy 101.70396 -279.427978)
			(xy 101.663522 -279.397372) (xy 101.628249 -279.360934) (xy 101.598973 -279.319523) (xy 101.576384 -279.274117)
			(xy 101.561016 -279.225788) (xy 101.553231 -279.175675) (xy 101.552756 -279.150318) (xy 2.509012 -279.150318)
			(xy 2.509012 -279.989984) (xy 88.866003 -279.989984) (xy 88.866003 -279.938216) (xy 88.874102 -279.887084)
			(xy 88.890099 -279.837849) (xy 88.913601 -279.791722) (xy 88.94403 -279.74984) (xy 88.980636 -279.713234)
			(xy 89.022517 -279.682805) (xy 89.068643 -279.659301) (xy 89.117878 -279.643303) (xy 89.16901 -279.635204)
			(xy 89.194894 -279.634696) (xy 89.220406 -279.635183) (xy 89.27082 -279.643042) (xy 89.319421 -279.658575)
			(xy 89.365049 -279.681409) (xy 89.406615 -279.711) (xy 89.443126 -279.746642) (xy 89.4588 -279.766776)
			(xy 89.870788 -279.766776) (xy 89.886462 -279.746641) (xy 89.922972 -279.710998) (xy 89.964538 -279.681405)
			(xy 90.010166 -279.658569) (xy 90.058768 -279.643035) (xy 90.109182 -279.635173) (xy 90.134694 -279.634696)
			(xy 90.160586 -279.635109) (xy 90.211734 -279.643209) (xy 90.260984 -279.659211) (xy 90.307125 -279.68272)
			(xy 90.349021 -279.713158) (xy 90.385638 -279.749775) (xy 90.416077 -279.791669) (xy 90.439587 -279.83781)
			(xy 90.45559 -279.88706) (xy 90.463691 -279.938208) (xy 90.463691 -279.964134) (xy 96.383856 -279.964134)
			(xy 96.384364 -279.938227) (xy 96.39247 -279.88705) (xy 96.408482 -279.837771) (xy 96.432005 -279.791604)
			(xy 96.462461 -279.749685) (xy 96.499099 -279.713047) (xy 96.541018 -279.682591) (xy 96.587185 -279.659068)
			(xy 96.636464 -279.643056) (xy 96.687641 -279.63495) (xy 96.739455 -279.63495) (xy 96.790632 -279.643056)
			(xy 96.839911 -279.659068) (xy 96.886078 -279.682591) (xy 96.927997 -279.713047) (xy 96.964635 -279.749685)
			(xy 96.995091 -279.791604) (xy 97.018614 -279.837771) (xy 97.034626 -279.88705) (xy 97.042732 -279.938227)
			(xy 97.04324 -279.964134) (xy 97.042606 -279.991926) (xy 97.033158 -280.046702) (xy 97.024444 -280.0731)
			(xy 97.016824 -280.095198) (xy 97.221802 -280.450036) (xy 97.244662 -280.454354) (xy 97.269457 -280.45958)
			(xy 97.317195 -280.476563) (xy 97.361773 -280.50065) (xy 97.402139 -280.531276) (xy 97.437344 -280.567718)
			(xy 97.466557 -280.609118) (xy 97.489091 -280.6545) (xy 97.504415 -280.702797) (xy 97.512168 -280.752869)
			(xy 97.512632 -280.778204) (xy 97.512124 -280.804091) (xy 97.504025 -280.855229) (xy 97.488026 -280.904469)
			(xy 97.46452 -280.950601) (xy 97.434088 -280.992488) (xy 97.397478 -281.029098) (xy 97.355591 -281.05953)
			(xy 97.309459 -281.083036) (xy 97.260219 -281.099035) (xy 97.209081 -281.107134) (xy 97.157307 -281.107134)
			(xy 97.106169 -281.099035) (xy 97.056929 -281.083036) (xy 97.010797 -281.05953) (xy 96.96891 -281.029098)
			(xy 96.9323 -280.992488) (xy 96.901868 -280.950601) (xy 96.878362 -280.904469) (xy 96.862363 -280.855229)
			(xy 96.854264 -280.804091) (xy 96.853756 -280.778204) (xy 96.854288 -280.750496) (xy 96.863482 -280.695849)
			(xy 96.872044 -280.669492) (xy 96.879918 -280.647394) (xy 96.674686 -280.292302) (xy 96.651826 -280.287984)
			(xy 96.627038 -280.282731) (xy 96.579302 -280.265749) (xy 96.534727 -280.241664) (xy 96.494362 -280.211041)
			(xy 96.459158 -280.174603) (xy 96.429944 -280.133207) (xy 96.407407 -280.087828) (xy 96.39208 -280.039536)
			(xy 96.384322 -279.989467) (xy 96.383856 -279.964134) (xy 90.463691 -279.964134) (xy 90.463691 -279.989992)
			(xy 90.45559 -280.04114) (xy 90.439587 -280.09039) (xy 90.416077 -280.13653) (xy 90.385638 -280.178425)
			(xy 90.349021 -280.215042) (xy 90.307125 -280.24548) (xy 90.260984 -280.268989) (xy 90.211734 -280.284991)
			(xy 90.160586 -280.293091) (xy 90.134694 -280.293572) (xy 90.109181 -280.293107) (xy 90.058766 -280.285245)
			(xy 90.010163 -280.269709) (xy 89.964535 -280.24687) (xy 89.92297 -280.217275) (xy 89.886461 -280.181628)
			(xy 89.870788 -280.161492) (xy 89.4588 -280.161492) (xy 89.443124 -280.181626) (xy 89.406615 -280.21727)
			(xy 89.365051 -280.246864) (xy 89.319422 -280.269701) (xy 89.270821 -280.285235) (xy 89.220406 -280.293095)
			(xy 89.194894 -280.293572) (xy 89.16901 -280.292996) (xy 89.117878 -280.284897) (xy 89.068643 -280.268899)
			(xy 89.022517 -280.245395) (xy 88.980636 -280.214966) (xy 88.94403 -280.17836) (xy 88.913601 -280.136478)
			(xy 88.890099 -280.090351) (xy 88.874102 -280.041116) (xy 88.866003 -279.989984) (xy 2.509012 -279.989984)
			(xy 2.509012 -280.804107) (xy 86.51622 -280.804107) (xy 86.51622 -280.752293) (xy 86.524326 -280.701118)
			(xy 86.540337 -280.65184) (xy 86.563859 -280.605674) (xy 86.594314 -280.563756) (xy 86.630951 -280.527118)
			(xy 86.672869 -280.496662) (xy 86.719035 -280.473139) (xy 86.768312 -280.457127) (xy 86.819487 -280.449021)
			(xy 86.845394 -280.448512) (xy 86.870888 -280.448996) (xy 86.921265 -280.456856) (xy 86.969828 -280.472391)
			(xy 87.015416 -280.495227) (xy 87.056936 -280.52482) (xy 87.093398 -280.56046) (xy 87.109046 -280.580592)
			(xy 87.521542 -280.580592) (xy 87.537192 -280.560462) (xy 87.573653 -280.52482) (xy 87.615173 -280.495227)
			(xy 87.66076 -280.472389) (xy 87.709323 -280.456853) (xy 87.7597 -280.448991) (xy 87.785194 -280.448512)
			(xy 87.811104 -280.448985) (xy 87.862286 -280.457091) (xy 87.91157 -280.473103) (xy 87.957743 -280.496628)
			(xy 87.999666 -280.527087) (xy 88.036309 -280.563729) (xy 88.066768 -280.605652) (xy 88.090294 -280.651824)
			(xy 88.106308 -280.701108) (xy 88.114414 -280.75229) (xy 88.114414 -280.80411) (xy 88.106308 -280.855292)
			(xy 88.090294 -280.904576) (xy 88.066768 -280.950748) (xy 88.036309 -280.992671) (xy 87.999666 -281.029313)
			(xy 87.957743 -281.059772) (xy 87.91157 -281.083297) (xy 87.862286 -281.099309) (xy 87.811104 -281.107415)
			(xy 87.785194 -281.107896) (xy 87.7597 -281.107418) (xy 87.709323 -281.099555) (xy 87.660759 -281.08402)
			(xy 87.615172 -281.061182) (xy 87.573652 -281.031589) (xy 87.53719 -280.995948) (xy 87.521542 -280.975816)
			(xy 87.109046 -280.975816) (xy 87.093405 -280.995954) (xy 87.056942 -281.031594) (xy 87.01542 -281.061187)
			(xy 86.969831 -281.084023) (xy 86.921267 -281.099558) (xy 86.870888 -281.107418) (xy 86.845394 -281.107896)
			(xy 86.819487 -281.107379) (xy 86.768312 -281.099273) (xy 86.719035 -281.083261) (xy 86.672869 -281.059738)
			(xy 86.630951 -281.029282) (xy 86.594314 -280.992644) (xy 86.563859 -280.950726) (xy 86.540337 -280.90456)
			(xy 86.524326 -280.855282) (xy 86.51622 -280.804107) (xy 2.509012 -280.804107) (xy 2.509012 -282.405836)
			(xy 86.515956 -282.405836) (xy 86.516374 -282.380488) (xy 86.524157 -282.330393) (xy 86.539514 -282.282079)
			(xy 86.562083 -282.236685) (xy 86.591333 -282.195278) (xy 86.626575 -282.158835) (xy 86.666978 -282.128214)
			(xy 86.711591 -282.104137) (xy 86.759364 -282.08717) (xy 86.78418 -282.081986) (xy 86.80704 -282.077668)
			(xy 87.012018 -281.722576) (xy 87.004398 -281.700732) (xy 86.995753 -281.67439) (xy 86.986439 -281.619739)
			(xy 86.985856 -281.59202) (xy 86.986364 -281.566113) (xy 86.99447 -281.514936) (xy 87.010482 -281.465657)
			(xy 87.034005 -281.41949) (xy 87.064461 -281.377571) (xy 87.101099 -281.340933) (xy 87.143018 -281.310477)
			(xy 87.189185 -281.286954) (xy 87.238464 -281.270942) (xy 87.289641 -281.262836) (xy 87.341455 -281.262836)
			(xy 87.392632 -281.270942) (xy 87.441911 -281.286954) (xy 87.488078 -281.310477) (xy 87.529997 -281.340933)
			(xy 87.566635 -281.377571) (xy 87.597091 -281.41949) (xy 87.620614 -281.465657) (xy 87.636626 -281.514936)
			(xy 87.644732 -281.566113) (xy 87.64524 -281.59202) (xy 88.865456 -281.59202) (xy 88.86595 -281.566675)
			(xy 88.87372 -281.516583) (xy 88.889066 -281.468271) (xy 88.911624 -281.422876) (xy 88.940864 -281.381469)
			(xy 88.976098 -281.345025) (xy 89.016493 -281.314403) (xy 89.0611 -281.290323) (xy 89.108866 -281.273355)
			(xy 89.13368 -281.26817) (xy 89.15654 -281.263852) (xy 89.361518 -280.909014) (xy 89.353898 -280.88717)
			(xy 89.345254 -280.860761) (xy 89.335932 -280.805986) (xy 89.335356 -280.778204) (xy 89.335819 -280.752307)
			(xy 89.343918 -280.70115) (xy 89.359916 -280.651889) (xy 89.383421 -280.605736) (xy 89.413854 -280.563826)
			(xy 89.450466 -280.527191) (xy 89.492357 -280.496731) (xy 89.538495 -280.473197) (xy 89.587746 -280.457167)
			(xy 89.638897 -280.449036) (xy 89.664794 -280.448512) (xy 89.690671 -280.448974) (xy 89.741789 -280.457066)
			(xy 89.791012 -280.473052) (xy 89.83713 -280.496539) (xy 89.879007 -280.526949) (xy 89.915615 -280.563533)
			(xy 89.946051 -280.605391) (xy 89.969567 -280.651494) (xy 89.985584 -280.700707) (xy 89.993709 -280.751819)
			(xy 89.994232 -280.777696) (xy 89.994232 -280.778204) (xy 92.154756 -280.778204) (xy 92.155193 -280.752292)
			(xy 92.163301 -280.701107) (xy 92.179316 -280.65182) (xy 92.202845 -280.605646) (xy 92.233308 -280.563722)
			(xy 92.269955 -280.527079) (xy 92.311884 -280.496622) (xy 92.358061 -280.473099) (xy 92.40735 -280.45709)
			(xy 92.458536 -280.44899) (xy 92.484448 -280.448512) (xy 92.510327 -280.448924) (xy 92.561446 -280.457025)
			(xy 92.61067 -280.473018) (xy 92.656788 -280.496511) (xy 92.698665 -280.526927) (xy 92.735272 -280.563516)
			(xy 92.765707 -280.605379) (xy 92.789222 -280.651486) (xy 92.805239 -280.700702) (xy 92.813363 -280.751818)
			(xy 92.813886 -280.777696) (xy 92.813886 -280.778204) (xy 92.813354 -280.804107) (xy 94.97442 -280.804107)
			(xy 94.97442 -280.752293) (xy 94.982526 -280.701118) (xy 94.998537 -280.65184) (xy 95.022059 -280.605674)
			(xy 95.052514 -280.563756) (xy 95.089151 -280.527118) (xy 95.131069 -280.496662) (xy 95.177235 -280.473139)
			(xy 95.226512 -280.457127) (xy 95.277687 -280.449021) (xy 95.303594 -280.448512) (xy 95.329106 -280.448992)
			(xy 95.379521 -280.456852) (xy 95.428122 -280.472385) (xy 95.473751 -280.495221) (xy 95.515316 -280.524814)
			(xy 95.551826 -280.560457) (xy 95.5675 -280.580592) (xy 95.979742 -280.580592) (xy 95.995389 -280.560435)
			(xy 96.031904 -280.524793) (xy 96.073475 -280.495202) (xy 96.119109 -280.472369) (xy 96.167716 -280.45684)
			(xy 96.218134 -280.448986) (xy 96.243648 -280.448512) (xy 96.269553 -280.449016) (xy 96.320725 -280.457128)
			(xy 96.369997 -280.473144) (xy 96.416159 -280.49667) (xy 96.458071 -280.527127) (xy 96.494704 -280.563765)
			(xy 96.525155 -280.605682) (xy 96.548675 -280.651847) (xy 96.564684 -280.701122) (xy 96.572788 -280.752295)
			(xy 96.572788 -280.804105) (xy 96.564684 -280.855278) (xy 96.548675 -280.904553) (xy 96.525155 -280.950718)
			(xy 96.494704 -280.992635) (xy 96.458071 -281.029273) (xy 96.416159 -281.05973) (xy 96.369997 -281.083256)
			(xy 96.320725 -281.099272) (xy 96.269553 -281.107384) (xy 96.243648 -281.107896) (xy 96.218137 -281.107382)
			(xy 96.167724 -281.099529) (xy 96.119123 -281.084002) (xy 96.073495 -281.061173) (xy 96.031928 -281.031586)
			(xy 95.995417 -280.995948) (xy 95.979742 -280.975816) (xy 95.5675 -280.975816) (xy 95.551831 -280.995955)
			(xy 95.51532 -281.031598) (xy 95.473753 -281.06119) (xy 95.428124 -281.084026) (xy 95.379522 -281.099559)
			(xy 95.329106 -281.107419) (xy 95.303594 -281.107896) (xy 95.277687 -281.107379) (xy 95.226512 -281.099273)
			(xy 95.177235 -281.083261) (xy 95.131069 -281.059738) (xy 95.089151 -281.029282) (xy 95.052514 -280.992644)
			(xy 95.022059 -280.950726) (xy 94.998537 -280.90456) (xy 94.982526 -280.855282) (xy 94.97442 -280.804107)
			(xy 92.813354 -280.804107) (xy 92.813315 -280.805986) (xy 92.803991 -280.860762) (xy 92.795344 -280.88717)
			(xy 92.787724 -280.909014) (xy 92.992702 -281.263852) (xy 93.015562 -281.26817) (xy 93.04036 -281.273381)
			(xy 93.0881 -281.290365) (xy 93.132678 -281.314454) (xy 93.173045 -281.345081) (xy 93.20825 -281.381525)
			(xy 93.237463 -281.422927) (xy 93.259996 -281.468312) (xy 93.275318 -281.51661) (xy 93.283069 -281.566685)
			(xy 93.283532 -281.59202) (xy 93.283024 -281.617907) (xy 93.274925 -281.669045) (xy 93.258926 -281.718285)
			(xy 93.23542 -281.764417) (xy 93.204988 -281.806304) (xy 93.168378 -281.842914) (xy 93.126491 -281.873346)
			(xy 93.080359 -281.896852) (xy 93.031119 -281.912851) (xy 92.979981 -281.92095) (xy 92.928207 -281.92095)
			(xy 92.877069 -281.912851) (xy 92.827829 -281.896852) (xy 92.781697 -281.873346) (xy 92.73981 -281.842914)
			(xy 92.7032 -281.806304) (xy 92.672768 -281.764417) (xy 92.649262 -281.718285) (xy 92.633263 -281.669045)
			(xy 92.625164 -281.617907) (xy 92.624656 -281.59202) (xy 92.625203 -281.564313) (xy 92.634391 -281.509667)
			(xy 92.642944 -281.483308) (xy 92.650564 -281.461464) (xy 92.445586 -281.106372) (xy 92.422726 -281.102054)
			(xy 92.397931 -281.096829) (xy 92.350193 -281.079845) (xy 92.305616 -281.055757) (xy 92.265251 -281.025131)
			(xy 92.230046 -280.988689) (xy 92.200833 -280.947289) (xy 92.178299 -280.901907) (xy 92.162974 -280.853611)
			(xy 92.15522 -280.803539) (xy 92.154756 -280.778204) (xy 89.994232 -280.778204) (xy 89.993765 -280.803528)
			(xy 89.986033 -280.853583) (xy 89.970734 -280.901865) (xy 89.94823 -280.947239) (xy 89.91905 -280.988637)
			(xy 89.883881 -281.025084) (xy 89.843551 -281.055722) (xy 89.799008 -281.079831) (xy 89.751302 -281.096842)
			(xy 89.726516 -281.102054) (xy 89.703656 -281.106372) (xy 89.498678 -281.46121) (xy 89.506298 -281.483054)
			(xy 89.51491 -281.50934) (xy 89.524233 -281.563858) (xy 89.52484 -281.591512) (xy 89.52484 -281.59202)
			(xy 89.524332 -281.617905) (xy 90.745336 -281.617905) (xy 90.745336 -281.566095) (xy 90.753441 -281.514922)
			(xy 90.769451 -281.465646) (xy 90.792973 -281.419482) (xy 90.823426 -281.377566) (xy 90.860062 -281.34093)
			(xy 90.901977 -281.310476) (xy 90.948141 -281.286954) (xy 90.997416 -281.270943) (xy 91.048589 -281.262837)
			(xy 91.074494 -281.262328) (xy 91.100006 -281.262802) (xy 91.150421 -281.270662) (xy 91.199024 -281.286196)
			(xy 91.244652 -281.309033) (xy 91.286218 -281.338627) (xy 91.322727 -281.374272) (xy 91.3384 -281.394408)
			(xy 91.750388 -281.394408) (xy 91.766071 -281.37428) (xy 91.802578 -281.338635) (xy 91.844142 -281.309041)
			(xy 91.889768 -281.286203) (xy 91.938369 -281.270668) (xy 91.988782 -281.262806) (xy 92.014294 -281.262328)
			(xy 92.040205 -281.262769) (xy 92.09139 -281.270875) (xy 92.140676 -281.286888) (xy 92.186851 -281.310415)
			(xy 92.228777 -281.340875) (xy 92.265421 -281.377519) (xy 92.295882 -281.419444) (xy 92.319409 -281.465618)
			(xy 92.335423 -281.514904) (xy 92.34353 -281.566089) (xy 92.34353 -281.617911) (xy 92.335423 -281.669096)
			(xy 92.319409 -281.718382) (xy 92.295882 -281.764556) (xy 92.265421 -281.806481) (xy 92.228777 -281.843125)
			(xy 92.186851 -281.873585) (xy 92.140676 -281.897112) (xy 92.09139 -281.913125) (xy 92.040205 -281.921231)
			(xy 92.014294 -281.921712) (xy 91.988782 -281.921231) (xy 91.938368 -281.91337) (xy 91.889767 -281.897836)
			(xy 91.844138 -281.875001) (xy 91.802573 -281.845409) (xy 91.766062 -281.809767) (xy 91.750388 -281.789632)
			(xy 91.3384 -281.789632) (xy 91.322735 -281.809774) (xy 91.286223 -281.845417) (xy 91.244655 -281.875008)
			(xy 91.199025 -281.897843) (xy 91.150422 -281.913376) (xy 91.100006 -281.921235) (xy 91.074494 -281.921712)
			(xy 91.048589 -281.921163) (xy 90.997416 -281.913057) (xy 90.948141 -281.897046) (xy 90.901977 -281.873524)
			(xy 90.860062 -281.84307) (xy 90.823426 -281.806434) (xy 90.792973 -281.764518) (xy 90.769451 -281.718354)
			(xy 90.753441 -281.669078) (xy 90.745336 -281.617905) (xy 89.524332 -281.617905) (xy 89.524332 -281.617927)
			(xy 89.516226 -281.669104) (xy 89.500214 -281.718383) (xy 89.476691 -281.76455) (xy 89.446235 -281.806469)
			(xy 89.409597 -281.843107) (xy 89.367678 -281.873563) (xy 89.321511 -281.897086) (xy 89.272232 -281.913098)
			(xy 89.221055 -281.921204) (xy 89.169241 -281.921204) (xy 89.118064 -281.913098) (xy 89.068785 -281.897086)
			(xy 89.022618 -281.873563) (xy 88.980699 -281.843107) (xy 88.944061 -281.806469) (xy 88.913605 -281.76455)
			(xy 88.890082 -281.718383) (xy 88.87407 -281.669104) (xy 88.865964 -281.617927) (xy 88.865456 -281.59202)
			(xy 87.64524 -281.59202) (xy 87.644785 -281.617367) (xy 87.637009 -281.66746) (xy 87.621658 -281.715773)
			(xy 87.599094 -281.761168) (xy 87.569849 -281.802575) (xy 87.534611 -281.839019) (xy 87.494211 -281.86964)
			(xy 87.449601 -281.893718) (xy 87.401831 -281.910686) (xy 87.377016 -281.91587) (xy 87.354156 -281.920188)
			(xy 87.149178 -282.27528) (xy 87.156798 -282.297124) (xy 87.165433 -282.32347) (xy 87.174753 -282.378118)
			(xy 87.17534 -282.405836) (xy 87.455756 -282.405836) (xy 87.456264 -282.379949) (xy 87.464363 -282.328811)
			(xy 87.480362 -282.279571) (xy 87.503868 -282.233439) (xy 87.5343 -282.191552) (xy 87.57091 -282.154942)
			(xy 87.612797 -282.12451) (xy 87.658929 -282.101004) (xy 87.708169 -282.085005) (xy 87.759307 -282.076906)
			(xy 87.811081 -282.076906) (xy 87.862219 -282.085005) (xy 87.911459 -282.101004) (xy 87.957591 -282.12451)
			(xy 87.999478 -282.154942) (xy 88.036088 -282.191552) (xy 88.06652 -282.233439) (xy 88.090026 -282.279571)
			(xy 88.106025 -282.328811) (xy 88.114124 -282.379949) (xy 88.114632 -282.405836) (xy 88.114145 -282.431709)
			(xy 88.396026 -282.431709) (xy 88.396026 -282.379891) (xy 88.404133 -282.328711) (xy 88.420147 -282.27943)
			(xy 88.443674 -282.233261) (xy 88.474134 -282.191341) (xy 88.510778 -282.154703) (xy 88.552702 -282.124249)
			(xy 88.598874 -282.100729) (xy 88.648158 -282.084722) (xy 88.699339 -282.076622) (xy 88.725248 -282.076144)
			(xy 88.750741 -282.076648) (xy 88.801118 -282.084503) (xy 88.849682 -282.100032) (xy 88.895269 -282.122865)
			(xy 88.936791 -282.152454) (xy 88.973252 -282.188093) (xy 88.9889 -282.208224) (xy 89.401396 -282.208224)
			(xy 89.417024 -282.188075) (xy 89.453488 -282.152433) (xy 89.495013 -282.122841) (xy 89.540604 -282.100006)
			(xy 89.589171 -282.084474) (xy 89.639553 -282.076619) (xy 89.665048 -282.076144) (xy 89.690956 -282.076584)
			(xy 89.742132 -282.084696) (xy 89.79141 -282.100714) (xy 89.837576 -282.124242) (xy 89.879493 -282.154702)
			(xy 89.916129 -282.191344) (xy 89.946583 -282.233265) (xy 89.970105 -282.279434) (xy 89.986115 -282.328714)
			(xy 89.99422 -282.379892) (xy 89.99422 -282.431708) (xy 89.986115 -282.482886) (xy 89.970105 -282.532166)
			(xy 89.946583 -282.578335) (xy 89.916129 -282.620256) (xy 89.879493 -282.656898) (xy 89.837576 -282.687358)
			(xy 89.79141 -282.710886) (xy 89.742132 -282.726904) (xy 89.690956 -282.735016) (xy 89.665048 -282.735528)
			(xy 89.639556 -282.734998) (xy 89.589182 -282.727145) (xy 89.54062 -282.711619) (xy 89.495033 -282.688791)
			(xy 89.453511 -282.659207) (xy 89.417046 -282.623576) (xy 89.401396 -282.603448) (xy 88.9889 -282.603448)
			(xy 88.973236 -282.623567) (xy 88.936776 -282.659207) (xy 88.895259 -282.6888) (xy 88.849675 -282.71164)
			(xy 88.801115 -282.727179) (xy 88.750741 -282.735046) (xy 88.725248 -282.735528) (xy 88.699339 -282.734978)
			(xy 88.648158 -282.726878) (xy 88.598874 -282.710871) (xy 88.552702 -282.687351) (xy 88.510778 -282.656897)
			(xy 88.474134 -282.620259) (xy 88.443674 -282.578339) (xy 88.420147 -282.53217) (xy 88.404133 -282.482889)
			(xy 88.396026 -282.431709) (xy 88.114145 -282.431709) (xy 88.11411 -282.433545) (xy 88.10491 -282.488191)
			(xy 88.096344 -282.514548) (xy 88.08847 -282.536646) (xy 88.293702 -282.891738) (xy 88.316562 -282.896056)
			(xy 88.341357 -282.90128) (xy 88.389096 -282.918263) (xy 88.433673 -282.942351) (xy 88.47404 -282.972977)
			(xy 88.509244 -283.009419) (xy 88.538458 -283.050819) (xy 88.560992 -283.096202) (xy 88.576316 -283.144498)
			(xy 88.584068 -283.194571) (xy 88.584532 -283.219906) (xy 90.745056 -283.219906) (xy 90.74558 -283.194573)
			(xy 90.75333 -283.144505) (xy 90.768649 -283.096211) (xy 90.791176 -283.05083) (xy 90.820381 -283.009429)
			(xy 90.855576 -282.972983) (xy 90.895932 -282.942351) (xy 90.9405 -282.918254) (xy 90.988229 -282.901258)
			(xy 91.013026 -282.896056) (xy 91.035886 -282.891738) (xy 91.241118 -282.536392) (xy 91.233498 -282.514548)
			(xy 91.224857 -282.488204) (xy 91.215541 -282.433555) (xy 91.214956 -282.405836) (xy 91.215464 -282.379929)
			(xy 91.22357 -282.328752) (xy 91.239582 -282.279473) (xy 91.263105 -282.233306) (xy 91.293561 -282.191387)
			(xy 91.330199 -282.154749) (xy 91.372118 -282.124293) (xy 91.418285 -282.10077) (xy 91.467564 -282.084758)
			(xy 91.518741 -282.076652) (xy 91.570555 -282.076652) (xy 91.621732 -282.084758) (xy 91.671011 -282.10077)
			(xy 91.717178 -282.124293) (xy 91.759097 -282.154749) (xy 91.795735 -282.191387) (xy 91.826191 -282.233306)
			(xy 91.849714 -282.279473) (xy 91.865726 -282.328752) (xy 91.873832 -282.379929) (xy 91.87434 -282.405836)
			(xy 93.094556 -282.405836) (xy 93.094974 -282.380488) (xy 93.102757 -282.330393) (xy 93.118114 -282.282079)
			(xy 93.140683 -282.236685) (xy 93.169933 -282.195278) (xy 93.205175 -282.158835) (xy 93.245578 -282.128214)
			(xy 93.290191 -282.104137) (xy 93.337964 -282.08717) (xy 93.36278 -282.081986) (xy 93.38564 -282.077668)
			(xy 93.590618 -281.72283) (xy 93.582744 -281.700986) (xy 93.574162 -281.674568) (xy 93.564967 -281.619792)
			(xy 93.564456 -281.59202) (xy 93.564964 -281.566133) (xy 93.573063 -281.514995) (xy 93.589062 -281.465755)
			(xy 93.612568 -281.419623) (xy 93.643 -281.377736) (xy 93.67961 -281.341126) (xy 93.721497 -281.310694)
			(xy 93.767629 -281.287188) (xy 93.816869 -281.271189) (xy 93.868007 -281.26309) (xy 93.919781 -281.26309)
			(xy 93.970919 -281.271189) (xy 94.020159 -281.287188) (xy 94.066291 -281.310694) (xy 94.108178 -281.341126)
			(xy 94.144788 -281.377736) (xy 94.17522 -281.419623) (xy 94.198726 -281.465755) (xy 94.214725 -281.514995)
			(xy 94.222824 -281.566133) (xy 94.223332 -281.59202) (xy 94.222842 -281.617354) (xy 94.215087 -281.667425)
			(xy 94.199764 -281.71572) (xy 94.177233 -281.761102) (xy 94.148024 -281.802503) (xy 94.112825 -281.838948)
			(xy 94.072465 -281.869579) (xy 94.027893 -281.893676) (xy 93.980161 -281.910669) (xy 93.955362 -281.91587)
			(xy 93.932502 -281.920188) (xy 93.727524 -282.275026) (xy 93.735398 -282.297124) (xy 93.744018 -282.323474)
			(xy 93.753346 -282.378119) (xy 93.75394 -282.405836) (xy 94.974156 -282.405836) (xy 94.974616 -282.380501)
			(xy 94.982377 -282.33043) (xy 94.997705 -282.282135) (xy 95.020241 -282.236753) (xy 95.049454 -282.195352)
			(xy 95.084656 -282.158908) (xy 95.125019 -282.128277) (xy 95.169592 -282.104181) (xy 95.217327 -282.087187)
			(xy 95.242126 -282.081986) (xy 95.264986 -282.077668) (xy 95.470218 -281.722322) (xy 95.462598 -281.700478)
			(xy 95.45397 -281.674197) (xy 95.444658 -281.619675) (xy 95.444056 -281.59202) (xy 95.444564 -281.566113)
			(xy 95.45267 -281.514936) (xy 95.468682 -281.465657) (xy 95.492205 -281.41949) (xy 95.522661 -281.377571)
			(xy 95.559299 -281.340933) (xy 95.601218 -281.310477) (xy 95.647385 -281.286954) (xy 95.696664 -281.270942)
			(xy 95.747841 -281.262836) (xy 95.799655 -281.262836) (xy 95.850832 -281.270942) (xy 95.900111 -281.286954)
			(xy 95.946278 -281.310477) (xy 95.988197 -281.340933) (xy 96.024835 -281.377571) (xy 96.055291 -281.41949)
			(xy 96.078814 -281.465657) (xy 96.094826 -281.514936) (xy 96.102932 -281.566113) (xy 96.10344 -281.59202)
			(xy 97.323656 -281.59202) (xy 97.32415 -281.566675) (xy 97.33192 -281.516583) (xy 97.347266 -281.468271)
			(xy 97.369824 -281.422876) (xy 97.399064 -281.381469) (xy 97.434298 -281.345025) (xy 97.474693 -281.314403)
			(xy 97.5193 -281.290323) (xy 97.567066 -281.273355) (xy 97.59188 -281.26817) (xy 97.61474 -281.263852)
			(xy 97.819718 -280.909014) (xy 97.811844 -280.88717) (xy 97.803259 -280.860753) (xy 97.794066 -280.805977)
			(xy 97.793556 -280.778204) (xy 97.794064 -280.752317) (xy 97.802163 -280.701179) (xy 97.818162 -280.651939)
			(xy 97.841668 -280.605807) (xy 97.8721 -280.56392) (xy 97.90871 -280.52731) (xy 97.950597 -280.496878)
			(xy 97.996729 -280.473372) (xy 98.045969 -280.457373) (xy 98.097107 -280.449274) (xy 98.148881 -280.449274)
			(xy 98.200019 -280.457373) (xy 98.249259 -280.473372) (xy 98.295391 -280.496878) (xy 98.337278 -280.52731)
			(xy 98.373888 -280.56392) (xy 98.40432 -280.605807) (xy 98.427826 -280.651939) (xy 98.443825 -280.701179)
			(xy 98.451924 -280.752317) (xy 98.452432 -280.778204) (xy 100.612956 -280.778204) (xy 100.613464 -280.752317)
			(xy 100.621563 -280.701179) (xy 100.637562 -280.651939) (xy 100.661068 -280.605807) (xy 100.6915 -280.56392)
			(xy 100.72811 -280.52731) (xy 100.769997 -280.496878) (xy 100.816129 -280.473372) (xy 100.865369 -280.457373)
			(xy 100.916507 -280.449274) (xy 100.968281 -280.449274) (xy 101.019419 -280.457373) (xy 101.068659 -280.473372)
			(xy 101.114791 -280.496878) (xy 101.156678 -280.52731) (xy 101.193288 -280.56392) (xy 101.22372 -280.605807)
			(xy 101.247226 -280.651939) (xy 101.263225 -280.701179) (xy 101.271324 -280.752317) (xy 101.271832 -280.778204)
			(xy 103.432356 -280.778204) (xy 103.432864 -280.752317) (xy 103.440963 -280.701179) (xy 103.456962 -280.651939)
			(xy 103.480468 -280.605807) (xy 103.5109 -280.56392) (xy 103.54751 -280.52731) (xy 103.589397 -280.496878)
			(xy 103.635529 -280.473372) (xy 103.684769 -280.457373) (xy 103.735907 -280.449274) (xy 103.787681 -280.449274)
			(xy 103.838819 -280.457373) (xy 103.888059 -280.473372) (xy 103.934191 -280.496878) (xy 103.976078 -280.52731)
			(xy 104.012688 -280.56392) (xy 104.04312 -280.605807) (xy 104.066626 -280.651939) (xy 104.082625 -280.701179)
			(xy 104.090724 -280.752317) (xy 104.091232 -280.778204) (xy 104.372156 -280.778204) (xy 104.372678 -280.752871)
			(xy 104.380429 -280.702803) (xy 104.395748 -280.654509) (xy 104.418275 -280.609127) (xy 104.44748 -280.567726)
			(xy 104.482675 -280.531281) (xy 104.523032 -280.500649) (xy 104.567599 -280.476552) (xy 104.615329 -280.459556)
			(xy 104.640126 -280.454354) (xy 104.662986 -280.450036) (xy 104.868218 -280.09469) (xy 104.860598 -280.072592)
			(xy 104.851973 -280.04631) (xy 104.842659 -279.991789) (xy 104.842056 -279.964134) (xy 104.842564 -279.938227)
			(xy 104.85067 -279.88705) (xy 104.866682 -279.837771) (xy 104.890205 -279.791604) (xy 104.920661 -279.749685)
			(xy 104.957299 -279.713047) (xy 104.999218 -279.682591) (xy 105.045385 -279.659068) (xy 105.094664 -279.643056)
			(xy 105.145841 -279.63495) (xy 105.197655 -279.63495) (xy 105.248832 -279.643056) (xy 105.298111 -279.659068)
			(xy 105.344278 -279.682591) (xy 105.386197 -279.713047) (xy 105.422835 -279.749685) (xy 105.453291 -279.791604)
			(xy 105.476814 -279.837771) (xy 105.492826 -279.88705) (xy 105.500932 -279.938227) (xy 105.50144 -279.964134)
			(xy 105.501001 -279.989499) (xy 105.500926 -279.989983) (xy 336.806103 -279.989983) (xy 336.806103 -279.938217)
			(xy 336.814201 -279.887089) (xy 336.830196 -279.837856) (xy 336.853696 -279.791732) (xy 336.884121 -279.749851)
			(xy 336.920722 -279.713245) (xy 336.9626 -279.682815) (xy 337.008721 -279.659311) (xy 337.057952 -279.64331)
			(xy 337.109079 -279.635206) (xy 337.134962 -279.634696) (xy 337.160473 -279.635206) (xy 337.210886 -279.64306)
			(xy 337.259487 -279.658588) (xy 337.305115 -279.681418) (xy 337.346681 -279.711006) (xy 337.383193 -279.746643)
			(xy 337.398868 -279.766776) (xy 337.810856 -279.766776) (xy 337.826548 -279.746656) (xy 337.863055 -279.711012)
			(xy 337.904617 -279.681418) (xy 337.950241 -279.658579) (xy 337.998839 -279.643041) (xy 338.049251 -279.635176)
			(xy 338.074762 -279.634696) (xy 338.100656 -279.635106) (xy 338.151807 -279.643203) (xy 338.201062 -279.659201)
			(xy 338.247208 -279.682709) (xy 338.289107 -279.713146) (xy 338.325729 -279.749764) (xy 338.356171 -279.79166)
			(xy 338.379684 -279.837803) (xy 338.395689 -279.887056) (xy 338.403791 -279.938206) (xy 338.403791 -279.964134)
			(xy 344.323924 -279.964134) (xy 344.324432 -279.938227) (xy 344.332538 -279.88705) (xy 344.34855 -279.837771)
			(xy 344.372073 -279.791604) (xy 344.402529 -279.749685) (xy 344.439167 -279.713047) (xy 344.481086 -279.682591)
			(xy 344.527253 -279.659068) (xy 344.576532 -279.643056) (xy 344.627709 -279.63495) (xy 344.679523 -279.63495)
			(xy 344.7307 -279.643056) (xy 344.779979 -279.659068) (xy 344.826146 -279.682591) (xy 344.868065 -279.713047)
			(xy 344.904703 -279.749685) (xy 344.935159 -279.791604) (xy 344.958682 -279.837771) (xy 344.974694 -279.88705)
			(xy 344.9828 -279.938227) (xy 344.983308 -279.964134) (xy 344.982671 -279.991925) (xy 344.973225 -280.046702)
			(xy 344.964512 -280.0731) (xy 344.956892 -280.095198) (xy 345.16187 -280.450036) (xy 345.18473 -280.454354)
			(xy 345.209535 -280.459531) (xy 345.257274 -280.476523) (xy 345.30185 -280.500619) (xy 345.342215 -280.531252)
			(xy 345.377417 -280.5677) (xy 345.406629 -280.609105) (xy 345.429161 -280.654492) (xy 345.444484 -280.702792)
			(xy 345.452236 -280.752868) (xy 345.4527 -280.778204) (xy 345.452192 -280.804091) (xy 345.444093 -280.855229)
			(xy 345.428094 -280.904469) (xy 345.404588 -280.950601) (xy 345.374156 -280.992488) (xy 345.337546 -281.029098)
			(xy 345.295659 -281.05953) (xy 345.249527 -281.083036) (xy 345.200287 -281.099035) (xy 345.149149 -281.107134)
			(xy 345.097375 -281.107134) (xy 345.046237 -281.099035) (xy 344.996997 -281.083036) (xy 344.950865 -281.05953)
			(xy 344.908978 -281.029098) (xy 344.872368 -280.992488) (xy 344.841936 -280.950601) (xy 344.81843 -280.904469)
			(xy 344.802431 -280.855229) (xy 344.794332 -280.804091) (xy 344.793824 -280.778204) (xy 344.794353 -280.750496)
			(xy 344.803549 -280.695849) (xy 344.812112 -280.669492) (xy 344.819986 -280.647394) (xy 344.614754 -280.292302)
			(xy 344.591894 -280.287984) (xy 344.567101 -280.282754) (xy 344.519365 -280.265768) (xy 344.47479 -280.241678)
			(xy 344.434426 -280.211052) (xy 344.399223 -280.174611) (xy 344.37001 -280.133213) (xy 344.347475 -280.087832)
			(xy 344.332148 -280.039538) (xy 344.32439 -279.989468) (xy 344.323924 -279.964134) (xy 338.403791 -279.964134)
			(xy 338.403791 -279.989994) (xy 338.395689 -280.041144) (xy 338.379684 -280.090397) (xy 338.356171 -280.13654)
			(xy 338.325729 -280.178436) (xy 338.289107 -280.215054) (xy 338.247208 -280.245491) (xy 338.201062 -280.268999)
			(xy 338.151807 -280.284997) (xy 338.100656 -280.293094) (xy 338.074762 -280.293572) (xy 338.049249 -280.293131)
			(xy 337.998832 -280.285263) (xy 337.950229 -280.269723) (xy 337.9046 -280.24688) (xy 337.863036 -280.21728)
			(xy 337.826528 -280.18163) (xy 337.810856 -280.161492) (xy 337.398868 -280.161492) (xy 337.383211 -280.181641)
			(xy 337.346698 -280.217284) (xy 337.305129 -280.246877) (xy 337.259498 -280.269711) (xy 337.210893 -280.285241)
			(xy 337.160475 -280.293097) (xy 337.134962 -280.293572) (xy 337.109079 -280.292994) (xy 337.057952 -280.28489)
			(xy 337.008721 -280.268889) (xy 336.9626 -280.245385) (xy 336.920722 -280.214955) (xy 336.884121 -280.178349)
			(xy 336.853696 -280.136468) (xy 336.830196 -280.090344) (xy 336.814201 -280.041111) (xy 336.806103 -279.989983)
			(xy 105.500926 -279.989983) (xy 105.493248 -280.039631) (xy 105.4779 -280.087982) (xy 105.45532 -280.133408)
			(xy 105.426041 -280.174835) (xy 105.390757 -280.211282) (xy 105.350301 -280.241888) (xy 105.305631 -280.26593)
			(xy 105.257803 -280.282837) (xy 105.232962 -280.287984) (xy 105.209848 -280.292302) (xy 105.00487 -280.647394)
			(xy 105.012744 -280.669492) (xy 105.021304 -280.69585) (xy 105.030503 -280.750496) (xy 105.031032 -280.778204)
			(xy 105.030524 -280.804091) (xy 105.030521 -280.804107) (xy 105.31222 -280.804107) (xy 105.31222 -280.752293)
			(xy 105.320326 -280.701118) (xy 105.336337 -280.65184) (xy 105.359859 -280.605674) (xy 105.390314 -280.563756)
			(xy 105.426951 -280.527118) (xy 105.468869 -280.496662) (xy 105.515035 -280.473139) (xy 105.564312 -280.457127)
			(xy 105.615487 -280.449021) (xy 105.641394 -280.448512) (xy 105.666906 -280.448992) (xy 105.717321 -280.456852)
			(xy 105.765922 -280.472385) (xy 105.811551 -280.495221) (xy 105.853116 -280.524814) (xy 105.889626 -280.560457)
			(xy 105.9053 -280.580592) (xy 106.317288 -280.580592) (xy 106.332966 -280.560461) (xy 106.369475 -280.524817)
			(xy 106.41104 -280.495223) (xy 106.456667 -280.472386) (xy 106.505268 -280.456852) (xy 106.555682 -280.44899)
			(xy 106.581194 -280.448512) (xy 106.607104 -280.448985) (xy 106.658286 -280.457091) (xy 106.70757 -280.473103)
			(xy 106.753743 -280.496628) (xy 106.795666 -280.527087) (xy 106.832309 -280.563729) (xy 106.862768 -280.605652)
			(xy 106.886294 -280.651824) (xy 106.902308 -280.701108) (xy 106.910414 -280.75229) (xy 106.910414 -280.804105)
			(xy 334.45632 -280.804105) (xy 334.45632 -280.752295) (xy 334.464425 -280.701122) (xy 334.480434 -280.651848)
			(xy 334.503953 -280.605684) (xy 334.534405 -280.563767) (xy 334.571038 -280.527129) (xy 334.612951 -280.496673)
			(xy 334.659113 -280.473148) (xy 334.708385 -280.457133) (xy 334.759557 -280.449023) (xy 334.785462 -280.448512)
			(xy 334.810955 -280.449019) (xy 334.861331 -280.456875) (xy 334.909894 -280.472404) (xy 334.955481 -280.495237)
			(xy 334.997003 -280.524825) (xy 335.033465 -280.560462) (xy 335.049114 -280.580592) (xy 335.46161 -280.580592)
			(xy 335.477279 -280.560477) (xy 335.513736 -280.524835) (xy 335.555252 -280.495239) (xy 335.600835 -280.472399)
			(xy 335.649395 -280.45686) (xy 335.699769 -280.448993) (xy 335.725262 -280.448512) (xy 335.751174 -280.448983)
			(xy 335.80236 -280.457084) (xy 335.851648 -280.473094) (xy 335.897825 -280.496618) (xy 335.939753 -280.527076)
			(xy 335.9764 -280.563718) (xy 336.006863 -280.605643) (xy 336.030391 -280.651817) (xy 336.046407 -280.701103)
			(xy 336.054514 -280.752288) (xy 336.054514 -280.804112) (xy 336.046407 -280.855297) (xy 336.030391 -280.904583)
			(xy 336.006863 -280.950757) (xy 335.9764 -280.992682) (xy 335.939753 -281.029324) (xy 335.897825 -281.059782)
			(xy 335.851648 -281.083306) (xy 335.80236 -281.099316) (xy 335.751174 -281.107417) (xy 335.725262 -281.107896)
			(xy 335.699767 -281.107441) (xy 335.649389 -281.099574) (xy 335.600825 -281.084033) (xy 335.555238 -281.061192)
			(xy 335.513718 -281.031594) (xy 335.477257 -280.99595) (xy 335.46161 -280.975816) (xy 335.049114 -280.975816)
			(xy 335.033491 -280.995969) (xy 334.997025 -281.031609) (xy 334.955498 -281.061199) (xy 334.909906 -281.084033)
			(xy 334.861339 -281.099564) (xy 334.810957 -281.107421) (xy 334.785462 -281.107896) (xy 334.759557 -281.107377)
			(xy 334.708385 -281.099267) (xy 334.659113 -281.083252) (xy 334.612951 -281.059727) (xy 334.571038 -281.029271)
			(xy 334.534405 -280.992633) (xy 334.503953 -280.950716) (xy 334.480434 -280.904552) (xy 334.464425 -280.855278)
			(xy 334.45632 -280.804105) (xy 106.910414 -280.804105) (xy 106.910414 -280.80411) (xy 106.902308 -280.855292)
			(xy 106.886294 -280.904576) (xy 106.862768 -280.950748) (xy 106.832309 -280.992671) (xy 106.795666 -281.029313)
			(xy 106.753743 -281.059772) (xy 106.70757 -281.083297) (xy 106.658286 -281.099309) (xy 106.607104 -281.107415)
			(xy 106.581194 -281.107896) (xy 106.555682 -281.107421) (xy 106.505267 -281.09956) (xy 106.456665 -281.084025)
			(xy 106.411037 -281.061188) (xy 106.369472 -281.031595) (xy 106.332962 -280.995951) (xy 106.317288 -280.975816)
			(xy 105.9053 -280.975816) (xy 105.889631 -280.995955) (xy 105.85312 -281.031598) (xy 105.811553 -281.06119)
			(xy 105.765924 -281.084026) (xy 105.717322 -281.099559) (xy 105.666906 -281.107419) (xy 105.641394 -281.107896)
			(xy 105.615487 -281.107379) (xy 105.564312 -281.099273) (xy 105.515035 -281.083261) (xy 105.468869 -281.059738)
			(xy 105.426951 -281.029282) (xy 105.390314 -280.992644) (xy 105.359859 -280.950726) (xy 105.336337 -280.90456)
			(xy 105.320326 -280.855282) (xy 105.31222 -280.804107) (xy 105.030521 -280.804107) (xy 105.022425 -280.855229)
			(xy 105.006426 -280.904469) (xy 104.98292 -280.950601) (xy 104.952488 -280.992488) (xy 104.915878 -281.029098)
			(xy 104.873991 -281.05953) (xy 104.827859 -281.083036) (xy 104.778619 -281.099035) (xy 104.727481 -281.107134)
			(xy 104.675707 -281.107134) (xy 104.624569 -281.099035) (xy 104.575329 -281.083036) (xy 104.529197 -281.05953)
			(xy 104.48731 -281.029098) (xy 104.4507 -280.992488) (xy 104.420268 -280.950601) (xy 104.396762 -280.904469)
			(xy 104.380763 -280.855229) (xy 104.372664 -280.804091) (xy 104.372156 -280.778204) (xy 104.091232 -280.778204)
			(xy 104.091232 -280.778712) (xy 104.090641 -280.806228) (xy 104.081455 -280.860489) (xy 104.072944 -280.886662)
			(xy 104.065324 -280.908506) (xy 104.270556 -281.263852) (xy 104.293416 -281.26817) (xy 104.318226 -281.273386)
			(xy 104.366003 -281.290334) (xy 104.410622 -281.314398) (xy 104.451028 -281.345012) (xy 104.48627 -281.381453)
			(xy 104.515516 -281.422861) (xy 104.538075 -281.468259) (xy 104.553416 -281.516576) (xy 104.561176 -281.566673)
			(xy 104.56164 -281.59202) (xy 105.781856 -281.59202) (xy 105.782364 -281.566113) (xy 105.79047 -281.514936)
			(xy 105.806482 -281.465657) (xy 105.830005 -281.41949) (xy 105.860461 -281.377571) (xy 105.897099 -281.340933)
			(xy 105.939018 -281.310477) (xy 105.985185 -281.286954) (xy 106.034464 -281.270942) (xy 106.085641 -281.262836)
			(xy 106.137455 -281.262836) (xy 106.188632 -281.270942) (xy 106.237911 -281.286954) (xy 106.284078 -281.310477)
			(xy 106.325997 -281.340933) (xy 106.362635 -281.377571) (xy 106.393091 -281.41949) (xy 106.416614 -281.465657)
			(xy 106.432626 -281.514936) (xy 106.440732 -281.566113) (xy 106.44124 -281.59202) (xy 106.44067 -281.619802)
			(xy 106.431345 -281.674578) (xy 106.422698 -281.700986) (xy 106.414824 -281.72283) (xy 106.619802 -282.077668)
			(xy 106.642662 -282.081986) (xy 106.667464 -282.087182) (xy 106.715205 -282.104167) (xy 106.759784 -282.128258)
			(xy 106.800151 -282.158887) (xy 106.835356 -282.195333) (xy 106.864568 -282.236737) (xy 106.8871 -282.282123)
			(xy 106.902422 -282.330424) (xy 106.910171 -282.3805) (xy 106.910632 -282.405836) (xy 334.456024 -282.405836)
			(xy 334.456468 -282.38049) (xy 334.46425 -282.330397) (xy 334.479605 -282.282085) (xy 334.502171 -282.236692)
			(xy 334.531418 -282.195286) (xy 334.566656 -282.158843) (xy 334.607056 -282.128222) (xy 334.651665 -282.104142)
			(xy 334.699433 -282.087172) (xy 334.724248 -282.081986) (xy 334.747108 -282.077668) (xy 334.952086 -281.722576)
			(xy 334.944466 -281.700732) (xy 334.93582 -281.67439) (xy 334.926507 -281.619739) (xy 334.925924 -281.59202)
			(xy 334.926432 -281.566113) (xy 334.934538 -281.514936) (xy 334.95055 -281.465657) (xy 334.974073 -281.41949)
			(xy 335.004529 -281.377571) (xy 335.041167 -281.340933) (xy 335.083086 -281.310477) (xy 335.129253 -281.286954)
			(xy 335.178532 -281.270942) (xy 335.229709 -281.262836) (xy 335.281523 -281.262836) (xy 335.3327 -281.270942)
			(xy 335.381979 -281.286954) (xy 335.428146 -281.310477) (xy 335.470065 -281.340933) (xy 335.506703 -281.377571)
			(xy 335.537159 -281.41949) (xy 335.560682 -281.465657) (xy 335.576694 -281.514936) (xy 335.5848 -281.566113)
			(xy 335.585308 -281.59202) (xy 336.805524 -281.59202) (xy 336.806044 -281.566676) (xy 336.813813 -281.516587)
			(xy 336.829157 -281.468277) (xy 336.851713 -281.422884) (xy 336.88095 -281.381477) (xy 336.916179 -281.345033)
			(xy 336.956571 -281.31441) (xy 337.001174 -281.290329) (xy 337.048936 -281.273357) (xy 337.073748 -281.26817)
			(xy 337.096608 -281.263852) (xy 337.301586 -280.909014) (xy 337.293966 -280.88717) (xy 337.285321 -280.860761)
			(xy 337.276 -280.805986) (xy 337.275424 -280.778204) (xy 337.275919 -280.752309) (xy 337.284017 -280.701155)
			(xy 337.300013 -280.651897) (xy 337.323515 -280.605746) (xy 337.353945 -280.563837) (xy 337.390553 -280.527202)
			(xy 337.432439 -280.496742) (xy 337.478573 -280.473206) (xy 337.527819 -280.457173) (xy 337.578967 -280.449038)
			(xy 337.604862 -280.448512) (xy 337.630738 -280.449004) (xy 337.681855 -280.457091) (xy 337.731077 -280.473073)
			(xy 337.777195 -280.496556) (xy 337.819073 -280.526962) (xy 337.855681 -280.563542) (xy 337.886118 -280.605398)
			(xy 337.909634 -280.651499) (xy 337.925652 -280.70071) (xy 337.933777 -280.75182) (xy 337.9343 -280.777696)
			(xy 337.9343 -280.778204) (xy 340.094824 -280.778204) (xy 340.095293 -280.752294) (xy 340.103399 -280.701112)
			(xy 340.119413 -280.651828) (xy 340.142939 -280.605656) (xy 340.173399 -280.563733) (xy 340.210042 -280.527091)
			(xy 340.251966 -280.496633) (xy 340.298139 -280.473108) (xy 340.347423 -280.457097) (xy 340.398606 -280.448992)
			(xy 340.424516 -280.448512) (xy 340.450394 -280.448954) (xy 340.501512 -280.457049) (xy 340.550736 -280.473038)
			(xy 340.596853 -280.496528) (xy 340.638731 -280.52694) (xy 340.675338 -280.563526) (xy 340.705774 -280.605386)
			(xy 340.729289 -280.651491) (xy 340.745307 -280.700705) (xy 340.753431 -280.751819) (xy 340.753954 -280.777696)
			(xy 340.753954 -280.778204) (xy 340.753418 -280.804105) (xy 342.91452 -280.804105) (xy 342.91452 -280.752295)
			(xy 342.922625 -280.701122) (xy 342.938634 -280.651848) (xy 342.962153 -280.605684) (xy 342.992605 -280.563767)
			(xy 343.029238 -280.527129) (xy 343.071151 -280.496673) (xy 343.117313 -280.473148) (xy 343.166585 -280.457133)
			(xy 343.217757 -280.449023) (xy 343.243662 -280.448512) (xy 343.269173 -280.449015) (xy 343.319587 -280.45687)
			(xy 343.368188 -280.472399) (xy 343.413817 -280.49523) (xy 343.455383 -280.524819) (xy 343.491894 -280.560459)
			(xy 343.507568 -280.580592) (xy 343.91981 -280.580592) (xy 343.935476 -280.56045) (xy 343.971987 -280.524807)
			(xy 344.013554 -280.495214) (xy 344.059184 -280.472379) (xy 344.107788 -280.456847) (xy 344.158204 -280.448988)
			(xy 344.183716 -280.448512) (xy 344.209623 -280.449014) (xy 344.260798 -280.457121) (xy 344.310075 -280.473134)
			(xy 344.356241 -280.496659) (xy 344.398158 -280.527115) (xy 344.434795 -280.563754) (xy 344.465249 -280.605673)
			(xy 344.488772 -280.65184) (xy 344.504782 -280.701117) (xy 344.512888 -280.752293) (xy 344.512888 -280.804107)
			(xy 344.504782 -280.855283) (xy 344.488772 -280.90456) (xy 344.465249 -280.950727) (xy 344.434795 -280.992646)
			(xy 344.398158 -281.029285) (xy 344.356241 -281.059741) (xy 344.310075 -281.083266) (xy 344.260798 -281.099279)
			(xy 344.209623 -281.107386) (xy 344.183716 -281.107896) (xy 344.158205 -281.107405) (xy 344.107791 -281.099547)
			(xy 344.059189 -281.084016) (xy 344.013561 -281.061182) (xy 343.971995 -281.031591) (xy 343.935484 -280.99595)
			(xy 343.91981 -280.975816) (xy 343.507568 -280.975816) (xy 343.491917 -280.99597) (xy 343.455403 -281.031612)
			(xy 343.413832 -281.061203) (xy 343.368199 -281.084036) (xy 343.319593 -281.099566) (xy 343.269175 -281.107421)
			(xy 343.243662 -281.107896) (xy 343.217757 -281.107377) (xy 343.166585 -281.099267) (xy 343.117313 -281.083252)
			(xy 343.071151 -281.059727) (xy 343.029238 -281.029271) (xy 342.992605 -280.992633) (xy 342.962153 -280.950716)
			(xy 342.938634 -280.904552) (xy 342.922625 -280.855278) (xy 342.91452 -280.804105) (xy 340.753418 -280.804105)
			(xy 340.753379 -280.805986) (xy 340.744058 -280.860762) (xy 340.735412 -280.88717) (xy 340.727792 -280.909014)
			(xy 340.93277 -281.263852) (xy 340.95563 -281.26817) (xy 340.980439 -281.273332) (xy 341.028178 -281.290325)
			(xy 341.072756 -281.314423) (xy 341.113121 -281.345058) (xy 341.148323 -281.381508) (xy 341.177534 -281.422915)
			(xy 341.200066 -281.468304) (xy 341.215387 -281.516606) (xy 341.223138 -281.566683) (xy 341.2236 -281.59202)
			(xy 341.223092 -281.617907) (xy 341.214993 -281.669045) (xy 341.198994 -281.718285) (xy 341.175488 -281.764417)
			(xy 341.145056 -281.806304) (xy 341.108446 -281.842914) (xy 341.066559 -281.873346) (xy 341.020427 -281.896852)
			(xy 340.971187 -281.912851) (xy 340.920049 -281.92095) (xy 340.868275 -281.92095) (xy 340.817137 -281.912851)
			(xy 340.767897 -281.896852) (xy 340.721765 -281.873346) (xy 340.679878 -281.842914) (xy 340.643268 -281.806304)
			(xy 340.612836 -281.764417) (xy 340.58933 -281.718285) (xy 340.573331 -281.669045) (xy 340.565232 -281.617907)
			(xy 340.564724 -281.59202) (xy 340.565273 -281.564313) (xy 340.574459 -281.509667) (xy 340.583012 -281.483308)
			(xy 340.590632 -281.461464) (xy 340.385654 -281.106372) (xy 340.362794 -281.102054) (xy 340.337994 -281.096852)
			(xy 340.290256 -281.079864) (xy 340.24568 -281.055771) (xy 340.205315 -281.025142) (xy 340.170112 -280.988697)
			(xy 340.140899 -280.947295) (xy 340.118366 -280.901911) (xy 340.103042 -280.853613) (xy 340.095288 -280.803539)
			(xy 340.094824 -280.778204) (xy 337.9343 -280.778204) (xy 337.933779 -280.803526) (xy 337.926048 -280.853575)
			(xy 337.910753 -280.901853) (xy 337.888254 -280.947223) (xy 337.859081 -280.988619) (xy 337.82392 -281.025066)
			(xy 337.783598 -281.055707) (xy 337.739064 -281.07982) (xy 337.691367 -281.096838) (xy 337.666584 -281.102054)
			(xy 337.643724 -281.106372) (xy 337.438746 -281.46121) (xy 337.446366 -281.483054) (xy 337.454977 -281.50934)
			(xy 337.464301 -281.563858) (xy 337.464908 -281.591512) (xy 337.464908 -281.59202) (xy 337.4644 -281.617904)
			(xy 338.685436 -281.617904) (xy 338.685436 -281.566096) (xy 338.69354 -281.514926) (xy 338.709548 -281.465654)
			(xy 338.733067 -281.419492) (xy 338.763517 -281.377577) (xy 338.800148 -281.340942) (xy 338.84206 -281.310487)
			(xy 338.888219 -281.286963) (xy 338.937489 -281.270949) (xy 338.988658 -281.262839) (xy 339.014562 -281.262328)
			(xy 339.040073 -281.262825) (xy 339.090487 -281.270681) (xy 339.139089 -281.28621) (xy 339.184718 -281.309042)
			(xy 339.226284 -281.338633) (xy 339.262794 -281.374274) (xy 339.278468 -281.394408) (xy 339.690456 -281.394408)
			(xy 339.706157 -281.374295) (xy 339.742661 -281.33865) (xy 339.784221 -281.309053) (xy 339.829844 -281.286213)
			(xy 339.878441 -281.270675) (xy 339.928852 -281.262808) (xy 339.954362 -281.262328) (xy 339.980275 -281.262767)
			(xy 340.031464 -281.270869) (xy 340.080754 -281.286879) (xy 340.126933 -281.310404) (xy 340.168863 -281.340863)
			(xy 340.205512 -281.377508) (xy 340.235976 -281.419434) (xy 340.259506 -281.465611) (xy 340.275522 -281.514899)
			(xy 340.28363 -281.566087) (xy 340.28363 -281.617913) (xy 340.275522 -281.669101) (xy 340.259506 -281.718389)
			(xy 340.235976 -281.764566) (xy 340.205512 -281.806492) (xy 340.168863 -281.843137) (xy 340.126933 -281.873596)
			(xy 340.080754 -281.897121) (xy 340.031464 -281.913131) (xy 339.980275 -281.921233) (xy 339.954362 -281.921712)
			(xy 339.928849 -281.921255) (xy 339.878434 -281.913389) (xy 339.829832 -281.89785) (xy 339.784204 -281.87501)
			(xy 339.742639 -281.845414) (xy 339.706129 -281.809768) (xy 339.690456 -281.789632) (xy 339.278468 -281.789632)
			(xy 339.262822 -281.80979) (xy 339.226306 -281.845431) (xy 339.184734 -281.875021) (xy 339.139101 -281.897853)
			(xy 339.090494 -281.913382) (xy 339.040076 -281.921238) (xy 339.014562 -281.921712) (xy 338.988658 -281.921161)
			(xy 338.937489 -281.913051) (xy 338.888219 -281.897037) (xy 338.84206 -281.873513) (xy 338.800148 -281.843058)
			(xy 338.763517 -281.806423) (xy 338.733067 -281.764508) (xy 338.709548 -281.718346) (xy 338.69354 -281.669074)
			(xy 338.685436 -281.617904) (xy 337.4644 -281.617904) (xy 337.4644 -281.617927) (xy 337.456294 -281.669104)
			(xy 337.440282 -281.718383) (xy 337.416759 -281.76455) (xy 337.386303 -281.806469) (xy 337.349665 -281.843107)
			(xy 337.307746 -281.873563) (xy 337.261579 -281.897086) (xy 337.2123 -281.913098) (xy 337.161123 -281.921204)
			(xy 337.109309 -281.921204) (xy 337.058132 -281.913098) (xy 337.008853 -281.897086) (xy 336.962686 -281.873563)
			(xy 336.920767 -281.843107) (xy 336.884129 -281.806469) (xy 336.853673 -281.76455) (xy 336.83015 -281.718383)
			(xy 336.814138 -281.669104) (xy 336.806032 -281.617927) (xy 336.805524 -281.59202) (xy 335.585308 -281.59202)
			(xy 335.584798 -281.617364) (xy 335.577024 -281.667452) (xy 335.561677 -281.715761) (xy 335.539118 -281.761152)
			(xy 335.50988 -281.802558) (xy 335.47465 -281.839001) (xy 335.434259 -281.869625) (xy 335.389657 -281.893707)
			(xy 335.341896 -281.910681) (xy 335.317084 -281.91587) (xy 335.294224 -281.920188) (xy 335.089246 -282.27528)
			(xy 335.096866 -282.297124) (xy 335.1055 -282.32347) (xy 335.114821 -282.378118) (xy 335.115408 -282.405836)
			(xy 335.395824 -282.405836) (xy 335.396332 -282.379949) (xy 335.404431 -282.328811) (xy 335.42043 -282.279571)
			(xy 335.443936 -282.233439) (xy 335.474368 -282.191552) (xy 335.510978 -282.154942) (xy 335.552865 -282.12451)
			(xy 335.598997 -282.101004) (xy 335.648237 -282.085005) (xy 335.699375 -282.076906) (xy 335.751149 -282.076906)
			(xy 335.802287 -282.085005) (xy 335.851527 -282.101004) (xy 335.897659 -282.12451) (xy 335.939546 -282.154942)
			(xy 335.976156 -282.191552) (xy 336.006588 -282.233439) (xy 336.030094 -282.279571) (xy 336.046093 -282.328811)
			(xy 336.054192 -282.379949) (xy 336.0547 -282.405836) (xy 336.054214 -282.431707) (xy 336.336126 -282.431707)
			(xy 336.336126 -282.379893) (xy 336.344232 -282.328716) (xy 336.360244 -282.279437) (xy 336.383768 -282.23327)
			(xy 336.414225 -282.191352) (xy 336.450864 -282.154714) (xy 336.492784 -282.12426) (xy 336.538952 -282.100738)
			(xy 336.588231 -282.084728) (xy 336.639409 -282.076625) (xy 336.665316 -282.076144) (xy 336.690811 -282.076599)
			(xy 336.74119 -282.084464) (xy 336.789755 -282.100003) (xy 336.835342 -282.122845) (xy 336.876862 -282.152443)
			(xy 336.913321 -282.188089) (xy 336.928968 -282.208224) (xy 337.341464 -282.208224) (xy 337.35711 -282.18809)
			(xy 337.393571 -282.152447) (xy 337.435092 -282.122853) (xy 337.480679 -282.100016) (xy 337.529243 -282.084481)
			(xy 337.579622 -282.076621) (xy 337.605116 -282.076144) (xy 337.631025 -282.076581) (xy 337.682206 -282.08469)
			(xy 337.731488 -282.100704) (xy 337.777658 -282.124231) (xy 337.819579 -282.154691) (xy 337.85622 -282.191333)
			(xy 337.886677 -282.233256) (xy 337.910202 -282.279427) (xy 337.926214 -282.32871) (xy 337.93432 -282.379891)
			(xy 337.93432 -282.431709) (xy 337.926214 -282.48289) (xy 337.910202 -282.532173) (xy 337.886677 -282.578344)
			(xy 337.85622 -282.620267) (xy 337.819579 -282.656909) (xy 337.777658 -282.687369) (xy 337.731488 -282.710896)
			(xy 337.682206 -282.72691) (xy 337.631025 -282.735019) (xy 337.605116 -282.735528) (xy 337.579623 -282.735021)
			(xy 337.529248 -282.727163) (xy 337.480686 -282.711632) (xy 337.435099 -282.6888) (xy 337.393577 -282.659213)
			(xy 337.357114 -282.623577) (xy 337.341464 -282.603448) (xy 336.928968 -282.603448) (xy 336.913322 -282.623582)
			(xy 336.876859 -282.659221) (xy 336.835338 -282.688813) (xy 336.78975 -282.71165) (xy 336.741187 -282.727186)
			(xy 336.69081 -282.735049) (xy 336.665316 -282.735528) (xy 336.639409 -282.734975) (xy 336.588231 -282.726872)
			(xy 336.538952 -282.710862) (xy 336.492784 -282.68734) (xy 336.450864 -282.656886) (xy 336.414225 -282.620248)
			(xy 336.383768 -282.57833) (xy 336.360244 -282.532163) (xy 336.344232 -282.482884) (xy 336.336126 -282.431707)
			(xy 336.054214 -282.431707) (xy 336.054179 -282.433545) (xy 336.044978 -282.488191) (xy 336.036412 -282.514548)
			(xy 336.028538 -282.536646) (xy 336.23377 -282.891738) (xy 336.25663 -282.896056) (xy 336.281436 -282.901231)
			(xy 336.329174 -282.918223) (xy 336.373751 -282.94232) (xy 336.414116 -282.972953) (xy 336.449318 -283.009401)
			(xy 336.478529 -283.050806) (xy 336.501062 -283.096194) (xy 336.516384 -283.144494) (xy 336.524137 -283.19457)
			(xy 336.5246 -283.219906) (xy 338.685124 -283.219906) (xy 338.685593 -283.194571) (xy 338.693345 -283.144497)
			(xy 338.708668 -283.096199) (xy 338.731201 -283.050814) (xy 338.760412 -283.009411) (xy 338.795615 -282.972966)
			(xy 338.83598 -282.942336) (xy 338.880556 -282.918243) (xy 338.928293 -282.901254) (xy 338.953094 -282.896056)
			(xy 338.975954 -282.891738) (xy 339.181186 -282.536392) (xy 339.173566 -282.514548) (xy 339.164924 -282.488205)
			(xy 339.155609 -282.433555) (xy 339.155024 -282.405836) (xy 339.155532 -282.379929) (xy 339.163638 -282.328752)
			(xy 339.17965 -282.279473) (xy 339.203173 -282.233306) (xy 339.233629 -282.191387) (xy 339.270267 -282.154749)
			(xy 339.312186 -282.124293) (xy 339.358353 -282.10077) (xy 339.407632 -282.084758) (xy 339.458809 -282.076652)
			(xy 339.510623 -282.076652) (xy 339.5618 -282.084758) (xy 339.611079 -282.10077) (xy 339.657246 -282.124293)
			(xy 339.699165 -282.154749) (xy 339.735803 -282.191387) (xy 339.766259 -282.233306) (xy 339.789782 -282.279473)
			(xy 339.805794 -282.328752) (xy 339.8139 -282.379929) (xy 339.814408 -282.405836) (xy 341.034624 -282.405836)
			(xy 341.035068 -282.38049) (xy 341.04285 -282.330397) (xy 341.058205 -282.282085) (xy 341.080771 -282.236692)
			(xy 341.110018 -282.195286) (xy 341.145256 -282.158843) (xy 341.185656 -282.128222) (xy 341.230265 -282.104142)
			(xy 341.278033 -282.087172) (xy 341.302848 -282.081986) (xy 341.325708 -282.077668) (xy 341.530686 -281.72283)
			(xy 341.522812 -281.700986) (xy 341.514229 -281.674568) (xy 341.505035 -281.619792) (xy 341.504524 -281.59202)
			(xy 341.505032 -281.566133) (xy 341.513131 -281.514995) (xy 341.52913 -281.465755) (xy 341.552636 -281.419623)
			(xy 341.583068 -281.377736) (xy 341.619678 -281.341126) (xy 341.661565 -281.310694) (xy 341.707697 -281.287188)
			(xy 341.756937 -281.271189) (xy 341.808075 -281.26309) (xy 341.859849 -281.26309) (xy 341.910987 -281.271189)
			(xy 341.960227 -281.287188) (xy 342.006359 -281.310694) (xy 342.048246 -281.341126) (xy 342.084856 -281.377736)
			(xy 342.115288 -281.419623) (xy 342.138794 -281.465755) (xy 342.154793 -281.514995) (xy 342.162892 -281.566133)
			(xy 342.1634 -281.59202) (xy 342.162935 -281.617355) (xy 342.15518 -281.667428) (xy 342.139855 -281.715725)
			(xy 342.117321 -281.761109) (xy 342.088109 -281.802511) (xy 342.052906 -281.838956) (xy 342.012542 -281.869586)
			(xy 341.967967 -281.89368) (xy 341.92023 -281.910671) (xy 341.89543 -281.91587) (xy 341.87257 -281.920188)
			(xy 341.667592 -282.275026) (xy 341.675466 -282.297124) (xy 341.684085 -282.323474) (xy 341.693414 -282.378119)
			(xy 341.694008 -282.405836) (xy 342.914224 -282.405836) (xy 342.914629 -282.380499) (xy 342.922392 -282.330422)
			(xy 342.937724 -282.282122) (xy 342.960266 -282.236737) (xy 342.989485 -282.195335) (xy 343.024695 -282.15889)
			(xy 343.065066 -282.128262) (xy 343.109648 -282.10417) (xy 343.157391 -282.087183) (xy 343.182194 -282.081986)
			(xy 343.205054 -282.077668) (xy 343.410286 -281.722322) (xy 343.402666 -281.700478) (xy 343.39404 -281.674196)
			(xy 343.384726 -281.619675) (xy 343.384124 -281.59202) (xy 343.384632 -281.566113) (xy 343.392738 -281.514936)
			(xy 343.40875 -281.465657) (xy 343.432273 -281.41949) (xy 343.462729 -281.377571) (xy 343.499367 -281.340933)
			(xy 343.541286 -281.310477) (xy 343.587453 -281.286954) (xy 343.636732 -281.270942) (xy 343.687909 -281.262836)
			(xy 343.739723 -281.262836) (xy 343.7909 -281.270942) (xy 343.840179 -281.286954) (xy 343.886346 -281.310477)
			(xy 343.928265 -281.340933) (xy 343.964903 -281.377571) (xy 343.995359 -281.41949) (xy 344.018882 -281.465657)
			(xy 344.034894 -281.514936) (xy 344.043 -281.566113) (xy 344.043508 -281.59202) (xy 345.263724 -281.59202)
			(xy 345.264244 -281.566676) (xy 345.272013 -281.516587) (xy 345.287357 -281.468277) (xy 345.309913 -281.422884)
			(xy 345.33915 -281.381477) (xy 345.374379 -281.345033) (xy 345.414771 -281.31441) (xy 345.459374 -281.290329)
			(xy 345.507136 -281.273357) (xy 345.531948 -281.26817) (xy 345.554808 -281.263852) (xy 345.759786 -280.909014)
			(xy 345.751912 -280.88717) (xy 345.743326 -280.860753) (xy 345.734134 -280.805977) (xy 345.733624 -280.778204)
			(xy 345.734132 -280.752317) (xy 345.742231 -280.701179) (xy 345.75823 -280.651939) (xy 345.781736 -280.605807)
			(xy 345.812168 -280.56392) (xy 345.848778 -280.52731) (xy 345.890665 -280.496878) (xy 345.936797 -280.473372)
			(xy 345.986037 -280.457373) (xy 346.037175 -280.449274) (xy 346.088949 -280.449274) (xy 346.140087 -280.457373)
			(xy 346.189327 -280.473372) (xy 346.235459 -280.496878) (xy 346.277346 -280.52731) (xy 346.313956 -280.56392)
			(xy 346.344388 -280.605807) (xy 346.367894 -280.651939) (xy 346.383893 -280.701179) (xy 346.391992 -280.752317)
			(xy 346.3925 -280.778204) (xy 348.553024 -280.778204) (xy 348.553532 -280.752317) (xy 348.561631 -280.701179)
			(xy 348.57763 -280.651939) (xy 348.601136 -280.605807) (xy 348.631568 -280.56392) (xy 348.668178 -280.52731)
			(xy 348.710065 -280.496878) (xy 348.756197 -280.473372) (xy 348.805437 -280.457373) (xy 348.856575 -280.449274)
			(xy 348.908349 -280.449274) (xy 348.959487 -280.457373) (xy 349.008727 -280.473372) (xy 349.054859 -280.496878)
			(xy 349.096746 -280.52731) (xy 349.133356 -280.56392) (xy 349.163788 -280.605807) (xy 349.187294 -280.651939)
			(xy 349.203293 -280.701179) (xy 349.211392 -280.752317) (xy 349.2119 -280.778204) (xy 351.372424 -280.778204)
			(xy 351.372932 -280.752317) (xy 351.381031 -280.701179) (xy 351.39703 -280.651939) (xy 351.420536 -280.605807)
			(xy 351.450968 -280.56392) (xy 351.487578 -280.52731) (xy 351.529465 -280.496878) (xy 351.575597 -280.473372)
			(xy 351.624837 -280.457373) (xy 351.675975 -280.449274) (xy 351.727749 -280.449274) (xy 351.778887 -280.457373)
			(xy 351.828127 -280.473372) (xy 351.874259 -280.496878) (xy 351.916146 -280.52731) (xy 351.952756 -280.56392)
			(xy 351.983188 -280.605807) (xy 352.006694 -280.651939) (xy 352.022693 -280.701179) (xy 352.030792 -280.752317)
			(xy 352.0313 -280.778204) (xy 352.312224 -280.778204) (xy 352.312691 -280.752869) (xy 352.320444 -280.702795)
			(xy 352.335767 -280.654496) (xy 352.3583 -280.609112) (xy 352.387511 -280.567709) (xy 352.422714 -280.531263)
			(xy 352.463079 -280.500633) (xy 352.507655 -280.47654) (xy 352.555393 -280.459552) (xy 352.580194 -280.454354)
			(xy 352.603054 -280.450036) (xy 352.808286 -280.09469) (xy 352.800666 -280.072592) (xy 352.792043 -280.046309)
			(xy 352.782727 -279.991789) (xy 352.782124 -279.964134) (xy 352.782632 -279.938227) (xy 352.790738 -279.88705)
			(xy 352.80675 -279.837771) (xy 352.830273 -279.791604) (xy 352.860729 -279.749685) (xy 352.897367 -279.713047)
			(xy 352.939286 -279.682591) (xy 352.985453 -279.659068) (xy 353.034732 -279.643056) (xy 353.085909 -279.63495)
			(xy 353.137723 -279.63495) (xy 353.1889 -279.643056) (xy 353.238179 -279.659068) (xy 353.284346 -279.682591)
			(xy 353.326265 -279.713047) (xy 353.362903 -279.749685) (xy 353.393359 -279.791604) (xy 353.416882 -279.837771)
			(xy 353.432894 -279.88705) (xy 353.441 -279.938227) (xy 353.441508 -279.964134) (xy 353.441095 -279.9895)
			(xy 353.433341 -280.039635) (xy 353.417991 -280.087988) (xy 353.395408 -280.133416) (xy 353.366127 -280.174843)
			(xy 353.330839 -280.211291) (xy 353.290379 -280.241896) (xy 353.245705 -280.265935) (xy 353.197873 -280.282839)
			(xy 353.17303 -280.287984) (xy 353.149916 -280.292302) (xy 352.944938 -280.647394) (xy 352.952812 -280.669492)
			(xy 352.961371 -280.695851) (xy 352.970571 -280.750496) (xy 352.9711 -280.778204) (xy 352.970592 -280.804091)
			(xy 352.97059 -280.804105) (xy 353.25232 -280.804105) (xy 353.25232 -280.752295) (xy 353.260425 -280.701122)
			(xy 353.276434 -280.651848) (xy 353.299953 -280.605684) (xy 353.330405 -280.563767) (xy 353.367038 -280.527129)
			(xy 353.408951 -280.496673) (xy 353.455113 -280.473148) (xy 353.504385 -280.457133) (xy 353.555557 -280.449023)
			(xy 353.581462 -280.448512) (xy 353.606973 -280.449015) (xy 353.657387 -280.45687) (xy 353.705988 -280.472399)
			(xy 353.751617 -280.49523) (xy 353.793183 -280.524819) (xy 353.829694 -280.560459) (xy 353.845368 -280.580592)
			(xy 354.257356 -280.580592) (xy 354.273053 -280.560476) (xy 354.309558 -280.524831) (xy 354.351119 -280.495236)
			(xy 354.396742 -280.472396) (xy 354.44534 -280.456858) (xy 354.495751 -280.448992) (xy 354.521262 -280.448512)
			(xy 354.547174 -280.448983) (xy 354.59836 -280.457084) (xy 354.647648 -280.473094) (xy 354.693825 -280.496618)
			(xy 354.735753 -280.527076) (xy 354.7724 -280.563718) (xy 354.802863 -280.605643) (xy 354.826391 -280.651817)
			(xy 354.842407 -280.701103) (xy 354.850514 -280.752288) (xy 354.850514 -280.804112) (xy 354.842407 -280.855297)
			(xy 354.826391 -280.904583) (xy 354.802863 -280.950757) (xy 354.7724 -280.992682) (xy 354.735753 -281.029324)
			(xy 354.693825 -281.059782) (xy 354.647648 -281.083306) (xy 354.59836 -281.099316) (xy 354.547174 -281.107417)
			(xy 354.521262 -281.107896) (xy 354.495749 -281.107445) (xy 354.445333 -281.099578) (xy 354.396731 -281.084039)
			(xy 354.351103 -281.061198) (xy 354.309538 -281.031601) (xy 354.273029 -280.995953) (xy 354.257356 -280.975816)
			(xy 353.845368 -280.975816) (xy 353.829717 -280.99597) (xy 353.793203 -281.031612) (xy 353.751632 -281.061203)
			(xy 353.705999 -281.084036) (xy 353.657393 -281.099566) (xy 353.606975 -281.107421) (xy 353.581462 -281.107896)
			(xy 353.555557 -281.107377) (xy 353.504385 -281.099267) (xy 353.455113 -281.083252) (xy 353.408951 -281.059727)
			(xy 353.367038 -281.029271) (xy 353.330405 -280.992633) (xy 353.299953 -280.950716) (xy 353.276434 -280.904552)
			(xy 353.260425 -280.855278) (xy 353.25232 -280.804105) (xy 352.97059 -280.804105) (xy 352.962493 -280.855229)
			(xy 352.946494 -280.904469) (xy 352.922988 -280.950601) (xy 352.892556 -280.992488) (xy 352.855946 -281.029098)
			(xy 352.814059 -281.05953) (xy 352.767927 -281.083036) (xy 352.718687 -281.099035) (xy 352.667549 -281.107134)
			(xy 352.615775 -281.107134) (xy 352.564637 -281.099035) (xy 352.515397 -281.083036) (xy 352.469265 -281.05953)
			(xy 352.427378 -281.029098) (xy 352.390768 -280.992488) (xy 352.360336 -280.950601) (xy 352.33683 -280.904469)
			(xy 352.320831 -280.855229) (xy 352.312732 -280.804091) (xy 352.312224 -280.778204) (xy 352.0313 -280.778204)
			(xy 352.0313 -280.778712) (xy 352.03071 -280.806228) (xy 352.021524 -280.860489) (xy 352.013012 -280.886662)
			(xy 352.005392 -280.908506) (xy 352.210624 -281.263852) (xy 352.233484 -281.26817) (xy 352.258305 -281.273337)
			(xy 352.306082 -281.290294) (xy 352.350699 -281.314367) (xy 352.391104 -281.344988) (xy 352.426344 -281.381435)
			(xy 352.455588 -281.422848) (xy 352.478145 -281.46825) (xy 352.493485 -281.516571) (xy 352.501244 -281.566671)
			(xy 352.501708 -281.59202) (xy 353.721924 -281.59202) (xy 353.722432 -281.566113) (xy 353.730538 -281.514936)
			(xy 353.74655 -281.465657) (xy 353.770073 -281.41949) (xy 353.800529 -281.377571) (xy 353.837167 -281.340933)
			(xy 353.879086 -281.310477) (xy 353.925253 -281.286954) (xy 353.974532 -281.270942) (xy 354.025709 -281.262836)
			(xy 354.077523 -281.262836) (xy 354.1287 -281.270942) (xy 354.177979 -281.286954) (xy 354.224146 -281.310477)
			(xy 354.266065 -281.340933) (xy 354.302703 -281.377571) (xy 354.333159 -281.41949) (xy 354.356682 -281.465657)
			(xy 354.372694 -281.514936) (xy 354.3808 -281.566113) (xy 354.381308 -281.59202) (xy 354.380739 -281.619802)
			(xy 354.371414 -281.674578) (xy 354.362766 -281.700986) (xy 354.354892 -281.72283) (xy 354.55987 -282.077668)
			(xy 354.58273 -282.081986) (xy 354.607543 -282.087133) (xy 354.655283 -282.104127) (xy 354.699861 -282.128227)
			(xy 354.740227 -282.158863) (xy 354.775429 -282.195315) (xy 354.80464 -282.236724) (xy 354.82717 -282.282115)
			(xy 354.84249 -282.330419) (xy 354.850239 -282.380498) (xy 354.8507 -282.405836) (xy 354.850192 -282.431723)
			(xy 354.842093 -282.482861) (xy 354.826094 -282.532101) (xy 354.802588 -282.578233) (xy 354.772156 -282.62012)
			(xy 354.735546 -282.65673) (xy 354.693659 -282.687162) (xy 354.647527 -282.710668) (xy 354.598287 -282.726667)
			(xy 354.547149 -282.734766) (xy 354.495375 -282.734766) (xy 354.444237 -282.726667) (xy 354.394997 -282.710668)
			(xy 354.348865 -282.687162) (xy 354.306978 -282.65673) (xy 354.270368 -282.62012) (xy 354.239936 -282.578233)
			(xy 354.21643 -282.532101) (xy 354.200431 -282.482861) (xy 354.192332 -282.431723) (xy 354.191824 -282.405836)
			(xy 354.192361 -282.378128) (xy 354.201551 -282.323481) (xy 354.210112 -282.297124) (xy 354.217986 -282.275026)
			(xy 354.013008 -281.920188) (xy 353.990148 -281.91587) (xy 353.965319 -281.910737) (xy 353.917537 -281.893779)
			(xy 353.872916 -281.869705) (xy 353.832509 -281.83908) (xy 353.797268 -281.802629) (xy 353.768025 -281.761211)
			(xy 353.74547 -281.715803) (xy 353.730136 -281.667476) (xy 353.722383 -281.617371) (xy 353.721924 -281.59202)
			(xy 352.501708 -281.59202) (xy 352.5012 -281.617927) (xy 352.493094 -281.669104) (xy 352.477082 -281.718383)
			(xy 352.453559 -281.76455) (xy 352.423103 -281.806469) (xy 352.386465 -281.843107) (xy 352.344546 -281.873563)
			(xy 352.298379 -281.897086) (xy 352.2491 -281.913098) (xy 352.197923 -281.921204) (xy 352.146109 -281.921204)
			(xy 352.094932 -281.913098) (xy 352.045653 -281.897086) (xy 351.999486 -281.873563) (xy 351.957567 -281.843107)
			(xy 351.920929 -281.806469) (xy 351.890473 -281.76455) (xy 351.86695 -281.718383) (xy 351.850938 -281.669104)
			(xy 351.842832 -281.617927) (xy 351.842324 -281.59202) (xy 351.842922 -281.564303) (xy 351.852242 -281.509656)
			(xy 351.860866 -281.483308) (xy 351.86874 -281.46121) (xy 351.663762 -281.106372) (xy 351.640902 -281.102054)
			(xy 351.616072 -281.096882) (xy 351.568266 -281.079946) (xy 351.523618 -281.055889) (xy 351.483181 -281.025278)
			(xy 351.447909 -280.988835) (xy 351.418634 -280.947421) (xy 351.396047 -280.902011) (xy 351.380681 -280.853678)
			(xy 351.372898 -280.803562) (xy 351.372424 -280.778204) (xy 349.2119 -280.778204) (xy 349.2119 -280.778712)
			(xy 349.21131 -280.806228) (xy 349.202124 -280.860489) (xy 349.193612 -280.886662) (xy 349.185992 -280.908506)
			(xy 349.391224 -281.263852) (xy 349.414084 -281.26817) (xy 349.438905 -281.273337) (xy 349.486682 -281.290294)
			(xy 349.531299 -281.314367) (xy 349.571704 -281.344988) (xy 349.606944 -281.381435) (xy 349.636188 -281.422848)
			(xy 349.658745 -281.46825) (xy 349.674085 -281.516571) (xy 349.681844 -281.566671) (xy 349.682308 -281.59202)
			(xy 349.6818 -281.617927) (xy 349.673694 -281.669104) (xy 349.657682 -281.718383) (xy 349.634159 -281.76455)
			(xy 349.603703 -281.806469) (xy 349.567065 -281.843107) (xy 349.525146 -281.873563) (xy 349.478979 -281.897086)
			(xy 349.4297 -281.913098) (xy 349.378523 -281.921204) (xy 349.326709 -281.921204) (xy 349.275532 -281.913098)
			(xy 349.226253 -281.897086) (xy 349.180086 -281.873563) (xy 349.138167 -281.843107) (xy 349.101529 -281.806469)
			(xy 349.071073 -281.76455) (xy 349.04755 -281.718383) (xy 349.031538 -281.669104) (xy 349.023432 -281.617927)
			(xy 349.022924 -281.59202) (xy 349.023522 -281.564303) (xy 349.032842 -281.509656) (xy 349.041466 -281.483308)
			(xy 349.04934 -281.46121) (xy 348.844362 -281.106372) (xy 348.821502 -281.102054) (xy 348.796672 -281.096882)
			(xy 348.748866 -281.079946) (xy 348.704218 -281.055889) (xy 348.663781 -281.025278) (xy 348.628509 -280.988835)
			(xy 348.599234 -280.947421) (xy 348.576647 -280.902011) (xy 348.561281 -280.853678) (xy 348.553498 -280.803562)
			(xy 348.553024 -280.778204) (xy 346.3925 -280.778204) (xy 346.392021 -280.803539) (xy 346.384268 -280.853611)
			(xy 346.368945 -280.901908) (xy 346.346413 -280.947292) (xy 346.317203 -280.988694) (xy 346.282002 -281.025139)
			(xy 346.241639 -281.055769) (xy 346.197065 -281.079864) (xy 346.14933 -281.096855) (xy 346.12453 -281.102054)
			(xy 346.10167 -281.106372) (xy 345.896692 -281.46121) (xy 345.904566 -281.483308) (xy 345.913205 -281.509652)
			(xy 345.922521 -281.564301) (xy 345.923108 -281.59202) (xy 345.9226 -281.617909) (xy 347.143809 -281.617909)
			(xy 347.143809 -281.566091) (xy 347.151916 -281.514912) (xy 347.167929 -281.465631) (xy 347.191454 -281.419462)
			(xy 347.221912 -281.377541) (xy 347.258553 -281.340902) (xy 347.300475 -281.310446) (xy 347.346646 -281.286923)
			(xy 347.395928 -281.270912) (xy 347.447107 -281.262808) (xy 347.473016 -281.262328) (xy 347.498529 -281.262786)
			(xy 347.548945 -281.27065) (xy 347.597547 -281.286187) (xy 347.643176 -281.309027) (xy 347.684741 -281.338624)
			(xy 347.721249 -281.374271) (xy 347.736922 -281.394408) (xy 348.14891 -281.394408) (xy 348.16458 -281.37427)
			(xy 348.20109 -281.338625) (xy 348.242656 -281.309032) (xy 348.288285 -281.286196) (xy 348.336888 -281.270663)
			(xy 348.387304 -281.262804) (xy 348.412816 -281.262328) (xy 348.438724 -281.262797) (xy 348.489902 -281.270905)
			(xy 348.539182 -281.286919) (xy 348.585349 -281.310445) (xy 348.627269 -281.340903) (xy 348.663907 -281.377543)
			(xy 348.694363 -281.419464) (xy 348.717887 -281.465633) (xy 348.733899 -281.514914) (xy 348.742004 -281.566092)
			(xy 348.742004 -281.617908) (xy 348.733899 -281.669086) (xy 348.717887 -281.718367) (xy 348.694363 -281.764536)
			(xy 348.663907 -281.806457) (xy 348.627269 -281.843097) (xy 348.585349 -281.873555) (xy 348.539182 -281.897081)
			(xy 348.489902 -281.913095) (xy 348.438724 -281.921203) (xy 348.412816 -281.921712) (xy 348.387305 -281.921215)
			(xy 348.336891 -281.913357) (xy 348.28829 -281.897827) (xy 348.242662 -281.874994) (xy 348.201096 -281.845405)
			(xy 348.164585 -281.809765) (xy 348.14891 -281.789632) (xy 347.736922 -281.789632) (xy 347.721245 -281.809764)
			(xy 347.684735 -281.845407) (xy 347.64317 -281.875) (xy 347.597542 -281.897836) (xy 347.548942 -281.913371)
			(xy 347.498528 -281.921234) (xy 347.473016 -281.921712) (xy 347.447107 -281.921192) (xy 347.395928 -281.913088)
			(xy 347.346646 -281.897077) (xy 347.300475 -281.873554) (xy 347.258553 -281.843098) (xy 347.221912 -281.806459)
			(xy 347.191454 -281.764538) (xy 347.167929 -281.718369) (xy 347.151916 -281.669088) (xy 347.143809 -281.617909)
			(xy 345.9226 -281.617909) (xy 345.9226 -281.617927) (xy 345.914494 -281.669104) (xy 345.898482 -281.718383)
			(xy 345.874959 -281.76455) (xy 345.844503 -281.806469) (xy 345.807865 -281.843107) (xy 345.765946 -281.873563)
			(xy 345.719779 -281.897086) (xy 345.6705 -281.913098) (xy 345.619323 -281.921204) (xy 345.567509 -281.921204)
			(xy 345.516332 -281.913098) (xy 345.467053 -281.897086) (xy 345.420886 -281.873563) (xy 345.378967 -281.843107)
			(xy 345.342329 -281.806469) (xy 345.311873 -281.76455) (xy 345.28835 -281.718383) (xy 345.272338 -281.669104)
			(xy 345.264232 -281.617927) (xy 345.263724 -281.59202) (xy 344.043508 -281.59202) (xy 344.043045 -281.617395)
			(xy 344.035274 -281.667545) (xy 344.019903 -281.71591) (xy 343.997297 -281.761346) (xy 343.967989 -281.802777)
			(xy 343.932674 -281.839223) (xy 343.892188 -281.869822) (xy 343.847487 -281.893849) (xy 343.79963 -281.910736)
			(xy 343.774776 -281.91587) (xy 343.751916 -281.920188) (xy 343.546938 -282.275026) (xy 343.554812 -282.297124)
			(xy 343.563378 -282.32348) (xy 343.572573 -282.378127) (xy 343.5731 -282.405836) (xy 343.854024 -282.405836)
			(xy 343.854532 -282.379949) (xy 343.862631 -282.328811) (xy 343.87863 -282.279571) (xy 343.902136 -282.233439)
			(xy 343.932568 -282.191552) (xy 343.969178 -282.154942) (xy 344.011065 -282.12451) (xy 344.057197 -282.101004)
			(xy 344.106437 -282.085005) (xy 344.157575 -282.076906) (xy 344.209349 -282.076906) (xy 344.260487 -282.085005)
			(xy 344.309727 -282.101004) (xy 344.355859 -282.12451) (xy 344.397746 -282.154942) (xy 344.434356 -282.191552)
			(xy 344.464788 -282.233439) (xy 344.488294 -282.279571) (xy 344.504293 -282.328811) (xy 344.512392 -282.379949)
			(xy 344.5129 -282.405836) (xy 344.5129 -282.406344) (xy 344.512364 -282.431703) (xy 344.794152 -282.431703)
			(xy 344.794152 -282.379897) (xy 344.802256 -282.32873) (xy 344.818263 -282.27946) (xy 344.841781 -282.2333)
			(xy 344.872229 -282.191388) (xy 344.908859 -282.154754) (xy 344.950768 -282.124301) (xy 344.996925 -282.100778)
			(xy 345.046193 -282.084765) (xy 345.097359 -282.076655) (xy 345.123262 -282.076144) (xy 345.148774 -282.076635)
			(xy 345.199188 -282.084491) (xy 345.247791 -282.100021) (xy 345.293419 -282.122855) (xy 345.334985 -282.152446)
			(xy 345.371495 -282.188089) (xy 345.387168 -282.208224) (xy 345.799156 -282.208224) (xy 345.814861 -282.188115)
			(xy 345.851364 -282.152468) (xy 345.892922 -282.122871) (xy 345.938545 -282.10003) (xy 345.987141 -282.084491)
			(xy 346.037552 -282.076624) (xy 346.063062 -282.076144) (xy 346.088976 -282.076551) (xy 346.140167 -282.084653)
			(xy 346.18946 -282.100664) (xy 346.235642 -282.12419) (xy 346.277574 -282.154651) (xy 346.314224 -282.191297)
			(xy 346.34469 -282.233226) (xy 346.368221 -282.279404) (xy 346.384238 -282.328696) (xy 346.392346 -282.379886)
			(xy 346.392346 -282.431714) (xy 346.384238 -282.482904) (xy 346.368221 -282.532196) (xy 346.34469 -282.578374)
			(xy 346.314224 -282.620303) (xy 346.277574 -282.656949) (xy 346.235642 -282.68741) (xy 346.18946 -282.710936)
			(xy 346.140167 -282.726947) (xy 346.088976 -282.735049) (xy 346.063062 -282.735528) (xy 346.03755 -282.735064)
			(xy 345.987135 -282.727199) (xy 345.938534 -282.711661) (xy 345.892906 -282.688822) (xy 345.85134 -282.659228)
			(xy 345.81483 -282.623584) (xy 345.799156 -282.603448) (xy 345.387168 -282.603448) (xy 345.371526 -282.623609)
			(xy 345.335009 -282.659249) (xy 345.293436 -282.688839) (xy 345.247802 -282.71167) (xy 345.199195 -282.727199)
			(xy 345.148776 -282.735054) (xy 345.123262 -282.735528) (xy 345.097359 -282.734945) (xy 345.046193 -282.726835)
			(xy 344.996925 -282.710822) (xy 344.950768 -282.687299) (xy 344.908859 -282.656846) (xy 344.872229 -282.620212)
			(xy 344.841781 -282.5783) (xy 344.818263 -282.53214) (xy 344.802256 -282.48287) (xy 344.794152 -282.431703)
			(xy 344.512364 -282.431703) (xy 344.512318 -282.43386) (xy 344.503126 -282.488122) (xy 344.494612 -282.514294)
			(xy 344.486992 -282.536392) (xy 344.692224 -282.891738) (xy 344.715084 -282.896056) (xy 344.739902 -282.901236)
			(xy 344.787678 -282.918192) (xy 344.832294 -282.942264) (xy 344.872699 -282.972884) (xy 344.907939 -283.009329)
			(xy 344.937183 -283.05074) (xy 344.959741 -283.09614) (xy 344.975082 -283.14446) (xy 344.982843 -283.194558)
			(xy 344.983308 -283.219906) (xy 347.143324 -283.219906) (xy 347.143831 -283.194562) (xy 347.151603 -283.144472)
			(xy 347.166948 -283.096161) (xy 347.189506 -283.050768) (xy 347.218745 -283.009362) (xy 347.253975 -282.972918)
			(xy 347.294368 -282.942295) (xy 347.338972 -282.918214) (xy 347.386736 -282.901243) (xy 347.411548 -282.896056)
			(xy 347.434408 -282.891738) (xy 347.639386 -282.5369) (xy 347.631766 -282.514802) (xy 347.623129 -282.488391)
			(xy 347.613803 -282.433617) (xy 347.613224 -282.405836) (xy 347.613732 -282.379949) (xy 347.621831 -282.328811)
			(xy 347.63783 -282.279571) (xy 347.661336 -282.233439) (xy 347.691768 -282.191552) (xy 347.728378 -282.154942)
			(xy 347.770265 -282.12451) (xy 347.816397 -282.101004) (xy 347.865637 -282.085005) (xy 347.916775 -282.076906)
			(xy 347.968549 -282.076906) (xy 348.019687 -282.085005) (xy 348.068927 -282.101004) (xy 348.115059 -282.12451)
			(xy 348.156946 -282.154942) (xy 348.193556 -282.191552) (xy 348.223988 -282.233439) (xy 348.247494 -282.279571)
			(xy 348.263493 -282.328811) (xy 348.271592 -282.379949) (xy 348.2721 -282.405836) (xy 349.492824 -282.405836)
			(xy 349.493229 -282.380499) (xy 349.500992 -282.330422) (xy 349.516324 -282.282122) (xy 349.538866 -282.236737)
			(xy 349.568085 -282.195335) (xy 349.603295 -282.15889) (xy 349.643666 -282.128262) (xy 349.688248 -282.10417)
			(xy 349.735991 -282.087183) (xy 349.760794 -282.081986) (xy 349.783654 -282.077668) (xy 349.988886 -281.722322)
			(xy 349.981266 -281.700478) (xy 349.97264 -281.674196) (xy 349.963326 -281.619675) (xy 349.962724 -281.59202)
			(xy 349.963232 -281.566113) (xy 349.971338 -281.514936) (xy 349.98735 -281.465657) (xy 350.010873 -281.41949)
			(xy 350.041329 -281.377571) (xy 350.077967 -281.340933) (xy 350.119886 -281.310477) (xy 350.166053 -281.286954)
			(xy 350.215332 -281.270942) (xy 350.266509 -281.262836) (xy 350.318323 -281.262836) (xy 350.3695 -281.270942)
			(xy 350.418779 -281.286954) (xy 350.464946 -281.310477) (xy 350.506865 -281.340933) (xy 350.543503 -281.377571)
			(xy 350.573959 -281.41949) (xy 350.597482 -281.465657) (xy 350.613494 -281.514936) (xy 350.6216 -281.566113)
			(xy 350.622108 -281.59202) (xy 350.621645 -281.617395) (xy 350.613874 -281.667545) (xy 350.598503 -281.71591)
			(xy 350.575897 -281.761346) (xy 350.546589 -281.802777) (xy 350.511274 -281.839223) (xy 350.470788 -281.869822)
			(xy 350.426087 -281.893849) (xy 350.37823 -281.910736) (xy 350.353376 -281.91587) (xy 350.330516 -281.920188)
			(xy 350.125538 -282.275026) (xy 350.133412 -282.297124) (xy 350.141978 -282.32348) (xy 350.151173 -282.378127)
			(xy 350.1517 -282.405836) (xy 350.151192 -282.431703) (xy 351.372752 -282.431703) (xy 351.372752 -282.379897)
			(xy 351.380856 -282.32873) (xy 351.396863 -282.27946) (xy 351.420381 -282.2333) (xy 351.450829 -282.191388)
			(xy 351.487459 -282.154754) (xy 351.529368 -282.124301) (xy 351.575525 -282.100778) (xy 351.624793 -282.084765)
			(xy 351.675959 -282.076655) (xy 351.701862 -282.076144) (xy 351.727374 -282.076635) (xy 351.777788 -282.084491)
			(xy 351.826391 -282.100021) (xy 351.872019 -282.122855) (xy 351.913585 -282.152446) (xy 351.950095 -282.188089)
			(xy 351.965768 -282.208224) (xy 352.377756 -282.208224) (xy 352.393461 -282.188115) (xy 352.429964 -282.152468)
			(xy 352.471522 -282.122871) (xy 352.517145 -282.10003) (xy 352.565741 -282.084491) (xy 352.616152 -282.076624)
			(xy 352.641662 -282.076144) (xy 352.667576 -282.076551) (xy 352.718767 -282.084653) (xy 352.76806 -282.100664)
			(xy 352.814242 -282.12419) (xy 352.856174 -282.154651) (xy 352.892824 -282.191297) (xy 352.92329 -282.233226)
			(xy 352.946821 -282.279404) (xy 352.962838 -282.328696) (xy 352.970946 -282.379886) (xy 352.970946 -282.431714)
			(xy 352.962838 -282.482904) (xy 352.946821 -282.532196) (xy 352.92329 -282.578374) (xy 352.892824 -282.620303)
			(xy 352.856174 -282.656949) (xy 352.814242 -282.68741) (xy 352.76806 -282.710936) (xy 352.718767 -282.726947)
			(xy 352.667576 -282.735049) (xy 352.641662 -282.735528) (xy 352.61615 -282.735064) (xy 352.565735 -282.727199)
			(xy 352.517134 -282.711661) (xy 352.471506 -282.688822) (xy 352.42994 -282.659228) (xy 352.39343 -282.623584)
			(xy 352.377756 -282.603448) (xy 351.965768 -282.603448) (xy 351.950126 -282.623609) (xy 351.913609 -282.659249)
			(xy 351.872036 -282.688839) (xy 351.826402 -282.71167) (xy 351.777795 -282.727199) (xy 351.727376 -282.735054)
			(xy 351.701862 -282.735528) (xy 351.675959 -282.734945) (xy 351.624793 -282.726835) (xy 351.575525 -282.710822)
			(xy 351.529368 -282.687299) (xy 351.487459 -282.656846) (xy 351.450829 -282.620212) (xy 351.420381 -282.5783)
			(xy 351.396863 -282.53214) (xy 351.380856 -282.48287) (xy 351.372752 -282.431703) (xy 350.151192 -282.431703)
			(xy 350.151192 -282.431723) (xy 350.143093 -282.482861) (xy 350.127094 -282.532101) (xy 350.103588 -282.578233)
			(xy 350.073156 -282.62012) (xy 350.036546 -282.65673) (xy 349.994659 -282.687162) (xy 349.948527 -282.710668)
			(xy 349.899287 -282.726667) (xy 349.848149 -282.734766) (xy 349.796375 -282.734766) (xy 349.745237 -282.726667)
			(xy 349.695997 -282.710668) (xy 349.649865 -282.687162) (xy 349.607978 -282.65673) (xy 349.571368 -282.62012)
			(xy 349.540936 -282.578233) (xy 349.51743 -282.532101) (xy 349.501431 -282.482861) (xy 349.493332 -282.431723)
			(xy 349.492824 -282.405836) (xy 348.2721 -282.405836) (xy 348.271608 -282.431158) (xy 348.263872 -282.481209)
			(xy 348.248573 -282.529487) (xy 348.22607 -282.574858) (xy 348.196893 -282.616254) (xy 348.161729 -282.6527)
			(xy 348.121404 -282.68334) (xy 348.076868 -282.707453) (xy 348.029168 -282.72447) (xy 348.004384 -282.729686)
			(xy 347.981524 -282.734004) (xy 347.776292 -283.089096) (xy 347.784166 -283.111194) (xy 347.792802 -283.137539)
			(xy 347.80212 -283.192188) (xy 347.802708 -283.219906) (xy 347.8022 -283.24579) (xy 349.023649 -283.24579)
			(xy 349.023649 -283.19401) (xy 349.03175 -283.142868) (xy 349.047751 -283.093623) (xy 349.071259 -283.047487)
			(xy 349.101695 -283.005597) (xy 349.13831 -282.968985) (xy 349.180201 -282.938551) (xy 349.226338 -282.915045)
			(xy 349.275584 -282.899046) (xy 349.326726 -282.890948) (xy 349.352616 -282.890468) (xy 349.378128 -282.890949)
			(xy 349.428541 -282.898811) (xy 349.477143 -282.914346) (xy 349.522771 -282.937181) (xy 349.564336 -282.966773)
			(xy 349.600848 -283.002414) (xy 349.616522 -283.022548) (xy 350.02851 -283.022548) (xy 350.044163 -283.002397)
			(xy 350.080679 -282.966756) (xy 350.122249 -282.937166) (xy 350.167881 -282.914333) (xy 350.216486 -282.898802)
			(xy 350.266903 -282.890944) (xy 350.292416 -282.890468) (xy 350.318303 -282.890965) (xy 350.369439 -282.899066)
			(xy 350.418679 -282.915067) (xy 350.464809 -282.938574) (xy 350.506694 -282.969007) (xy 350.543303 -283.005618)
			(xy 350.573735 -283.047505) (xy 350.597239 -283.093636) (xy 350.613237 -283.142876) (xy 350.621336 -283.194013)
			(xy 350.621336 -283.219906) (xy 352.782124 -283.219906) (xy 352.782631 -283.194562) (xy 352.790403 -283.144472)
			(xy 352.805748 -283.096161) (xy 352.828306 -283.050768) (xy 352.857545 -283.009362) (xy 352.892775 -282.972918)
			(xy 352.933168 -282.942295) (xy 352.977772 -282.918214) (xy 353.025536 -282.901243) (xy 353.050348 -282.896056)
			(xy 353.073208 -282.891738) (xy 353.278186 -282.5369) (xy 353.270566 -282.514802) (xy 353.261929 -282.488391)
			(xy 353.252603 -282.433617) (xy 353.252024 -282.405836) (xy 353.252532 -282.379949) (xy 353.260631 -282.328811)
			(xy 353.27663 -282.279571) (xy 353.300136 -282.233439) (xy 353.330568 -282.191552) (xy 353.367178 -282.154942)
			(xy 353.409065 -282.12451) (xy 353.455197 -282.101004) (xy 353.504437 -282.085005) (xy 353.555575 -282.076906)
			(xy 353.607349 -282.076906) (xy 353.658487 -282.085005) (xy 353.707727 -282.101004) (xy 353.753859 -282.12451)
			(xy 353.795746 -282.154942) (xy 353.832356 -282.191552) (xy 353.862788 -282.233439) (xy 353.886294 -282.279571)
			(xy 353.902293 -282.328811) (xy 353.910392 -282.379949) (xy 353.9109 -282.405836) (xy 353.910408 -282.431158)
			(xy 353.902672 -282.481209) (xy 353.887373 -282.529487) (xy 353.86487 -282.574858) (xy 353.835693 -282.616254)
			(xy 353.800529 -282.6527) (xy 353.760204 -282.68334) (xy 353.715668 -282.707453) (xy 353.667968 -282.72447)
			(xy 353.643184 -282.729686) (xy 353.620324 -282.734004) (xy 353.415092 -283.089096) (xy 353.422966 -283.111194)
			(xy 353.431602 -283.137539) (xy 353.44092 -283.192188) (xy 353.441508 -283.219906) (xy 353.441 -283.245813)
			(xy 353.432894 -283.29699) (xy 353.416882 -283.346269) (xy 353.393359 -283.392436) (xy 353.362903 -283.434355)
			(xy 353.326265 -283.470993) (xy 353.284346 -283.501449) (xy 353.238179 -283.524972) (xy 353.1889 -283.540984)
			(xy 353.137723 -283.54909) (xy 353.085909 -283.54909) (xy 353.034732 -283.540984) (xy 352.985453 -283.524972)
			(xy 352.939286 -283.501449) (xy 352.897367 -283.470993) (xy 352.860729 -283.434355) (xy 352.830273 -283.392436)
			(xy 352.80675 -283.346269) (xy 352.790738 -283.29699) (xy 352.782632 -283.245813) (xy 352.782124 -283.219906)
			(xy 350.621336 -283.219906) (xy 350.621336 -283.245787) (xy 350.613237 -283.296924) (xy 350.597239 -283.346164)
			(xy 350.573735 -283.392295) (xy 350.543303 -283.434182) (xy 350.506694 -283.470793) (xy 350.464809 -283.501226)
			(xy 350.418679 -283.524733) (xy 350.369439 -283.540734) (xy 350.318303 -283.548835) (xy 350.292416 -283.549344)
			(xy 350.266904 -283.548874) (xy 350.216488 -283.541014) (xy 350.167885 -283.52548) (xy 350.122256 -283.502643)
			(xy 350.080691 -283.473047) (xy 350.044182 -283.437401) (xy 350.02851 -283.417264) (xy 349.616522 -283.417264)
			(xy 349.600826 -283.437381) (xy 349.564322 -283.473028) (xy 349.522762 -283.502625) (xy 349.477138 -283.525464)
			(xy 349.428539 -283.541001) (xy 349.378127 -283.548865) (xy 349.352616 -283.549344) (xy 349.326726 -283.548852)
			(xy 349.275584 -283.540754) (xy 349.226338 -283.524755) (xy 349.180201 -283.501249) (xy 349.13831 -283.470815)
			(xy 349.101695 -283.434203) (xy 349.071259 -283.392313) (xy 349.047751 -283.346177) (xy 349.03175 -283.296932)
			(xy 349.023649 -283.24579) (xy 347.8022 -283.24579) (xy 347.8022 -283.245813) (xy 347.794094 -283.29699)
			(xy 347.778082 -283.346269) (xy 347.754559 -283.392436) (xy 347.724103 -283.434355) (xy 347.687465 -283.470993)
			(xy 347.645546 -283.501449) (xy 347.599379 -283.524972) (xy 347.5501 -283.540984) (xy 347.498923 -283.54909)
			(xy 347.447109 -283.54909) (xy 347.395932 -283.540984) (xy 347.346653 -283.524972) (xy 347.300486 -283.501449)
			(xy 347.258567 -283.470993) (xy 347.221929 -283.434355) (xy 347.191473 -283.392436) (xy 347.16795 -283.346269)
			(xy 347.151938 -283.29699) (xy 347.143832 -283.245813) (xy 347.143324 -283.219906) (xy 344.983308 -283.219906)
			(xy 344.9828 -283.245813) (xy 344.974694 -283.29699) (xy 344.958682 -283.346269) (xy 344.935159 -283.392436)
			(xy 344.904703 -283.434355) (xy 344.868065 -283.470993) (xy 344.826146 -283.501449) (xy 344.779979 -283.524972)
			(xy 344.7307 -283.540984) (xy 344.679523 -283.54909) (xy 344.627709 -283.54909) (xy 344.576532 -283.540984)
			(xy 344.527253 -283.524972) (xy 344.481086 -283.501449) (xy 344.439167 -283.470993) (xy 344.402529 -283.434355)
			(xy 344.372073 -283.392436) (xy 344.34855 -283.346269) (xy 344.332538 -283.29699) (xy 344.324432 -283.245813)
			(xy 344.323924 -283.219906) (xy 344.324518 -283.192189) (xy 344.333841 -283.137542) (xy 344.342466 -283.111194)
			(xy 344.35034 -283.089096) (xy 344.145362 -282.734004) (xy 344.122248 -282.729686) (xy 344.097423 -282.724538)
			(xy 344.049642 -282.707582) (xy 344.005022 -282.683508) (xy 343.964615 -282.652886) (xy 343.929374 -282.616436)
			(xy 343.900131 -282.57502) (xy 343.877575 -282.529614) (xy 343.862239 -282.481289) (xy 343.854484 -282.431186)
			(xy 343.854024 -282.405836) (xy 343.5731 -282.405836) (xy 343.572592 -282.431723) (xy 343.564493 -282.482861)
			(xy 343.548494 -282.532101) (xy 343.524988 -282.578233) (xy 343.494556 -282.62012) (xy 343.457946 -282.65673)
			(xy 343.416059 -282.687162) (xy 343.369927 -282.710668) (xy 343.320687 -282.726667) (xy 343.269549 -282.734766)
			(xy 343.217775 -282.734766) (xy 343.166637 -282.726667) (xy 343.117397 -282.710668) (xy 343.071265 -282.687162)
			(xy 343.029378 -282.65673) (xy 342.992768 -282.62012) (xy 342.962336 -282.578233) (xy 342.93883 -282.532101)
			(xy 342.922831 -282.482861) (xy 342.914732 -282.431723) (xy 342.914224 -282.405836) (xy 341.694008 -282.405836)
			(xy 341.6935 -282.431743) (xy 341.685394 -282.48292) (xy 341.669382 -282.532199) (xy 341.645859 -282.578366)
			(xy 341.615403 -282.620285) (xy 341.578765 -282.656923) (xy 341.536846 -282.687379) (xy 341.490679 -282.710902)
			(xy 341.4414 -282.726914) (xy 341.390223 -282.73502) (xy 341.338409 -282.73502) (xy 341.287232 -282.726914)
			(xy 341.237953 -282.710902) (xy 341.191786 -282.687379) (xy 341.149867 -282.656923) (xy 341.113229 -282.620285)
			(xy 341.082773 -282.578366) (xy 341.05925 -282.532199) (xy 341.043238 -282.48292) (xy 341.035132 -282.431743)
			(xy 341.034624 -282.405836) (xy 339.814408 -282.405836) (xy 339.813997 -282.431202) (xy 339.806243 -282.481337)
			(xy 339.790893 -282.52969) (xy 339.768309 -282.575118) (xy 339.739027 -282.616545) (xy 339.703739 -282.652993)
			(xy 339.663279 -282.683598) (xy 339.618605 -282.707637) (xy 339.570773 -282.724541) (xy 339.54593 -282.729686)
			(xy 339.52307 -282.734004) (xy 339.318092 -283.089096) (xy 339.325712 -283.11094) (xy 339.33426 -283.137236)
			(xy 339.343458 -283.191753) (xy 339.344 -283.219398) (xy 339.344 -283.219906) (xy 339.343492 -283.245785)
			(xy 340.565275 -283.245785) (xy 340.565275 -283.194015) (xy 340.573373 -283.142882) (xy 340.58937 -283.093646)
			(xy 340.612872 -283.047517) (xy 340.643299 -283.005633) (xy 340.679904 -282.969024) (xy 340.721785 -282.938592)
			(xy 340.76791 -282.915085) (xy 340.817145 -282.899082) (xy 340.868277 -282.890978) (xy 340.894162 -282.890468)
			(xy 340.919672 -282.890989) (xy 340.970084 -282.898843) (xy 341.018684 -282.914369) (xy 341.064312 -282.937197)
			(xy 341.105879 -282.966782) (xy 341.142392 -283.002417) (xy 341.158068 -283.022548) (xy 341.570056 -283.022548)
			(xy 341.585741 -283.002422) (xy 341.62225 -282.96678) (xy 341.663813 -282.937187) (xy 341.709439 -282.91435)
			(xy 341.758039 -282.898813) (xy 341.808451 -282.890948) (xy 341.833962 -282.890468) (xy 341.859854 -282.890934)
			(xy 341.911001 -282.89903) (xy 341.960252 -282.915027) (xy 342.006393 -282.938533) (xy 342.048289 -282.968968)
			(xy 342.084908 -283.005582) (xy 342.115347 -283.047475) (xy 342.138858 -283.093613) (xy 342.154861 -283.142862)
			(xy 342.162963 -283.194008) (xy 342.162963 -283.245792) (xy 342.154861 -283.296938) (xy 342.138858 -283.346187)
			(xy 342.115347 -283.392325) (xy 342.084908 -283.434218) (xy 342.048289 -283.470832) (xy 342.006393 -283.501267)
			(xy 341.960252 -283.524773) (xy 341.911001 -283.54077) (xy 341.859854 -283.548866) (xy 341.833962 -283.549344)
			(xy 341.808448 -283.548913) (xy 341.75803 -283.541045) (xy 341.709427 -283.525503) (xy 341.663798 -283.502658)
			(xy 341.622234 -283.473056) (xy 341.585727 -283.437404) (xy 341.570056 -283.417264) (xy 341.158068 -283.417264)
			(xy 341.142404 -283.437407) (xy 341.105893 -283.473052) (xy 341.064326 -283.502646) (xy 341.018696 -283.525481)
			(xy 340.970092 -283.541013) (xy 340.919675 -283.548869) (xy 340.894162 -283.549344) (xy 340.868277 -283.548822)
			(xy 340.817145 -283.540718) (xy 340.76791 -283.524715) (xy 340.721785 -283.501208) (xy 340.679904 -283.470776)
			(xy 340.643299 -283.434167) (xy 340.612872 -283.392283) (xy 340.58937 -283.346154) (xy 340.573373 -283.296918)
			(xy 340.565275 -283.245785) (xy 339.343492 -283.245785) (xy 339.343492 -283.245793) (xy 339.335393 -283.296931)
			(xy 339.319394 -283.346171) (xy 339.295888 -283.392303) (xy 339.265456 -283.43419) (xy 339.228846 -283.4708)
			(xy 339.186959 -283.501232) (xy 339.140827 -283.524738) (xy 339.091587 -283.540737) (xy 339.040449 -283.548836)
			(xy 338.988675 -283.548836) (xy 338.937537 -283.540737) (xy 338.888297 -283.524738) (xy 338.842165 -283.501232)
			(xy 338.800278 -283.4708) (xy 338.763668 -283.43419) (xy 338.733236 -283.392303) (xy 338.70973 -283.346171)
			(xy 338.693731 -283.296931) (xy 338.685632 -283.245793) (xy 338.685124 -283.219906) (xy 336.5246 -283.219906)
			(xy 336.524092 -283.245793) (xy 336.515993 -283.296931) (xy 336.499994 -283.346171) (xy 336.476488 -283.392303)
			(xy 336.446056 -283.43419) (xy 336.409446 -283.4708) (xy 336.367559 -283.501232) (xy 336.321427 -283.524738)
			(xy 336.272187 -283.540737) (xy 336.221049 -283.548836) (xy 336.169275 -283.548836) (xy 336.118137 -283.540737)
			(xy 336.068897 -283.524738) (xy 336.022765 -283.501232) (xy 335.980878 -283.4708) (xy 335.944268 -283.43419)
			(xy 335.913836 -283.392303) (xy 335.89033 -283.346171) (xy 335.874331 -283.296931) (xy 335.866232 -283.245793)
			(xy 335.865724 -283.219906) (xy 335.866254 -283.192198) (xy 335.875449 -283.137551) (xy 335.884012 -283.111194)
			(xy 335.891886 -283.089096) (xy 335.686654 -282.734004) (xy 335.663794 -282.729686) (xy 335.639001 -282.724454)
			(xy 335.591266 -282.707468) (xy 335.546691 -282.683379) (xy 335.506327 -282.652753) (xy 335.471124 -282.616312)
			(xy 335.441911 -282.574914) (xy 335.419375 -282.529534) (xy 335.404048 -282.48124) (xy 335.396291 -282.43117)
			(xy 335.395824 -282.405836) (xy 335.115408 -282.405836) (xy 335.1149 -282.431743) (xy 335.106794 -282.48292)
			(xy 335.090782 -282.532199) (xy 335.067259 -282.578366) (xy 335.036803 -282.620285) (xy 335.000165 -282.656923)
			(xy 334.958246 -282.687379) (xy 334.912079 -282.710902) (xy 334.8628 -282.726914) (xy 334.811623 -282.73502)
			(xy 334.759809 -282.73502) (xy 334.708632 -282.726914) (xy 334.659353 -282.710902) (xy 334.613186 -282.687379)
			(xy 334.571267 -282.656923) (xy 334.534629 -282.620285) (xy 334.504173 -282.578366) (xy 334.48065 -282.532199)
			(xy 334.464638 -282.48292) (xy 334.456532 -282.431743) (xy 334.456024 -282.405836) (xy 106.910632 -282.405836)
			(xy 106.910124 -282.431723) (xy 106.902025 -282.482861) (xy 106.886026 -282.532101) (xy 106.86252 -282.578233)
			(xy 106.832088 -282.62012) (xy 106.795478 -282.65673) (xy 106.753591 -282.687162) (xy 106.707459 -282.710668)
			(xy 106.658219 -282.726667) (xy 106.607081 -282.734766) (xy 106.555307 -282.734766) (xy 106.504169 -282.726667)
			(xy 106.454929 -282.710668) (xy 106.408797 -282.687162) (xy 106.36691 -282.65673) (xy 106.3303 -282.62012)
			(xy 106.299868 -282.578233) (xy 106.276362 -282.532101) (xy 106.260363 -282.482861) (xy 106.252264 -282.431723)
			(xy 106.251756 -282.405836) (xy 106.252296 -282.378128) (xy 106.261484 -282.323482) (xy 106.270044 -282.297124)
			(xy 106.277918 -282.275026) (xy 106.07294 -281.920188) (xy 106.05008 -281.91587) (xy 106.025256 -281.910713)
			(xy 105.977474 -281.893761) (xy 105.932853 -281.86969) (xy 105.892445 -281.839069) (xy 105.857203 -281.802621)
			(xy 105.827959 -281.761205) (xy 105.805403 -281.715799) (xy 105.790068 -281.667474) (xy 105.782315 -281.61737)
			(xy 105.781856 -281.59202) (xy 104.56164 -281.59202) (xy 104.561132 -281.617927) (xy 104.553026 -281.669104)
			(xy 104.537014 -281.718383) (xy 104.513491 -281.76455) (xy 104.483035 -281.806469) (xy 104.446397 -281.843107)
			(xy 104.404478 -281.873563) (xy 104.358311 -281.897086) (xy 104.309032 -281.913098) (xy 104.257855 -281.921204)
			(xy 104.206041 -281.921204) (xy 104.154864 -281.913098) (xy 104.105585 -281.897086) (xy 104.059418 -281.873563)
			(xy 104.017499 -281.843107) (xy 103.980861 -281.806469) (xy 103.950405 -281.76455) (xy 103.926882 -281.718383)
			(xy 103.91087 -281.669104) (xy 103.902764 -281.617927) (xy 103.902256 -281.59202) (xy 103.902852 -281.564303)
			(xy 103.912174 -281.509656) (xy 103.920798 -281.483308) (xy 103.928672 -281.46121) (xy 103.723694 -281.106372)
			(xy 103.700834 -281.102054) (xy 103.676009 -281.096858) (xy 103.628203 -281.079927) (xy 103.583555 -281.055874)
			(xy 103.543117 -281.025267) (xy 103.507844 -280.988827) (xy 103.478568 -280.947415) (xy 103.45598 -280.902007)
			(xy 103.440613 -280.853676) (xy 103.43283 -280.803562) (xy 103.432356 -280.778204) (xy 101.271832 -280.778204)
			(xy 101.271832 -280.778712) (xy 101.271241 -280.806228) (xy 101.262055 -280.860489) (xy 101.253544 -280.886662)
			(xy 101.245924 -280.908506) (xy 101.451156 -281.263852) (xy 101.474016 -281.26817) (xy 101.498826 -281.273386)
			(xy 101.546603 -281.290334) (xy 101.591222 -281.314398) (xy 101.631628 -281.345012) (xy 101.66687 -281.381453)
			(xy 101.696116 -281.422861) (xy 101.718675 -281.468259) (xy 101.734016 -281.516576) (xy 101.741776 -281.566673)
			(xy 101.74224 -281.59202) (xy 101.741732 -281.617927) (xy 101.733626 -281.669104) (xy 101.717614 -281.718383)
			(xy 101.694091 -281.76455) (xy 101.663635 -281.806469) (xy 101.626997 -281.843107) (xy 101.585078 -281.873563)
			(xy 101.538911 -281.897086) (xy 101.489632 -281.913098) (xy 101.438455 -281.921204) (xy 101.386641 -281.921204)
			(xy 101.335464 -281.913098) (xy 101.286185 -281.897086) (xy 101.240018 -281.873563) (xy 101.198099 -281.843107)
			(xy 101.161461 -281.806469) (xy 101.131005 -281.76455) (xy 101.107482 -281.718383) (xy 101.09147 -281.669104)
			(xy 101.083364 -281.617927) (xy 101.082856 -281.59202) (xy 101.083452 -281.564303) (xy 101.092774 -281.509656)
			(xy 101.101398 -281.483308) (xy 101.109272 -281.46121) (xy 100.904294 -281.106372) (xy 100.881434 -281.102054)
			(xy 100.856609 -281.096858) (xy 100.808803 -281.079927) (xy 100.764155 -281.055874) (xy 100.723717 -281.025267)
			(xy 100.688444 -280.988827) (xy 100.659168 -280.947415) (xy 100.63658 -280.902007) (xy 100.621213 -280.853676)
			(xy 100.61343 -280.803562) (xy 100.612956 -280.778204) (xy 98.452432 -280.778204) (xy 98.451927 -280.803537)
			(xy 98.444175 -280.853607) (xy 98.428854 -280.901902) (xy 98.406324 -280.947284) (xy 98.377117 -280.988685)
			(xy 98.34192 -281.025131) (xy 98.301561 -281.055762) (xy 98.256992 -281.079859) (xy 98.20926 -281.096853)
			(xy 98.184462 -281.102054) (xy 98.161602 -281.106372) (xy 97.956624 -281.46121) (xy 97.964498 -281.483308)
			(xy 97.973138 -281.509652) (xy 97.982453 -281.564301) (xy 97.98304 -281.59202) (xy 97.982532 -281.61791)
			(xy 99.20371 -281.61791) (xy 99.20371 -281.56609) (xy 99.211817 -281.514907) (xy 99.227832 -281.465624)
			(xy 99.25136 -281.419452) (xy 99.281822 -281.37753) (xy 99.318467 -281.34089) (xy 99.360393 -281.310435)
			(xy 99.406568 -281.286913) (xy 99.455854 -281.270906) (xy 99.507038 -281.262806) (xy 99.532948 -281.262328)
			(xy 99.558462 -281.262762) (xy 99.608879 -281.270631) (xy 99.657482 -281.286173) (xy 99.70311 -281.309017)
			(xy 99.744675 -281.338618) (xy 99.781182 -281.374269) (xy 99.796854 -281.394408) (xy 100.208842 -281.394408)
			(xy 100.224493 -281.374254) (xy 100.261007 -281.338611) (xy 100.302577 -281.309019) (xy 100.34821 -281.286186)
			(xy 100.396816 -281.270657) (xy 100.447235 -281.262802) (xy 100.472748 -281.262328) (xy 100.498654 -281.2628)
			(xy 100.549829 -281.270912) (xy 100.599104 -281.286928) (xy 100.645267 -281.310456) (xy 100.687182 -281.340914)
			(xy 100.723817 -281.377554) (xy 100.754269 -281.419474) (xy 100.77779 -281.465641) (xy 100.7938 -281.514918)
			(xy 100.801904 -281.566093) (xy 100.801904 -281.617907) (xy 100.7938 -281.669082) (xy 100.77779 -281.718359)
			(xy 100.754269 -281.764526) (xy 100.723817 -281.806446) (xy 100.687182 -281.843086) (xy 100.645267 -281.873544)
			(xy 100.599104 -281.897072) (xy 100.549829 -281.913088) (xy 100.498654 -281.9212) (xy 100.472748 -281.921712)
			(xy 100.447238 -281.921192) (xy 100.396825 -281.913339) (xy 100.348225 -281.897813) (xy 100.302596 -281.874985)
			(xy 100.26103 -281.8454) (xy 100.224517 -281.809764) (xy 100.208842 -281.789632) (xy 99.796854 -281.789632)
			(xy 99.781158 -281.809749) (xy 99.744652 -281.845392) (xy 99.703091 -281.874987) (xy 99.657467 -281.897826)
			(xy 99.60887 -281.913365) (xy 99.558459 -281.921231) (xy 99.532948 -281.921712) (xy 99.507038 -281.921194)
			(xy 99.455854 -281.913094) (xy 99.406568 -281.897087) (xy 99.360393 -281.873565) (xy 99.318467 -281.84311)
			(xy 99.281822 -281.80647) (xy 99.25136 -281.764548) (xy 99.227832 -281.718376) (xy 99.211817 -281.669093)
			(xy 99.20371 -281.61791) (xy 97.982532 -281.61791) (xy 97.982532 -281.617927) (xy 97.974426 -281.669104)
			(xy 97.958414 -281.718383) (xy 97.934891 -281.76455) (xy 97.904435 -281.806469) (xy 97.867797 -281.843107)
			(xy 97.825878 -281.873563) (xy 97.779711 -281.897086) (xy 97.730432 -281.913098) (xy 97.679255 -281.921204)
			(xy 97.627441 -281.921204) (xy 97.576264 -281.913098) (xy 97.526985 -281.897086) (xy 97.480818 -281.873563)
			(xy 97.438899 -281.843107) (xy 97.402261 -281.806469) (xy 97.371805 -281.76455) (xy 97.348282 -281.718383)
			(xy 97.33227 -281.669104) (xy 97.324164 -281.617927) (xy 97.323656 -281.59202) (xy 96.10344 -281.59202)
			(xy 96.103032 -281.617397) (xy 96.095259 -281.667553) (xy 96.079885 -281.715923) (xy 96.057273 -281.761362)
			(xy 96.027958 -281.802795) (xy 95.992635 -281.839241) (xy 95.95214 -281.869837) (xy 95.907431 -281.89386)
			(xy 95.859566 -281.910741) (xy 95.834708 -281.91587) (xy 95.811848 -281.920188) (xy 95.60687 -282.275026)
			(xy 95.614744 -282.297124) (xy 95.623311 -282.32348) (xy 95.632506 -282.378127) (xy 95.633032 -282.405836)
			(xy 95.913956 -282.405836) (xy 95.914464 -282.379949) (xy 95.922563 -282.328811) (xy 95.938562 -282.279571)
			(xy 95.962068 -282.233439) (xy 95.9925 -282.191552) (xy 96.02911 -282.154942) (xy 96.070997 -282.12451)
			(xy 96.117129 -282.101004) (xy 96.166369 -282.085005) (xy 96.217507 -282.076906) (xy 96.269281 -282.076906)
			(xy 96.320419 -282.085005) (xy 96.369659 -282.101004) (xy 96.415791 -282.12451) (xy 96.457678 -282.154942)
			(xy 96.494288 -282.191552) (xy 96.52472 -282.233439) (xy 96.548226 -282.279571) (xy 96.564225 -282.328811)
			(xy 96.572324 -282.379949) (xy 96.572832 -282.405836) (xy 96.572832 -282.406344) (xy 96.572295 -282.431704)
			(xy 96.854052 -282.431704) (xy 96.854052 -282.379896) (xy 96.862157 -282.328725) (xy 96.878166 -282.279453)
			(xy 96.901687 -282.233291) (xy 96.932138 -282.191377) (xy 96.968772 -282.154742) (xy 97.010686 -282.12429)
			(xy 97.056847 -282.100769) (xy 97.106119 -282.084758) (xy 97.15729 -282.076653) (xy 97.183194 -282.076144)
			(xy 97.208707 -282.076611) (xy 97.259122 -282.084472) (xy 97.307725 -282.100007) (xy 97.353354 -282.122845)
			(xy 97.394919 -282.152441) (xy 97.431427 -282.188087) (xy 97.4471 -282.208224) (xy 97.859088 -282.208224)
			(xy 97.874775 -282.188099) (xy 97.911281 -282.152454) (xy 97.952843 -282.122858) (xy 97.998469 -282.10002)
			(xy 98.047069 -282.084484) (xy 98.097483 -282.076622) (xy 98.122994 -282.076144) (xy 98.148907 -282.076553)
			(xy 98.200094 -282.08466) (xy 98.249383 -282.100674) (xy 98.295559 -282.124201) (xy 98.337487 -282.154663)
			(xy 98.374133 -282.191308) (xy 98.404596 -282.233235) (xy 98.428124 -282.279412) (xy 98.444139 -282.3287)
			(xy 98.452246 -282.379887) (xy 98.452246 -282.431713) (xy 98.444139 -282.4829) (xy 98.428124 -282.532188)
			(xy 98.404596 -282.578365) (xy 98.374133 -282.620292) (xy 98.337487 -282.656937) (xy 98.295559 -282.687399)
			(xy 98.249383 -282.710926) (xy 98.200094 -282.72694) (xy 98.148907 -282.735047) (xy 98.122994 -282.735528)
			(xy 98.097483 -282.735041) (xy 98.047069 -282.72718) (xy 97.998468 -282.711647) (xy 97.95284 -282.688813)
			(xy 97.911274 -282.659222) (xy 97.874762 -282.623582) (xy 97.859088 -282.603448) (xy 97.4471 -282.603448)
			(xy 97.43144 -282.623594) (xy 97.394926 -282.659235) (xy 97.353357 -282.688826) (xy 97.307726 -282.71166)
			(xy 97.259123 -282.727192) (xy 97.208707 -282.735052) (xy 97.183194 -282.735528) (xy 97.15729 -282.734947)
			(xy 97.106119 -282.726842) (xy 97.056847 -282.710831) (xy 97.010686 -282.68731) (xy 96.968772 -282.656858)
			(xy 96.932138 -282.620223) (xy 96.901687 -282.578309) (xy 96.878166 -282.532147) (xy 96.862157 -282.482875)
			(xy 96.854052 -282.431704) (xy 96.572295 -282.431704) (xy 96.572249 -282.43386) (xy 96.563058 -282.488121)
			(xy 96.554544 -282.514294) (xy 96.546924 -282.536392) (xy 96.752156 -282.891738) (xy 96.775016 -282.896056)
			(xy 96.799823 -282.901285) (xy 96.847599 -282.918232) (xy 96.892217 -282.942295) (xy 96.932623 -282.972907)
			(xy 96.967865 -283.009346) (xy 96.997111 -283.050752) (xy 97.019671 -283.096149) (xy 97.035013 -283.144464)
			(xy 97.042775 -283.194559) (xy 97.04324 -283.219906) (xy 99.203256 -283.219906) (xy 99.203737 -283.19456)
			(xy 99.21151 -283.144468) (xy 99.226857 -283.096156) (xy 99.249417 -283.050761) (xy 99.278659 -283.009354)
			(xy 99.313894 -282.97291) (xy 99.354291 -282.942288) (xy 99.398899 -282.918209) (xy 99.446666 -282.901241)
			(xy 99.47148 -282.896056) (xy 99.49434 -282.891738) (xy 99.699318 -282.5369) (xy 99.691698 -282.514802)
			(xy 99.683062 -282.488391) (xy 99.673735 -282.433617) (xy 99.673156 -282.405836) (xy 99.673664 -282.379949)
			(xy 99.681763 -282.328811) (xy 99.697762 -282.279571) (xy 99.721268 -282.233439) (xy 99.7517 -282.191552)
			(xy 99.78831 -282.154942) (xy 99.830197 -282.12451) (xy 99.876329 -282.101004) (xy 99.925569 -282.085005)
			(xy 99.976707 -282.076906) (xy 100.028481 -282.076906) (xy 100.079619 -282.085005) (xy 100.128859 -282.101004)
			(xy 100.174991 -282.12451) (xy 100.216878 -282.154942) (xy 100.253488 -282.191552) (xy 100.28392 -282.233439)
			(xy 100.307426 -282.279571) (xy 100.323425 -282.328811) (xy 100.331524 -282.379949) (xy 100.332032 -282.405836)
			(xy 101.552756 -282.405836) (xy 101.553216 -282.380501) (xy 101.560977 -282.33043) (xy 101.576305 -282.282135)
			(xy 101.598841 -282.236753) (xy 101.628054 -282.195352) (xy 101.663256 -282.158908) (xy 101.703619 -282.128277)
			(xy 101.748192 -282.104181) (xy 101.795927 -282.087187) (xy 101.820726 -282.081986) (xy 101.843586 -282.077668)
			(xy 102.048818 -281.722322) (xy 102.041198 -281.700478) (xy 102.03257 -281.674197) (xy 102.023258 -281.619675)
			(xy 102.022656 -281.59202) (xy 102.023164 -281.566113) (xy 102.03127 -281.514936) (xy 102.047282 -281.465657)
			(xy 102.070805 -281.41949) (xy 102.101261 -281.377571) (xy 102.137899 -281.340933) (xy 102.179818 -281.310477)
			(xy 102.225985 -281.286954) (xy 102.275264 -281.270942) (xy 102.326441 -281.262836) (xy 102.378255 -281.262836)
			(xy 102.429432 -281.270942) (xy 102.478711 -281.286954) (xy 102.524878 -281.310477) (xy 102.566797 -281.340933)
			(xy 102.603435 -281.377571) (xy 102.633891 -281.41949) (xy 102.657414 -281.465657) (xy 102.673426 -281.514936)
			(xy 102.681532 -281.566113) (xy 102.68204 -281.59202) (xy 102.681632 -281.617397) (xy 102.673859 -281.667553)
			(xy 102.658485 -281.715923) (xy 102.635873 -281.761362) (xy 102.606558 -281.802795) (xy 102.571235 -281.839241)
			(xy 102.53074 -281.869837) (xy 102.486031 -281.89386) (xy 102.438166 -281.910741) (xy 102.413308 -281.91587)
			(xy 102.390448 -281.920188) (xy 102.18547 -282.275026) (xy 102.193344 -282.297124) (xy 102.201911 -282.32348)
			(xy 102.211106 -282.378127) (xy 102.211632 -282.405836) (xy 102.211124 -282.431704) (xy 103.432652 -282.431704)
			(xy 103.432652 -282.379896) (xy 103.440757 -282.328725) (xy 103.456766 -282.279453) (xy 103.480287 -282.233291)
			(xy 103.510738 -282.191377) (xy 103.547372 -282.154742) (xy 103.589286 -282.12429) (xy 103.635447 -282.100769)
			(xy 103.684719 -282.084758) (xy 103.73589 -282.076653) (xy 103.761794 -282.076144) (xy 103.787307 -282.076611)
			(xy 103.837722 -282.084472) (xy 103.886325 -282.100007) (xy 103.931954 -282.122845) (xy 103.973519 -282.152441)
			(xy 104.010027 -282.188087) (xy 104.0257 -282.208224) (xy 104.437688 -282.208224) (xy 104.453375 -282.188099)
			(xy 104.489881 -282.152454) (xy 104.531443 -282.122858) (xy 104.577069 -282.10002) (xy 104.625669 -282.084484)
			(xy 104.676083 -282.076622) (xy 104.701594 -282.076144) (xy 104.727507 -282.076553) (xy 104.778694 -282.08466)
			(xy 104.827983 -282.100674) (xy 104.874159 -282.124201) (xy 104.916087 -282.154663) (xy 104.952733 -282.191308)
			(xy 104.983196 -282.233235) (xy 105.006724 -282.279412) (xy 105.022739 -282.3287) (xy 105.030846 -282.379887)
			(xy 105.030846 -282.431713) (xy 105.022739 -282.4829) (xy 105.006724 -282.532188) (xy 104.983196 -282.578365)
			(xy 104.952733 -282.620292) (xy 104.916087 -282.656937) (xy 104.874159 -282.687399) (xy 104.827983 -282.710926)
			(xy 104.778694 -282.72694) (xy 104.727507 -282.735047) (xy 104.701594 -282.735528) (xy 104.676083 -282.735041)
			(xy 104.625669 -282.72718) (xy 104.577068 -282.711647) (xy 104.53144 -282.688813) (xy 104.489874 -282.659222)
			(xy 104.453362 -282.623582) (xy 104.437688 -282.603448) (xy 104.0257 -282.603448) (xy 104.01004 -282.623594)
			(xy 103.973526 -282.659235) (xy 103.931957 -282.688826) (xy 103.886326 -282.71166) (xy 103.837723 -282.727192)
			(xy 103.787307 -282.735052) (xy 103.761794 -282.735528) (xy 103.73589 -282.734947) (xy 103.684719 -282.726842)
			(xy 103.635447 -282.710831) (xy 103.589286 -282.68731) (xy 103.547372 -282.656858) (xy 103.510738 -282.620223)
			(xy 103.480287 -282.578309) (xy 103.456766 -282.532147) (xy 103.440757 -282.482875) (xy 103.432652 -282.431704)
			(xy 102.211124 -282.431704) (xy 102.211124 -282.431723) (xy 102.203025 -282.482861) (xy 102.187026 -282.532101)
			(xy 102.16352 -282.578233) (xy 102.133088 -282.62012) (xy 102.096478 -282.65673) (xy 102.054591 -282.687162)
			(xy 102.008459 -282.710668) (xy 101.959219 -282.726667) (xy 101.908081 -282.734766) (xy 101.856307 -282.734766)
			(xy 101.805169 -282.726667) (xy 101.755929 -282.710668) (xy 101.709797 -282.687162) (xy 101.66791 -282.65673)
			(xy 101.6313 -282.62012) (xy 101.600868 -282.578233) (xy 101.577362 -282.532101) (xy 101.561363 -282.482861)
			(xy 101.553264 -282.431723) (xy 101.552756 -282.405836) (xy 100.332032 -282.405836) (xy 100.331594 -282.431161)
			(xy 100.323857 -282.481217) (xy 100.308554 -282.5295) (xy 100.286046 -282.574874) (xy 100.256862 -282.616272)
			(xy 100.22169 -282.652718) (xy 100.181356 -282.683356) (xy 100.136812 -282.707464) (xy 100.089103 -282.724474)
			(xy 100.064316 -282.729686) (xy 100.041456 -282.734004) (xy 99.836224 -283.089096) (xy 99.844098 -283.111194)
			(xy 99.852735 -283.137539) (xy 99.862052 -283.192188) (xy 99.86264 -283.219906) (xy 99.862132 -283.245791)
			(xy 101.083549 -283.245791) (xy 101.083549 -283.194009) (xy 101.091651 -283.142863) (xy 101.107654 -283.093616)
			(xy 101.131165 -283.047478) (xy 101.161604 -283.005586) (xy 101.198223 -282.968973) (xy 101.240119 -282.93854)
			(xy 101.28626 -282.915036) (xy 101.33551 -282.89904) (xy 101.386657 -282.890946) (xy 101.412548 -282.890468)
			(xy 101.43806 -282.890926) (xy 101.488475 -282.898793) (xy 101.537077 -282.914332) (xy 101.582705 -282.937172)
			(xy 101.62427 -282.966767) (xy 101.66078 -283.002412) (xy 101.676454 -283.022548) (xy 102.088442 -283.022548)
			(xy 102.104077 -283.002381) (xy 102.140596 -282.966741) (xy 102.18217 -282.937153) (xy 102.227806 -282.914323)
			(xy 102.276414 -282.898795) (xy 102.326834 -282.890941) (xy 102.352348 -282.890468) (xy 102.378233 -282.890967)
			(xy 102.429366 -282.899073) (xy 102.478601 -282.915077) (xy 102.524727 -282.938585) (xy 102.566608 -282.969019)
			(xy 102.603213 -283.005629) (xy 102.63364 -283.047514) (xy 102.657142 -283.093643) (xy 102.673139 -283.142881)
			(xy 102.681237 -283.194015) (xy 102.681237 -283.219906) (xy 104.842056 -283.219906) (xy 104.842537 -283.19456)
			(xy 104.85031 -283.144468) (xy 104.865657 -283.096156) (xy 104.888217 -283.050761) (xy 104.917459 -283.009354)
			(xy 104.952694 -282.97291) (xy 104.993091 -282.942288) (xy 105.037699 -282.918209) (xy 105.085466 -282.901241)
			(xy 105.11028 -282.896056) (xy 105.13314 -282.891738) (xy 105.338118 -282.5369) (xy 105.330498 -282.514802)
			(xy 105.321862 -282.488391) (xy 105.312535 -282.433617) (xy 105.311956 -282.405836) (xy 105.312464 -282.379949)
			(xy 105.320563 -282.328811) (xy 105.336562 -282.279571) (xy 105.360068 -282.233439) (xy 105.3905 -282.191552)
			(xy 105.42711 -282.154942) (xy 105.468997 -282.12451) (xy 105.515129 -282.101004) (xy 105.564369 -282.085005)
			(xy 105.615507 -282.076906) (xy 105.667281 -282.076906) (xy 105.718419 -282.085005) (xy 105.767659 -282.101004)
			(xy 105.813791 -282.12451) (xy 105.855678 -282.154942) (xy 105.892288 -282.191552) (xy 105.92272 -282.233439)
			(xy 105.946226 -282.279571) (xy 105.962225 -282.328811) (xy 105.970324 -282.379949) (xy 105.970832 -282.405836)
			(xy 105.970394 -282.431161) (xy 105.962657 -282.481217) (xy 105.947354 -282.5295) (xy 105.924846 -282.574874)
			(xy 105.895662 -282.616272) (xy 105.86049 -282.652718) (xy 105.820156 -282.683356) (xy 105.775612 -282.707464)
			(xy 105.727903 -282.724474) (xy 105.703116 -282.729686) (xy 105.680256 -282.734004) (xy 105.475024 -283.089096)
			(xy 105.482898 -283.111194) (xy 105.491535 -283.137539) (xy 105.500852 -283.192188) (xy 105.50144 -283.219906)
			(xy 105.500932 -283.245813) (xy 105.492826 -283.29699) (xy 105.476814 -283.346269) (xy 105.453291 -283.392436)
			(xy 105.422835 -283.434355) (xy 105.386197 -283.470993) (xy 105.344278 -283.501449) (xy 105.298111 -283.524972)
			(xy 105.248832 -283.540984) (xy 105.197655 -283.54909) (xy 105.145841 -283.54909) (xy 105.094664 -283.540984)
			(xy 105.045385 -283.524972) (xy 104.999218 -283.501449) (xy 104.957299 -283.470993) (xy 104.920661 -283.434355)
			(xy 104.890205 -283.392436) (xy 104.866682 -283.346269) (xy 104.85067 -283.29699) (xy 104.842564 -283.245813)
			(xy 104.842056 -283.219906) (xy 102.681237 -283.219906) (xy 102.681237 -283.245785) (xy 102.673139 -283.296919)
			(xy 102.657142 -283.346157) (xy 102.63364 -283.392286) (xy 102.603213 -283.434171) (xy 102.566608 -283.470781)
			(xy 102.524727 -283.501215) (xy 102.478601 -283.524723) (xy 102.429366 -283.540727) (xy 102.378233 -283.548833)
			(xy 102.352348 -283.549344) (xy 102.326836 -283.548851) (xy 102.276422 -283.540996) (xy 102.227819 -283.525467)
			(xy 102.18219 -283.502633) (xy 102.140624 -283.473042) (xy 102.104115 -283.437399) (xy 102.088442 -283.417264)
			(xy 101.676454 -283.417264) (xy 101.660739 -283.437366) (xy 101.624239 -283.473014) (xy 101.582683 -283.502612)
			(xy 101.537062 -283.525454) (xy 101.488467 -283.540995) (xy 101.438058 -283.548863) (xy 101.412548 -283.549344)
			(xy 101.386657 -283.548854) (xy 101.33551 -283.54076) (xy 101.28626 -283.524764) (xy 101.240119 -283.50126)
			(xy 101.198223 -283.470827) (xy 101.161604 -283.434214) (xy 101.131165 -283.392322) (xy 101.107654 -283.346184)
			(xy 101.091651 -283.296937) (xy 101.083549 -283.245791) (xy 99.862132 -283.245791) (xy 99.862132 -283.245813)
			(xy 99.854026 -283.29699) (xy 99.838014 -283.346269) (xy 99.814491 -283.392436) (xy 99.784035 -283.434355)
			(xy 99.747397 -283.470993) (xy 99.705478 -283.501449) (xy 99.659311 -283.524972) (xy 99.610032 -283.540984)
			(xy 99.558855 -283.54909) (xy 99.507041 -283.54909) (xy 99.455864 -283.540984) (xy 99.406585 -283.524972)
			(xy 99.360418 -283.501449) (xy 99.318499 -283.470993) (xy 99.281861 -283.434355) (xy 99.251405 -283.392436)
			(xy 99.227882 -283.346269) (xy 99.21187 -283.29699) (xy 99.203764 -283.245813) (xy 99.203256 -283.219906)
			(xy 97.04324 -283.219906) (xy 97.042732 -283.245813) (xy 97.034626 -283.29699) (xy 97.018614 -283.346269)
			(xy 96.995091 -283.392436) (xy 96.964635 -283.434355) (xy 96.927997 -283.470993) (xy 96.886078 -283.501449)
			(xy 96.839911 -283.524972) (xy 96.790632 -283.540984) (xy 96.739455 -283.54909) (xy 96.687641 -283.54909)
			(xy 96.636464 -283.540984) (xy 96.587185 -283.524972) (xy 96.541018 -283.501449) (xy 96.499099 -283.470993)
			(xy 96.462461 -283.434355) (xy 96.432005 -283.392436) (xy 96.408482 -283.346269) (xy 96.39247 -283.29699)
			(xy 96.384364 -283.245813) (xy 96.383856 -283.219906) (xy 96.384448 -283.192189) (xy 96.393773 -283.137542)
			(xy 96.402398 -283.111194) (xy 96.410272 -283.089096) (xy 96.205294 -282.734004) (xy 96.18218 -282.729686)
			(xy 96.15736 -282.724514) (xy 96.109579 -282.707563) (xy 96.064958 -282.683494) (xy 96.024551 -282.652875)
			(xy 95.989309 -282.616428) (xy 95.960065 -282.575014) (xy 95.937508 -282.52961) (xy 95.922171 -282.481287)
			(xy 95.914416 -282.431185) (xy 95.913956 -282.405836) (xy 95.633032 -282.405836) (xy 95.632524 -282.431723)
			(xy 95.624425 -282.482861) (xy 95.608426 -282.532101) (xy 95.58492 -282.578233) (xy 95.554488 -282.62012)
			(xy 95.517878 -282.65673) (xy 95.475991 -282.687162) (xy 95.429859 -282.710668) (xy 95.380619 -282.726667)
			(xy 95.329481 -282.734766) (xy 95.277707 -282.734766) (xy 95.226569 -282.726667) (xy 95.177329 -282.710668)
			(xy 95.131197 -282.687162) (xy 95.08931 -282.65673) (xy 95.0527 -282.62012) (xy 95.022268 -282.578233)
			(xy 94.998762 -282.532101) (xy 94.982763 -282.482861) (xy 94.974664 -282.431723) (xy 94.974156 -282.405836)
			(xy 93.75394 -282.405836) (xy 93.753432 -282.431743) (xy 93.745326 -282.48292) (xy 93.729314 -282.532199)
			(xy 93.705791 -282.578366) (xy 93.675335 -282.620285) (xy 93.638697 -282.656923) (xy 93.596778 -282.687379)
			(xy 93.550611 -282.710902) (xy 93.501332 -282.726914) (xy 93.450155 -282.73502) (xy 93.398341 -282.73502)
			(xy 93.347164 -282.726914) (xy 93.297885 -282.710902) (xy 93.251718 -282.687379) (xy 93.209799 -282.656923)
			(xy 93.173161 -282.620285) (xy 93.142705 -282.578366) (xy 93.119182 -282.532199) (xy 93.10317 -282.48292)
			(xy 93.095064 -282.431743) (xy 93.094556 -282.405836) (xy 91.87434 -282.405836) (xy 91.873903 -282.431201)
			(xy 91.86615 -282.481333) (xy 91.850801 -282.529685) (xy 91.828221 -282.575111) (xy 91.798942 -282.616537)
			(xy 91.763657 -282.652984) (xy 91.723202 -282.683591) (xy 91.678531 -282.707632) (xy 91.630703 -282.724539)
			(xy 91.605862 -282.729686) (xy 91.583002 -282.734004) (xy 91.378024 -283.089096) (xy 91.385644 -283.11094)
			(xy 91.394193 -283.137235) (xy 91.40339 -283.191753) (xy 91.403932 -283.219398) (xy 91.403932 -283.219906)
			(xy 91.403424 -283.245787) (xy 92.625176 -283.245787) (xy 92.625176 -283.194013) (xy 92.633275 -283.142878)
			(xy 92.649273 -283.093638) (xy 92.672778 -283.047508) (xy 92.703209 -283.005622) (xy 92.739818 -282.969013)
			(xy 92.781703 -282.938581) (xy 92.827833 -282.915076) (xy 92.877072 -282.899076) (xy 92.928207 -282.890976)
			(xy 92.954094 -282.890468) (xy 92.979605 -282.890965) (xy 93.030018 -282.898824) (xy 93.078619 -282.914355)
			(xy 93.124247 -282.937187) (xy 93.165813 -282.966776) (xy 93.202325 -283.002415) (xy 93.218 -283.022548)
			(xy 93.629988 -283.022548) (xy 93.645654 -283.002407) (xy 93.682167 -282.966766) (xy 93.723734 -282.937174)
			(xy 93.769364 -282.91434) (xy 93.817967 -282.898806) (xy 93.868382 -282.890945) (xy 93.893894 -282.890468)
			(xy 93.919784 -282.890937) (xy 93.970927 -282.899036) (xy 94.020174 -282.915037) (xy 94.066311 -282.938544)
			(xy 94.108202 -282.968979) (xy 94.144817 -283.005593) (xy 94.175253 -283.047484) (xy 94.198761 -283.093621)
			(xy 94.214762 -283.142867) (xy 94.222863 -283.19401) (xy 94.222863 -283.24579) (xy 94.214762 -283.296933)
			(xy 94.198761 -283.346179) (xy 94.175253 -283.392316) (xy 94.144817 -283.434207) (xy 94.108202 -283.470821)
			(xy 94.066311 -283.501256) (xy 94.020174 -283.524763) (xy 93.970927 -283.540764) (xy 93.919784 -283.548863)
			(xy 93.893894 -283.549344) (xy 93.868381 -283.54889) (xy 93.817964 -283.541027) (xy 93.769361 -283.52549)
			(xy 93.723732 -283.502649) (xy 93.682168 -283.473051) (xy 93.64566 -283.437402) (xy 93.629988 -283.417264)
			(xy 93.218 -283.417264) (xy 93.202317 -283.437392) (xy 93.16581 -283.473038) (xy 93.124247 -283.502633)
			(xy 93.078621 -283.525471) (xy 93.03002 -283.541006) (xy 92.979606 -283.548867) (xy 92.954094 -283.549344)
			(xy 92.928207 -283.548824) (xy 92.877072 -283.540724) (xy 92.827833 -283.524724) (xy 92.781703 -283.501219)
			(xy 92.739818 -283.470787) (xy 92.703209 -283.434178) (xy 92.672778 -283.392292) (xy 92.649273 -283.346162)
			(xy 92.633275 -283.296922) (xy 92.625176 -283.245787) (xy 91.403424 -283.245787) (xy 91.403424 -283.245793)
			(xy 91.395325 -283.296931) (xy 91.379326 -283.346171) (xy 91.35582 -283.392303) (xy 91.325388 -283.43419)
			(xy 91.288778 -283.4708) (xy 91.246891 -283.501232) (xy 91.200759 -283.524738) (xy 91.151519 -283.540737)
			(xy 91.100381 -283.548836) (xy 91.048607 -283.548836) (xy 90.997469 -283.540737) (xy 90.948229 -283.524738)
			(xy 90.902097 -283.501232) (xy 90.86021 -283.4708) (xy 90.8236 -283.43419) (xy 90.793168 -283.392303)
			(xy 90.769662 -283.346171) (xy 90.753663 -283.296931) (xy 90.745564 -283.245793) (xy 90.745056 -283.219906)
			(xy 88.584532 -283.219906) (xy 88.584024 -283.245793) (xy 88.575925 -283.296931) (xy 88.559926 -283.346171)
			(xy 88.53642 -283.392303) (xy 88.505988 -283.43419) (xy 88.469378 -283.4708) (xy 88.427491 -283.501232)
			(xy 88.381359 -283.524738) (xy 88.332119 -283.540737) (xy 88.280981 -283.548836) (xy 88.229207 -283.548836)
			(xy 88.178069 -283.540737) (xy 88.128829 -283.524738) (xy 88.082697 -283.501232) (xy 88.04081 -283.4708)
			(xy 88.0042 -283.43419) (xy 87.973768 -283.392303) (xy 87.950262 -283.346171) (xy 87.934263 -283.296931)
			(xy 87.926164 -283.245793) (xy 87.925656 -283.219906) (xy 87.926189 -283.192198) (xy 87.935382 -283.137551)
			(xy 87.943944 -283.111194) (xy 87.951818 -283.089096) (xy 87.746586 -282.734004) (xy 87.723726 -282.729686)
			(xy 87.698938 -282.724431) (xy 87.651203 -282.70745) (xy 87.606628 -282.683364) (xy 87.566263 -282.652742)
			(xy 87.531059 -282.616304) (xy 87.501844 -282.574908) (xy 87.479308 -282.52953) (xy 87.463981 -282.481238)
			(xy 87.456223 -282.431169) (xy 87.455756 -282.405836) (xy 87.17534 -282.405836) (xy 87.174832 -282.431743)
			(xy 87.166726 -282.48292) (xy 87.150714 -282.532199) (xy 87.127191 -282.578366) (xy 87.096735 -282.620285)
			(xy 87.060097 -282.656923) (xy 87.018178 -282.687379) (xy 86.972011 -282.710902) (xy 86.922732 -282.726914)
			(xy 86.871555 -282.73502) (xy 86.819741 -282.73502) (xy 86.768564 -282.726914) (xy 86.719285 -282.710902)
			(xy 86.673118 -282.687379) (xy 86.631199 -282.656923) (xy 86.594561 -282.620285) (xy 86.564105 -282.578366)
			(xy 86.540582 -282.532199) (xy 86.52457 -282.48292) (xy 86.516464 -282.431743) (xy 86.515956 -282.405836)
			(xy 2.509012 -282.405836) (xy 2.509012 -284.033722) (xy 86.515956 -284.033722) (xy 86.516464 -284.007815)
			(xy 86.52457 -283.956638) (xy 86.540582 -283.907359) (xy 86.564105 -283.861192) (xy 86.594561 -283.819273)
			(xy 86.631199 -283.782635) (xy 86.673118 -283.752179) (xy 86.719285 -283.728656) (xy 86.768564 -283.712644)
			(xy 86.819741 -283.704538) (xy 86.871555 -283.704538) (xy 86.922732 -283.712644) (xy 86.972011 -283.728656)
			(xy 87.018178 -283.752179) (xy 87.060097 -283.782635) (xy 87.096735 -283.819273) (xy 87.127191 -283.861192)
			(xy 87.150714 -283.907359) (xy 87.166726 -283.956638) (xy 87.174832 -284.007815) (xy 87.17534 -284.033722)
			(xy 334.456024 -284.033722) (xy 334.456532 -284.007815) (xy 334.464638 -283.956638) (xy 334.48065 -283.907359)
			(xy 334.504173 -283.861192) (xy 334.534629 -283.819273) (xy 334.571267 -283.782635) (xy 334.613186 -283.752179)
			(xy 334.659353 -283.728656) (xy 334.708632 -283.712644) (xy 334.759809 -283.704538) (xy 334.811623 -283.704538)
			(xy 334.8628 -283.712644) (xy 334.912079 -283.728656) (xy 334.958246 -283.752179) (xy 335.000165 -283.782635)
			(xy 335.036803 -283.819273) (xy 335.067259 -283.861192) (xy 335.090782 -283.907359) (xy 335.106794 -283.956638)
			(xy 335.1149 -284.007815) (xy 335.115408 -284.033722) (xy 335.114819 -284.06144) (xy 335.105492 -284.116086)
			(xy 335.096866 -284.142434) (xy 335.088992 -284.164532) (xy 335.29397 -284.51937) (xy 335.31683 -284.523688)
			(xy 335.341643 -284.528833) (xy 335.389384 -284.545828) (xy 335.433962 -284.569927) (xy 335.474328 -284.600564)
			(xy 335.50953 -284.637016) (xy 335.538741 -284.678425) (xy 335.561271 -284.723817) (xy 335.576591 -284.772121)
			(xy 335.584339 -284.8222) (xy 335.5848 -284.847538) (xy 335.584292 -284.873425) (xy 335.576193 -284.924563)
			(xy 335.560194 -284.973803) (xy 335.536688 -285.019935) (xy 335.506256 -285.061822) (xy 335.469646 -285.098432)
			(xy 335.427759 -285.128864) (xy 335.381627 -285.15237) (xy 335.332387 -285.168369) (xy 335.281249 -285.176468)
			(xy 335.229475 -285.176468) (xy 335.178337 -285.168369) (xy 335.129097 -285.15237) (xy 335.082965 -285.128864)
			(xy 335.041078 -285.098432) (xy 335.004468 -285.061822) (xy 334.974036 -285.019935) (xy 334.95053 -284.973803)
			(xy 334.934531 -284.924563) (xy 334.926432 -284.873425) (xy 334.925924 -284.847538) (xy 334.926462 -284.81983)
			(xy 334.935651 -284.765183) (xy 334.944212 -284.738826) (xy 334.952086 -284.716728) (xy 334.747108 -284.36189)
			(xy 334.724248 -284.357572) (xy 334.699419 -284.352437) (xy 334.651638 -284.33548) (xy 334.607017 -284.311405)
			(xy 334.56661 -284.280781) (xy 334.531369 -284.24433) (xy 334.502126 -284.202912) (xy 334.479571 -284.157504)
			(xy 334.464236 -284.109178) (xy 334.456483 -284.059073) (xy 334.456024 -284.033722) (xy 87.17534 -284.033722)
			(xy 87.174755 -284.06144) (xy 87.165426 -284.116086) (xy 87.156798 -284.142434) (xy 87.148924 -284.164532)
			(xy 87.353902 -284.51937) (xy 87.376762 -284.523688) (xy 87.401564 -284.528882) (xy 87.449305 -284.545867)
			(xy 87.493884 -284.569958) (xy 87.534252 -284.600587) (xy 87.569457 -284.637033) (xy 87.598669 -284.678438)
			(xy 87.621201 -284.723825) (xy 87.636522 -284.772125) (xy 87.644271 -284.822202) (xy 87.644732 -284.847538)
			(xy 87.644224 -284.873425) (xy 87.636125 -284.924563) (xy 87.620126 -284.973803) (xy 87.59662 -285.019935)
			(xy 87.566188 -285.061822) (xy 87.529578 -285.098432) (xy 87.487691 -285.128864) (xy 87.441559 -285.15237)
			(xy 87.392319 -285.168369) (xy 87.341181 -285.176468) (xy 87.289407 -285.176468) (xy 87.238269 -285.168369)
			(xy 87.189029 -285.15237) (xy 87.142897 -285.128864) (xy 87.10101 -285.098432) (xy 87.0644 -285.061822)
			(xy 87.033968 -285.019935) (xy 87.010462 -284.973803) (xy 86.994463 -284.924563) (xy 86.986364 -284.873425)
			(xy 86.985856 -284.847538) (xy 86.986397 -284.81983) (xy 86.995584 -284.765184) (xy 87.004144 -284.738826)
			(xy 87.012018 -284.716728) (xy 86.80704 -284.36189) (xy 86.78418 -284.357572) (xy 86.759356 -284.352414)
			(xy 86.711575 -284.335461) (xy 86.666954 -284.311391) (xy 86.626545 -284.28077) (xy 86.591303 -284.244322)
			(xy 86.56206 -284.202906) (xy 86.539504 -284.1575) (xy 86.524169 -284.109175) (xy 86.516415 -284.059072)
			(xy 86.515956 -284.033722) (xy 2.509012 -284.033722) (xy 2.509012 -284.873384) (xy 85.106807 -284.873384)
			(xy 85.106807 -284.821616) (xy 85.114906 -284.770485) (xy 85.130903 -284.72125) (xy 85.154405 -284.675125)
			(xy 85.184833 -284.633243) (xy 85.221438 -284.596637) (xy 85.263319 -284.566208) (xy 85.309445 -284.542705)
			(xy 85.358679 -284.526707) (xy 85.40981 -284.518608) (xy 85.435694 -284.5181) (xy 85.461187 -284.518588)
			(xy 85.511565 -284.526449) (xy 85.560127 -284.541983) (xy 85.605714 -284.564818) (xy 85.647235 -284.594409)
			(xy 85.683698 -284.630049) (xy 85.699346 -284.65018) (xy 86.111842 -284.65018) (xy 86.127489 -284.630047)
			(xy 86.163951 -284.594407) (xy 86.205472 -284.564814) (xy 86.251059 -284.541976) (xy 86.299622 -284.526441)
			(xy 86.35 -284.518579) (xy 86.375494 -284.5181) (xy 86.401387 -284.518505) (xy 86.452535 -284.526605)
			(xy 86.501786 -284.542607) (xy 86.547927 -284.566116) (xy 86.589823 -284.596555) (xy 86.626441 -284.633172)
			(xy 86.65688 -284.675067) (xy 86.680391 -284.721208) (xy 86.696394 -284.770459) (xy 86.704495 -284.821607)
			(xy 86.704495 -284.873393) (xy 86.696394 -284.924541) (xy 86.680391 -284.973792) (xy 86.65688 -285.019933)
			(xy 86.626441 -285.061828) (xy 86.589823 -285.098445) (xy 86.547927 -285.128884) (xy 86.501786 -285.152393)
			(xy 86.452535 -285.168395) (xy 86.401387 -285.176495) (xy 86.375494 -285.176976) (xy 86.35 -285.176506)
			(xy 86.299621 -285.168643) (xy 86.251058 -285.153106) (xy 86.205471 -285.130267) (xy 86.16395 -285.100672)
			(xy 86.127489 -285.065029) (xy 86.111842 -285.044896) (xy 85.699346 -285.044896) (xy 85.683699 -285.065029)
			(xy 85.647238 -285.100671) (xy 85.605717 -285.130265) (xy 85.56013 -285.153102) (xy 85.511566 -285.168637)
			(xy 85.461188 -285.176498) (xy 85.435694 -285.176976) (xy 85.40981 -285.176392) (xy 85.358679 -285.168293)
			(xy 85.309445 -285.152295) (xy 85.263319 -285.128792) (xy 85.221438 -285.098363) (xy 85.184833 -285.061757)
			(xy 85.154405 -285.019875) (xy 85.130903 -284.97375) (xy 85.114906 -284.924515) (xy 85.106807 -284.873384)
			(xy 2.509012 -284.873384) (xy 2.509012 -285.661354) (xy 87.455756 -285.661354) (xy 87.456232 -285.63602)
			(xy 87.46399 -285.585949) (xy 87.479317 -285.537654) (xy 87.50185 -285.492273) (xy 87.531061 -285.450872)
			(xy 87.566261 -285.414427) (xy 87.606622 -285.383796) (xy 87.651194 -285.3597) (xy 87.698927 -285.342705)
			(xy 87.723726 -285.337504) (xy 87.746586 -285.333186) (xy 87.951564 -284.978094) (xy 87.943944 -284.95625)
			(xy 87.935376 -284.929894) (xy 87.926181 -284.875247) (xy 87.925656 -284.847538) (xy 87.926164 -284.821651)
			(xy 87.934263 -284.770513) (xy 87.950262 -284.721273) (xy 87.973768 -284.675141) (xy 88.0042 -284.633254)
			(xy 88.04081 -284.596644) (xy 88.082697 -284.566212) (xy 88.128829 -284.542706) (xy 88.178069 -284.526707)
			(xy 88.229207 -284.518608) (xy 88.280981 -284.518608) (xy 88.332119 -284.526707) (xy 88.381359 -284.542706)
			(xy 88.427491 -284.566212) (xy 88.469378 -284.596644) (xy 88.505988 -284.633254) (xy 88.53642 -284.675141)
			(xy 88.559926 -284.721273) (xy 88.575925 -284.770513) (xy 88.584024 -284.821651) (xy 88.584532 -284.847538)
			(xy 88.584058 -284.872872) (xy 88.576301 -284.922944) (xy 88.560975 -284.971239) (xy 88.538441 -285.016622)
			(xy 88.50923 -285.058022) (xy 88.47403 -285.094467) (xy 88.433668 -285.125098) (xy 88.389095 -285.149194)
			(xy 88.341361 -285.166187) (xy 88.316562 -285.171388) (xy 88.293702 -285.175706) (xy 88.088724 -285.530798)
			(xy 88.096344 -285.552642) (xy 88.104909 -285.578999) (xy 88.114106 -285.633646) (xy 88.114632 -285.661354)
			(xy 89.335356 -285.661354) (xy 89.335864 -285.635467) (xy 89.343963 -285.584329) (xy 89.359962 -285.535089)
			(xy 89.383468 -285.488957) (xy 89.4139 -285.44707) (xy 89.45051 -285.41046) (xy 89.492397 -285.380028)
			(xy 89.538529 -285.356522) (xy 89.587769 -285.340523) (xy 89.638907 -285.332424) (xy 89.690681 -285.332424)
			(xy 89.741819 -285.340523) (xy 89.791059 -285.356522) (xy 89.837191 -285.380028) (xy 89.879078 -285.41046)
			(xy 89.915688 -285.44707) (xy 89.94612 -285.488957) (xy 89.969626 -285.535089) (xy 89.985625 -285.584329)
			(xy 89.993724 -285.635467) (xy 89.994232 -285.661354) (xy 90.275156 -285.661354) (xy 90.27559 -285.636007)
			(xy 90.28337 -285.585913) (xy 90.298725 -285.537599) (xy 90.321292 -285.492204) (xy 90.35054 -285.450798)
			(xy 90.385779 -285.414354) (xy 90.426181 -285.383733) (xy 90.470793 -285.359656) (xy 90.518564 -285.342688)
			(xy 90.54338 -285.337504) (xy 90.56624 -285.333186) (xy 90.771218 -284.978348) (xy 90.763344 -284.956504)
			(xy 90.754767 -284.930085) (xy 90.745569 -284.87531) (xy 90.745056 -284.847538) (xy 90.745564 -284.821651)
			(xy 90.753663 -284.770513) (xy 90.769662 -284.721273) (xy 90.793168 -284.675141) (xy 90.8236 -284.633254)
			(xy 90.86021 -284.596644) (xy 90.902097 -284.566212) (xy 90.948229 -284.542706) (xy 90.997469 -284.526707)
			(xy 91.048607 -284.518608) (xy 91.100381 -284.518608) (xy 91.151519 -284.526707) (xy 91.200759 -284.542706)
			(xy 91.246891 -284.566212) (xy 91.288778 -284.596644) (xy 91.325388 -284.633254) (xy 91.35582 -284.675141)
			(xy 91.379326 -284.721273) (xy 91.395325 -284.770513) (xy 91.403424 -284.821651) (xy 91.403932 -284.847538)
			(xy 91.403458 -284.872872) (xy 91.395701 -284.922944) (xy 91.380375 -284.971239) (xy 91.357841 -285.016622)
			(xy 91.32863 -285.058022) (xy 91.29343 -285.094467) (xy 91.253068 -285.125098) (xy 91.208495 -285.149194)
			(xy 91.160761 -285.166187) (xy 91.135962 -285.171388) (xy 91.113102 -285.175706) (xy 90.908124 -285.530544)
			(xy 90.915998 -285.552642) (xy 90.924622 -285.57899) (xy 90.933948 -285.633636) (xy 90.93454 -285.661354)
			(xy 91.214956 -285.661354) (xy 91.215464 -285.635447) (xy 91.22357 -285.58427) (xy 91.239582 -285.534991)
			(xy 91.263105 -285.488824) (xy 91.293561 -285.446905) (xy 91.330199 -285.410267) (xy 91.372118 -285.379811)
			(xy 91.418285 -285.356288) (xy 91.467564 -285.340276) (xy 91.518741 -285.33217) (xy 91.570555 -285.33217)
			(xy 91.621732 -285.340276) (xy 91.671011 -285.356288) (xy 91.717178 -285.379811) (xy 91.759097 -285.410267)
			(xy 91.795735 -285.446905) (xy 91.826191 -285.488824) (xy 91.849714 -285.534991) (xy 91.865726 -285.58427)
			(xy 91.873832 -285.635447) (xy 91.87434 -285.661354) (xy 92.154756 -285.661354) (xy 92.155232 -285.63602)
			(xy 92.16299 -285.585949) (xy 92.178317 -285.537654) (xy 92.20085 -285.492273) (xy 92.230061 -285.450872)
			(xy 92.265261 -285.414427) (xy 92.305622 -285.383796) (xy 92.350194 -285.3597) (xy 92.397927 -285.342705)
			(xy 92.422726 -285.337504) (xy 92.445586 -285.333186) (xy 92.650818 -284.97784) (xy 92.643198 -284.955996)
			(xy 92.634574 -284.929714) (xy 92.625259 -284.875193) (xy 92.624656 -284.847538) (xy 92.625164 -284.821631)
			(xy 92.63327 -284.770454) (xy 92.649282 -284.721175) (xy 92.672805 -284.675008) (xy 92.703261 -284.633089)
			(xy 92.739899 -284.596451) (xy 92.781818 -284.565995) (xy 92.827985 -284.542472) (xy 92.877264 -284.52646)
			(xy 92.928441 -284.518354) (xy 92.980255 -284.518354) (xy 93.031432 -284.52646) (xy 93.080711 -284.542472)
			(xy 93.126878 -284.565995) (xy 93.168797 -284.596451) (xy 93.205435 -284.633089) (xy 93.235891 -284.675008)
			(xy 93.259414 -284.721175) (xy 93.275426 -284.770454) (xy 93.283532 -284.821631) (xy 93.28404 -284.847538)
			(xy 93.283648 -284.872916) (xy 93.275873 -284.923072) (xy 93.260496 -284.971442) (xy 93.237881 -285.016882)
			(xy 93.208565 -285.058314) (xy 93.17324 -285.09476) (xy 93.132743 -285.125356) (xy 93.088033 -285.149379)
			(xy 93.040166 -285.166259) (xy 93.015308 -285.171388) (xy 92.992448 -285.175706) (xy 92.78747 -285.530544)
			(xy 92.795344 -285.552642) (xy 92.803916 -285.578997) (xy 92.813107 -285.633645) (xy 92.813632 -285.661354)
			(xy 93.094556 -285.661354) (xy 93.095064 -285.635467) (xy 93.103163 -285.584329) (xy 93.119162 -285.535089)
			(xy 93.142668 -285.488957) (xy 93.1731 -285.44707) (xy 93.20971 -285.41046) (xy 93.251597 -285.380028)
			(xy 93.297729 -285.356522) (xy 93.346969 -285.340523) (xy 93.398107 -285.332424) (xy 93.449881 -285.332424)
			(xy 93.501019 -285.340523) (xy 93.550259 -285.356522) (xy 93.596391 -285.380028) (xy 93.638278 -285.41046)
			(xy 93.674888 -285.44707) (xy 93.70532 -285.488957) (xy 93.728826 -285.535089) (xy 93.744825 -285.584329)
			(xy 93.752924 -285.635467) (xy 93.753432 -285.661354) (xy 94.034356 -285.661354) (xy 94.034832 -285.63602)
			(xy 94.04259 -285.585949) (xy 94.057917 -285.537654) (xy 94.08045 -285.492273) (xy 94.109661 -285.450872)
			(xy 94.144861 -285.414427) (xy 94.185222 -285.383796) (xy 94.229794 -285.3597) (xy 94.277527 -285.342705)
			(xy 94.302326 -285.337504) (xy 94.325186 -285.333186) (xy 94.530418 -284.97784) (xy 94.522798 -284.955996)
			(xy 94.514174 -284.929714) (xy 94.504859 -284.875193) (xy 94.504256 -284.847538) (xy 94.504764 -284.821631)
			(xy 94.51287 -284.770454) (xy 94.528882 -284.721175) (xy 94.552405 -284.675008) (xy 94.582861 -284.633089)
			(xy 94.619499 -284.596451) (xy 94.661418 -284.565995) (xy 94.707585 -284.542472) (xy 94.756864 -284.52646)
			(xy 94.808041 -284.518354) (xy 94.859855 -284.518354) (xy 94.911032 -284.52646) (xy 94.960311 -284.542472)
			(xy 95.006478 -284.565995) (xy 95.048397 -284.596451) (xy 95.085035 -284.633089) (xy 95.115491 -284.675008)
			(xy 95.139014 -284.721175) (xy 95.155026 -284.770454) (xy 95.163132 -284.821631) (xy 95.16364 -284.847538)
			(xy 95.163248 -284.872916) (xy 95.155473 -284.923072) (xy 95.140096 -284.971442) (xy 95.117481 -285.016882)
			(xy 95.088165 -285.058314) (xy 95.05284 -285.09476) (xy 95.012343 -285.125356) (xy 94.967633 -285.149379)
			(xy 94.919766 -285.166259) (xy 94.894908 -285.171388) (xy 94.872048 -285.175706) (xy 94.66707 -285.530544)
			(xy 94.674944 -285.552642) (xy 94.683516 -285.578997) (xy 94.692707 -285.633645) (xy 94.693232 -285.661354)
			(xy 94.974156 -285.661354) (xy 94.974664 -285.635467) (xy 94.982763 -285.584329) (xy 94.998762 -285.535089)
			(xy 95.022268 -285.488957) (xy 95.0527 -285.44707) (xy 95.08931 -285.41046) (xy 95.131197 -285.380028)
			(xy 95.177329 -285.356522) (xy 95.226569 -285.340523) (xy 95.277707 -285.332424) (xy 95.329481 -285.332424)
			(xy 95.380619 -285.340523) (xy 95.429859 -285.356522) (xy 95.475991 -285.380028) (xy 95.517878 -285.41046)
			(xy 95.554488 -285.44707) (xy 95.58492 -285.488957) (xy 95.608426 -285.535089) (xy 95.624425 -285.584329)
			(xy 95.632524 -285.635467) (xy 95.633032 -285.661354) (xy 95.913956 -285.661354) (xy 95.914432 -285.63602)
			(xy 95.92219 -285.585949) (xy 95.937517 -285.537654) (xy 95.96005 -285.492273) (xy 95.989261 -285.450872)
			(xy 96.024461 -285.414427) (xy 96.064822 -285.383796) (xy 96.109394 -285.3597) (xy 96.157127 -285.342705)
			(xy 96.181926 -285.337504) (xy 96.204786 -285.333186) (xy 96.410018 -284.97784) (xy 96.402398 -284.955996)
			(xy 96.393774 -284.929714) (xy 96.384459 -284.875193) (xy 96.383856 -284.847538) (xy 96.384364 -284.821631)
			(xy 96.39247 -284.770454) (xy 96.408482 -284.721175) (xy 96.432005 -284.675008) (xy 96.462461 -284.633089)
			(xy 96.499099 -284.596451) (xy 96.541018 -284.565995) (xy 96.587185 -284.542472) (xy 96.636464 -284.52646)
			(xy 96.687641 -284.518354) (xy 96.739455 -284.518354) (xy 96.790632 -284.52646) (xy 96.839911 -284.542472)
			(xy 96.886078 -284.565995) (xy 96.927997 -284.596451) (xy 96.964635 -284.633089) (xy 96.995091 -284.675008)
			(xy 97.018614 -284.721175) (xy 97.034626 -284.770454) (xy 97.042732 -284.821631) (xy 97.04324 -284.847538)
			(xy 97.042848 -284.872916) (xy 97.035073 -284.923072) (xy 97.019696 -284.971442) (xy 96.997081 -285.016882)
			(xy 96.967765 -285.058314) (xy 96.93244 -285.09476) (xy 96.891943 -285.125356) (xy 96.847233 -285.149379)
			(xy 96.799366 -285.166259) (xy 96.774508 -285.171388) (xy 96.751648 -285.175706) (xy 96.54667 -285.530544)
			(xy 96.554544 -285.552642) (xy 96.563116 -285.578997) (xy 96.572307 -285.633645) (xy 96.572832 -285.661354)
			(xy 96.853756 -285.661354) (xy 96.854264 -285.635467) (xy 96.862363 -285.584329) (xy 96.878362 -285.535089)
			(xy 96.901868 -285.488957) (xy 96.9323 -285.44707) (xy 96.96891 -285.41046) (xy 97.010797 -285.380028)
			(xy 97.056929 -285.356522) (xy 97.106169 -285.340523) (xy 97.157307 -285.332424) (xy 97.209081 -285.332424)
			(xy 97.260219 -285.340523) (xy 97.309459 -285.356522) (xy 97.355591 -285.380028) (xy 97.397478 -285.41046)
			(xy 97.434088 -285.44707) (xy 97.46452 -285.488957) (xy 97.488026 -285.535089) (xy 97.504025 -285.584329)
			(xy 97.512124 -285.635467) (xy 97.512632 -285.661354) (xy 97.793556 -285.661354) (xy 97.794032 -285.63602)
			(xy 97.80179 -285.585949) (xy 97.817117 -285.537654) (xy 97.83965 -285.492273) (xy 97.868861 -285.450872)
			(xy 97.904061 -285.414427) (xy 97.944422 -285.383796) (xy 97.988994 -285.3597) (xy 98.036727 -285.342705)
			(xy 98.061526 -285.337504) (xy 98.084386 -285.333186) (xy 98.289618 -284.97784) (xy 98.281998 -284.955996)
			(xy 98.273374 -284.929714) (xy 98.264059 -284.875193) (xy 98.263456 -284.847538) (xy 98.263964 -284.821631)
			(xy 98.27207 -284.770454) (xy 98.288082 -284.721175) (xy 98.311605 -284.675008) (xy 98.342061 -284.633089)
			(xy 98.378699 -284.596451) (xy 98.420618 -284.565995) (xy 98.466785 -284.542472) (xy 98.516064 -284.52646)
			(xy 98.567241 -284.518354) (xy 98.619055 -284.518354) (xy 98.670232 -284.52646) (xy 98.719511 -284.542472)
			(xy 98.765678 -284.565995) (xy 98.807597 -284.596451) (xy 98.844235 -284.633089) (xy 98.874691 -284.675008)
			(xy 98.898214 -284.721175) (xy 98.914226 -284.770454) (xy 98.922332 -284.821631) (xy 98.92284 -284.847538)
			(xy 98.922448 -284.872916) (xy 98.914673 -284.923072) (xy 98.899296 -284.971442) (xy 98.876681 -285.016882)
			(xy 98.847365 -285.058314) (xy 98.81204 -285.09476) (xy 98.771543 -285.125356) (xy 98.726833 -285.149379)
			(xy 98.678966 -285.166259) (xy 98.654108 -285.171388) (xy 98.631248 -285.175706) (xy 98.42627 -285.530544)
			(xy 98.434144 -285.552642) (xy 98.442716 -285.578997) (xy 98.451907 -285.633645) (xy 98.452432 -285.661354)
			(xy 98.733356 -285.661354) (xy 98.733864 -285.635467) (xy 98.741963 -285.584329) (xy 98.757962 -285.535089)
			(xy 98.781468 -285.488957) (xy 98.8119 -285.44707) (xy 98.84851 -285.41046) (xy 98.890397 -285.380028)
			(xy 98.936529 -285.356522) (xy 98.985769 -285.340523) (xy 99.036907 -285.332424) (xy 99.088681 -285.332424)
			(xy 99.139819 -285.340523) (xy 99.189059 -285.356522) (xy 99.235191 -285.380028) (xy 99.277078 -285.41046)
			(xy 99.313688 -285.44707) (xy 99.34412 -285.488957) (xy 99.367626 -285.535089) (xy 99.383625 -285.584329)
			(xy 99.391724 -285.635467) (xy 99.392232 -285.661354) (xy 99.673156 -285.661354) (xy 99.673632 -285.63602)
			(xy 99.68139 -285.585949) (xy 99.696717 -285.537654) (xy 99.71925 -285.492273) (xy 99.748461 -285.450872)
			(xy 99.783661 -285.414427) (xy 99.824022 -285.383796) (xy 99.868594 -285.3597) (xy 99.916327 -285.342705)
			(xy 99.941126 -285.337504) (xy 99.963986 -285.333186) (xy 100.169218 -284.97784) (xy 100.161598 -284.955996)
			(xy 100.152974 -284.929714) (xy 100.143659 -284.875193) (xy 100.143056 -284.847538) (xy 100.143564 -284.821631)
			(xy 100.15167 -284.770454) (xy 100.167682 -284.721175) (xy 100.191205 -284.675008) (xy 100.221661 -284.633089)
			(xy 100.258299 -284.596451) (xy 100.300218 -284.565995) (xy 100.346385 -284.542472) (xy 100.395664 -284.52646)
			(xy 100.446841 -284.518354) (xy 100.498655 -284.518354) (xy 100.549832 -284.52646) (xy 100.599111 -284.542472)
			(xy 100.645278 -284.565995) (xy 100.687197 -284.596451) (xy 100.723835 -284.633089) (xy 100.754291 -284.675008)
			(xy 100.777814 -284.721175) (xy 100.793826 -284.770454) (xy 100.801932 -284.821631) (xy 100.80244 -284.847538)
			(xy 100.802048 -284.872916) (xy 100.794273 -284.923072) (xy 100.778896 -284.971442) (xy 100.756281 -285.016882)
			(xy 100.726965 -285.058314) (xy 100.69164 -285.09476) (xy 100.651143 -285.125356) (xy 100.606433 -285.149379)
			(xy 100.558566 -285.166259) (xy 100.533708 -285.171388) (xy 100.510848 -285.175706) (xy 100.30587 -285.530544)
			(xy 100.313744 -285.552642) (xy 100.322316 -285.578997) (xy 100.331507 -285.633645) (xy 100.332032 -285.661354)
			(xy 100.612956 -285.661354) (xy 100.613464 -285.635467) (xy 100.621563 -285.584329) (xy 100.637562 -285.535089)
			(xy 100.661068 -285.488957) (xy 100.6915 -285.44707) (xy 100.72811 -285.41046) (xy 100.769997 -285.380028)
			(xy 100.816129 -285.356522) (xy 100.865369 -285.340523) (xy 100.916507 -285.332424) (xy 100.968281 -285.332424)
			(xy 101.019419 -285.340523) (xy 101.068659 -285.356522) (xy 101.114791 -285.380028) (xy 101.156678 -285.41046)
			(xy 101.193288 -285.44707) (xy 101.22372 -285.488957) (xy 101.247226 -285.535089) (xy 101.263225 -285.584329)
			(xy 101.271324 -285.635467) (xy 101.271832 -285.661354) (xy 101.552756 -285.661354) (xy 101.553232 -285.63602)
			(xy 101.56099 -285.585949) (xy 101.576317 -285.537654) (xy 101.59885 -285.492273) (xy 101.628061 -285.450872)
			(xy 101.663261 -285.414427) (xy 101.703622 -285.383796) (xy 101.748194 -285.3597) (xy 101.795927 -285.342705)
			(xy 101.820726 -285.337504) (xy 101.843586 -285.333186) (xy 102.048818 -284.97784) (xy 102.041198 -284.955996)
			(xy 102.032574 -284.929714) (xy 102.023259 -284.875193) (xy 102.022656 -284.847538) (xy 102.023164 -284.821631)
			(xy 102.03127 -284.770454) (xy 102.047282 -284.721175) (xy 102.070805 -284.675008) (xy 102.101261 -284.633089)
			(xy 102.137899 -284.596451) (xy 102.179818 -284.565995) (xy 102.225985 -284.542472) (xy 102.275264 -284.52646)
			(xy 102.326441 -284.518354) (xy 102.378255 -284.518354) (xy 102.429432 -284.52646) (xy 102.478711 -284.542472)
			(xy 102.524878 -284.565995) (xy 102.566797 -284.596451) (xy 102.603435 -284.633089) (xy 102.633891 -284.675008)
			(xy 102.657414 -284.721175) (xy 102.673426 -284.770454) (xy 102.681532 -284.821631) (xy 102.68204 -284.847538)
			(xy 102.681648 -284.872916) (xy 102.673873 -284.923072) (xy 102.658496 -284.971442) (xy 102.635881 -285.016882)
			(xy 102.606565 -285.058314) (xy 102.57124 -285.09476) (xy 102.530743 -285.125356) (xy 102.486033 -285.149379)
			(xy 102.438166 -285.166259) (xy 102.413308 -285.171388) (xy 102.390448 -285.175706) (xy 102.18547 -285.530544)
			(xy 102.193344 -285.552642) (xy 102.201916 -285.578997) (xy 102.211107 -285.633645) (xy 102.211632 -285.661354)
			(xy 102.492556 -285.661354) (xy 102.493064 -285.635467) (xy 102.501163 -285.584329) (xy 102.517162 -285.535089)
			(xy 102.540668 -285.488957) (xy 102.5711 -285.44707) (xy 102.60771 -285.41046) (xy 102.649597 -285.380028)
			(xy 102.695729 -285.356522) (xy 102.744969 -285.340523) (xy 102.796107 -285.332424) (xy 102.847881 -285.332424)
			(xy 102.899019 -285.340523) (xy 102.948259 -285.356522) (xy 102.994391 -285.380028) (xy 103.036278 -285.41046)
			(xy 103.072888 -285.44707) (xy 103.10332 -285.488957) (xy 103.126826 -285.535089) (xy 103.142825 -285.584329)
			(xy 103.150924 -285.635467) (xy 103.151432 -285.661354) (xy 103.432356 -285.661354) (xy 103.432832 -285.63602)
			(xy 103.44059 -285.585949) (xy 103.455917 -285.537654) (xy 103.47845 -285.492273) (xy 103.507661 -285.450872)
			(xy 103.542861 -285.414427) (xy 103.583222 -285.383796) (xy 103.627794 -285.3597) (xy 103.675527 -285.342705)
			(xy 103.700326 -285.337504) (xy 103.723186 -285.333186) (xy 103.928418 -284.97784) (xy 103.920798 -284.955996)
			(xy 103.912174 -284.929714) (xy 103.902859 -284.875193) (xy 103.902256 -284.847538) (xy 103.902764 -284.821631)
			(xy 103.91087 -284.770454) (xy 103.926882 -284.721175) (xy 103.950405 -284.675008) (xy 103.980861 -284.633089)
			(xy 104.017499 -284.596451) (xy 104.059418 -284.565995) (xy 104.105585 -284.542472) (xy 104.154864 -284.52646)
			(xy 104.206041 -284.518354) (xy 104.257855 -284.518354) (xy 104.309032 -284.52646) (xy 104.358311 -284.542472)
			(xy 104.404478 -284.565995) (xy 104.446397 -284.596451) (xy 104.483035 -284.633089) (xy 104.513491 -284.675008)
			(xy 104.537014 -284.721175) (xy 104.553026 -284.770454) (xy 104.561132 -284.821631) (xy 104.56164 -284.847538)
			(xy 118.939056 -284.847538) (xy 118.939564 -284.821631) (xy 118.94767 -284.770454) (xy 118.963682 -284.721175)
			(xy 118.987205 -284.675008) (xy 119.017661 -284.633089) (xy 119.054299 -284.596451) (xy 119.096218 -284.565995)
			(xy 119.142385 -284.542472) (xy 119.191664 -284.52646) (xy 119.242841 -284.518354) (xy 119.294655 -284.518354)
			(xy 119.345832 -284.52646) (xy 119.395111 -284.542472) (xy 119.441278 -284.565995) (xy 119.483197 -284.596451)
			(xy 119.519835 -284.633089) (xy 119.550291 -284.675008) (xy 119.573814 -284.721175) (xy 119.589826 -284.770454)
			(xy 119.597932 -284.821631) (xy 119.59844 -284.847538) (xy 120.818656 -284.847538) (xy 120.819164 -284.821631)
			(xy 120.82727 -284.770454) (xy 120.843282 -284.721175) (xy 120.866805 -284.675008) (xy 120.897261 -284.633089)
			(xy 120.933899 -284.596451) (xy 120.975818 -284.565995) (xy 121.021985 -284.542472) (xy 121.071264 -284.52646)
			(xy 121.122441 -284.518354) (xy 121.174255 -284.518354) (xy 121.225432 -284.52646) (xy 121.274711 -284.542472)
			(xy 121.320878 -284.565995) (xy 121.362797 -284.596451) (xy 121.399435 -284.633089) (xy 121.429891 -284.675008)
			(xy 121.453414 -284.721175) (xy 121.469426 -284.770454) (xy 121.477532 -284.821631) (xy 121.47804 -284.847538)
			(xy 122.698256 -284.847538) (xy 122.698764 -284.821631) (xy 122.70687 -284.770454) (xy 122.722882 -284.721175)
			(xy 122.746405 -284.675008) (xy 122.776861 -284.633089) (xy 122.813499 -284.596451) (xy 122.855418 -284.565995)
			(xy 122.901585 -284.542472) (xy 122.950864 -284.52646) (xy 123.002041 -284.518354) (xy 123.053855 -284.518354)
			(xy 123.105032 -284.52646) (xy 123.154311 -284.542472) (xy 123.200478 -284.565995) (xy 123.242397 -284.596451)
			(xy 123.279035 -284.633089) (xy 123.309491 -284.675008) (xy 123.333014 -284.721175) (xy 123.349026 -284.770454)
			(xy 123.357132 -284.821631) (xy 123.35764 -284.847538) (xy 124.577856 -284.847538) (xy 124.578364 -284.821631)
			(xy 124.58647 -284.770454) (xy 124.602482 -284.721175) (xy 124.626005 -284.675008) (xy 124.656461 -284.633089)
			(xy 124.693099 -284.596451) (xy 124.735018 -284.565995) (xy 124.781185 -284.542472) (xy 124.830464 -284.52646)
			(xy 124.881641 -284.518354) (xy 124.933455 -284.518354) (xy 124.984632 -284.52646) (xy 125.033911 -284.542472)
			(xy 125.080078 -284.565995) (xy 125.121997 -284.596451) (xy 125.158635 -284.633089) (xy 125.189091 -284.675008)
			(xy 125.212614 -284.721175) (xy 125.228626 -284.770454) (xy 125.236732 -284.821631) (xy 125.23724 -284.847538)
			(xy 126.457456 -284.847538) (xy 126.457964 -284.821631) (xy 126.46607 -284.770454) (xy 126.482082 -284.721175)
			(xy 126.505605 -284.675008) (xy 126.536061 -284.633089) (xy 126.572699 -284.596451) (xy 126.614618 -284.565995)
			(xy 126.660785 -284.542472) (xy 126.710064 -284.52646) (xy 126.761241 -284.518354) (xy 126.813055 -284.518354)
			(xy 126.864232 -284.52646) (xy 126.913511 -284.542472) (xy 126.959678 -284.565995) (xy 127.001597 -284.596451)
			(xy 127.038235 -284.633089) (xy 127.068691 -284.675008) (xy 127.092214 -284.721175) (xy 127.108226 -284.770454)
			(xy 127.116332 -284.821631) (xy 127.11684 -284.847538) (xy 128.337056 -284.847538) (xy 128.337564 -284.821631)
			(xy 128.34567 -284.770454) (xy 128.361682 -284.721175) (xy 128.385205 -284.675008) (xy 128.415661 -284.633089)
			(xy 128.452299 -284.596451) (xy 128.494218 -284.565995) (xy 128.540385 -284.542472) (xy 128.589664 -284.52646)
			(xy 128.640841 -284.518354) (xy 128.692655 -284.518354) (xy 128.743832 -284.52646) (xy 128.793111 -284.542472)
			(xy 128.839278 -284.565995) (xy 128.881197 -284.596451) (xy 128.917835 -284.633089) (xy 128.948291 -284.675008)
			(xy 128.971814 -284.721175) (xy 128.987826 -284.770454) (xy 128.995932 -284.821631) (xy 128.99644 -284.847538)
			(xy 130.216656 -284.847538) (xy 130.217164 -284.821631) (xy 130.22527 -284.770454) (xy 130.241282 -284.721175)
			(xy 130.264805 -284.675008) (xy 130.295261 -284.633089) (xy 130.331899 -284.596451) (xy 130.373818 -284.565995)
			(xy 130.419985 -284.542472) (xy 130.469264 -284.52646) (xy 130.520441 -284.518354) (xy 130.572255 -284.518354)
			(xy 130.623432 -284.52646) (xy 130.672711 -284.542472) (xy 130.718878 -284.565995) (xy 130.760797 -284.596451)
			(xy 130.797435 -284.633089) (xy 130.827891 -284.675008) (xy 130.851414 -284.721175) (xy 130.867426 -284.770454)
			(xy 130.875532 -284.821631) (xy 130.87604 -284.847538) (xy 132.096256 -284.847538) (xy 132.096764 -284.821631)
			(xy 132.10487 -284.770454) (xy 132.120882 -284.721175) (xy 132.144405 -284.675008) (xy 132.174861 -284.633089)
			(xy 132.211499 -284.596451) (xy 132.253418 -284.565995) (xy 132.299585 -284.542472) (xy 132.348864 -284.52646)
			(xy 132.400041 -284.518354) (xy 132.451855 -284.518354) (xy 132.503032 -284.52646) (xy 132.552311 -284.542472)
			(xy 132.598478 -284.565995) (xy 132.640397 -284.596451) (xy 132.677035 -284.633089) (xy 132.707491 -284.675008)
			(xy 132.731014 -284.721175) (xy 132.747026 -284.770454) (xy 132.755132 -284.821631) (xy 132.75564 -284.847538)
			(xy 132.755075 -284.873383) (xy 333.046907 -284.873383) (xy 333.046907 -284.821618) (xy 333.055005 -284.77049)
			(xy 333.071 -284.721258) (xy 333.094499 -284.675134) (xy 333.124924 -284.633254) (xy 333.161525 -284.596648)
			(xy 333.203402 -284.566219) (xy 333.249523 -284.542714) (xy 333.298753 -284.526713) (xy 333.34988 -284.51861)
			(xy 333.375762 -284.5181) (xy 333.401254 -284.518612) (xy 333.451631 -284.526467) (xy 333.500193 -284.541996)
			(xy 333.54578 -284.564827) (xy 333.587302 -284.594415) (xy 333.623765 -284.63005) (xy 333.639414 -284.65018)
			(xy 334.05191 -284.65018) (xy 334.067576 -284.630063) (xy 334.104034 -284.594421) (xy 334.145551 -284.564826)
			(xy 334.191135 -284.541986) (xy 334.239694 -284.526447) (xy 334.290069 -284.518581) (xy 334.315562 -284.5181)
			(xy 334.341456 -284.518502) (xy 334.392608 -284.526599) (xy 334.441864 -284.542598) (xy 334.48801 -284.566106)
			(xy 334.52991 -284.596543) (xy 334.566532 -284.633161) (xy 334.596975 -284.675058) (xy 334.620488 -284.721201)
			(xy 334.636492 -284.770455) (xy 334.644595 -284.821606) (xy 334.644595 -284.873394) (xy 334.636492 -284.924545)
			(xy 334.620488 -284.973799) (xy 334.596975 -285.019942) (xy 334.566532 -285.061839) (xy 334.52991 -285.098457)
			(xy 334.48801 -285.128894) (xy 334.441864 -285.152402) (xy 334.392608 -285.168401) (xy 334.341456 -285.176498)
			(xy 334.315562 -285.176976) (xy 334.290067 -285.176529) (xy 334.239687 -285.168661) (xy 334.191123 -285.15312)
			(xy 334.145536 -285.130277) (xy 334.104016 -285.100678) (xy 334.067557 -285.065031) (xy 334.05191 -285.044896)
			(xy 333.639414 -285.044896) (xy 333.623786 -285.065045) (xy 333.587321 -285.100686) (xy 333.545796 -285.130277)
			(xy 333.500205 -285.153112) (xy 333.451638 -285.168644) (xy 333.401257 -285.176501) (xy 333.375762 -285.176976)
			(xy 333.34988 -285.17639) (xy 333.298753 -285.168287) (xy 333.249523 -285.152286) (xy 333.203402 -285.128781)
			(xy 333.161525 -285.098352) (xy 333.124924 -285.061746) (xy 333.094499 -285.019866) (xy 333.071 -284.973742)
			(xy 333.055005 -284.92451) (xy 333.046907 -284.873383) (xy 132.755075 -284.873383) (xy 132.755034 -284.875255)
			(xy 132.745719 -284.929901) (xy 132.737098 -284.95625) (xy 132.729224 -284.978348) (xy 132.934202 -285.333186)
			(xy 132.957062 -285.337504) (xy 132.981868 -285.342683) (xy 133.02961 -285.359669) (xy 133.07419 -285.383762)
			(xy 133.114558 -285.414393) (xy 133.149763 -285.450841) (xy 133.178975 -285.492247) (xy 133.201506 -285.537636)
			(xy 133.216825 -285.585939) (xy 133.224572 -285.636017) (xy 133.225032 -285.661354) (xy 133.224524 -285.687241)
			(xy 133.216425 -285.738379) (xy 133.200426 -285.787619) (xy 133.17692 -285.833751) (xy 133.146488 -285.875638)
			(xy 133.109878 -285.912248) (xy 133.067991 -285.94268) (xy 133.021859 -285.966186) (xy 132.972619 -285.982185)
			(xy 132.921481 -285.990284) (xy 132.869707 -285.990284) (xy 132.818569 -285.982185) (xy 132.769329 -285.966186)
			(xy 132.723197 -285.94268) (xy 132.68131 -285.912248) (xy 132.6447 -285.875638) (xy 132.614268 -285.833751)
			(xy 132.590762 -285.787619) (xy 132.574763 -285.738379) (xy 132.566664 -285.687241) (xy 132.566156 -285.661354)
			(xy 132.566701 -285.633647) (xy 132.575886 -285.579) (xy 132.584444 -285.552642) (xy 132.592318 -285.530544)
			(xy 132.38734 -285.175706) (xy 132.36448 -285.171388) (xy 132.33966 -285.166215) (xy 132.29188 -285.149263)
			(xy 132.247259 -285.125194) (xy 132.206851 -285.094575) (xy 132.171609 -285.058129) (xy 132.142365 -285.016715)
			(xy 132.119809 -284.971312) (xy 132.104472 -284.922989) (xy 132.096717 -284.872887) (xy 132.096256 -284.847538)
			(xy 130.87604 -284.847538) (xy 130.875434 -284.875255) (xy 130.866119 -284.929901) (xy 130.857498 -284.95625)
			(xy 130.849624 -284.978348) (xy 131.054602 -285.333186) (xy 131.077462 -285.337504) (xy 131.102268 -285.342683)
			(xy 131.15001 -285.359669) (xy 131.19459 -285.383762) (xy 131.234958 -285.414393) (xy 131.270163 -285.450841)
			(xy 131.299375 -285.492247) (xy 131.321906 -285.537636) (xy 131.337225 -285.585939) (xy 131.344972 -285.636017)
			(xy 131.345432 -285.661354) (xy 131.344924 -285.687241) (xy 131.336825 -285.738379) (xy 131.320826 -285.787619)
			(xy 131.29732 -285.833751) (xy 131.266888 -285.875638) (xy 131.230278 -285.912248) (xy 131.188391 -285.94268)
			(xy 131.142259 -285.966186) (xy 131.093019 -285.982185) (xy 131.041881 -285.990284) (xy 130.990107 -285.990284)
			(xy 130.938969 -285.982185) (xy 130.889729 -285.966186) (xy 130.843597 -285.94268) (xy 130.80171 -285.912248)
			(xy 130.7651 -285.875638) (xy 130.734668 -285.833751) (xy 130.711162 -285.787619) (xy 130.695163 -285.738379)
			(xy 130.687064 -285.687241) (xy 130.686556 -285.661354) (xy 130.687101 -285.633647) (xy 130.696286 -285.579)
			(xy 130.704844 -285.552642) (xy 130.712718 -285.530544) (xy 130.50774 -285.175706) (xy 130.48488 -285.171388)
			(xy 130.46006 -285.166215) (xy 130.41228 -285.149263) (xy 130.367659 -285.125194) (xy 130.327251 -285.094575)
			(xy 130.292009 -285.058129) (xy 130.262765 -285.016715) (xy 130.240209 -284.971312) (xy 130.224872 -284.922989)
			(xy 130.217117 -284.872887) (xy 130.216656 -284.847538) (xy 128.99644 -284.847538) (xy 128.995834 -284.875255)
			(xy 128.986519 -284.929901) (xy 128.977898 -284.95625) (xy 128.970024 -284.978348) (xy 129.175002 -285.333186)
			(xy 129.197862 -285.337504) (xy 129.222668 -285.342683) (xy 129.27041 -285.359669) (xy 129.31499 -285.383762)
			(xy 129.355358 -285.414393) (xy 129.390563 -285.450841) (xy 129.419775 -285.492247) (xy 129.442306 -285.537636)
			(xy 129.457625 -285.585939) (xy 129.465372 -285.636017) (xy 129.465832 -285.661354) (xy 129.465324 -285.687241)
			(xy 129.457225 -285.738379) (xy 129.441226 -285.787619) (xy 129.41772 -285.833751) (xy 129.387288 -285.875638)
			(xy 129.350678 -285.912248) (xy 129.308791 -285.94268) (xy 129.262659 -285.966186) (xy 129.213419 -285.982185)
			(xy 129.162281 -285.990284) (xy 129.110507 -285.990284) (xy 129.059369 -285.982185) (xy 129.010129 -285.966186)
			(xy 128.963997 -285.94268) (xy 128.92211 -285.912248) (xy 128.8855 -285.875638) (xy 128.855068 -285.833751)
			(xy 128.831562 -285.787619) (xy 128.815563 -285.738379) (xy 128.807464 -285.687241) (xy 128.806956 -285.661354)
			(xy 128.807501 -285.633647) (xy 128.816686 -285.579) (xy 128.825244 -285.552642) (xy 128.833118 -285.530544)
			(xy 128.62814 -285.175706) (xy 128.60528 -285.171388) (xy 128.58046 -285.166215) (xy 128.53268 -285.149263)
			(xy 128.488059 -285.125194) (xy 128.447651 -285.094575) (xy 128.412409 -285.058129) (xy 128.383165 -285.016715)
			(xy 128.360609 -284.971312) (xy 128.345272 -284.922989) (xy 128.337517 -284.872887) (xy 128.337056 -284.847538)
			(xy 127.11684 -284.847538) (xy 127.116234 -284.875255) (xy 127.106919 -284.929901) (xy 127.098298 -284.95625)
			(xy 127.090424 -284.978348) (xy 127.295402 -285.333186) (xy 127.318262 -285.337504) (xy 127.343068 -285.342683)
			(xy 127.39081 -285.359669) (xy 127.43539 -285.383762) (xy 127.475758 -285.414393) (xy 127.510963 -285.450841)
			(xy 127.540175 -285.492247) (xy 127.562706 -285.537636) (xy 127.578025 -285.585939) (xy 127.585772 -285.636017)
			(xy 127.586232 -285.661354) (xy 127.585724 -285.687241) (xy 127.577625 -285.738379) (xy 127.561626 -285.787619)
			(xy 127.53812 -285.833751) (xy 127.507688 -285.875638) (xy 127.471078 -285.912248) (xy 127.429191 -285.94268)
			(xy 127.383059 -285.966186) (xy 127.333819 -285.982185) (xy 127.282681 -285.990284) (xy 127.230907 -285.990284)
			(xy 127.179769 -285.982185) (xy 127.130529 -285.966186) (xy 127.084397 -285.94268) (xy 127.04251 -285.912248)
			(xy 127.0059 -285.875638) (xy 126.975468 -285.833751) (xy 126.951962 -285.787619) (xy 126.935963 -285.738379)
			(xy 126.927864 -285.687241) (xy 126.927356 -285.661354) (xy 126.927901 -285.633647) (xy 126.937086 -285.579)
			(xy 126.945644 -285.552642) (xy 126.953518 -285.530544) (xy 126.74854 -285.175706) (xy 126.72568 -285.171388)
			(xy 126.70086 -285.166215) (xy 126.65308 -285.149263) (xy 126.608459 -285.125194) (xy 126.568051 -285.094575)
			(xy 126.532809 -285.058129) (xy 126.503565 -285.016715) (xy 126.481009 -284.971312) (xy 126.465672 -284.922989)
			(xy 126.457917 -284.872887) (xy 126.457456 -284.847538) (xy 125.23724 -284.847538) (xy 125.236634 -284.875255)
			(xy 125.227319 -284.929901) (xy 125.218698 -284.95625) (xy 125.210824 -284.978348) (xy 125.415802 -285.333186)
			(xy 125.438662 -285.337504) (xy 125.463468 -285.342683) (xy 125.51121 -285.359669) (xy 125.55579 -285.383762)
			(xy 125.596158 -285.414393) (xy 125.631363 -285.450841) (xy 125.660575 -285.492247) (xy 125.683106 -285.537636)
			(xy 125.698425 -285.585939) (xy 125.706172 -285.636017) (xy 125.706632 -285.661354) (xy 125.706124 -285.687241)
			(xy 125.698025 -285.738379) (xy 125.682026 -285.787619) (xy 125.65852 -285.833751) (xy 125.628088 -285.875638)
			(xy 125.591478 -285.912248) (xy 125.549591 -285.94268) (xy 125.503459 -285.966186) (xy 125.454219 -285.982185)
			(xy 125.403081 -285.990284) (xy 125.351307 -285.990284) (xy 125.300169 -285.982185) (xy 125.250929 -285.966186)
			(xy 125.204797 -285.94268) (xy 125.16291 -285.912248) (xy 125.1263 -285.875638) (xy 125.095868 -285.833751)
			(xy 125.072362 -285.787619) (xy 125.056363 -285.738379) (xy 125.048264 -285.687241) (xy 125.047756 -285.661354)
			(xy 125.048301 -285.633647) (xy 125.057486 -285.579) (xy 125.066044 -285.552642) (xy 125.073918 -285.530544)
			(xy 124.86894 -285.175706) (xy 124.84608 -285.171388) (xy 124.82126 -285.166215) (xy 124.77348 -285.149263)
			(xy 124.728859 -285.125194) (xy 124.688451 -285.094575) (xy 124.653209 -285.058129) (xy 124.623965 -285.016715)
			(xy 124.601409 -284.971312) (xy 124.586072 -284.922989) (xy 124.578317 -284.872887) (xy 124.577856 -284.847538)
			(xy 123.35764 -284.847538) (xy 123.357034 -284.875255) (xy 123.347719 -284.929901) (xy 123.339098 -284.95625)
			(xy 123.331224 -284.978348) (xy 123.536202 -285.333186) (xy 123.559062 -285.337504) (xy 123.583868 -285.342683)
			(xy 123.63161 -285.359669) (xy 123.67619 -285.383762) (xy 123.716558 -285.414393) (xy 123.751763 -285.450841)
			(xy 123.780975 -285.492247) (xy 123.803506 -285.537636) (xy 123.818825 -285.585939) (xy 123.826572 -285.636017)
			(xy 123.827032 -285.661354) (xy 123.826524 -285.687241) (xy 123.818425 -285.738379) (xy 123.802426 -285.787619)
			(xy 123.77892 -285.833751) (xy 123.748488 -285.875638) (xy 123.711878 -285.912248) (xy 123.669991 -285.94268)
			(xy 123.623859 -285.966186) (xy 123.574619 -285.982185) (xy 123.523481 -285.990284) (xy 123.471707 -285.990284)
			(xy 123.420569 -285.982185) (xy 123.371329 -285.966186) (xy 123.325197 -285.94268) (xy 123.28331 -285.912248)
			(xy 123.2467 -285.875638) (xy 123.216268 -285.833751) (xy 123.192762 -285.787619) (xy 123.176763 -285.738379)
			(xy 123.168664 -285.687241) (xy 123.168156 -285.661354) (xy 123.168701 -285.633647) (xy 123.177886 -285.579)
			(xy 123.186444 -285.552642) (xy 123.194318 -285.530544) (xy 122.98934 -285.175706) (xy 122.96648 -285.171388)
			(xy 122.94166 -285.166215) (xy 122.89388 -285.149263) (xy 122.849259 -285.125194) (xy 122.808851 -285.094575)
			(xy 122.773609 -285.058129) (xy 122.744365 -285.016715) (xy 122.721809 -284.971312) (xy 122.706472 -284.922989)
			(xy 122.698717 -284.872887) (xy 122.698256 -284.847538) (xy 121.47804 -284.847538) (xy 121.477434 -284.875255)
			(xy 121.468119 -284.929901) (xy 121.459498 -284.95625) (xy 121.451624 -284.978348) (xy 121.656602 -285.333186)
			(xy 121.679462 -285.337504) (xy 121.704268 -285.342683) (xy 121.75201 -285.359669) (xy 121.79659 -285.383762)
			(xy 121.836958 -285.414393) (xy 121.872163 -285.450841) (xy 121.901375 -285.492247) (xy 121.923906 -285.537636)
			(xy 121.939225 -285.585939) (xy 121.946972 -285.636017) (xy 121.947432 -285.661354) (xy 121.946924 -285.687241)
			(xy 121.938825 -285.738379) (xy 121.922826 -285.787619) (xy 121.89932 -285.833751) (xy 121.868888 -285.875638)
			(xy 121.832278 -285.912248) (xy 121.790391 -285.94268) (xy 121.744259 -285.966186) (xy 121.695019 -285.982185)
			(xy 121.643881 -285.990284) (xy 121.592107 -285.990284) (xy 121.540969 -285.982185) (xy 121.491729 -285.966186)
			(xy 121.445597 -285.94268) (xy 121.40371 -285.912248) (xy 121.3671 -285.875638) (xy 121.336668 -285.833751)
			(xy 121.313162 -285.787619) (xy 121.297163 -285.738379) (xy 121.289064 -285.687241) (xy 121.288556 -285.661354)
			(xy 121.289101 -285.633647) (xy 121.298286 -285.579) (xy 121.306844 -285.552642) (xy 121.314718 -285.530544)
			(xy 121.10974 -285.175706) (xy 121.08688 -285.171388) (xy 121.06206 -285.166215) (xy 121.01428 -285.149263)
			(xy 120.969659 -285.125194) (xy 120.929251 -285.094575) (xy 120.894009 -285.058129) (xy 120.864765 -285.016715)
			(xy 120.842209 -284.971312) (xy 120.826872 -284.922989) (xy 120.819117 -284.872887) (xy 120.818656 -284.847538)
			(xy 119.59844 -284.847538) (xy 119.597834 -284.875255) (xy 119.588519 -284.929901) (xy 119.579898 -284.95625)
			(xy 119.572024 -284.978348) (xy 119.777002 -285.333186) (xy 119.799862 -285.337504) (xy 119.824668 -285.342683)
			(xy 119.87241 -285.359669) (xy 119.91699 -285.383762) (xy 119.957358 -285.414393) (xy 119.992563 -285.450841)
			(xy 120.021775 -285.492247) (xy 120.044306 -285.537636) (xy 120.059625 -285.585939) (xy 120.067372 -285.636017)
			(xy 120.067832 -285.661354) (xy 120.067324 -285.687241) (xy 120.059225 -285.738379) (xy 120.043226 -285.787619)
			(xy 120.01972 -285.833751) (xy 119.989288 -285.875638) (xy 119.952678 -285.912248) (xy 119.910791 -285.94268)
			(xy 119.864659 -285.966186) (xy 119.815419 -285.982185) (xy 119.764281 -285.990284) (xy 119.712507 -285.990284)
			(xy 119.661369 -285.982185) (xy 119.612129 -285.966186) (xy 119.565997 -285.94268) (xy 119.52411 -285.912248)
			(xy 119.4875 -285.875638) (xy 119.457068 -285.833751) (xy 119.433562 -285.787619) (xy 119.417563 -285.738379)
			(xy 119.409464 -285.687241) (xy 119.408956 -285.661354) (xy 119.409501 -285.633647) (xy 119.418686 -285.579)
			(xy 119.427244 -285.552642) (xy 119.435118 -285.530544) (xy 119.23014 -285.175706) (xy 119.20728 -285.171388)
			(xy 119.18246 -285.166215) (xy 119.13468 -285.149263) (xy 119.090059 -285.125194) (xy 119.049651 -285.094575)
			(xy 119.014409 -285.058129) (xy 118.985165 -285.016715) (xy 118.962609 -284.971312) (xy 118.947272 -284.922989)
			(xy 118.939517 -284.872887) (xy 118.939056 -284.847538) (xy 104.56164 -284.847538) (xy 104.561248 -284.872916)
			(xy 104.553473 -284.923072) (xy 104.538096 -284.971442) (xy 104.515481 -285.016882) (xy 104.486165 -285.058314)
			(xy 104.45084 -285.09476) (xy 104.410343 -285.125356) (xy 104.365633 -285.149379) (xy 104.317766 -285.166259)
			(xy 104.292908 -285.171388) (xy 104.270048 -285.175706) (xy 104.06507 -285.530544) (xy 104.072944 -285.552642)
			(xy 104.081516 -285.578997) (xy 104.090707 -285.633645) (xy 104.091232 -285.661354) (xy 104.090724 -285.687241)
			(xy 104.082625 -285.738379) (xy 104.066626 -285.787619) (xy 104.04312 -285.833751) (xy 104.012688 -285.875638)
			(xy 103.976078 -285.912248) (xy 103.934191 -285.94268) (xy 103.888059 -285.966186) (xy 103.838819 -285.982185)
			(xy 103.787681 -285.990284) (xy 103.735907 -285.990284) (xy 103.684769 -285.982185) (xy 103.635529 -285.966186)
			(xy 103.589397 -285.94268) (xy 103.54751 -285.912248) (xy 103.5109 -285.875638) (xy 103.480468 -285.833751)
			(xy 103.456962 -285.787619) (xy 103.440963 -285.738379) (xy 103.432864 -285.687241) (xy 103.432356 -285.661354)
			(xy 103.151432 -285.661354) (xy 103.151432 -285.661862) (xy 103.150853 -285.689379) (xy 103.141659 -285.74364)
			(xy 103.133144 -285.769812) (xy 103.125524 -285.79191) (xy 103.330756 -286.147256) (xy 103.353616 -286.151574)
			(xy 103.378427 -286.156786) (xy 103.426204 -286.173734) (xy 103.470823 -286.197799) (xy 103.51123 -286.228413)
			(xy 103.546472 -286.264855) (xy 103.575717 -286.306263) (xy 103.598276 -286.351662) (xy 103.613617 -286.399979)
			(xy 103.621377 -286.450077) (xy 103.62184 -286.475424) (xy 119.878856 -286.475424) (xy 119.879354 -286.450079)
			(xy 119.887123 -286.399987) (xy 119.902468 -286.351675) (xy 119.925026 -286.306281) (xy 119.954266 -286.264873)
			(xy 119.989499 -286.228429) (xy 120.029894 -286.197807) (xy 120.0745 -286.173728) (xy 120.122266 -286.156759)
			(xy 120.14708 -286.151574) (xy 120.16994 -286.147256) (xy 120.374918 -285.792164) (xy 120.367044 -285.77032)
			(xy 120.358471 -285.743899) (xy 120.34927 -285.689126) (xy 120.348756 -285.661354) (xy 120.349264 -285.635467)
			(xy 120.357363 -285.584329) (xy 120.373362 -285.535089) (xy 120.396868 -285.488957) (xy 120.4273 -285.44707)
			(xy 120.46391 -285.41046) (xy 120.505797 -285.380028) (xy 120.551929 -285.356522) (xy 120.601169 -285.340523)
			(xy 120.652307 -285.332424) (xy 120.704081 -285.332424) (xy 120.755219 -285.340523) (xy 120.804459 -285.356522)
			(xy 120.850591 -285.380028) (xy 120.892478 -285.41046) (xy 120.929088 -285.44707) (xy 120.95952 -285.488957)
			(xy 120.983026 -285.535089) (xy 120.999025 -285.584329) (xy 121.007124 -285.635467) (xy 121.007632 -285.661354)
			(xy 121.007172 -285.686689) (xy 120.999413 -285.736761) (xy 120.984085 -285.785057) (xy 120.961549 -285.830439)
			(xy 120.932336 -285.87184) (xy 120.897134 -285.908285) (xy 120.856771 -285.938915) (xy 120.812197 -285.963011)
			(xy 120.764462 -285.980004) (xy 120.739662 -285.985204) (xy 120.716802 -285.989522) (xy 120.511824 -286.344614)
			(xy 120.519698 -286.366458) (xy 120.528349 -286.392865) (xy 120.537666 -286.447642) (xy 120.53824 -286.475424)
			(xy 121.758456 -286.475424) (xy 121.758954 -286.450079) (xy 121.766723 -286.399987) (xy 121.782068 -286.351675)
			(xy 121.804626 -286.306281) (xy 121.833866 -286.264873) (xy 121.869099 -286.228429) (xy 121.909494 -286.197807)
			(xy 121.9541 -286.173728) (xy 122.001866 -286.156759) (xy 122.02668 -286.151574) (xy 122.04954 -286.147256)
			(xy 122.254518 -285.792164) (xy 122.246644 -285.77032) (xy 122.238071 -285.743899) (xy 122.22887 -285.689126)
			(xy 122.228356 -285.661354) (xy 122.228864 -285.635467) (xy 122.236963 -285.584329) (xy 122.252962 -285.535089)
			(xy 122.276468 -285.488957) (xy 122.3069 -285.44707) (xy 122.34351 -285.41046) (xy 122.385397 -285.380028)
			(xy 122.431529 -285.356522) (xy 122.480769 -285.340523) (xy 122.531907 -285.332424) (xy 122.583681 -285.332424)
			(xy 122.634819 -285.340523) (xy 122.684059 -285.356522) (xy 122.730191 -285.380028) (xy 122.772078 -285.41046)
			(xy 122.808688 -285.44707) (xy 122.83912 -285.488957) (xy 122.862626 -285.535089) (xy 122.878625 -285.584329)
			(xy 122.886724 -285.635467) (xy 122.887232 -285.661354) (xy 122.886772 -285.686689) (xy 122.879013 -285.736761)
			(xy 122.863685 -285.785057) (xy 122.841149 -285.830439) (xy 122.811936 -285.87184) (xy 122.776734 -285.908285)
			(xy 122.736371 -285.938915) (xy 122.691797 -285.963011) (xy 122.644062 -285.980004) (xy 122.619262 -285.985204)
			(xy 122.596402 -285.989522) (xy 122.391424 -286.344614) (xy 122.399298 -286.366458) (xy 122.407949 -286.392865)
			(xy 122.417266 -286.447642) (xy 122.41784 -286.475424) (xy 123.638056 -286.475424) (xy 123.638554 -286.450079)
			(xy 123.646323 -286.399987) (xy 123.661668 -286.351675) (xy 123.684226 -286.306281) (xy 123.713466 -286.264873)
			(xy 123.748699 -286.228429) (xy 123.789094 -286.197807) (xy 123.8337 -286.173728) (xy 123.881466 -286.156759)
			(xy 123.90628 -286.151574) (xy 123.92914 -286.147256) (xy 124.134118 -285.792164) (xy 124.126244 -285.77032)
			(xy 124.117671 -285.743899) (xy 124.10847 -285.689126) (xy 124.107956 -285.661354) (xy 124.108464 -285.635467)
			(xy 124.116563 -285.584329) (xy 124.132562 -285.535089) (xy 124.156068 -285.488957) (xy 124.1865 -285.44707)
			(xy 124.22311 -285.41046) (xy 124.264997 -285.380028) (xy 124.311129 -285.356522) (xy 124.360369 -285.340523)
			(xy 124.411507 -285.332424) (xy 124.463281 -285.332424) (xy 124.514419 -285.340523) (xy 124.563659 -285.356522)
			(xy 124.609791 -285.380028) (xy 124.651678 -285.41046) (xy 124.688288 -285.44707) (xy 124.71872 -285.488957)
			(xy 124.742226 -285.535089) (xy 124.758225 -285.584329) (xy 124.766324 -285.635467) (xy 124.766832 -285.661354)
			(xy 124.766372 -285.686689) (xy 124.758613 -285.736761) (xy 124.743285 -285.785057) (xy 124.720749 -285.830439)
			(xy 124.691536 -285.87184) (xy 124.656334 -285.908285) (xy 124.615971 -285.938915) (xy 124.571397 -285.963011)
			(xy 124.523662 -285.980004) (xy 124.498862 -285.985204) (xy 124.476002 -285.989522) (xy 124.271024 -286.344614)
			(xy 124.278898 -286.366458) (xy 124.287549 -286.392865) (xy 124.296866 -286.447642) (xy 124.29744 -286.475424)
			(xy 125.517656 -286.475424) (xy 125.518154 -286.450079) (xy 125.525923 -286.399987) (xy 125.541268 -286.351675)
			(xy 125.563826 -286.306281) (xy 125.593066 -286.264873) (xy 125.628299 -286.228429) (xy 125.668694 -286.197807)
			(xy 125.7133 -286.173728) (xy 125.761066 -286.156759) (xy 125.78588 -286.151574) (xy 125.80874 -286.147256)
			(xy 126.013718 -285.792164) (xy 126.005844 -285.77032) (xy 125.997271 -285.743899) (xy 125.98807 -285.689126)
			(xy 125.987556 -285.661354) (xy 125.988064 -285.635467) (xy 125.996163 -285.584329) (xy 126.012162 -285.535089)
			(xy 126.035668 -285.488957) (xy 126.0661 -285.44707) (xy 126.10271 -285.41046) (xy 126.144597 -285.380028)
			(xy 126.190729 -285.356522) (xy 126.239969 -285.340523) (xy 126.291107 -285.332424) (xy 126.342881 -285.332424)
			(xy 126.394019 -285.340523) (xy 126.443259 -285.356522) (xy 126.489391 -285.380028) (xy 126.531278 -285.41046)
			(xy 126.567888 -285.44707) (xy 126.59832 -285.488957) (xy 126.621826 -285.535089) (xy 126.637825 -285.584329)
			(xy 126.645924 -285.635467) (xy 126.646432 -285.661354) (xy 126.645972 -285.686689) (xy 126.638213 -285.736761)
			(xy 126.622885 -285.785057) (xy 126.600349 -285.830439) (xy 126.571136 -285.87184) (xy 126.535934 -285.908285)
			(xy 126.495571 -285.938915) (xy 126.450997 -285.963011) (xy 126.403262 -285.980004) (xy 126.378462 -285.985204)
			(xy 126.355602 -285.989522) (xy 126.150624 -286.344614) (xy 126.158498 -286.366458) (xy 126.167149 -286.392865)
			(xy 126.176466 -286.447642) (xy 126.17704 -286.475424) (xy 127.397256 -286.475424) (xy 127.397754 -286.450079)
			(xy 127.405523 -286.399987) (xy 127.420868 -286.351675) (xy 127.443426 -286.306281) (xy 127.472666 -286.264873)
			(xy 127.507899 -286.228429) (xy 127.548294 -286.197807) (xy 127.5929 -286.173728) (xy 127.640666 -286.156759)
			(xy 127.66548 -286.151574) (xy 127.68834 -286.147256) (xy 127.893318 -285.792164) (xy 127.885444 -285.77032)
			(xy 127.876871 -285.743899) (xy 127.86767 -285.689126) (xy 127.867156 -285.661354) (xy 127.867664 -285.635467)
			(xy 127.875763 -285.584329) (xy 127.891762 -285.535089) (xy 127.915268 -285.488957) (xy 127.9457 -285.44707)
			(xy 127.98231 -285.41046) (xy 128.024197 -285.380028) (xy 128.070329 -285.356522) (xy 128.119569 -285.340523)
			(xy 128.170707 -285.332424) (xy 128.222481 -285.332424) (xy 128.273619 -285.340523) (xy 128.322859 -285.356522)
			(xy 128.368991 -285.380028) (xy 128.410878 -285.41046) (xy 128.447488 -285.44707) (xy 128.47792 -285.488957)
			(xy 128.501426 -285.535089) (xy 128.517425 -285.584329) (xy 128.525524 -285.635467) (xy 128.526032 -285.661354)
			(xy 128.525572 -285.686689) (xy 128.517813 -285.736761) (xy 128.502485 -285.785057) (xy 128.479949 -285.830439)
			(xy 128.450736 -285.87184) (xy 128.415534 -285.908285) (xy 128.375171 -285.938915) (xy 128.330597 -285.963011)
			(xy 128.282862 -285.980004) (xy 128.258062 -285.985204) (xy 128.235202 -285.989522) (xy 128.030224 -286.344614)
			(xy 128.038098 -286.366458) (xy 128.046749 -286.392865) (xy 128.056066 -286.447642) (xy 128.05664 -286.475424)
			(xy 129.276856 -286.475424) (xy 129.277354 -286.450079) (xy 129.285123 -286.399987) (xy 129.300468 -286.351675)
			(xy 129.323026 -286.306281) (xy 129.352266 -286.264873) (xy 129.387499 -286.228429) (xy 129.427894 -286.197807)
			(xy 129.4725 -286.173728) (xy 129.520266 -286.156759) (xy 129.54508 -286.151574) (xy 129.56794 -286.147256)
			(xy 129.772918 -285.792164) (xy 129.765044 -285.77032) (xy 129.756471 -285.743899) (xy 129.74727 -285.689126)
			(xy 129.746756 -285.661354) (xy 129.747264 -285.635467) (xy 129.755363 -285.584329) (xy 129.771362 -285.535089)
			(xy 129.794868 -285.488957) (xy 129.8253 -285.44707) (xy 129.86191 -285.41046) (xy 129.903797 -285.380028)
			(xy 129.949929 -285.356522) (xy 129.999169 -285.340523) (xy 130.050307 -285.332424) (xy 130.102081 -285.332424)
			(xy 130.153219 -285.340523) (xy 130.202459 -285.356522) (xy 130.248591 -285.380028) (xy 130.290478 -285.41046)
			(xy 130.327088 -285.44707) (xy 130.35752 -285.488957) (xy 130.381026 -285.535089) (xy 130.397025 -285.584329)
			(xy 130.405124 -285.635467) (xy 130.405632 -285.661354) (xy 130.405172 -285.686689) (xy 130.397413 -285.736761)
			(xy 130.382085 -285.785057) (xy 130.359549 -285.830439) (xy 130.330336 -285.87184) (xy 130.295134 -285.908285)
			(xy 130.254771 -285.938915) (xy 130.210197 -285.963011) (xy 130.162462 -285.980004) (xy 130.137662 -285.985204)
			(xy 130.114802 -285.989522) (xy 129.909824 -286.344614) (xy 129.917698 -286.366458) (xy 129.926349 -286.392865)
			(xy 129.935666 -286.447642) (xy 129.93624 -286.475424) (xy 131.156456 -286.475424) (xy 131.156954 -286.450079)
			(xy 131.164723 -286.399987) (xy 131.180068 -286.351675) (xy 131.202626 -286.306281) (xy 131.231866 -286.264873)
			(xy 131.267099 -286.228429) (xy 131.307494 -286.197807) (xy 131.3521 -286.173728) (xy 131.399866 -286.156759)
			(xy 131.42468 -286.151574) (xy 131.44754 -286.147256) (xy 131.652518 -285.792164) (xy 131.644644 -285.77032)
			(xy 131.636071 -285.743899) (xy 131.62687 -285.689126) (xy 131.626356 -285.661354) (xy 131.626864 -285.635467)
			(xy 131.634963 -285.584329) (xy 131.650962 -285.535089) (xy 131.674468 -285.488957) (xy 131.7049 -285.44707)
			(xy 131.74151 -285.41046) (xy 131.783397 -285.380028) (xy 131.829529 -285.356522) (xy 131.878769 -285.340523)
			(xy 131.929907 -285.332424) (xy 131.981681 -285.332424) (xy 132.032819 -285.340523) (xy 132.082059 -285.356522)
			(xy 132.128191 -285.380028) (xy 132.170078 -285.41046) (xy 132.206688 -285.44707) (xy 132.23712 -285.488957)
			(xy 132.260626 -285.535089) (xy 132.276625 -285.584329) (xy 132.284724 -285.635467) (xy 132.285232 -285.661354)
			(xy 132.284772 -285.686689) (xy 132.277013 -285.736761) (xy 132.261685 -285.785057) (xy 132.239149 -285.830439)
			(xy 132.209936 -285.87184) (xy 132.174734 -285.908285) (xy 132.134371 -285.938915) (xy 132.089797 -285.963011)
			(xy 132.042062 -285.980004) (xy 132.017262 -285.985204) (xy 131.994402 -285.989522) (xy 131.789424 -286.344614)
			(xy 131.797298 -286.366458) (xy 131.805949 -286.392865) (xy 131.815266 -286.447642) (xy 131.81584 -286.475424)
			(xy 133.036056 -286.475424) (xy 133.036554 -286.450079) (xy 133.044323 -286.399987) (xy 133.059668 -286.351675)
			(xy 133.082226 -286.306281) (xy 133.111466 -286.264873) (xy 133.146699 -286.228429) (xy 133.187094 -286.197807)
			(xy 133.2317 -286.173728) (xy 133.279466 -286.156759) (xy 133.30428 -286.151574) (xy 133.32714 -286.147256)
			(xy 133.532118 -285.792164) (xy 133.524244 -285.77032) (xy 133.515671 -285.743899) (xy 133.50647 -285.689126)
			(xy 133.505956 -285.661354) (xy 133.506464 -285.635467) (xy 133.514563 -285.584329) (xy 133.530562 -285.535089)
			(xy 133.554068 -285.488957) (xy 133.5845 -285.44707) (xy 133.62111 -285.41046) (xy 133.662997 -285.380028)
			(xy 133.709129 -285.356522) (xy 133.758369 -285.340523) (xy 133.809507 -285.332424) (xy 133.861281 -285.332424)
			(xy 133.912419 -285.340523) (xy 133.961659 -285.356522) (xy 134.007791 -285.380028) (xy 134.049678 -285.41046)
			(xy 134.086288 -285.44707) (xy 134.11672 -285.488957) (xy 134.140226 -285.535089) (xy 134.156225 -285.584329)
			(xy 134.164324 -285.635467) (xy 134.164832 -285.661354) (xy 335.395824 -285.661354) (xy 335.396245 -285.636017)
			(xy 335.404005 -285.585941) (xy 335.419335 -285.537642) (xy 335.441875 -285.492257) (xy 335.471092 -285.450854)
			(xy 335.5063 -285.41441) (xy 335.54667 -285.383781) (xy 335.59125 -285.359689) (xy 335.638992 -285.342701)
			(xy 335.663794 -285.337504) (xy 335.686654 -285.333186) (xy 335.891632 -284.978094) (xy 335.884012 -284.95625)
			(xy 335.875447 -284.929893) (xy 335.86625 -284.875247) (xy 335.865724 -284.847538) (xy 335.866232 -284.821651)
			(xy 335.874331 -284.770513) (xy 335.89033 -284.721273) (xy 335.913836 -284.675141) (xy 335.944268 -284.633254)
			(xy 335.980878 -284.596644) (xy 336.022765 -284.566212) (xy 336.068897 -284.542706) (xy 336.118137 -284.526707)
			(xy 336.169275 -284.518608) (xy 336.221049 -284.518608) (xy 336.272187 -284.526707) (xy 336.321427 -284.542706)
			(xy 336.367559 -284.566212) (xy 336.409446 -284.596644) (xy 336.446056 -284.633254) (xy 336.476488 -284.675141)
			(xy 336.499994 -284.721273) (xy 336.515993 -284.770513) (xy 336.524092 -284.821651) (xy 336.5246 -284.847538)
			(xy 336.524152 -284.872874) (xy 336.516394 -284.922948) (xy 336.501066 -284.971245) (xy 336.47853 -285.016629)
			(xy 336.449316 -285.058031) (xy 336.414111 -285.094476) (xy 336.373746 -285.125106) (xy 336.329169 -285.149199)
			(xy 336.281431 -285.16619) (xy 336.25663 -285.171388) (xy 336.23377 -285.175706) (xy 336.028792 -285.530798)
			(xy 336.036412 -285.552642) (xy 336.044976 -285.578999) (xy 336.054174 -285.633646) (xy 336.0547 -285.661354)
			(xy 337.275424 -285.661354) (xy 337.275932 -285.635467) (xy 337.284031 -285.584329) (xy 337.30003 -285.535089)
			(xy 337.323536 -285.488957) (xy 337.353968 -285.44707) (xy 337.390578 -285.41046) (xy 337.432465 -285.380028)
			(xy 337.478597 -285.356522) (xy 337.527837 -285.340523) (xy 337.578975 -285.332424) (xy 337.630749 -285.332424)
			(xy 337.681887 -285.340523) (xy 337.731127 -285.356522) (xy 337.777259 -285.380028) (xy 337.819146 -285.41046)
			(xy 337.855756 -285.44707) (xy 337.886188 -285.488957) (xy 337.909694 -285.535089) (xy 337.925693 -285.584329)
			(xy 337.933792 -285.635467) (xy 337.9343 -285.661354) (xy 338.215224 -285.661354) (xy 338.215684 -285.636008)
			(xy 338.223463 -285.585916) (xy 338.238816 -285.537605) (xy 338.26138 -285.492212) (xy 338.290625 -285.450806)
			(xy 338.325861 -285.414363) (xy 338.366259 -285.383741) (xy 338.410867 -285.359661) (xy 338.458634 -285.34269)
			(xy 338.483448 -285.337504) (xy 338.506308 -285.333186) (xy 338.711286 -284.978348) (xy 338.703412 -284.956504)
			(xy 338.694834 -284.930085) (xy 338.685636 -284.87531) (xy 338.685124 -284.847538) (xy 338.685632 -284.821651)
			(xy 338.693731 -284.770513) (xy 338.70973 -284.721273) (xy 338.733236 -284.675141) (xy 338.763668 -284.633254)
			(xy 338.800278 -284.596644) (xy 338.842165 -284.566212) (xy 338.888297 -284.542706) (xy 338.937537 -284.526707)
			(xy 338.988675 -284.518608) (xy 339.040449 -284.518608) (xy 339.091587 -284.526707) (xy 339.140827 -284.542706)
			(xy 339.186959 -284.566212) (xy 339.228846 -284.596644) (xy 339.265456 -284.633254) (xy 339.295888 -284.675141)
			(xy 339.319394 -284.721273) (xy 339.335393 -284.770513) (xy 339.343492 -284.821651) (xy 339.344 -284.847538)
			(xy 339.343552 -284.872874) (xy 339.335794 -284.922948) (xy 339.320466 -284.971245) (xy 339.29793 -285.016629)
			(xy 339.268716 -285.058031) (xy 339.233511 -285.094476) (xy 339.193146 -285.125106) (xy 339.148569 -285.149199)
			(xy 339.100831 -285.16619) (xy 339.07603 -285.171388) (xy 339.05317 -285.175706) (xy 338.848192 -285.530544)
			(xy 338.856066 -285.552642) (xy 338.86469 -285.578991) (xy 338.874015 -285.633637) (xy 338.874608 -285.661354)
			(xy 339.155024 -285.661354) (xy 339.155532 -285.635447) (xy 339.163638 -285.58427) (xy 339.17965 -285.534991)
			(xy 339.203173 -285.488824) (xy 339.233629 -285.446905) (xy 339.270267 -285.410267) (xy 339.312186 -285.379811)
			(xy 339.358353 -285.356288) (xy 339.407632 -285.340276) (xy 339.458809 -285.33217) (xy 339.510623 -285.33217)
			(xy 339.5618 -285.340276) (xy 339.611079 -285.356288) (xy 339.657246 -285.379811) (xy 339.699165 -285.410267)
			(xy 339.735803 -285.446905) (xy 339.766259 -285.488824) (xy 339.789782 -285.534991) (xy 339.805794 -285.58427)
			(xy 339.8139 -285.635447) (xy 339.814408 -285.661354) (xy 340.094824 -285.661354) (xy 340.095245 -285.636017)
			(xy 340.103005 -285.585941) (xy 340.118335 -285.537642) (xy 340.140875 -285.492257) (xy 340.170092 -285.450854)
			(xy 340.2053 -285.41441) (xy 340.24567 -285.383781) (xy 340.29025 -285.359689) (xy 340.337992 -285.342701)
			(xy 340.362794 -285.337504) (xy 340.385654 -285.333186) (xy 340.590886 -284.97784) (xy 340.583266 -284.955996)
			(xy 340.574644 -284.929713) (xy 340.565327 -284.875193) (xy 340.564724 -284.847538) (xy 340.565232 -284.821631)
			(xy 340.573338 -284.770454) (xy 340.58935 -284.721175) (xy 340.612873 -284.675008) (xy 340.643329 -284.633089)
			(xy 340.679967 -284.596451) (xy 340.721886 -284.565995) (xy 340.768053 -284.542472) (xy 340.817332 -284.52646)
			(xy 340.868509 -284.518354) (xy 340.920323 -284.518354) (xy 340.9715 -284.52646) (xy 341.020779 -284.542472)
			(xy 341.066946 -284.565995) (xy 341.108865 -284.596451) (xy 341.145503 -284.633089) (xy 341.175959 -284.675008)
			(xy 341.199482 -284.721175) (xy 341.215494 -284.770454) (xy 341.2236 -284.821631) (xy 341.224108 -284.847538)
			(xy 341.223661 -284.872913) (xy 341.215887 -284.923064) (xy 341.200514 -284.97143) (xy 341.177905 -285.016866)
			(xy 341.148596 -285.058297) (xy 341.113279 -285.094742) (xy 341.072791 -285.125341) (xy 341.028089 -285.149367)
			(xy 340.980231 -285.166254) (xy 340.955376 -285.171388) (xy 340.932516 -285.175706) (xy 340.727538 -285.530544)
			(xy 340.735412 -285.552642) (xy 340.743983 -285.578997) (xy 340.753175 -285.633645) (xy 340.7537 -285.661354)
			(xy 341.034624 -285.661354) (xy 341.035132 -285.635467) (xy 341.043231 -285.584329) (xy 341.05923 -285.535089)
			(xy 341.082736 -285.488957) (xy 341.113168 -285.44707) (xy 341.149778 -285.41046) (xy 341.191665 -285.380028)
			(xy 341.237797 -285.356522) (xy 341.287037 -285.340523) (xy 341.338175 -285.332424) (xy 341.389949 -285.332424)
			(xy 341.441087 -285.340523) (xy 341.490327 -285.356522) (xy 341.536459 -285.380028) (xy 341.578346 -285.41046)
			(xy 341.614956 -285.44707) (xy 341.645388 -285.488957) (xy 341.668894 -285.535089) (xy 341.684893 -285.584329)
			(xy 341.692992 -285.635467) (xy 341.6935 -285.661354) (xy 341.974424 -285.661354) (xy 341.974845 -285.636017)
			(xy 341.982605 -285.585941) (xy 341.997935 -285.537642) (xy 342.020475 -285.492257) (xy 342.049692 -285.450854)
			(xy 342.0849 -285.41441) (xy 342.12527 -285.383781) (xy 342.16985 -285.359689) (xy 342.217592 -285.342701)
			(xy 342.242394 -285.337504) (xy 342.265254 -285.333186) (xy 342.470486 -284.97784) (xy 342.462866 -284.955996)
			(xy 342.454244 -284.929713) (xy 342.444927 -284.875193) (xy 342.444324 -284.847538) (xy 342.444832 -284.821631)
			(xy 342.452938 -284.770454) (xy 342.46895 -284.721175) (xy 342.492473 -284.675008) (xy 342.522929 -284.633089)
			(xy 342.559567 -284.596451) (xy 342.601486 -284.565995) (xy 342.647653 -284.542472) (xy 342.696932 -284.52646)
			(xy 342.748109 -284.518354) (xy 342.799923 -284.518354) (xy 342.8511 -284.52646) (xy 342.900379 -284.542472)
			(xy 342.946546 -284.565995) (xy 342.988465 -284.596451) (xy 343.025103 -284.633089) (xy 343.055559 -284.675008)
			(xy 343.079082 -284.721175) (xy 343.095094 -284.770454) (xy 343.1032 -284.821631) (xy 343.103708 -284.847538)
			(xy 343.103261 -284.872913) (xy 343.095487 -284.923064) (xy 343.080114 -284.97143) (xy 343.057505 -285.016866)
			(xy 343.028196 -285.058297) (xy 342.992879 -285.094742) (xy 342.952391 -285.125341) (xy 342.907689 -285.149367)
			(xy 342.859831 -285.166254) (xy 342.834976 -285.171388) (xy 342.812116 -285.175706) (xy 342.607138 -285.530544)
			(xy 342.615012 -285.552642) (xy 342.623583 -285.578997) (xy 342.632775 -285.633645) (xy 342.6333 -285.661354)
			(xy 342.914224 -285.661354) (xy 342.914732 -285.635467) (xy 342.922831 -285.584329) (xy 342.93883 -285.535089)
			(xy 342.962336 -285.488957) (xy 342.992768 -285.44707) (xy 343.029378 -285.41046) (xy 343.071265 -285.380028)
			(xy 343.117397 -285.356522) (xy 343.166637 -285.340523) (xy 343.217775 -285.332424) (xy 343.269549 -285.332424)
			(xy 343.320687 -285.340523) (xy 343.369927 -285.356522) (xy 343.416059 -285.380028) (xy 343.457946 -285.41046)
			(xy 343.494556 -285.44707) (xy 343.524988 -285.488957) (xy 343.548494 -285.535089) (xy 343.564493 -285.584329)
			(xy 343.572592 -285.635467) (xy 343.5731 -285.661354) (xy 343.854024 -285.661354) (xy 343.854445 -285.636017)
			(xy 343.862205 -285.585941) (xy 343.877535 -285.537642) (xy 343.900075 -285.492257) (xy 343.929292 -285.450854)
			(xy 343.9645 -285.41441) (xy 344.00487 -285.383781) (xy 344.04945 -285.359689) (xy 344.097192 -285.342701)
			(xy 344.121994 -285.337504) (xy 344.144854 -285.333186) (xy 344.350086 -284.97784) (xy 344.342466 -284.955996)
			(xy 344.333844 -284.929713) (xy 344.324527 -284.875193) (xy 344.323924 -284.847538) (xy 344.324432 -284.821631)
			(xy 344.332538 -284.770454) (xy 344.34855 -284.721175) (xy 344.372073 -284.675008) (xy 344.402529 -284.633089)
			(xy 344.439167 -284.596451) (xy 344.481086 -284.565995) (xy 344.527253 -284.542472) (xy 344.576532 -284.52646)
			(xy 344.627709 -284.518354) (xy 344.679523 -284.518354) (xy 344.7307 -284.52646) (xy 344.779979 -284.542472)
			(xy 344.826146 -284.565995) (xy 344.868065 -284.596451) (xy 344.904703 -284.633089) (xy 344.935159 -284.675008)
			(xy 344.958682 -284.721175) (xy 344.974694 -284.770454) (xy 344.9828 -284.821631) (xy 344.983308 -284.847538)
			(xy 344.982861 -284.872913) (xy 344.975087 -284.923064) (xy 344.959714 -284.97143) (xy 344.937105 -285.016866)
			(xy 344.907796 -285.058297) (xy 344.872479 -285.094742) (xy 344.831991 -285.125341) (xy 344.787289 -285.149367)
			(xy 344.739431 -285.166254) (xy 344.714576 -285.171388) (xy 344.691716 -285.175706) (xy 344.486738 -285.530544)
			(xy 344.494612 -285.552642) (xy 344.503183 -285.578997) (xy 344.512375 -285.633645) (xy 344.5129 -285.661354)
			(xy 344.793824 -285.661354) (xy 344.794332 -285.635467) (xy 344.802431 -285.584329) (xy 344.81843 -285.535089)
			(xy 344.841936 -285.488957) (xy 344.872368 -285.44707) (xy 344.908978 -285.41046) (xy 344.950865 -285.380028)
			(xy 344.996997 -285.356522) (xy 345.046237 -285.340523) (xy 345.097375 -285.332424) (xy 345.149149 -285.332424)
			(xy 345.200287 -285.340523) (xy 345.249527 -285.356522) (xy 345.295659 -285.380028) (xy 345.337546 -285.41046)
			(xy 345.374156 -285.44707) (xy 345.404588 -285.488957) (xy 345.428094 -285.535089) (xy 345.444093 -285.584329)
			(xy 345.452192 -285.635467) (xy 345.4527 -285.661354) (xy 345.733624 -285.661354) (xy 345.734045 -285.636017)
			(xy 345.741805 -285.585941) (xy 345.757135 -285.537642) (xy 345.779675 -285.492257) (xy 345.808892 -285.450854)
			(xy 345.8441 -285.41441) (xy 345.88447 -285.383781) (xy 345.92905 -285.359689) (xy 345.976792 -285.342701)
			(xy 346.001594 -285.337504) (xy 346.024454 -285.333186) (xy 346.229686 -284.97784) (xy 346.222066 -284.955996)
			(xy 346.213444 -284.929713) (xy 346.204127 -284.875193) (xy 346.203524 -284.847538) (xy 346.204032 -284.821631)
			(xy 346.212138 -284.770454) (xy 346.22815 -284.721175) (xy 346.251673 -284.675008) (xy 346.282129 -284.633089)
			(xy 346.318767 -284.596451) (xy 346.360686 -284.565995) (xy 346.406853 -284.542472) (xy 346.456132 -284.52646)
			(xy 346.507309 -284.518354) (xy 346.559123 -284.518354) (xy 346.6103 -284.52646) (xy 346.659579 -284.542472)
			(xy 346.705746 -284.565995) (xy 346.747665 -284.596451) (xy 346.784303 -284.633089) (xy 346.814759 -284.675008)
			(xy 346.838282 -284.721175) (xy 346.854294 -284.770454) (xy 346.8624 -284.821631) (xy 346.862908 -284.847538)
			(xy 346.862461 -284.872913) (xy 346.854687 -284.923064) (xy 346.839314 -284.97143) (xy 346.816705 -285.016866)
			(xy 346.787396 -285.058297) (xy 346.752079 -285.094742) (xy 346.711591 -285.125341) (xy 346.666889 -285.149367)
			(xy 346.619031 -285.166254) (xy 346.594176 -285.171388) (xy 346.571316 -285.175706) (xy 346.366338 -285.530544)
			(xy 346.374212 -285.552642) (xy 346.382783 -285.578997) (xy 346.391975 -285.633645) (xy 346.3925 -285.661354)
			(xy 346.673424 -285.661354) (xy 346.673932 -285.635467) (xy 346.682031 -285.584329) (xy 346.69803 -285.535089)
			(xy 346.721536 -285.488957) (xy 346.751968 -285.44707) (xy 346.788578 -285.41046) (xy 346.830465 -285.380028)
			(xy 346.876597 -285.356522) (xy 346.925837 -285.340523) (xy 346.976975 -285.332424) (xy 347.028749 -285.332424)
			(xy 347.079887 -285.340523) (xy 347.129127 -285.356522) (xy 347.175259 -285.380028) (xy 347.217146 -285.41046)
			(xy 347.253756 -285.44707) (xy 347.284188 -285.488957) (xy 347.307694 -285.535089) (xy 347.323693 -285.584329)
			(xy 347.331792 -285.635467) (xy 347.3323 -285.661354) (xy 347.613224 -285.661354) (xy 347.613645 -285.636017)
			(xy 347.621405 -285.585941) (xy 347.636735 -285.537642) (xy 347.659275 -285.492257) (xy 347.688492 -285.450854)
			(xy 347.7237 -285.41441) (xy 347.76407 -285.383781) (xy 347.80865 -285.359689) (xy 347.856392 -285.342701)
			(xy 347.881194 -285.337504) (xy 347.904054 -285.333186) (xy 348.109286 -284.97784) (xy 348.101666 -284.955996)
			(xy 348.093044 -284.929713) (xy 348.083727 -284.875193) (xy 348.083124 -284.847538) (xy 348.083632 -284.821631)
			(xy 348.091738 -284.770454) (xy 348.10775 -284.721175) (xy 348.131273 -284.675008) (xy 348.161729 -284.633089)
			(xy 348.198367 -284.596451) (xy 348.240286 -284.565995) (xy 348.286453 -284.542472) (xy 348.335732 -284.52646)
			(xy 348.386909 -284.518354) (xy 348.438723 -284.518354) (xy 348.4899 -284.52646) (xy 348.539179 -284.542472)
			(xy 348.585346 -284.565995) (xy 348.627265 -284.596451) (xy 348.663903 -284.633089) (xy 348.694359 -284.675008)
			(xy 348.717882 -284.721175) (xy 348.733894 -284.770454) (xy 348.742 -284.821631) (xy 348.742508 -284.847538)
			(xy 348.742061 -284.872913) (xy 348.734287 -284.923064) (xy 348.718914 -284.97143) (xy 348.696305 -285.016866)
			(xy 348.666996 -285.058297) (xy 348.631679 -285.094742) (xy 348.591191 -285.125341) (xy 348.546489 -285.149367)
			(xy 348.498631 -285.166254) (xy 348.473776 -285.171388) (xy 348.450916 -285.175706) (xy 348.245938 -285.530544)
			(xy 348.253812 -285.552642) (xy 348.262383 -285.578997) (xy 348.271575 -285.633645) (xy 348.2721 -285.661354)
			(xy 348.553024 -285.661354) (xy 348.553532 -285.635467) (xy 348.561631 -285.584329) (xy 348.57763 -285.535089)
			(xy 348.601136 -285.488957) (xy 348.631568 -285.44707) (xy 348.668178 -285.41046) (xy 348.710065 -285.380028)
			(xy 348.756197 -285.356522) (xy 348.805437 -285.340523) (xy 348.856575 -285.332424) (xy 348.908349 -285.332424)
			(xy 348.959487 -285.340523) (xy 349.008727 -285.356522) (xy 349.054859 -285.380028) (xy 349.096746 -285.41046)
			(xy 349.133356 -285.44707) (xy 349.163788 -285.488957) (xy 349.187294 -285.535089) (xy 349.203293 -285.584329)
			(xy 349.211392 -285.635467) (xy 349.2119 -285.661354) (xy 349.492824 -285.661354) (xy 349.493245 -285.636017)
			(xy 349.501005 -285.585941) (xy 349.516335 -285.537642) (xy 349.538875 -285.492257) (xy 349.568092 -285.450854)
			(xy 349.6033 -285.41441) (xy 349.64367 -285.383781) (xy 349.68825 -285.359689) (xy 349.735992 -285.342701)
			(xy 349.760794 -285.337504) (xy 349.783654 -285.333186) (xy 349.988886 -284.97784) (xy 349.981266 -284.955996)
			(xy 349.972644 -284.929713) (xy 349.963327 -284.875193) (xy 349.962724 -284.847538) (xy 349.963232 -284.821631)
			(xy 349.971338 -284.770454) (xy 349.98735 -284.721175) (xy 350.010873 -284.675008) (xy 350.041329 -284.633089)
			(xy 350.077967 -284.596451) (xy 350.119886 -284.565995) (xy 350.166053 -284.542472) (xy 350.215332 -284.52646)
			(xy 350.266509 -284.518354) (xy 350.318323 -284.518354) (xy 350.3695 -284.52646) (xy 350.418779 -284.542472)
			(xy 350.464946 -284.565995) (xy 350.506865 -284.596451) (xy 350.543503 -284.633089) (xy 350.573959 -284.675008)
			(xy 350.597482 -284.721175) (xy 350.613494 -284.770454) (xy 350.6216 -284.821631) (xy 350.622108 -284.847538)
			(xy 350.621661 -284.872913) (xy 350.613887 -284.923064) (xy 350.598514 -284.97143) (xy 350.575905 -285.016866)
			(xy 350.546596 -285.058297) (xy 350.511279 -285.094742) (xy 350.470791 -285.125341) (xy 350.426089 -285.149367)
			(xy 350.378231 -285.166254) (xy 350.353376 -285.171388) (xy 350.330516 -285.175706) (xy 350.125538 -285.530544)
			(xy 350.133412 -285.552642) (xy 350.141983 -285.578997) (xy 350.151175 -285.633645) (xy 350.1517 -285.661354)
			(xy 350.432624 -285.661354) (xy 350.433132 -285.635467) (xy 350.441231 -285.584329) (xy 350.45723 -285.535089)
			(xy 350.480736 -285.488957) (xy 350.511168 -285.44707) (xy 350.547778 -285.41046) (xy 350.589665 -285.380028)
			(xy 350.635797 -285.356522) (xy 350.685037 -285.340523) (xy 350.736175 -285.332424) (xy 350.787949 -285.332424)
			(xy 350.839087 -285.340523) (xy 350.888327 -285.356522) (xy 350.934459 -285.380028) (xy 350.976346 -285.41046)
			(xy 351.012956 -285.44707) (xy 351.043388 -285.488957) (xy 351.066894 -285.535089) (xy 351.082893 -285.584329)
			(xy 351.090992 -285.635467) (xy 351.0915 -285.661354) (xy 351.372424 -285.661354) (xy 351.372845 -285.636017)
			(xy 351.380605 -285.585941) (xy 351.395935 -285.537642) (xy 351.418475 -285.492257) (xy 351.447692 -285.450854)
			(xy 351.4829 -285.41441) (xy 351.52327 -285.383781) (xy 351.56785 -285.359689) (xy 351.615592 -285.342701)
			(xy 351.640394 -285.337504) (xy 351.663254 -285.333186) (xy 351.868486 -284.97784) (xy 351.860866 -284.955996)
			(xy 351.852244 -284.929713) (xy 351.842927 -284.875193) (xy 351.842324 -284.847538) (xy 351.842832 -284.821631)
			(xy 351.850938 -284.770454) (xy 351.86695 -284.721175) (xy 351.890473 -284.675008) (xy 351.920929 -284.633089)
			(xy 351.957567 -284.596451) (xy 351.999486 -284.565995) (xy 352.045653 -284.542472) (xy 352.094932 -284.52646)
			(xy 352.146109 -284.518354) (xy 352.197923 -284.518354) (xy 352.2491 -284.52646) (xy 352.298379 -284.542472)
			(xy 352.344546 -284.565995) (xy 352.386465 -284.596451) (xy 352.423103 -284.633089) (xy 352.453559 -284.675008)
			(xy 352.477082 -284.721175) (xy 352.493094 -284.770454) (xy 352.5012 -284.821631) (xy 352.501708 -284.847538)
			(xy 366.879124 -284.847538) (xy 366.879632 -284.821631) (xy 366.887738 -284.770454) (xy 366.90375 -284.721175)
			(xy 366.927273 -284.675008) (xy 366.957729 -284.633089) (xy 366.994367 -284.596451) (xy 367.036286 -284.565995)
			(xy 367.082453 -284.542472) (xy 367.131732 -284.52646) (xy 367.182909 -284.518354) (xy 367.234723 -284.518354)
			(xy 367.2859 -284.52646) (xy 367.335179 -284.542472) (xy 367.381346 -284.565995) (xy 367.423265 -284.596451)
			(xy 367.459903 -284.633089) (xy 367.490359 -284.675008) (xy 367.513882 -284.721175) (xy 367.529894 -284.770454)
			(xy 367.538 -284.821631) (xy 367.538508 -284.847538) (xy 368.758724 -284.847538) (xy 368.759232 -284.821631)
			(xy 368.767338 -284.770454) (xy 368.78335 -284.721175) (xy 368.806873 -284.675008) (xy 368.837329 -284.633089)
			(xy 368.873967 -284.596451) (xy 368.915886 -284.565995) (xy 368.962053 -284.542472) (xy 369.011332 -284.52646)
			(xy 369.062509 -284.518354) (xy 369.114323 -284.518354) (xy 369.1655 -284.52646) (xy 369.214779 -284.542472)
			(xy 369.260946 -284.565995) (xy 369.302865 -284.596451) (xy 369.339503 -284.633089) (xy 369.369959 -284.675008)
			(xy 369.393482 -284.721175) (xy 369.409494 -284.770454) (xy 369.4176 -284.821631) (xy 369.418108 -284.847538)
			(xy 370.638324 -284.847538) (xy 370.638832 -284.821631) (xy 370.646938 -284.770454) (xy 370.66295 -284.721175)
			(xy 370.686473 -284.675008) (xy 370.716929 -284.633089) (xy 370.753567 -284.596451) (xy 370.795486 -284.565995)
			(xy 370.841653 -284.542472) (xy 370.890932 -284.52646) (xy 370.942109 -284.518354) (xy 370.993923 -284.518354)
			(xy 371.0451 -284.52646) (xy 371.094379 -284.542472) (xy 371.140546 -284.565995) (xy 371.182465 -284.596451)
			(xy 371.219103 -284.633089) (xy 371.249559 -284.675008) (xy 371.273082 -284.721175) (xy 371.289094 -284.770454)
			(xy 371.2972 -284.821631) (xy 371.297708 -284.847538) (xy 372.517924 -284.847538) (xy 372.518432 -284.821631)
			(xy 372.526538 -284.770454) (xy 372.54255 -284.721175) (xy 372.566073 -284.675008) (xy 372.596529 -284.633089)
			(xy 372.633167 -284.596451) (xy 372.675086 -284.565995) (xy 372.721253 -284.542472) (xy 372.770532 -284.52646)
			(xy 372.821709 -284.518354) (xy 372.873523 -284.518354) (xy 372.9247 -284.52646) (xy 372.973979 -284.542472)
			(xy 373.020146 -284.565995) (xy 373.062065 -284.596451) (xy 373.098703 -284.633089) (xy 373.129159 -284.675008)
			(xy 373.152682 -284.721175) (xy 373.168694 -284.770454) (xy 373.1768 -284.821631) (xy 373.177308 -284.847538)
			(xy 374.397524 -284.847538) (xy 374.398032 -284.821631) (xy 374.406138 -284.770454) (xy 374.42215 -284.721175)
			(xy 374.445673 -284.675008) (xy 374.476129 -284.633089) (xy 374.512767 -284.596451) (xy 374.554686 -284.565995)
			(xy 374.600853 -284.542472) (xy 374.650132 -284.52646) (xy 374.701309 -284.518354) (xy 374.753123 -284.518354)
			(xy 374.8043 -284.52646) (xy 374.853579 -284.542472) (xy 374.899746 -284.565995) (xy 374.941665 -284.596451)
			(xy 374.978303 -284.633089) (xy 375.008759 -284.675008) (xy 375.032282 -284.721175) (xy 375.048294 -284.770454)
			(xy 375.0564 -284.821631) (xy 375.056908 -284.847538) (xy 376.277124 -284.847538) (xy 376.277632 -284.821631)
			(xy 376.285738 -284.770454) (xy 376.30175 -284.721175) (xy 376.325273 -284.675008) (xy 376.355729 -284.633089)
			(xy 376.392367 -284.596451) (xy 376.434286 -284.565995) (xy 376.480453 -284.542472) (xy 376.529732 -284.52646)
			(xy 376.580909 -284.518354) (xy 376.632723 -284.518354) (xy 376.6839 -284.52646) (xy 376.733179 -284.542472)
			(xy 376.779346 -284.565995) (xy 376.821265 -284.596451) (xy 376.857903 -284.633089) (xy 376.888359 -284.675008)
			(xy 376.911882 -284.721175) (xy 376.927894 -284.770454) (xy 376.936 -284.821631) (xy 376.936508 -284.847538)
			(xy 378.156724 -284.847538) (xy 378.157232 -284.821631) (xy 378.165338 -284.770454) (xy 378.18135 -284.721175)
			(xy 378.204873 -284.675008) (xy 378.235329 -284.633089) (xy 378.271967 -284.596451) (xy 378.313886 -284.565995)
			(xy 378.360053 -284.542472) (xy 378.409332 -284.52646) (xy 378.460509 -284.518354) (xy 378.512323 -284.518354)
			(xy 378.5635 -284.52646) (xy 378.612779 -284.542472) (xy 378.658946 -284.565995) (xy 378.700865 -284.596451)
			(xy 378.737503 -284.633089) (xy 378.767959 -284.675008) (xy 378.791482 -284.721175) (xy 378.807494 -284.770454)
			(xy 378.8156 -284.821631) (xy 378.816108 -284.847538) (xy 380.036324 -284.847538) (xy 380.036832 -284.821631)
			(xy 380.044938 -284.770454) (xy 380.06095 -284.721175) (xy 380.084473 -284.675008) (xy 380.114929 -284.633089)
			(xy 380.151567 -284.596451) (xy 380.193486 -284.565995) (xy 380.239653 -284.542472) (xy 380.288932 -284.52646)
			(xy 380.340109 -284.518354) (xy 380.391923 -284.518354) (xy 380.4431 -284.52646) (xy 380.492379 -284.542472)
			(xy 380.538546 -284.565995) (xy 380.580465 -284.596451) (xy 380.617103 -284.633089) (xy 380.647559 -284.675008)
			(xy 380.671082 -284.721175) (xy 380.687094 -284.770454) (xy 380.6952 -284.821631) (xy 380.695708 -284.847538)
			(xy 380.695098 -284.875255) (xy 380.685785 -284.929901) (xy 380.677166 -284.95625) (xy 380.669292 -284.978348)
			(xy 380.87427 -285.333186) (xy 380.89713 -285.337504) (xy 380.921947 -285.342634) (xy 380.969689 -285.35963)
			(xy 381.014267 -285.383731) (xy 381.054634 -285.414369) (xy 381.089836 -285.450823) (xy 381.119046 -285.492235)
			(xy 381.141576 -285.537628) (xy 381.156894 -285.585934) (xy 381.16464 -285.636016) (xy 381.1651 -285.661354)
			(xy 381.164592 -285.687241) (xy 381.156493 -285.738379) (xy 381.140494 -285.787619) (xy 381.116988 -285.833751)
			(xy 381.086556 -285.875638) (xy 381.049946 -285.912248) (xy 381.008059 -285.94268) (xy 380.961927 -285.966186)
			(xy 380.912687 -285.982185) (xy 380.861549 -285.990284) (xy 380.809775 -285.990284) (xy 380.758637 -285.982185)
			(xy 380.709397 -285.966186) (xy 380.663265 -285.94268) (xy 380.621378 -285.912248) (xy 380.584768 -285.875638)
			(xy 380.554336 -285.833751) (xy 380.53083 -285.787619) (xy 380.514831 -285.738379) (xy 380.506732 -285.687241)
			(xy 380.506224 -285.661354) (xy 380.506766 -285.633646) (xy 380.515953 -285.579) (xy 380.524512 -285.552642)
			(xy 380.532386 -285.530544) (xy 380.327408 -285.175706) (xy 380.304548 -285.171388) (xy 380.279723 -285.166238)
			(xy 380.231943 -285.149282) (xy 380.187323 -285.125209) (xy 380.146916 -285.094586) (xy 380.111675 -285.058137)
			(xy 380.082431 -285.016721) (xy 380.059876 -284.971315) (xy 380.044539 -284.922991) (xy 380.036785 -284.872888)
			(xy 380.036324 -284.847538) (xy 378.816108 -284.847538) (xy 378.815498 -284.875255) (xy 378.806185 -284.929901)
			(xy 378.797566 -284.95625) (xy 378.789692 -284.978348) (xy 378.99467 -285.333186) (xy 379.01753 -285.337504)
			(xy 379.042347 -285.342634) (xy 379.090089 -285.35963) (xy 379.134667 -285.383731) (xy 379.175034 -285.414369)
			(xy 379.210236 -285.450823) (xy 379.239446 -285.492235) (xy 379.261976 -285.537628) (xy 379.277294 -285.585934)
			(xy 379.28504 -285.636016) (xy 379.2855 -285.661354) (xy 379.284992 -285.687241) (xy 379.276893 -285.738379)
			(xy 379.260894 -285.787619) (xy 379.237388 -285.833751) (xy 379.206956 -285.875638) (xy 379.170346 -285.912248)
			(xy 379.128459 -285.94268) (xy 379.082327 -285.966186) (xy 379.033087 -285.982185) (xy 378.981949 -285.990284)
			(xy 378.930175 -285.990284) (xy 378.879037 -285.982185) (xy 378.829797 -285.966186) (xy 378.783665 -285.94268)
			(xy 378.741778 -285.912248) (xy 378.705168 -285.875638) (xy 378.674736 -285.833751) (xy 378.65123 -285.787619)
			(xy 378.635231 -285.738379) (xy 378.627132 -285.687241) (xy 378.626624 -285.661354) (xy 378.627166 -285.633646)
			(xy 378.636353 -285.579) (xy 378.644912 -285.552642) (xy 378.652786 -285.530544) (xy 378.447808 -285.175706)
			(xy 378.424948 -285.171388) (xy 378.400123 -285.166238) (xy 378.352343 -285.149282) (xy 378.307723 -285.125209)
			(xy 378.267316 -285.094586) (xy 378.232075 -285.058137) (xy 378.202831 -285.016721) (xy 378.180276 -284.971315)
			(xy 378.164939 -284.922991) (xy 378.157185 -284.872888) (xy 378.156724 -284.847538) (xy 376.936508 -284.847538)
			(xy 376.935898 -284.875255) (xy 376.926585 -284.929901) (xy 376.917966 -284.95625) (xy 376.910092 -284.978348)
			(xy 377.11507 -285.333186) (xy 377.13793 -285.337504) (xy 377.162747 -285.342634) (xy 377.210489 -285.35963)
			(xy 377.255067 -285.383731) (xy 377.295434 -285.414369) (xy 377.330636 -285.450823) (xy 377.359846 -285.492235)
			(xy 377.382376 -285.537628) (xy 377.397694 -285.585934) (xy 377.40544 -285.636016) (xy 377.4059 -285.661354)
			(xy 377.405392 -285.687241) (xy 377.397293 -285.738379) (xy 377.381294 -285.787619) (xy 377.357788 -285.833751)
			(xy 377.327356 -285.875638) (xy 377.290746 -285.912248) (xy 377.248859 -285.94268) (xy 377.202727 -285.966186)
			(xy 377.153487 -285.982185) (xy 377.102349 -285.990284) (xy 377.050575 -285.990284) (xy 376.999437 -285.982185)
			(xy 376.950197 -285.966186) (xy 376.904065 -285.94268) (xy 376.862178 -285.912248) (xy 376.825568 -285.875638)
			(xy 376.795136 -285.833751) (xy 376.77163 -285.787619) (xy 376.755631 -285.738379) (xy 376.747532 -285.687241)
			(xy 376.747024 -285.661354) (xy 376.747566 -285.633646) (xy 376.756753 -285.579) (xy 376.765312 -285.552642)
			(xy 376.773186 -285.530544) (xy 376.568208 -285.175706) (xy 376.545348 -285.171388) (xy 376.520523 -285.166238)
			(xy 376.472743 -285.149282) (xy 376.428123 -285.125209) (xy 376.387716 -285.094586) (xy 376.352475 -285.058137)
			(xy 376.323231 -285.016721) (xy 376.300676 -284.971315) (xy 376.285339 -284.922991) (xy 376.277585 -284.872888)
			(xy 376.277124 -284.847538) (xy 375.056908 -284.847538) (xy 375.056298 -284.875255) (xy 375.046985 -284.929901)
			(xy 375.038366 -284.95625) (xy 375.030492 -284.978348) (xy 375.23547 -285.333186) (xy 375.25833 -285.337504)
			(xy 375.283147 -285.342634) (xy 375.330889 -285.35963) (xy 375.375467 -285.383731) (xy 375.415834 -285.414369)
			(xy 375.451036 -285.450823) (xy 375.480246 -285.492235) (xy 375.502776 -285.537628) (xy 375.518094 -285.585934)
			(xy 375.52584 -285.636016) (xy 375.5263 -285.661354) (xy 375.525792 -285.687241) (xy 375.517693 -285.738379)
			(xy 375.501694 -285.787619) (xy 375.478188 -285.833751) (xy 375.447756 -285.875638) (xy 375.411146 -285.912248)
			(xy 375.369259 -285.94268) (xy 375.323127 -285.966186) (xy 375.273887 -285.982185) (xy 375.222749 -285.990284)
			(xy 375.170975 -285.990284) (xy 375.119837 -285.982185) (xy 375.070597 -285.966186) (xy 375.024465 -285.94268)
			(xy 374.982578 -285.912248) (xy 374.945968 -285.875638) (xy 374.915536 -285.833751) (xy 374.89203 -285.787619)
			(xy 374.876031 -285.738379) (xy 374.867932 -285.687241) (xy 374.867424 -285.661354) (xy 374.867966 -285.633646)
			(xy 374.877153 -285.579) (xy 374.885712 -285.552642) (xy 374.893586 -285.530544) (xy 374.688608 -285.175706)
			(xy 374.665748 -285.171388) (xy 374.640923 -285.166238) (xy 374.593143 -285.149282) (xy 374.548523 -285.125209)
			(xy 374.508116 -285.094586) (xy 374.472875 -285.058137) (xy 374.443631 -285.016721) (xy 374.421076 -284.971315)
			(xy 374.405739 -284.922991) (xy 374.397985 -284.872888) (xy 374.397524 -284.847538) (xy 373.177308 -284.847538)
			(xy 373.176698 -284.875255) (xy 373.167385 -284.929901) (xy 373.158766 -284.95625) (xy 373.150892 -284.978348)
			(xy 373.35587 -285.333186) (xy 373.37873 -285.337504) (xy 373.403547 -285.342634) (xy 373.451289 -285.35963)
			(xy 373.495867 -285.383731) (xy 373.536234 -285.414369) (xy 373.571436 -285.450823) (xy 373.600646 -285.492235)
			(xy 373.623176 -285.537628) (xy 373.638494 -285.585934) (xy 373.64624 -285.636016) (xy 373.6467 -285.661354)
			(xy 373.646192 -285.687241) (xy 373.638093 -285.738379) (xy 373.622094 -285.787619) (xy 373.598588 -285.833751)
			(xy 373.568156 -285.875638) (xy 373.531546 -285.912248) (xy 373.489659 -285.94268) (xy 373.443527 -285.966186)
			(xy 373.394287 -285.982185) (xy 373.343149 -285.990284) (xy 373.291375 -285.990284) (xy 373.240237 -285.982185)
			(xy 373.190997 -285.966186) (xy 373.144865 -285.94268) (xy 373.102978 -285.912248) (xy 373.066368 -285.875638)
			(xy 373.035936 -285.833751) (xy 373.01243 -285.787619) (xy 372.996431 -285.738379) (xy 372.988332 -285.687241)
			(xy 372.987824 -285.661354) (xy 372.988366 -285.633646) (xy 372.997553 -285.579) (xy 373.006112 -285.552642)
			(xy 373.013986 -285.530544) (xy 372.809008 -285.175706) (xy 372.786148 -285.171388) (xy 372.761323 -285.166238)
			(xy 372.713543 -285.149282) (xy 372.668923 -285.125209) (xy 372.628516 -285.094586) (xy 372.593275 -285.058137)
			(xy 372.564031 -285.016721) (xy 372.541476 -284.971315) (xy 372.526139 -284.922991) (xy 372.518385 -284.872888)
			(xy 372.517924 -284.847538) (xy 371.297708 -284.847538) (xy 371.297098 -284.875255) (xy 371.287785 -284.929901)
			(xy 371.279166 -284.95625) (xy 371.271292 -284.978348) (xy 371.47627 -285.333186) (xy 371.49913 -285.337504)
			(xy 371.523947 -285.342634) (xy 371.571689 -285.35963) (xy 371.616267 -285.383731) (xy 371.656634 -285.414369)
			(xy 371.691836 -285.450823) (xy 371.721046 -285.492235) (xy 371.743576 -285.537628) (xy 371.758894 -285.585934)
			(xy 371.76664 -285.636016) (xy 371.7671 -285.661354) (xy 371.766592 -285.687241) (xy 371.758493 -285.738379)
			(xy 371.742494 -285.787619) (xy 371.718988 -285.833751) (xy 371.688556 -285.875638) (xy 371.651946 -285.912248)
			(xy 371.610059 -285.94268) (xy 371.563927 -285.966186) (xy 371.514687 -285.982185) (xy 371.463549 -285.990284)
			(xy 371.411775 -285.990284) (xy 371.360637 -285.982185) (xy 371.311397 -285.966186) (xy 371.265265 -285.94268)
			(xy 371.223378 -285.912248) (xy 371.186768 -285.875638) (xy 371.156336 -285.833751) (xy 371.13283 -285.787619)
			(xy 371.116831 -285.738379) (xy 371.108732 -285.687241) (xy 371.108224 -285.661354) (xy 371.108766 -285.633646)
			(xy 371.117953 -285.579) (xy 371.126512 -285.552642) (xy 371.134386 -285.530544) (xy 370.929408 -285.175706)
			(xy 370.906548 -285.171388) (xy 370.881723 -285.166238) (xy 370.833943 -285.149282) (xy 370.789323 -285.125209)
			(xy 370.748916 -285.094586) (xy 370.713675 -285.058137) (xy 370.684431 -285.016721) (xy 370.661876 -284.971315)
			(xy 370.646539 -284.922991) (xy 370.638785 -284.872888) (xy 370.638324 -284.847538) (xy 369.418108 -284.847538)
			(xy 369.417498 -284.875255) (xy 369.408185 -284.929901) (xy 369.399566 -284.95625) (xy 369.391692 -284.978348)
			(xy 369.59667 -285.333186) (xy 369.61953 -285.337504) (xy 369.644347 -285.342634) (xy 369.692089 -285.35963)
			(xy 369.736667 -285.383731) (xy 369.777034 -285.414369) (xy 369.812236 -285.450823) (xy 369.841446 -285.492235)
			(xy 369.863976 -285.537628) (xy 369.879294 -285.585934) (xy 369.88704 -285.636016) (xy 369.8875 -285.661354)
			(xy 369.886992 -285.687241) (xy 369.878893 -285.738379) (xy 369.862894 -285.787619) (xy 369.839388 -285.833751)
			(xy 369.808956 -285.875638) (xy 369.772346 -285.912248) (xy 369.730459 -285.94268) (xy 369.684327 -285.966186)
			(xy 369.635087 -285.982185) (xy 369.583949 -285.990284) (xy 369.532175 -285.990284) (xy 369.481037 -285.982185)
			(xy 369.431797 -285.966186) (xy 369.385665 -285.94268) (xy 369.343778 -285.912248) (xy 369.307168 -285.875638)
			(xy 369.276736 -285.833751) (xy 369.25323 -285.787619) (xy 369.237231 -285.738379) (xy 369.229132 -285.687241)
			(xy 369.228624 -285.661354) (xy 369.229166 -285.633646) (xy 369.238353 -285.579) (xy 369.246912 -285.552642)
			(xy 369.254786 -285.530544) (xy 369.049808 -285.175706) (xy 369.026948 -285.171388) (xy 369.002123 -285.166238)
			(xy 368.954343 -285.149282) (xy 368.909723 -285.125209) (xy 368.869316 -285.094586) (xy 368.834075 -285.058137)
			(xy 368.804831 -285.016721) (xy 368.782276 -284.971315) (xy 368.766939 -284.922991) (xy 368.759185 -284.872888)
			(xy 368.758724 -284.847538) (xy 367.538508 -284.847538) (xy 367.537898 -284.875255) (xy 367.528585 -284.929901)
			(xy 367.519966 -284.95625) (xy 367.512092 -284.978348) (xy 367.71707 -285.333186) (xy 367.73993 -285.337504)
			(xy 367.764747 -285.342634) (xy 367.812489 -285.35963) (xy 367.857067 -285.383731) (xy 367.897434 -285.414369)
			(xy 367.932636 -285.450823) (xy 367.961846 -285.492235) (xy 367.984376 -285.537628) (xy 367.999694 -285.585934)
			(xy 368.00744 -285.636016) (xy 368.0079 -285.661354) (xy 368.007392 -285.687241) (xy 367.999293 -285.738379)
			(xy 367.983294 -285.787619) (xy 367.959788 -285.833751) (xy 367.929356 -285.875638) (xy 367.892746 -285.912248)
			(xy 367.850859 -285.94268) (xy 367.804727 -285.966186) (xy 367.755487 -285.982185) (xy 367.704349 -285.990284)
			(xy 367.652575 -285.990284) (xy 367.601437 -285.982185) (xy 367.552197 -285.966186) (xy 367.506065 -285.94268)
			(xy 367.464178 -285.912248) (xy 367.427568 -285.875638) (xy 367.397136 -285.833751) (xy 367.37363 -285.787619)
			(xy 367.357631 -285.738379) (xy 367.349532 -285.687241) (xy 367.349024 -285.661354) (xy 367.349566 -285.633646)
			(xy 367.358753 -285.579) (xy 367.367312 -285.552642) (xy 367.375186 -285.530544) (xy 367.170208 -285.175706)
			(xy 367.147348 -285.171388) (xy 367.122523 -285.166238) (xy 367.074743 -285.149282) (xy 367.030123 -285.125209)
			(xy 366.989716 -285.094586) (xy 366.954475 -285.058137) (xy 366.925231 -285.016721) (xy 366.902676 -284.971315)
			(xy 366.887339 -284.922991) (xy 366.879585 -284.872888) (xy 366.879124 -284.847538) (xy 352.501708 -284.847538)
			(xy 352.501261 -284.872913) (xy 352.493487 -284.923064) (xy 352.478114 -284.97143) (xy 352.455505 -285.016866)
			(xy 352.426196 -285.058297) (xy 352.390879 -285.094742) (xy 352.350391 -285.125341) (xy 352.305689 -285.149367)
			(xy 352.257831 -285.166254) (xy 352.232976 -285.171388) (xy 352.210116 -285.175706) (xy 352.005138 -285.530544)
			(xy 352.013012 -285.552642) (xy 352.021583 -285.578997) (xy 352.030775 -285.633645) (xy 352.0313 -285.661354)
			(xy 352.030792 -285.687241) (xy 352.022693 -285.738379) (xy 352.006694 -285.787619) (xy 351.983188 -285.833751)
			(xy 351.952756 -285.875638) (xy 351.916146 -285.912248) (xy 351.874259 -285.94268) (xy 351.828127 -285.966186)
			(xy 351.778887 -285.982185) (xy 351.727749 -285.990284) (xy 351.675975 -285.990284) (xy 351.624837 -285.982185)
			(xy 351.575597 -285.966186) (xy 351.529465 -285.94268) (xy 351.487578 -285.912248) (xy 351.450968 -285.875638)
			(xy 351.420536 -285.833751) (xy 351.39703 -285.787619) (xy 351.381031 -285.738379) (xy 351.372932 -285.687241)
			(xy 351.372424 -285.661354) (xy 351.0915 -285.661354) (xy 351.0915 -285.661862) (xy 351.090923 -285.689379)
			(xy 351.081728 -285.74364) (xy 351.073212 -285.769812) (xy 351.065592 -285.79191) (xy 351.270824 -286.147256)
			(xy 351.293684 -286.151574) (xy 351.318506 -286.156737) (xy 351.366283 -286.173695) (xy 351.410901 -286.197768)
			(xy 351.451306 -286.22839) (xy 351.486546 -286.264837) (xy 351.515789 -286.30625) (xy 351.538346 -286.351653)
			(xy 351.553685 -286.399975) (xy 351.561445 -286.450075) (xy 351.561908 -286.475424) (xy 367.818924 -286.475424)
			(xy 367.819448 -286.45008) (xy 367.827216 -286.399991) (xy 367.842559 -286.351681) (xy 367.865115 -286.306288)
			(xy 367.894351 -286.264882) (xy 367.92958 -286.228438) (xy 367.969972 -286.197814) (xy 368.014574 -286.173733)
			(xy 368.062336 -286.156761) (xy 368.087148 -286.151574) (xy 368.110008 -286.147256) (xy 368.314986 -285.792164)
			(xy 368.307112 -285.77032) (xy 368.298538 -285.7439) (xy 368.289338 -285.689126) (xy 368.288824 -285.661354)
			(xy 368.289332 -285.635467) (xy 368.297431 -285.584329) (xy 368.31343 -285.535089) (xy 368.336936 -285.488957)
			(xy 368.367368 -285.44707) (xy 368.403978 -285.41046) (xy 368.445865 -285.380028) (xy 368.491997 -285.356522)
			(xy 368.541237 -285.340523) (xy 368.592375 -285.332424) (xy 368.644149 -285.332424) (xy 368.695287 -285.340523)
			(xy 368.744527 -285.356522) (xy 368.790659 -285.380028) (xy 368.832546 -285.41046) (xy 368.869156 -285.44707)
			(xy 368.899588 -285.488957) (xy 368.923094 -285.535089) (xy 368.939093 -285.584329) (xy 368.947192 -285.635467)
			(xy 368.9477 -285.661354) (xy 368.947266 -285.68669) (xy 368.939506 -285.736765) (xy 368.924176 -285.785062)
			(xy 368.901638 -285.830446) (xy 368.872422 -285.871848) (xy 368.837216 -285.908293) (xy 368.796849 -285.938922)
			(xy 368.752271 -285.963016) (xy 368.704531 -285.980006) (xy 368.67973 -285.985204) (xy 368.65687 -285.989522)
			(xy 368.451892 -286.344614) (xy 368.459766 -286.366458) (xy 368.468419 -286.392864) (xy 368.477734 -286.447642)
			(xy 368.478308 -286.475424) (xy 369.698524 -286.475424) (xy 369.699048 -286.45008) (xy 369.706816 -286.399991)
			(xy 369.722159 -286.351681) (xy 369.744715 -286.306288) (xy 369.773951 -286.264882) (xy 369.80918 -286.228438)
			(xy 369.849572 -286.197814) (xy 369.894174 -286.173733) (xy 369.941936 -286.156761) (xy 369.966748 -286.151574)
			(xy 369.989608 -286.147256) (xy 370.194586 -285.792164) (xy 370.186712 -285.77032) (xy 370.178138 -285.7439)
			(xy 370.168938 -285.689126) (xy 370.168424 -285.661354) (xy 370.168932 -285.635467) (xy 370.177031 -285.584329)
			(xy 370.19303 -285.535089) (xy 370.216536 -285.488957) (xy 370.246968 -285.44707) (xy 370.283578 -285.41046)
			(xy 370.325465 -285.380028) (xy 370.371597 -285.356522) (xy 370.420837 -285.340523) (xy 370.471975 -285.332424)
			(xy 370.523749 -285.332424) (xy 370.574887 -285.340523) (xy 370.624127 -285.356522) (xy 370.670259 -285.380028)
			(xy 370.712146 -285.41046) (xy 370.748756 -285.44707) (xy 370.779188 -285.488957) (xy 370.802694 -285.535089)
			(xy 370.818693 -285.584329) (xy 370.826792 -285.635467) (xy 370.8273 -285.661354) (xy 370.826866 -285.68669)
			(xy 370.819106 -285.736765) (xy 370.803776 -285.785062) (xy 370.781238 -285.830446) (xy 370.752022 -285.871848)
			(xy 370.716816 -285.908293) (xy 370.676449 -285.938922) (xy 370.631871 -285.963016) (xy 370.584131 -285.980006)
			(xy 370.55933 -285.985204) (xy 370.53647 -285.989522) (xy 370.331492 -286.344614) (xy 370.339366 -286.366458)
			(xy 370.348019 -286.392864) (xy 370.357334 -286.447642) (xy 370.357908 -286.475424) (xy 371.578124 -286.475424)
			(xy 371.578648 -286.45008) (xy 371.586416 -286.399991) (xy 371.601759 -286.351681) (xy 371.624315 -286.306288)
			(xy 371.653551 -286.264882) (xy 371.68878 -286.228438) (xy 371.729172 -286.197814) (xy 371.773774 -286.173733)
			(xy 371.821536 -286.156761) (xy 371.846348 -286.151574) (xy 371.869208 -286.147256) (xy 372.074186 -285.792164)
			(xy 372.066312 -285.77032) (xy 372.057738 -285.7439) (xy 372.048538 -285.689126) (xy 372.048024 -285.661354)
			(xy 372.048532 -285.635467) (xy 372.056631 -285.584329) (xy 372.07263 -285.535089) (xy 372.096136 -285.488957)
			(xy 372.126568 -285.44707) (xy 372.163178 -285.41046) (xy 372.205065 -285.380028) (xy 372.251197 -285.356522)
			(xy 372.300437 -285.340523) (xy 372.351575 -285.332424) (xy 372.403349 -285.332424) (xy 372.454487 -285.340523)
			(xy 372.503727 -285.356522) (xy 372.549859 -285.380028) (xy 372.591746 -285.41046) (xy 372.628356 -285.44707)
			(xy 372.658788 -285.488957) (xy 372.682294 -285.535089) (xy 372.698293 -285.584329) (xy 372.706392 -285.635467)
			(xy 372.7069 -285.661354) (xy 372.706466 -285.68669) (xy 372.698706 -285.736765) (xy 372.683376 -285.785062)
			(xy 372.660838 -285.830446) (xy 372.631622 -285.871848) (xy 372.596416 -285.908293) (xy 372.556049 -285.938922)
			(xy 372.511471 -285.963016) (xy 372.463731 -285.980006) (xy 372.43893 -285.985204) (xy 372.41607 -285.989522)
			(xy 372.211092 -286.344614) (xy 372.218966 -286.366458) (xy 372.227619 -286.392864) (xy 372.236934 -286.447642)
			(xy 372.237508 -286.475424) (xy 373.457724 -286.475424) (xy 373.458248 -286.45008) (xy 373.466016 -286.399991)
			(xy 373.481359 -286.351681) (xy 373.503915 -286.306288) (xy 373.533151 -286.264882) (xy 373.56838 -286.228438)
			(xy 373.608772 -286.197814) (xy 373.653374 -286.173733) (xy 373.701136 -286.156761) (xy 373.725948 -286.151574)
			(xy 373.748808 -286.147256) (xy 373.953786 -285.792164) (xy 373.945912 -285.77032) (xy 373.937338 -285.7439)
			(xy 373.928138 -285.689126) (xy 373.927624 -285.661354) (xy 373.928132 -285.635467) (xy 373.936231 -285.584329)
			(xy 373.95223 -285.535089) (xy 373.975736 -285.488957) (xy 374.006168 -285.44707) (xy 374.042778 -285.41046)
			(xy 374.084665 -285.380028) (xy 374.130797 -285.356522) (xy 374.180037 -285.340523) (xy 374.231175 -285.332424)
			(xy 374.282949 -285.332424) (xy 374.334087 -285.340523) (xy 374.383327 -285.356522) (xy 374.429459 -285.380028)
			(xy 374.471346 -285.41046) (xy 374.507956 -285.44707) (xy 374.538388 -285.488957) (xy 374.561894 -285.535089)
			(xy 374.577893 -285.584329) (xy 374.585992 -285.635467) (xy 374.5865 -285.661354) (xy 374.586066 -285.68669)
			(xy 374.578306 -285.736765) (xy 374.562976 -285.785062) (xy 374.540438 -285.830446) (xy 374.511222 -285.871848)
			(xy 374.476016 -285.908293) (xy 374.435649 -285.938922) (xy 374.391071 -285.963016) (xy 374.343331 -285.980006)
			(xy 374.31853 -285.985204) (xy 374.29567 -285.989522) (xy 374.090692 -286.344614) (xy 374.098566 -286.366458)
			(xy 374.107219 -286.392864) (xy 374.116534 -286.447642) (xy 374.117108 -286.475424) (xy 375.337324 -286.475424)
			(xy 375.337848 -286.45008) (xy 375.345616 -286.399991) (xy 375.360959 -286.351681) (xy 375.383515 -286.306288)
			(xy 375.412751 -286.264882) (xy 375.44798 -286.228438) (xy 375.488372 -286.197814) (xy 375.532974 -286.173733)
			(xy 375.580736 -286.156761) (xy 375.605548 -286.151574) (xy 375.628408 -286.147256) (xy 375.833386 -285.792164)
			(xy 375.825512 -285.77032) (xy 375.816938 -285.7439) (xy 375.807738 -285.689126) (xy 375.807224 -285.661354)
			(xy 375.807732 -285.635467) (xy 375.815831 -285.584329) (xy 375.83183 -285.535089) (xy 375.855336 -285.488957)
			(xy 375.885768 -285.44707) (xy 375.922378 -285.41046) (xy 375.964265 -285.380028) (xy 376.010397 -285.356522)
			(xy 376.059637 -285.340523) (xy 376.110775 -285.332424) (xy 376.162549 -285.332424) (xy 376.213687 -285.340523)
			(xy 376.262927 -285.356522) (xy 376.309059 -285.380028) (xy 376.350946 -285.41046) (xy 376.387556 -285.44707)
			(xy 376.417988 -285.488957) (xy 376.441494 -285.535089) (xy 376.457493 -285.584329) (xy 376.465592 -285.635467)
			(xy 376.4661 -285.661354) (xy 376.465666 -285.68669) (xy 376.457906 -285.736765) (xy 376.442576 -285.785062)
			(xy 376.420038 -285.830446) (xy 376.390822 -285.871848) (xy 376.355616 -285.908293) (xy 376.315249 -285.938922)
			(xy 376.270671 -285.963016) (xy 376.222931 -285.980006) (xy 376.19813 -285.985204) (xy 376.17527 -285.989522)
			(xy 375.970292 -286.344614) (xy 375.978166 -286.366458) (xy 375.986819 -286.392864) (xy 375.996134 -286.447642)
			(xy 375.996708 -286.475424) (xy 377.216924 -286.475424) (xy 377.217448 -286.45008) (xy 377.225216 -286.399991)
			(xy 377.240559 -286.351681) (xy 377.263115 -286.306288) (xy 377.292351 -286.264882) (xy 377.32758 -286.228438)
			(xy 377.367972 -286.197814) (xy 377.412574 -286.173733) (xy 377.460336 -286.156761) (xy 377.485148 -286.151574)
			(xy 377.508008 -286.147256) (xy 377.712986 -285.792164) (xy 377.705112 -285.77032) (xy 377.696538 -285.7439)
			(xy 377.687338 -285.689126) (xy 377.686824 -285.661354) (xy 377.687332 -285.635467) (xy 377.695431 -285.584329)
			(xy 377.71143 -285.535089) (xy 377.734936 -285.488957) (xy 377.765368 -285.44707) (xy 377.801978 -285.41046)
			(xy 377.843865 -285.380028) (xy 377.889997 -285.356522) (xy 377.939237 -285.340523) (xy 377.990375 -285.332424)
			(xy 378.042149 -285.332424) (xy 378.093287 -285.340523) (xy 378.142527 -285.356522) (xy 378.188659 -285.380028)
			(xy 378.230546 -285.41046) (xy 378.267156 -285.44707) (xy 378.297588 -285.488957) (xy 378.321094 -285.535089)
			(xy 378.337093 -285.584329) (xy 378.345192 -285.635467) (xy 378.3457 -285.661354) (xy 378.345266 -285.68669)
			(xy 378.337506 -285.736765) (xy 378.322176 -285.785062) (xy 378.299638 -285.830446) (xy 378.270422 -285.871848)
			(xy 378.235216 -285.908293) (xy 378.194849 -285.938922) (xy 378.150271 -285.963016) (xy 378.102531 -285.980006)
			(xy 378.07773 -285.985204) (xy 378.05487 -285.989522) (xy 377.849892 -286.344614) (xy 377.857766 -286.366458)
			(xy 377.866419 -286.392864) (xy 377.875734 -286.447642) (xy 377.876308 -286.475424) (xy 379.096524 -286.475424)
			(xy 379.097048 -286.45008) (xy 379.104816 -286.399991) (xy 379.120159 -286.351681) (xy 379.142715 -286.306288)
			(xy 379.171951 -286.264882) (xy 379.20718 -286.228438) (xy 379.247572 -286.197814) (xy 379.292174 -286.173733)
			(xy 379.339936 -286.156761) (xy 379.364748 -286.151574) (xy 379.387608 -286.147256) (xy 379.592586 -285.792164)
			(xy 379.584712 -285.77032) (xy 379.576138 -285.7439) (xy 379.566938 -285.689126) (xy 379.566424 -285.661354)
			(xy 379.566932 -285.635467) (xy 379.575031 -285.584329) (xy 379.59103 -285.535089) (xy 379.614536 -285.488957)
			(xy 379.644968 -285.44707) (xy 379.681578 -285.41046) (xy 379.723465 -285.380028) (xy 379.769597 -285.356522)
			(xy 379.818837 -285.340523) (xy 379.869975 -285.332424) (xy 379.921749 -285.332424) (xy 379.972887 -285.340523)
			(xy 380.022127 -285.356522) (xy 380.068259 -285.380028) (xy 380.110146 -285.41046) (xy 380.146756 -285.44707)
			(xy 380.177188 -285.488957) (xy 380.200694 -285.535089) (xy 380.216693 -285.584329) (xy 380.224792 -285.635467)
			(xy 380.2253 -285.661354) (xy 380.224866 -285.68669) (xy 380.217106 -285.736765) (xy 380.201776 -285.785062)
			(xy 380.179238 -285.830446) (xy 380.150022 -285.871848) (xy 380.114816 -285.908293) (xy 380.074449 -285.938922)
			(xy 380.029871 -285.963016) (xy 379.982131 -285.980006) (xy 379.95733 -285.985204) (xy 379.93447 -285.989522)
			(xy 379.729492 -286.344614) (xy 379.737366 -286.366458) (xy 379.746019 -286.392864) (xy 379.755334 -286.447642)
			(xy 379.755908 -286.475424) (xy 380.976124 -286.475424) (xy 380.976648 -286.45008) (xy 380.984416 -286.399991)
			(xy 380.999759 -286.351681) (xy 381.022315 -286.306288) (xy 381.051551 -286.264882) (xy 381.08678 -286.228438)
			(xy 381.127172 -286.197814) (xy 381.171774 -286.173733) (xy 381.219536 -286.156761) (xy 381.244348 -286.151574)
			(xy 381.267208 -286.147256) (xy 381.472186 -285.792164) (xy 381.464312 -285.77032) (xy 381.455738 -285.7439)
			(xy 381.446538 -285.689126) (xy 381.446024 -285.661354) (xy 381.446532 -285.635467) (xy 381.454631 -285.584329)
			(xy 381.47063 -285.535089) (xy 381.494136 -285.488957) (xy 381.524568 -285.44707) (xy 381.561178 -285.41046)
			(xy 381.603065 -285.380028) (xy 381.649197 -285.356522) (xy 381.698437 -285.340523) (xy 381.749575 -285.332424)
			(xy 381.801349 -285.332424) (xy 381.852487 -285.340523) (xy 381.901727 -285.356522) (xy 381.947859 -285.380028)
			(xy 381.989746 -285.41046) (xy 382.026356 -285.44707) (xy 382.056788 -285.488957) (xy 382.080294 -285.535089)
			(xy 382.096293 -285.584329) (xy 382.104392 -285.635467) (xy 382.1049 -285.661354) (xy 382.104466 -285.68669)
			(xy 382.096706 -285.736765) (xy 382.081376 -285.785062) (xy 382.058838 -285.830446) (xy 382.029622 -285.871848)
			(xy 381.994416 -285.908293) (xy 381.954049 -285.938922) (xy 381.909471 -285.963016) (xy 381.861731 -285.980006)
			(xy 381.83693 -285.985204) (xy 381.81407 -285.989522) (xy 381.609092 -286.344614) (xy 381.616966 -286.366458)
			(xy 381.625619 -286.392864) (xy 381.634934 -286.447642) (xy 381.635508 -286.475424) (xy 381.635 -286.501331)
			(xy 381.626894 -286.552508) (xy 381.610882 -286.601787) (xy 381.587359 -286.647954) (xy 381.556903 -286.689873)
			(xy 381.520265 -286.726511) (xy 381.478346 -286.756967) (xy 381.432179 -286.78049) (xy 381.3829 -286.796502)
			(xy 381.331723 -286.804608) (xy 381.279909 -286.804608) (xy 381.228732 -286.796502) (xy 381.179453 -286.78049)
			(xy 381.133286 -286.756967) (xy 381.091367 -286.726511) (xy 381.054729 -286.689873) (xy 381.024273 -286.647954)
			(xy 381.00075 -286.601787) (xy 380.984738 -286.552508) (xy 380.976632 -286.501331) (xy 380.976124 -286.475424)
			(xy 379.755908 -286.475424) (xy 379.7554 -286.501331) (xy 379.747294 -286.552508) (xy 379.731282 -286.601787)
			(xy 379.707759 -286.647954) (xy 379.677303 -286.689873) (xy 379.640665 -286.726511) (xy 379.598746 -286.756967)
			(xy 379.552579 -286.78049) (xy 379.5033 -286.796502) (xy 379.452123 -286.804608) (xy 379.400309 -286.804608)
			(xy 379.349132 -286.796502) (xy 379.299853 -286.78049) (xy 379.253686 -286.756967) (xy 379.211767 -286.726511)
			(xy 379.175129 -286.689873) (xy 379.144673 -286.647954) (xy 379.12115 -286.601787) (xy 379.105138 -286.552508)
			(xy 379.097032 -286.501331) (xy 379.096524 -286.475424) (xy 377.876308 -286.475424) (xy 377.8758 -286.501331)
			(xy 377.867694 -286.552508) (xy 377.851682 -286.601787) (xy 377.828159 -286.647954) (xy 377.797703 -286.689873)
			(xy 377.761065 -286.726511) (xy 377.719146 -286.756967) (xy 377.672979 -286.78049) (xy 377.6237 -286.796502)
			(xy 377.572523 -286.804608) (xy 377.520709 -286.804608) (xy 377.469532 -286.796502) (xy 377.420253 -286.78049)
			(xy 377.374086 -286.756967) (xy 377.332167 -286.726511) (xy 377.295529 -286.689873) (xy 377.265073 -286.647954)
			(xy 377.24155 -286.601787) (xy 377.225538 -286.552508) (xy 377.217432 -286.501331) (xy 377.216924 -286.475424)
			(xy 375.996708 -286.475424) (xy 375.9962 -286.501331) (xy 375.988094 -286.552508) (xy 375.972082 -286.601787)
			(xy 375.948559 -286.647954) (xy 375.918103 -286.689873) (xy 375.881465 -286.726511) (xy 375.839546 -286.756967)
			(xy 375.793379 -286.78049) (xy 375.7441 -286.796502) (xy 375.692923 -286.804608) (xy 375.641109 -286.804608)
			(xy 375.589932 -286.796502) (xy 375.540653 -286.78049) (xy 375.494486 -286.756967) (xy 375.452567 -286.726511)
			(xy 375.415929 -286.689873) (xy 375.385473 -286.647954) (xy 375.36195 -286.601787) (xy 375.345938 -286.552508)
			(xy 375.337832 -286.501331) (xy 375.337324 -286.475424) (xy 374.117108 -286.475424) (xy 374.1166 -286.501331)
			(xy 374.108494 -286.552508) (xy 374.092482 -286.601787) (xy 374.068959 -286.647954) (xy 374.038503 -286.689873)
			(xy 374.001865 -286.726511) (xy 373.959946 -286.756967) (xy 373.913779 -286.78049) (xy 373.8645 -286.796502)
			(xy 373.813323 -286.804608) (xy 373.761509 -286.804608) (xy 373.710332 -286.796502) (xy 373.661053 -286.78049)
			(xy 373.614886 -286.756967) (xy 373.572967 -286.726511) (xy 373.536329 -286.689873) (xy 373.505873 -286.647954)
			(xy 373.48235 -286.601787) (xy 373.466338 -286.552508) (xy 373.458232 -286.501331) (xy 373.457724 -286.475424)
			(xy 372.237508 -286.475424) (xy 372.237 -286.501331) (xy 372.228894 -286.552508) (xy 372.212882 -286.601787)
			(xy 372.189359 -286.647954) (xy 372.158903 -286.689873) (xy 372.122265 -286.726511) (xy 372.080346 -286.756967)
			(xy 372.034179 -286.78049) (xy 371.9849 -286.796502) (xy 371.933723 -286.804608) (xy 371.881909 -286.804608)
			(xy 371.830732 -286.796502) (xy 371.781453 -286.78049) (xy 371.735286 -286.756967) (xy 371.693367 -286.726511)
			(xy 371.656729 -286.689873) (xy 371.626273 -286.647954) (xy 371.60275 -286.601787) (xy 371.586738 -286.552508)
			(xy 371.578632 -286.501331) (xy 371.578124 -286.475424) (xy 370.357908 -286.475424) (xy 370.3574 -286.501331)
			(xy 370.349294 -286.552508) (xy 370.333282 -286.601787) (xy 370.309759 -286.647954) (xy 370.279303 -286.689873)
			(xy 370.242665 -286.726511) (xy 370.200746 -286.756967) (xy 370.154579 -286.78049) (xy 370.1053 -286.796502)
			(xy 370.054123 -286.804608) (xy 370.002309 -286.804608) (xy 369.951132 -286.796502) (xy 369.901853 -286.78049)
			(xy 369.855686 -286.756967) (xy 369.813767 -286.726511) (xy 369.777129 -286.689873) (xy 369.746673 -286.647954)
			(xy 369.72315 -286.601787) (xy 369.707138 -286.552508) (xy 369.699032 -286.501331) (xy 369.698524 -286.475424)
			(xy 368.478308 -286.475424) (xy 368.4778 -286.501331) (xy 368.469694 -286.552508) (xy 368.453682 -286.601787)
			(xy 368.430159 -286.647954) (xy 368.399703 -286.689873) (xy 368.363065 -286.726511) (xy 368.321146 -286.756967)
			(xy 368.274979 -286.78049) (xy 368.2257 -286.796502) (xy 368.174523 -286.804608) (xy 368.122709 -286.804608)
			(xy 368.071532 -286.796502) (xy 368.022253 -286.78049) (xy 367.976086 -286.756967) (xy 367.934167 -286.726511)
			(xy 367.897529 -286.689873) (xy 367.867073 -286.647954) (xy 367.84355 -286.601787) (xy 367.827538 -286.552508)
			(xy 367.819432 -286.501331) (xy 367.818924 -286.475424) (xy 351.561908 -286.475424) (xy 351.5614 -286.501331)
			(xy 351.553294 -286.552508) (xy 351.537282 -286.601787) (xy 351.513759 -286.647954) (xy 351.483303 -286.689873)
			(xy 351.446665 -286.726511) (xy 351.404746 -286.756967) (xy 351.358579 -286.78049) (xy 351.3093 -286.796502)
			(xy 351.258123 -286.804608) (xy 351.206309 -286.804608) (xy 351.155132 -286.796502) (xy 351.105853 -286.78049)
			(xy 351.059686 -286.756967) (xy 351.017767 -286.726511) (xy 350.981129 -286.689873) (xy 350.950673 -286.647954)
			(xy 350.92715 -286.601787) (xy 350.911138 -286.552508) (xy 350.903032 -286.501331) (xy 350.902524 -286.475424)
			(xy 350.903123 -286.447707) (xy 350.912443 -286.39306) (xy 350.921066 -286.366712) (xy 350.92894 -286.344614)
			(xy 350.723962 -285.989522) (xy 350.700848 -285.985204) (xy 350.676027 -285.980039) (xy 350.628247 -285.963084)
			(xy 350.583628 -285.939012) (xy 350.543222 -285.908392) (xy 350.507981 -285.871945) (xy 350.478737 -285.830531)
			(xy 350.45618 -285.785127) (xy 350.440843 -285.736804) (xy 350.433086 -285.686703) (xy 350.432624 -285.661354)
			(xy 350.1517 -285.661354) (xy 350.151192 -285.687241) (xy 350.143093 -285.738379) (xy 350.127094 -285.787619)
			(xy 350.103588 -285.833751) (xy 350.073156 -285.875638) (xy 350.036546 -285.912248) (xy 349.994659 -285.94268)
			(xy 349.948527 -285.966186) (xy 349.899287 -285.982185) (xy 349.848149 -285.990284) (xy 349.796375 -285.990284)
			(xy 349.745237 -285.982185) (xy 349.695997 -285.966186) (xy 349.649865 -285.94268) (xy 349.607978 -285.912248)
			(xy 349.571368 -285.875638) (xy 349.540936 -285.833751) (xy 349.51743 -285.787619) (xy 349.501431 -285.738379)
			(xy 349.493332 -285.687241) (xy 349.492824 -285.661354) (xy 349.2119 -285.661354) (xy 349.2119 -285.661862)
			(xy 349.211323 -285.689379) (xy 349.202128 -285.74364) (xy 349.193612 -285.769812) (xy 349.185992 -285.79191)
			(xy 349.391224 -286.147256) (xy 349.414084 -286.151574) (xy 349.438906 -286.156737) (xy 349.486683 -286.173695)
			(xy 349.531301 -286.197768) (xy 349.571706 -286.22839) (xy 349.606946 -286.264837) (xy 349.636189 -286.30625)
			(xy 349.658746 -286.351653) (xy 349.674085 -286.399975) (xy 349.681845 -286.450075) (xy 349.682308 -286.475424)
			(xy 349.6818 -286.501331) (xy 349.673694 -286.552508) (xy 349.657682 -286.601787) (xy 349.634159 -286.647954)
			(xy 349.603703 -286.689873) (xy 349.567065 -286.726511) (xy 349.525146 -286.756967) (xy 349.478979 -286.78049)
			(xy 349.4297 -286.796502) (xy 349.378523 -286.804608) (xy 349.326709 -286.804608) (xy 349.275532 -286.796502)
			(xy 349.226253 -286.78049) (xy 349.180086 -286.756967) (xy 349.138167 -286.726511) (xy 349.101529 -286.689873)
			(xy 349.071073 -286.647954) (xy 349.04755 -286.601787) (xy 349.031538 -286.552508) (xy 349.023432 -286.501331)
			(xy 349.022924 -286.475424) (xy 349.023523 -286.447707) (xy 349.032843 -286.39306) (xy 349.041466 -286.366712)
			(xy 349.04934 -286.344614) (xy 348.844362 -285.989522) (xy 348.821248 -285.985204) (xy 348.796427 -285.980039)
			(xy 348.748647 -285.963084) (xy 348.704028 -285.939012) (xy 348.663622 -285.908392) (xy 348.628381 -285.871945)
			(xy 348.599137 -285.830531) (xy 348.57658 -285.785127) (xy 348.561243 -285.736804) (xy 348.553486 -285.686703)
			(xy 348.553024 -285.661354) (xy 348.2721 -285.661354) (xy 348.271592 -285.687241) (xy 348.263493 -285.738379)
			(xy 348.247494 -285.787619) (xy 348.223988 -285.833751) (xy 348.193556 -285.875638) (xy 348.156946 -285.912248)
			(xy 348.115059 -285.94268) (xy 348.068927 -285.966186) (xy 348.019687 -285.982185) (xy 347.968549 -285.990284)
			(xy 347.916775 -285.990284) (xy 347.865637 -285.982185) (xy 347.816397 -285.966186) (xy 347.770265 -285.94268)
			(xy 347.728378 -285.912248) (xy 347.691768 -285.875638) (xy 347.661336 -285.833751) (xy 347.63783 -285.787619)
			(xy 347.621831 -285.738379) (xy 347.613732 -285.687241) (xy 347.613224 -285.661354) (xy 347.3323 -285.661354)
			(xy 347.3323 -285.661862) (xy 347.331723 -285.689379) (xy 347.322528 -285.74364) (xy 347.314012 -285.769812)
			(xy 347.306392 -285.79191) (xy 347.511624 -286.147256) (xy 347.534484 -286.151574) (xy 347.559306 -286.156737)
			(xy 347.607083 -286.173695) (xy 347.651701 -286.197768) (xy 347.692106 -286.22839) (xy 347.727346 -286.264837)
			(xy 347.756589 -286.30625) (xy 347.779146 -286.351653) (xy 347.794485 -286.399975) (xy 347.802245 -286.450075)
			(xy 347.802708 -286.475424) (xy 347.8022 -286.501331) (xy 347.794094 -286.552508) (xy 347.778082 -286.601787)
			(xy 347.754559 -286.647954) (xy 347.724103 -286.689873) (xy 347.687465 -286.726511) (xy 347.645546 -286.756967)
			(xy 347.599379 -286.78049) (xy 347.5501 -286.796502) (xy 347.498923 -286.804608) (xy 347.447109 -286.804608)
			(xy 347.395932 -286.796502) (xy 347.346653 -286.78049) (xy 347.300486 -286.756967) (xy 347.258567 -286.726511)
			(xy 347.221929 -286.689873) (xy 347.191473 -286.647954) (xy 347.16795 -286.601787) (xy 347.151938 -286.552508)
			(xy 347.143832 -286.501331) (xy 347.143324 -286.475424) (xy 347.143923 -286.447707) (xy 347.153243 -286.39306)
			(xy 347.161866 -286.366712) (xy 347.16974 -286.344614) (xy 346.964762 -285.989522) (xy 346.941648 -285.985204)
			(xy 346.916827 -285.980039) (xy 346.869047 -285.963084) (xy 346.824428 -285.939012) (xy 346.784022 -285.908392)
			(xy 346.748781 -285.871945) (xy 346.719537 -285.830531) (xy 346.69698 -285.785127) (xy 346.681643 -285.736804)
			(xy 346.673886 -285.686703) (xy 346.673424 -285.661354) (xy 346.3925 -285.661354) (xy 346.391992 -285.687241)
			(xy 346.383893 -285.738379) (xy 346.367894 -285.787619) (xy 346.344388 -285.833751) (xy 346.313956 -285.875638)
			(xy 346.277346 -285.912248) (xy 346.235459 -285.94268) (xy 346.189327 -285.966186) (xy 346.140087 -285.982185)
			(xy 346.088949 -285.990284) (xy 346.037175 -285.990284) (xy 345.986037 -285.982185) (xy 345.936797 -285.966186)
			(xy 345.890665 -285.94268) (xy 345.848778 -285.912248) (xy 345.812168 -285.875638) (xy 345.781736 -285.833751)
			(xy 345.75823 -285.787619) (xy 345.742231 -285.738379) (xy 345.734132 -285.687241) (xy 345.733624 -285.661354)
			(xy 345.4527 -285.661354) (xy 345.4527 -285.661862) (xy 345.452123 -285.689379) (xy 345.442928 -285.74364)
			(xy 345.434412 -285.769812) (xy 345.426792 -285.79191) (xy 345.632024 -286.147256) (xy 345.654884 -286.151574)
			(xy 345.679706 -286.156737) (xy 345.727483 -286.173695) (xy 345.772101 -286.197768) (xy 345.812506 -286.22839)
			(xy 345.847746 -286.264837) (xy 345.876989 -286.30625) (xy 345.899546 -286.351653) (xy 345.914885 -286.399975)
			(xy 345.922645 -286.450075) (xy 345.923108 -286.475424) (xy 345.9226 -286.501331) (xy 345.914494 -286.552508)
			(xy 345.898482 -286.601787) (xy 345.874959 -286.647954) (xy 345.844503 -286.689873) (xy 345.807865 -286.726511)
			(xy 345.765946 -286.756967) (xy 345.719779 -286.78049) (xy 345.6705 -286.796502) (xy 345.619323 -286.804608)
			(xy 345.567509 -286.804608) (xy 345.516332 -286.796502) (xy 345.467053 -286.78049) (xy 345.420886 -286.756967)
			(xy 345.378967 -286.726511) (xy 345.342329 -286.689873) (xy 345.311873 -286.647954) (xy 345.28835 -286.601787)
			(xy 345.272338 -286.552508) (xy 345.264232 -286.501331) (xy 345.263724 -286.475424) (xy 345.264323 -286.447707)
			(xy 345.273643 -286.39306) (xy 345.282266 -286.366712) (xy 345.29014 -286.344614) (xy 345.085162 -285.989522)
			(xy 345.062048 -285.985204) (xy 345.037227 -285.980039) (xy 344.989447 -285.963084) (xy 344.944828 -285.939012)
			(xy 344.904422 -285.908392) (xy 344.869181 -285.871945) (xy 344.839937 -285.830531) (xy 344.81738 -285.785127)
			(xy 344.802043 -285.736804) (xy 344.794286 -285.686703) (xy 344.793824 -285.661354) (xy 344.5129 -285.661354)
			(xy 344.512392 -285.687241) (xy 344.504293 -285.738379) (xy 344.488294 -285.787619) (xy 344.464788 -285.833751)
			(xy 344.434356 -285.875638) (xy 344.397746 -285.912248) (xy 344.355859 -285.94268) (xy 344.309727 -285.966186)
			(xy 344.260487 -285.982185) (xy 344.209349 -285.990284) (xy 344.157575 -285.990284) (xy 344.106437 -285.982185)
			(xy 344.057197 -285.966186) (xy 344.011065 -285.94268) (xy 343.969178 -285.912248) (xy 343.932568 -285.875638)
			(xy 343.902136 -285.833751) (xy 343.87863 -285.787619) (xy 343.862631 -285.738379) (xy 343.854532 -285.687241)
			(xy 343.854024 -285.661354) (xy 343.5731 -285.661354) (xy 343.5731 -285.661862) (xy 343.572523 -285.689379)
			(xy 343.563328 -285.74364) (xy 343.554812 -285.769812) (xy 343.547192 -285.79191) (xy 343.752424 -286.147256)
			(xy 343.775284 -286.151574) (xy 343.800106 -286.156737) (xy 343.847883 -286.173695) (xy 343.892501 -286.197768)
			(xy 343.932906 -286.22839) (xy 343.968146 -286.264837) (xy 343.997389 -286.30625) (xy 344.019946 -286.351653)
			(xy 344.035285 -286.399975) (xy 344.043045 -286.450075) (xy 344.043508 -286.475424) (xy 344.043 -286.501331)
			(xy 344.034894 -286.552508) (xy 344.018882 -286.601787) (xy 343.995359 -286.647954) (xy 343.964903 -286.689873)
			(xy 343.928265 -286.726511) (xy 343.886346 -286.756967) (xy 343.840179 -286.78049) (xy 343.7909 -286.796502)
			(xy 343.739723 -286.804608) (xy 343.687909 -286.804608) (xy 343.636732 -286.796502) (xy 343.587453 -286.78049)
			(xy 343.541286 -286.756967) (xy 343.499367 -286.726511) (xy 343.462729 -286.689873) (xy 343.432273 -286.647954)
			(xy 343.40875 -286.601787) (xy 343.392738 -286.552508) (xy 343.384632 -286.501331) (xy 343.384124 -286.475424)
			(xy 343.384723 -286.447707) (xy 343.394043 -286.39306) (xy 343.402666 -286.366712) (xy 343.41054 -286.344614)
			(xy 343.205562 -285.989522) (xy 343.182448 -285.985204) (xy 343.157627 -285.980039) (xy 343.109847 -285.963084)
			(xy 343.065228 -285.939012) (xy 343.024822 -285.908392) (xy 342.989581 -285.871945) (xy 342.960337 -285.830531)
			(xy 342.93778 -285.785127) (xy 342.922443 -285.736804) (xy 342.914686 -285.686703) (xy 342.914224 -285.661354)
			(xy 342.6333 -285.661354) (xy 342.632792 -285.687241) (xy 342.624693 -285.738379) (xy 342.608694 -285.787619)
			(xy 342.585188 -285.833751) (xy 342.554756 -285.875638) (xy 342.518146 -285.912248) (xy 342.476259 -285.94268)
			(xy 342.430127 -285.966186) (xy 342.380887 -285.982185) (xy 342.329749 -285.990284) (xy 342.277975 -285.990284)
			(xy 342.226837 -285.982185) (xy 342.177597 -285.966186) (xy 342.131465 -285.94268) (xy 342.089578 -285.912248)
			(xy 342.052968 -285.875638) (xy 342.022536 -285.833751) (xy 341.99903 -285.787619) (xy 341.983031 -285.738379)
			(xy 341.974932 -285.687241) (xy 341.974424 -285.661354) (xy 341.6935 -285.661354) (xy 341.6935 -285.661862)
			(xy 341.692923 -285.689379) (xy 341.683728 -285.74364) (xy 341.675212 -285.769812) (xy 341.667592 -285.79191)
			(xy 341.872824 -286.147256) (xy 341.895684 -286.151574) (xy 341.920506 -286.156737) (xy 341.968283 -286.173695)
			(xy 342.012901 -286.197768) (xy 342.053306 -286.22839) (xy 342.088546 -286.264837) (xy 342.117789 -286.30625)
			(xy 342.140346 -286.351653) (xy 342.155685 -286.399975) (xy 342.163445 -286.450075) (xy 342.163908 -286.475424)
			(xy 342.1634 -286.501331) (xy 342.155294 -286.552508) (xy 342.139282 -286.601787) (xy 342.115759 -286.647954)
			(xy 342.085303 -286.689873) (xy 342.048665 -286.726511) (xy 342.006746 -286.756967) (xy 341.960579 -286.78049)
			(xy 341.9113 -286.796502) (xy 341.860123 -286.804608) (xy 341.808309 -286.804608) (xy 341.757132 -286.796502)
			(xy 341.707853 -286.78049) (xy 341.661686 -286.756967) (xy 341.619767 -286.726511) (xy 341.583129 -286.689873)
			(xy 341.552673 -286.647954) (xy 341.52915 -286.601787) (xy 341.513138 -286.552508) (xy 341.505032 -286.501331)
			(xy 341.504524 -286.475424) (xy 341.505123 -286.447707) (xy 341.514443 -286.39306) (xy 341.523066 -286.366712)
			(xy 341.53094 -286.344614) (xy 341.325962 -285.989522) (xy 341.302848 -285.985204) (xy 341.278027 -285.980039)
			(xy 341.230247 -285.963084) (xy 341.185628 -285.939012) (xy 341.145222 -285.908392) (xy 341.109981 -285.871945)
			(xy 341.080737 -285.830531) (xy 341.05818 -285.785127) (xy 341.042843 -285.736804) (xy 341.035086 -285.686703)
			(xy 341.034624 -285.661354) (xy 340.7537 -285.661354) (xy 340.753192 -285.687241) (xy 340.745093 -285.738379)
			(xy 340.729094 -285.787619) (xy 340.705588 -285.833751) (xy 340.675156 -285.875638) (xy 340.638546 -285.912248)
			(xy 340.596659 -285.94268) (xy 340.550527 -285.966186) (xy 340.501287 -285.982185) (xy 340.450149 -285.990284)
			(xy 340.398375 -285.990284) (xy 340.347237 -285.982185) (xy 340.297997 -285.966186) (xy 340.251865 -285.94268)
			(xy 340.209978 -285.912248) (xy 340.173368 -285.875638) (xy 340.142936 -285.833751) (xy 340.11943 -285.787619)
			(xy 340.103431 -285.738379) (xy 340.095332 -285.687241) (xy 340.094824 -285.661354) (xy 339.814408 -285.661354)
			(xy 339.813802 -285.689071) (xy 339.804487 -285.743717) (xy 339.795866 -285.770066) (xy 339.787992 -285.792164)
			(xy 339.993224 -286.147256) (xy 340.016084 -286.151574) (xy 340.040906 -286.156737) (xy 340.088683 -286.173695)
			(xy 340.133301 -286.197768) (xy 340.173706 -286.22839) (xy 340.208946 -286.264837) (xy 340.238189 -286.30625)
			(xy 340.260746 -286.351653) (xy 340.276085 -286.399975) (xy 340.283845 -286.450075) (xy 340.284308 -286.475424)
			(xy 340.2838 -286.501331) (xy 340.275694 -286.552508) (xy 340.259682 -286.601787) (xy 340.236159 -286.647954)
			(xy 340.205703 -286.689873) (xy 340.169065 -286.726511) (xy 340.127146 -286.756967) (xy 340.080979 -286.78049)
			(xy 340.0317 -286.796502) (xy 339.980523 -286.804608) (xy 339.928709 -286.804608) (xy 339.877532 -286.796502)
			(xy 339.828253 -286.78049) (xy 339.782086 -286.756967) (xy 339.740167 -286.726511) (xy 339.703529 -286.689873)
			(xy 339.673073 -286.647954) (xy 339.64955 -286.601787) (xy 339.633538 -286.552508) (xy 339.625432 -286.501331)
			(xy 339.624924 -286.475424) (xy 339.625523 -286.447707) (xy 339.634843 -286.39306) (xy 339.643466 -286.366712)
			(xy 339.65134 -286.344614) (xy 339.446108 -285.989522) (xy 339.423248 -285.985204) (xy 339.398427 -285.980039)
			(xy 339.350647 -285.963084) (xy 339.306028 -285.939012) (xy 339.265622 -285.908392) (xy 339.230381 -285.871945)
			(xy 339.201137 -285.830531) (xy 339.17858 -285.785127) (xy 339.163243 -285.736804) (xy 339.155486 -285.686703)
			(xy 339.155024 -285.661354) (xy 338.874608 -285.661354) (xy 338.8741 -285.687261) (xy 338.865994 -285.738438)
			(xy 338.849982 -285.787717) (xy 338.826459 -285.833884) (xy 338.796003 -285.875803) (xy 338.759365 -285.912441)
			(xy 338.717446 -285.942897) (xy 338.671279 -285.96642) (xy 338.622 -285.982432) (xy 338.570823 -285.990538)
			(xy 338.519009 -285.990538) (xy 338.467832 -285.982432) (xy 338.418553 -285.96642) (xy 338.372386 -285.942897)
			(xy 338.330467 -285.912441) (xy 338.293829 -285.875803) (xy 338.263373 -285.833884) (xy 338.23985 -285.787717)
			(xy 338.223838 -285.738438) (xy 338.215732 -285.687261) (xy 338.215224 -285.661354) (xy 337.9343 -285.661354)
			(xy 337.933759 -285.689062) (xy 337.924571 -285.743708) (xy 337.916012 -285.770066) (xy 337.908138 -285.792164)
			(xy 338.11337 -286.147256) (xy 338.13623 -286.151574) (xy 338.16104 -286.156732) (xy 338.20878 -286.173726)
			(xy 338.253357 -286.197824) (xy 338.293722 -286.228459) (xy 338.328925 -286.264909) (xy 338.358136 -286.306317)
			(xy 338.380667 -286.351707) (xy 338.395988 -286.400009) (xy 338.403738 -286.450087) (xy 338.4042 -286.475424)
			(xy 338.403692 -286.501311) (xy 338.395593 -286.552449) (xy 338.379594 -286.601689) (xy 338.356088 -286.647821)
			(xy 338.325656 -286.689708) (xy 338.289046 -286.726318) (xy 338.247159 -286.75675) (xy 338.201027 -286.780256)
			(xy 338.151787 -286.796255) (xy 338.100649 -286.804354) (xy 338.048875 -286.804354) (xy 337.997737 -286.796255)
			(xy 337.948497 -286.780256) (xy 337.902365 -286.75675) (xy 337.860478 -286.726318) (xy 337.823868 -286.689708)
			(xy 337.793436 -286.647821) (xy 337.76993 -286.601689) (xy 337.753931 -286.552449) (xy 337.745832 -286.501311)
			(xy 337.745324 -286.475424) (xy 337.745858 -286.447716) (xy 337.75505 -286.393069) (xy 337.763612 -286.366712)
			(xy 337.771486 -286.344614) (xy 337.566254 -285.989522) (xy 337.543394 -285.985204) (xy 337.518583 -285.980049)
			(xy 337.470842 -285.963057) (xy 337.426263 -285.93896) (xy 337.385896 -285.908325) (xy 337.350693 -285.871874)
			(xy 337.321482 -285.830466) (xy 337.298951 -285.785075) (xy 337.283632 -285.736771) (xy 337.275885 -285.686692)
			(xy 337.275424 -285.661354) (xy 336.0547 -285.661354) (xy 336.054192 -285.687241) (xy 336.046093 -285.738379)
			(xy 336.030094 -285.787619) (xy 336.006588 -285.833751) (xy 335.976156 -285.875638) (xy 335.939546 -285.912248)
			(xy 335.897659 -285.94268) (xy 335.851527 -285.966186) (xy 335.802287 -285.982185) (xy 335.751149 -285.990284)
			(xy 335.699375 -285.990284) (xy 335.648237 -285.982185) (xy 335.598997 -285.966186) (xy 335.552865 -285.94268)
			(xy 335.510978 -285.912248) (xy 335.474368 -285.875638) (xy 335.443936 -285.833751) (xy 335.42043 -285.787619)
			(xy 335.404431 -285.738379) (xy 335.396332 -285.687241) (xy 335.395824 -285.661354) (xy 134.164832 -285.661354)
			(xy 134.164372 -285.686689) (xy 134.156613 -285.736761) (xy 134.141285 -285.785057) (xy 134.118749 -285.830439)
			(xy 134.089536 -285.87184) (xy 134.054334 -285.908285) (xy 134.013971 -285.938915) (xy 133.969397 -285.963011)
			(xy 133.921662 -285.980004) (xy 133.896862 -285.985204) (xy 133.874002 -285.989522) (xy 133.669024 -286.344614)
			(xy 133.676898 -286.366458) (xy 133.685549 -286.392865) (xy 133.694866 -286.447642) (xy 133.69544 -286.475424)
			(xy 333.986124 -286.475424) (xy 333.986632 -286.449537) (xy 333.994731 -286.398399) (xy 334.01073 -286.349159)
			(xy 334.034236 -286.303027) (xy 334.064668 -286.26114) (xy 334.101278 -286.22453) (xy 334.143165 -286.194098)
			(xy 334.189297 -286.170592) (xy 334.238537 -286.154593) (xy 334.289675 -286.146494) (xy 334.341449 -286.146494)
			(xy 334.392587 -286.154593) (xy 334.441827 -286.170592) (xy 334.487959 -286.194098) (xy 334.529846 -286.22453)
			(xy 334.566456 -286.26114) (xy 334.596888 -286.303027) (xy 334.620394 -286.349159) (xy 334.636393 -286.398399)
			(xy 334.644492 -286.449537) (xy 334.645 -286.475424) (xy 334.644511 -286.501304) (xy 334.92624 -286.501304)
			(xy 334.92624 -286.449496) (xy 334.934344 -286.398327) (xy 334.950352 -286.349055) (xy 334.97387 -286.302894)
			(xy 335.00432 -286.26098) (xy 335.040951 -286.224345) (xy 335.082862 -286.19389) (xy 335.12902 -286.170367)
			(xy 335.17829 -286.154353) (xy 335.229459 -286.146243) (xy 335.255362 -286.145732) (xy 335.280855 -286.146231)
			(xy 335.331232 -286.154087) (xy 335.379796 -286.169618) (xy 335.425383 -286.192452) (xy 335.466904 -286.222042)
			(xy 335.503366 -286.257681) (xy 335.519014 -286.277812) (xy 335.93151 -286.277812) (xy 335.947185 -286.257701)
			(xy 335.98364 -286.222058) (xy 336.025155 -286.192461) (xy 336.070737 -286.16962) (xy 336.119296 -286.15408)
			(xy 336.16967 -286.146213) (xy 336.195162 -286.145732) (xy 336.221075 -286.146163) (xy 336.272264 -286.154265)
			(xy 336.321556 -286.170276) (xy 336.367735 -286.193801) (xy 336.409666 -286.22426) (xy 336.446315 -286.260905)
			(xy 336.47678 -286.302832) (xy 336.50031 -286.349009) (xy 336.516326 -286.398299) (xy 336.524434 -286.449487)
			(xy 336.524434 -286.501313) (xy 336.516326 -286.552501) (xy 336.50031 -286.601791) (xy 336.47678 -286.647968)
			(xy 336.446315 -286.689895) (xy 336.409666 -286.72654) (xy 336.367735 -286.756999) (xy 336.321556 -286.780524)
			(xy 336.272264 -286.796535) (xy 336.221075 -286.804637) (xy 336.195162 -286.805116) (xy 336.169668 -286.804653)
			(xy 336.11929 -286.796786) (xy 336.070727 -286.781247) (xy 336.02514 -286.758407) (xy 335.98362 -286.728811)
			(xy 335.947158 -286.693169) (xy 335.93151 -286.673036) (xy 335.519014 -286.673036) (xy 335.503397 -286.693193)
			(xy 335.466928 -286.728832) (xy 335.425401 -286.758421) (xy 335.379808 -286.781254) (xy 335.33124 -286.796785)
			(xy 335.280857 -286.804641) (xy 335.255362 -286.805116) (xy 335.229459 -286.804557) (xy 335.17829 -286.796447)
			(xy 335.12902 -286.780433) (xy 335.082862 -286.75691) (xy 335.040951 -286.726455) (xy 335.00432 -286.68982)
			(xy 334.97387 -286.647906) (xy 334.950352 -286.601745) (xy 334.934344 -286.552473) (xy 334.92624 -286.501304)
			(xy 334.644511 -286.501304) (xy 334.644476 -286.503132) (xy 334.635277 -286.557779) (xy 334.626712 -286.584136)
			(xy 334.619092 -286.60598) (xy 334.82407 -286.961072) (xy 334.84693 -286.96539) (xy 334.871744 -286.970533)
			(xy 334.919484 -286.987528) (xy 334.964063 -287.011628) (xy 335.004428 -287.042264) (xy 335.039631 -287.078717)
			(xy 335.068841 -287.120126) (xy 335.091372 -287.165518) (xy 335.106691 -287.213822) (xy 335.114439 -287.263902)
			(xy 335.1149 -287.28924) (xy 335.114392 -287.315127) (xy 335.106293 -287.366265) (xy 335.090294 -287.415505)
			(xy 335.066788 -287.461637) (xy 335.036356 -287.503524) (xy 334.999746 -287.540134) (xy 334.957859 -287.570566)
			(xy 334.911727 -287.594072) (xy 334.862487 -287.610071) (xy 334.811349 -287.61817) (xy 334.759575 -287.61817)
			(xy 334.708437 -287.610071) (xy 334.659197 -287.594072) (xy 334.613065 -287.570566) (xy 334.571178 -287.540134)
			(xy 334.534568 -287.503524) (xy 334.504136 -287.461637) (xy 334.48063 -287.415505) (xy 334.464631 -287.366265)
			(xy 334.456532 -287.315127) (xy 334.456024 -287.28924) (xy 334.456562 -287.261532) (xy 334.465751 -287.206885)
			(xy 334.474312 -287.180528) (xy 334.481932 -287.158684) (xy 334.276954 -286.803592) (xy 334.254094 -286.799274)
			(xy 334.229299 -286.794053) (xy 334.181562 -286.777067) (xy 334.136987 -286.752976) (xy 334.096622 -286.722349)
			(xy 334.061419 -286.685906) (xy 334.032206 -286.644507) (xy 334.009672 -286.599125) (xy 333.994346 -286.55083)
			(xy 333.98659 -286.500758) (xy 333.986124 -286.475424) (xy 133.69544 -286.475424) (xy 133.694932 -286.501331)
			(xy 133.686826 -286.552508) (xy 133.670814 -286.601787) (xy 133.647291 -286.647954) (xy 133.616835 -286.689873)
			(xy 133.580197 -286.726511) (xy 133.538278 -286.756967) (xy 133.492111 -286.78049) (xy 133.442832 -286.796502)
			(xy 133.391655 -286.804608) (xy 133.339841 -286.804608) (xy 133.288664 -286.796502) (xy 133.239385 -286.78049)
			(xy 133.193218 -286.756967) (xy 133.151299 -286.726511) (xy 133.114661 -286.689873) (xy 133.084205 -286.647954)
			(xy 133.060682 -286.601787) (xy 133.04467 -286.552508) (xy 133.036564 -286.501331) (xy 133.036056 -286.475424)
			(xy 131.81584 -286.475424) (xy 131.815332 -286.501331) (xy 131.807226 -286.552508) (xy 131.791214 -286.601787)
			(xy 131.767691 -286.647954) (xy 131.737235 -286.689873) (xy 131.700597 -286.726511) (xy 131.658678 -286.756967)
			(xy 131.612511 -286.78049) (xy 131.563232 -286.796502) (xy 131.512055 -286.804608) (xy 131.460241 -286.804608)
			(xy 131.409064 -286.796502) (xy 131.359785 -286.78049) (xy 131.313618 -286.756967) (xy 131.271699 -286.726511)
			(xy 131.235061 -286.689873) (xy 131.204605 -286.647954) (xy 131.181082 -286.601787) (xy 131.16507 -286.552508)
			(xy 131.156964 -286.501331) (xy 131.156456 -286.475424) (xy 129.93624 -286.475424) (xy 129.935732 -286.501331)
			(xy 129.927626 -286.552508) (xy 129.911614 -286.601787) (xy 129.888091 -286.647954) (xy 129.857635 -286.689873)
			(xy 129.820997 -286.726511) (xy 129.779078 -286.756967) (xy 129.732911 -286.78049) (xy 129.683632 -286.796502)
			(xy 129.632455 -286.804608) (xy 129.580641 -286.804608) (xy 129.529464 -286.796502) (xy 129.480185 -286.78049)
			(xy 129.434018 -286.756967) (xy 129.392099 -286.726511) (xy 129.355461 -286.689873) (xy 129.325005 -286.647954)
			(xy 129.301482 -286.601787) (xy 129.28547 -286.552508) (xy 129.277364 -286.501331) (xy 129.276856 -286.475424)
			(xy 128.05664 -286.475424) (xy 128.056132 -286.501331) (xy 128.048026 -286.552508) (xy 128.032014 -286.601787)
			(xy 128.008491 -286.647954) (xy 127.978035 -286.689873) (xy 127.941397 -286.726511) (xy 127.899478 -286.756967)
			(xy 127.853311 -286.78049) (xy 127.804032 -286.796502) (xy 127.752855 -286.804608) (xy 127.701041 -286.804608)
			(xy 127.649864 -286.796502) (xy 127.600585 -286.78049) (xy 127.554418 -286.756967) (xy 127.512499 -286.726511)
			(xy 127.475861 -286.689873) (xy 127.445405 -286.647954) (xy 127.421882 -286.601787) (xy 127.40587 -286.552508)
			(xy 127.397764 -286.501331) (xy 127.397256 -286.475424) (xy 126.17704 -286.475424) (xy 126.176532 -286.501331)
			(xy 126.168426 -286.552508) (xy 126.152414 -286.601787) (xy 126.128891 -286.647954) (xy 126.098435 -286.689873)
			(xy 126.061797 -286.726511) (xy 126.019878 -286.756967) (xy 125.973711 -286.78049) (xy 125.924432 -286.796502)
			(xy 125.873255 -286.804608) (xy 125.821441 -286.804608) (xy 125.770264 -286.796502) (xy 125.720985 -286.78049)
			(xy 125.674818 -286.756967) (xy 125.632899 -286.726511) (xy 125.596261 -286.689873) (xy 125.565805 -286.647954)
			(xy 125.542282 -286.601787) (xy 125.52627 -286.552508) (xy 125.518164 -286.501331) (xy 125.517656 -286.475424)
			(xy 124.29744 -286.475424) (xy 124.296932 -286.501331) (xy 124.288826 -286.552508) (xy 124.272814 -286.601787)
			(xy 124.249291 -286.647954) (xy 124.218835 -286.689873) (xy 124.182197 -286.726511) (xy 124.140278 -286.756967)
			(xy 124.094111 -286.78049) (xy 124.044832 -286.796502) (xy 123.993655 -286.804608) (xy 123.941841 -286.804608)
			(xy 123.890664 -286.796502) (xy 123.841385 -286.78049) (xy 123.795218 -286.756967) (xy 123.753299 -286.726511)
			(xy 123.716661 -286.689873) (xy 123.686205 -286.647954) (xy 123.662682 -286.601787) (xy 123.64667 -286.552508)
			(xy 123.638564 -286.501331) (xy 123.638056 -286.475424) (xy 122.41784 -286.475424) (xy 122.417332 -286.501331)
			(xy 122.409226 -286.552508) (xy 122.393214 -286.601787) (xy 122.369691 -286.647954) (xy 122.339235 -286.689873)
			(xy 122.302597 -286.726511) (xy 122.260678 -286.756967) (xy 122.214511 -286.78049) (xy 122.165232 -286.796502)
			(xy 122.114055 -286.804608) (xy 122.062241 -286.804608) (xy 122.011064 -286.796502) (xy 121.961785 -286.78049)
			(xy 121.915618 -286.756967) (xy 121.873699 -286.726511) (xy 121.837061 -286.689873) (xy 121.806605 -286.647954)
			(xy 121.783082 -286.601787) (xy 121.76707 -286.552508) (xy 121.758964 -286.501331) (xy 121.758456 -286.475424)
			(xy 120.53824 -286.475424) (xy 120.537732 -286.501331) (xy 120.529626 -286.552508) (xy 120.513614 -286.601787)
			(xy 120.490091 -286.647954) (xy 120.459635 -286.689873) (xy 120.422997 -286.726511) (xy 120.381078 -286.756967)
			(xy 120.334911 -286.78049) (xy 120.285632 -286.796502) (xy 120.234455 -286.804608) (xy 120.182641 -286.804608)
			(xy 120.131464 -286.796502) (xy 120.082185 -286.78049) (xy 120.036018 -286.756967) (xy 119.994099 -286.726511)
			(xy 119.957461 -286.689873) (xy 119.927005 -286.647954) (xy 119.903482 -286.601787) (xy 119.88747 -286.552508)
			(xy 119.879364 -286.501331) (xy 119.878856 -286.475424) (xy 103.62184 -286.475424) (xy 103.621332 -286.501331)
			(xy 103.613226 -286.552508) (xy 103.597214 -286.601787) (xy 103.573691 -286.647954) (xy 103.543235 -286.689873)
			(xy 103.506597 -286.726511) (xy 103.464678 -286.756967) (xy 103.418511 -286.78049) (xy 103.369232 -286.796502)
			(xy 103.318055 -286.804608) (xy 103.266241 -286.804608) (xy 103.215064 -286.796502) (xy 103.165785 -286.78049)
			(xy 103.119618 -286.756967) (xy 103.077699 -286.726511) (xy 103.041061 -286.689873) (xy 103.010605 -286.647954)
			(xy 102.987082 -286.601787) (xy 102.97107 -286.552508) (xy 102.962964 -286.501331) (xy 102.962456 -286.475424)
			(xy 102.963053 -286.447707) (xy 102.972374 -286.39306) (xy 102.980998 -286.366712) (xy 102.988872 -286.344614)
			(xy 102.783894 -285.989522) (xy 102.76078 -285.985204) (xy 102.735964 -285.980016) (xy 102.688184 -285.963065)
			(xy 102.643565 -285.938998) (xy 102.603157 -285.908381) (xy 102.567916 -285.871936) (xy 102.538671 -285.830525)
			(xy 102.516113 -285.785123) (xy 102.500775 -285.736802) (xy 102.493018 -285.686702) (xy 102.492556 -285.661354)
			(xy 102.211632 -285.661354) (xy 102.211124 -285.687241) (xy 102.203025 -285.738379) (xy 102.187026 -285.787619)
			(xy 102.16352 -285.833751) (xy 102.133088 -285.875638) (xy 102.096478 -285.912248) (xy 102.054591 -285.94268)
			(xy 102.008459 -285.966186) (xy 101.959219 -285.982185) (xy 101.908081 -285.990284) (xy 101.856307 -285.990284)
			(xy 101.805169 -285.982185) (xy 101.755929 -285.966186) (xy 101.709797 -285.94268) (xy 101.66791 -285.912248)
			(xy 101.6313 -285.875638) (xy 101.600868 -285.833751) (xy 101.577362 -285.787619) (xy 101.561363 -285.738379)
			(xy 101.553264 -285.687241) (xy 101.552756 -285.661354) (xy 101.271832 -285.661354) (xy 101.271832 -285.661862)
			(xy 101.271253 -285.689379) (xy 101.262059 -285.74364) (xy 101.253544 -285.769812) (xy 101.245924 -285.79191)
			(xy 101.451156 -286.147256) (xy 101.474016 -286.151574) (xy 101.498827 -286.156786) (xy 101.546604 -286.173734)
			(xy 101.591223 -286.197799) (xy 101.63163 -286.228413) (xy 101.666872 -286.264855) (xy 101.696117 -286.306263)
			(xy 101.718676 -286.351662) (xy 101.734017 -286.399979) (xy 101.741777 -286.450077) (xy 101.74224 -286.475424)
			(xy 101.741732 -286.501331) (xy 101.733626 -286.552508) (xy 101.717614 -286.601787) (xy 101.694091 -286.647954)
			(xy 101.663635 -286.689873) (xy 101.626997 -286.726511) (xy 101.585078 -286.756967) (xy 101.538911 -286.78049)
			(xy 101.489632 -286.796502) (xy 101.438455 -286.804608) (xy 101.386641 -286.804608) (xy 101.335464 -286.796502)
			(xy 101.286185 -286.78049) (xy 101.240018 -286.756967) (xy 101.198099 -286.726511) (xy 101.161461 -286.689873)
			(xy 101.131005 -286.647954) (xy 101.107482 -286.601787) (xy 101.09147 -286.552508) (xy 101.083364 -286.501331)
			(xy 101.082856 -286.475424) (xy 101.083453 -286.447707) (xy 101.092774 -286.39306) (xy 101.101398 -286.366712)
			(xy 101.109272 -286.344614) (xy 100.904294 -285.989522) (xy 100.88118 -285.985204) (xy 100.856364 -285.980016)
			(xy 100.808584 -285.963065) (xy 100.763965 -285.938998) (xy 100.723557 -285.908381) (xy 100.688316 -285.871936)
			(xy 100.659071 -285.830525) (xy 100.636513 -285.785123) (xy 100.621175 -285.736802) (xy 100.613418 -285.686702)
			(xy 100.612956 -285.661354) (xy 100.332032 -285.661354) (xy 100.331524 -285.687241) (xy 100.323425 -285.738379)
			(xy 100.307426 -285.787619) (xy 100.28392 -285.833751) (xy 100.253488 -285.875638) (xy 100.216878 -285.912248)
			(xy 100.174991 -285.94268) (xy 100.128859 -285.966186) (xy 100.079619 -285.982185) (xy 100.028481 -285.990284)
			(xy 99.976707 -285.990284) (xy 99.925569 -285.982185) (xy 99.876329 -285.966186) (xy 99.830197 -285.94268)
			(xy 99.78831 -285.912248) (xy 99.7517 -285.875638) (xy 99.721268 -285.833751) (xy 99.697762 -285.787619)
			(xy 99.681763 -285.738379) (xy 99.673664 -285.687241) (xy 99.673156 -285.661354) (xy 99.392232 -285.661354)
			(xy 99.392232 -285.661862) (xy 99.391653 -285.689379) (xy 99.382459 -285.74364) (xy 99.373944 -285.769812)
			(xy 99.366324 -285.79191) (xy 99.571556 -286.147256) (xy 99.594416 -286.151574) (xy 99.619227 -286.156786)
			(xy 99.667004 -286.173734) (xy 99.711623 -286.197799) (xy 99.75203 -286.228413) (xy 99.787272 -286.264855)
			(xy 99.816517 -286.306263) (xy 99.839076 -286.351662) (xy 99.854417 -286.399979) (xy 99.862177 -286.450077)
			(xy 99.86264 -286.475424) (xy 99.862132 -286.501331) (xy 99.854026 -286.552508) (xy 99.838014 -286.601787)
			(xy 99.814491 -286.647954) (xy 99.784035 -286.689873) (xy 99.747397 -286.726511) (xy 99.705478 -286.756967)
			(xy 99.659311 -286.78049) (xy 99.610032 -286.796502) (xy 99.558855 -286.804608) (xy 99.507041 -286.804608)
			(xy 99.455864 -286.796502) (xy 99.406585 -286.78049) (xy 99.360418 -286.756967) (xy 99.318499 -286.726511)
			(xy 99.281861 -286.689873) (xy 99.251405 -286.647954) (xy 99.227882 -286.601787) (xy 99.21187 -286.552508)
			(xy 99.203764 -286.501331) (xy 99.203256 -286.475424) (xy 99.203853 -286.447707) (xy 99.213174 -286.39306)
			(xy 99.221798 -286.366712) (xy 99.229672 -286.344614) (xy 99.024694 -285.989522) (xy 99.00158 -285.985204)
			(xy 98.976764 -285.980016) (xy 98.928984 -285.963065) (xy 98.884365 -285.938998) (xy 98.843957 -285.908381)
			(xy 98.808716 -285.871936) (xy 98.779471 -285.830525) (xy 98.756913 -285.785123) (xy 98.741575 -285.736802)
			(xy 98.733818 -285.686702) (xy 98.733356 -285.661354) (xy 98.452432 -285.661354) (xy 98.451924 -285.687241)
			(xy 98.443825 -285.738379) (xy 98.427826 -285.787619) (xy 98.40432 -285.833751) (xy 98.373888 -285.875638)
			(xy 98.337278 -285.912248) (xy 98.295391 -285.94268) (xy 98.249259 -285.966186) (xy 98.200019 -285.982185)
			(xy 98.148881 -285.990284) (xy 98.097107 -285.990284) (xy 98.045969 -285.982185) (xy 97.996729 -285.966186)
			(xy 97.950597 -285.94268) (xy 97.90871 -285.912248) (xy 97.8721 -285.875638) (xy 97.841668 -285.833751)
			(xy 97.818162 -285.787619) (xy 97.802163 -285.738379) (xy 97.794064 -285.687241) (xy 97.793556 -285.661354)
			(xy 97.512632 -285.661354) (xy 97.512632 -285.661862) (xy 97.512053 -285.689379) (xy 97.502859 -285.74364)
			(xy 97.494344 -285.769812) (xy 97.486724 -285.79191) (xy 97.691956 -286.147256) (xy 97.714816 -286.151574)
			(xy 97.739627 -286.156786) (xy 97.787404 -286.173734) (xy 97.832023 -286.197799) (xy 97.87243 -286.228413)
			(xy 97.907672 -286.264855) (xy 97.936917 -286.306263) (xy 97.959476 -286.351662) (xy 97.974817 -286.399979)
			(xy 97.982577 -286.450077) (xy 97.98304 -286.475424) (xy 97.982532 -286.501331) (xy 97.974426 -286.552508)
			(xy 97.958414 -286.601787) (xy 97.934891 -286.647954) (xy 97.904435 -286.689873) (xy 97.867797 -286.726511)
			(xy 97.825878 -286.756967) (xy 97.779711 -286.78049) (xy 97.730432 -286.796502) (xy 97.679255 -286.804608)
			(xy 97.627441 -286.804608) (xy 97.576264 -286.796502) (xy 97.526985 -286.78049) (xy 97.480818 -286.756967)
			(xy 97.438899 -286.726511) (xy 97.402261 -286.689873) (xy 97.371805 -286.647954) (xy 97.348282 -286.601787)
			(xy 97.33227 -286.552508) (xy 97.324164 -286.501331) (xy 97.323656 -286.475424) (xy 97.324253 -286.447707)
			(xy 97.333574 -286.39306) (xy 97.342198 -286.366712) (xy 97.350072 -286.344614) (xy 97.145094 -285.989522)
			(xy 97.12198 -285.985204) (xy 97.097164 -285.980016) (xy 97.049384 -285.963065) (xy 97.004765 -285.938998)
			(xy 96.964357 -285.908381) (xy 96.929116 -285.871936) (xy 96.899871 -285.830525) (xy 96.877313 -285.785123)
			(xy 96.861975 -285.736802) (xy 96.854218 -285.686702) (xy 96.853756 -285.661354) (xy 96.572832 -285.661354)
			(xy 96.572324 -285.687241) (xy 96.564225 -285.738379) (xy 96.548226 -285.787619) (xy 96.52472 -285.833751)
			(xy 96.494288 -285.875638) (xy 96.457678 -285.912248) (xy 96.415791 -285.94268) (xy 96.369659 -285.966186)
			(xy 96.320419 -285.982185) (xy 96.269281 -285.990284) (xy 96.217507 -285.990284) (xy 96.166369 -285.982185)
			(xy 96.117129 -285.966186) (xy 96.070997 -285.94268) (xy 96.02911 -285.912248) (xy 95.9925 -285.875638)
			(xy 95.962068 -285.833751) (xy 95.938562 -285.787619) (xy 95.922563 -285.738379) (xy 95.914464 -285.687241)
			(xy 95.913956 -285.661354) (xy 95.633032 -285.661354) (xy 95.633032 -285.661862) (xy 95.632453 -285.689379)
			(xy 95.623259 -285.74364) (xy 95.614744 -285.769812) (xy 95.607124 -285.79191) (xy 95.812356 -286.147256)
			(xy 95.835216 -286.151574) (xy 95.860027 -286.156786) (xy 95.907804 -286.173734) (xy 95.952423 -286.197799)
			(xy 95.99283 -286.228413) (xy 96.028072 -286.264855) (xy 96.057317 -286.306263) (xy 96.079876 -286.351662)
			(xy 96.095217 -286.399979) (xy 96.102977 -286.450077) (xy 96.10344 -286.475424) (xy 96.102932 -286.501331)
			(xy 96.094826 -286.552508) (xy 96.078814 -286.601787) (xy 96.055291 -286.647954) (xy 96.024835 -286.689873)
			(xy 95.988197 -286.726511) (xy 95.946278 -286.756967) (xy 95.900111 -286.78049) (xy 95.850832 -286.796502)
			(xy 95.799655 -286.804608) (xy 95.747841 -286.804608) (xy 95.696664 -286.796502) (xy 95.647385 -286.78049)
			(xy 95.601218 -286.756967) (xy 95.559299 -286.726511) (xy 95.522661 -286.689873) (xy 95.492205 -286.647954)
			(xy 95.468682 -286.601787) (xy 95.45267 -286.552508) (xy 95.444564 -286.501331) (xy 95.444056 -286.475424)
			(xy 95.444653 -286.447707) (xy 95.453974 -286.39306) (xy 95.462598 -286.366712) (xy 95.470472 -286.344614)
			(xy 95.265494 -285.989522) (xy 95.24238 -285.985204) (xy 95.217564 -285.980016) (xy 95.169784 -285.963065)
			(xy 95.125165 -285.938998) (xy 95.084757 -285.908381) (xy 95.049516 -285.871936) (xy 95.020271 -285.830525)
			(xy 94.997713 -285.785123) (xy 94.982375 -285.736802) (xy 94.974618 -285.686702) (xy 94.974156 -285.661354)
			(xy 94.693232 -285.661354) (xy 94.692724 -285.687241) (xy 94.684625 -285.738379) (xy 94.668626 -285.787619)
			(xy 94.64512 -285.833751) (xy 94.614688 -285.875638) (xy 94.578078 -285.912248) (xy 94.536191 -285.94268)
			(xy 94.490059 -285.966186) (xy 94.440819 -285.982185) (xy 94.389681 -285.990284) (xy 94.337907 -285.990284)
			(xy 94.286769 -285.982185) (xy 94.237529 -285.966186) (xy 94.191397 -285.94268) (xy 94.14951 -285.912248)
			(xy 94.1129 -285.875638) (xy 94.082468 -285.833751) (xy 94.058962 -285.787619) (xy 94.042963 -285.738379)
			(xy 94.034864 -285.687241) (xy 94.034356 -285.661354) (xy 93.753432 -285.661354) (xy 93.753432 -285.661862)
			(xy 93.752853 -285.689379) (xy 93.743659 -285.74364) (xy 93.735144 -285.769812) (xy 93.727524 -285.79191)
			(xy 93.932756 -286.147256) (xy 93.955616 -286.151574) (xy 93.980427 -286.156786) (xy 94.028204 -286.173734)
			(xy 94.072823 -286.197799) (xy 94.11323 -286.228413) (xy 94.148472 -286.264855) (xy 94.177717 -286.306263)
			(xy 94.200276 -286.351662) (xy 94.215617 -286.399979) (xy 94.223377 -286.450077) (xy 94.22384 -286.475424)
			(xy 94.223332 -286.501331) (xy 94.215226 -286.552508) (xy 94.199214 -286.601787) (xy 94.175691 -286.647954)
			(xy 94.145235 -286.689873) (xy 94.108597 -286.726511) (xy 94.066678 -286.756967) (xy 94.020511 -286.78049)
			(xy 93.971232 -286.796502) (xy 93.920055 -286.804608) (xy 93.868241 -286.804608) (xy 93.817064 -286.796502)
			(xy 93.767785 -286.78049) (xy 93.721618 -286.756967) (xy 93.679699 -286.726511) (xy 93.643061 -286.689873)
			(xy 93.612605 -286.647954) (xy 93.589082 -286.601787) (xy 93.57307 -286.552508) (xy 93.564964 -286.501331)
			(xy 93.564456 -286.475424) (xy 93.565053 -286.447707) (xy 93.574374 -286.39306) (xy 93.582998 -286.366712)
			(xy 93.590872 -286.344614) (xy 93.385894 -285.989522) (xy 93.36278 -285.985204) (xy 93.337964 -285.980016)
			(xy 93.290184 -285.963065) (xy 93.245565 -285.938998) (xy 93.205157 -285.908381) (xy 93.169916 -285.871936)
			(xy 93.140671 -285.830525) (xy 93.118113 -285.785123) (xy 93.102775 -285.736802) (xy 93.095018 -285.686702)
			(xy 93.094556 -285.661354) (xy 92.813632 -285.661354) (xy 92.813124 -285.687241) (xy 92.805025 -285.738379)
			(xy 92.789026 -285.787619) (xy 92.76552 -285.833751) (xy 92.735088 -285.875638) (xy 92.698478 -285.912248)
			(xy 92.656591 -285.94268) (xy 92.610459 -285.966186) (xy 92.561219 -285.982185) (xy 92.510081 -285.990284)
			(xy 92.458307 -285.990284) (xy 92.407169 -285.982185) (xy 92.357929 -285.966186) (xy 92.311797 -285.94268)
			(xy 92.26991 -285.912248) (xy 92.2333 -285.875638) (xy 92.202868 -285.833751) (xy 92.179362 -285.787619)
			(xy 92.163363 -285.738379) (xy 92.155264 -285.687241) (xy 92.154756 -285.661354) (xy 91.87434 -285.661354)
			(xy 91.873738 -285.689071) (xy 91.86442 -285.743718) (xy 91.855798 -285.770066) (xy 91.847924 -285.792164)
			(xy 92.053156 -286.147256) (xy 92.076016 -286.151574) (xy 92.100827 -286.156786) (xy 92.148604 -286.173734)
			(xy 92.193223 -286.197799) (xy 92.23363 -286.228413) (xy 92.268872 -286.264855) (xy 92.298117 -286.306263)
			(xy 92.320676 -286.351662) (xy 92.336017 -286.399979) (xy 92.343777 -286.450077) (xy 92.34424 -286.475424)
			(xy 92.343732 -286.501331) (xy 92.335626 -286.552508) (xy 92.319614 -286.601787) (xy 92.296091 -286.647954)
			(xy 92.265635 -286.689873) (xy 92.228997 -286.726511) (xy 92.187078 -286.756967) (xy 92.140911 -286.78049)
			(xy 92.091632 -286.796502) (xy 92.040455 -286.804608) (xy 91.988641 -286.804608) (xy 91.937464 -286.796502)
			(xy 91.888185 -286.78049) (xy 91.842018 -286.756967) (xy 91.800099 -286.726511) (xy 91.763461 -286.689873)
			(xy 91.733005 -286.647954) (xy 91.709482 -286.601787) (xy 91.69347 -286.552508) (xy 91.685364 -286.501331)
			(xy 91.684856 -286.475424) (xy 91.685453 -286.447707) (xy 91.694774 -286.39306) (xy 91.703398 -286.366712)
			(xy 91.711272 -286.344614) (xy 91.50604 -285.989522) (xy 91.48318 -285.985204) (xy 91.458364 -285.980016)
			(xy 91.410584 -285.963065) (xy 91.365965 -285.938998) (xy 91.325557 -285.908381) (xy 91.290316 -285.871936)
			(xy 91.261071 -285.830525) (xy 91.238513 -285.785123) (xy 91.223175 -285.736802) (xy 91.215418 -285.686702)
			(xy 91.214956 -285.661354) (xy 90.93454 -285.661354) (xy 90.934032 -285.687261) (xy 90.925926 -285.738438)
			(xy 90.909914 -285.787717) (xy 90.886391 -285.833884) (xy 90.855935 -285.875803) (xy 90.819297 -285.912441)
			(xy 90.777378 -285.942897) (xy 90.731211 -285.96642) (xy 90.681932 -285.982432) (xy 90.630755 -285.990538)
			(xy 90.578941 -285.990538) (xy 90.527764 -285.982432) (xy 90.478485 -285.96642) (xy 90.432318 -285.942897)
			(xy 90.390399 -285.912441) (xy 90.353761 -285.875803) (xy 90.323305 -285.833884) (xy 90.299782 -285.787717)
			(xy 90.28377 -285.738438) (xy 90.275664 -285.687261) (xy 90.275156 -285.661354) (xy 89.994232 -285.661354)
			(xy 89.993689 -285.689062) (xy 89.984503 -285.743708) (xy 89.975944 -285.770066) (xy 89.96807 -285.792164)
			(xy 90.173302 -286.147256) (xy 90.196162 -286.151574) (xy 90.220961 -286.156781) (xy 90.268701 -286.173765)
			(xy 90.31328 -286.197855) (xy 90.353647 -286.228483) (xy 90.388851 -286.264927) (xy 90.418064 -286.30633)
			(xy 90.440597 -286.351715) (xy 90.455919 -286.400014) (xy 90.46367 -286.450088) (xy 90.464132 -286.475424)
			(xy 90.463624 -286.501311) (xy 90.455525 -286.552449) (xy 90.439526 -286.601689) (xy 90.41602 -286.647821)
			(xy 90.385588 -286.689708) (xy 90.348978 -286.726318) (xy 90.307091 -286.75675) (xy 90.260959 -286.780256)
			(xy 90.211719 -286.796255) (xy 90.160581 -286.804354) (xy 90.108807 -286.804354) (xy 90.057669 -286.796255)
			(xy 90.008429 -286.780256) (xy 89.962297 -286.75675) (xy 89.92041 -286.726318) (xy 89.8838 -286.689708)
			(xy 89.853368 -286.647821) (xy 89.829862 -286.601689) (xy 89.813863 -286.552449) (xy 89.805764 -286.501311)
			(xy 89.805256 -286.475424) (xy 89.805793 -286.447716) (xy 89.814983 -286.393069) (xy 89.823544 -286.366712)
			(xy 89.831418 -286.344614) (xy 89.626186 -285.989522) (xy 89.603326 -285.985204) (xy 89.57852 -285.980026)
			(xy 89.530779 -285.963039) (xy 89.486199 -285.938946) (xy 89.445832 -285.908314) (xy 89.410627 -285.871866)
			(xy 89.381416 -285.83046) (xy 89.358884 -285.785071) (xy 89.343564 -285.736769) (xy 89.335817 -285.686691)
			(xy 89.335356 -285.661354) (xy 88.114632 -285.661354) (xy 88.114124 -285.687241) (xy 88.106025 -285.738379)
			(xy 88.090026 -285.787619) (xy 88.06652 -285.833751) (xy 88.036088 -285.875638) (xy 87.999478 -285.912248)
			(xy 87.957591 -285.94268) (xy 87.911459 -285.966186) (xy 87.862219 -285.982185) (xy 87.811081 -285.990284)
			(xy 87.759307 -285.990284) (xy 87.708169 -285.982185) (xy 87.658929 -285.966186) (xy 87.612797 -285.94268)
			(xy 87.57091 -285.912248) (xy 87.5343 -285.875638) (xy 87.503868 -285.833751) (xy 87.480362 -285.787619)
			(xy 87.464363 -285.738379) (xy 87.456264 -285.687241) (xy 87.455756 -285.661354) (xy 2.509012 -285.661354)
			(xy 2.509012 -286.475424) (xy 86.046056 -286.475424) (xy 86.046564 -286.449537) (xy 86.054663 -286.398399)
			(xy 86.070662 -286.349159) (xy 86.094168 -286.303027) (xy 86.1246 -286.26114) (xy 86.16121 -286.22453)
			(xy 86.203097 -286.194098) (xy 86.249229 -286.170592) (xy 86.298469 -286.154593) (xy 86.349607 -286.146494)
			(xy 86.401381 -286.146494) (xy 86.452519 -286.154593) (xy 86.501759 -286.170592) (xy 86.547891 -286.194098)
			(xy 86.589778 -286.22453) (xy 86.626388 -286.26114) (xy 86.65682 -286.303027) (xy 86.680326 -286.349159)
			(xy 86.696325 -286.398399) (xy 86.704424 -286.449537) (xy 86.704932 -286.475424) (xy 86.704442 -286.501305)
			(xy 86.98614 -286.501305) (xy 86.98614 -286.449495) (xy 86.994245 -286.398322) (xy 87.010255 -286.349048)
			(xy 87.033776 -286.302885) (xy 87.064229 -286.260969) (xy 87.100864 -286.224333) (xy 87.142779 -286.193879)
			(xy 87.188942 -286.170357) (xy 87.238217 -286.154347) (xy 87.289389 -286.146241) (xy 87.315294 -286.145732)
			(xy 87.340788 -286.146208) (xy 87.391166 -286.154069) (xy 87.43973 -286.169604) (xy 87.485317 -286.192442)
			(xy 87.526838 -286.222037) (xy 87.563299 -286.257679) (xy 87.578946 -286.277812) (xy 87.991442 -286.277812)
			(xy 88.007098 -286.257686) (xy 88.043557 -286.222043) (xy 88.085076 -286.192449) (xy 88.130661 -286.16961)
			(xy 88.179224 -286.154073) (xy 88.229601 -286.146211) (xy 88.255094 -286.145732) (xy 88.281006 -286.146165)
			(xy 88.332191 -286.154271) (xy 88.381478 -286.170285) (xy 88.427653 -286.193811) (xy 88.469579 -286.224272)
			(xy 88.506224 -286.260916) (xy 88.536685 -286.302842) (xy 88.560213 -286.349016) (xy 88.576227 -286.398303)
			(xy 88.584334 -286.449488) (xy 88.584334 -286.501312) (xy 88.576227 -286.552497) (xy 88.560213 -286.601784)
			(xy 88.536685 -286.647958) (xy 88.506224 -286.689884) (xy 88.469579 -286.726528) (xy 88.427653 -286.756989)
			(xy 88.381478 -286.780515) (xy 88.332191 -286.796529) (xy 88.281006 -286.804635) (xy 88.255094 -286.805116)
			(xy 88.229601 -286.80463) (xy 88.179224 -286.796768) (xy 88.130661 -286.781233) (xy 88.085074 -286.758397)
			(xy 88.043553 -286.728806) (xy 88.007091 -286.693167) (xy 87.991442 -286.673036) (xy 87.578946 -286.673036)
			(xy 87.56331 -286.693178) (xy 87.526845 -286.728817) (xy 87.485322 -286.758409) (xy 87.439733 -286.781244)
			(xy 87.391168 -286.796778) (xy 87.340788 -286.804638) (xy 87.315294 -286.805116) (xy 87.289389 -286.804559)
			(xy 87.238217 -286.796453) (xy 87.188942 -286.780443) (xy 87.142779 -286.756921) (xy 87.100864 -286.726467)
			(xy 87.064229 -286.689831) (xy 87.033776 -286.647915) (xy 87.010255 -286.601752) (xy 86.994245 -286.552478)
			(xy 86.98614 -286.501305) (xy 86.704442 -286.501305) (xy 86.704407 -286.503132) (xy 86.695209 -286.557779)
			(xy 86.686644 -286.584136) (xy 86.679024 -286.60598) (xy 86.884002 -286.961072) (xy 86.906862 -286.96539)
			(xy 86.931665 -286.970582) (xy 86.979406 -286.987567) (xy 87.023985 -287.011659) (xy 87.064353 -287.042288)
			(xy 87.099557 -287.078734) (xy 87.12877 -287.120139) (xy 87.151302 -287.165526) (xy 87.166622 -287.213827)
			(xy 87.174371 -287.263904) (xy 87.174832 -287.28924) (xy 87.174324 -287.315127) (xy 87.166225 -287.366265)
			(xy 87.150226 -287.415505) (xy 87.12672 -287.461637) (xy 87.096288 -287.503524) (xy 87.059678 -287.540134)
			(xy 87.017791 -287.570566) (xy 86.971659 -287.594072) (xy 86.922419 -287.610071) (xy 86.871281 -287.61817)
			(xy 86.819507 -287.61817) (xy 86.768369 -287.610071) (xy 86.719129 -287.594072) (xy 86.672997 -287.570566)
			(xy 86.63111 -287.540134) (xy 86.5945 -287.503524) (xy 86.564068 -287.461637) (xy 86.540562 -287.415505)
			(xy 86.524563 -287.366265) (xy 86.516464 -287.315127) (xy 86.515956 -287.28924) (xy 86.516497 -287.261532)
			(xy 86.525685 -287.206886) (xy 86.534244 -287.180528) (xy 86.541864 -287.158684) (xy 86.336886 -286.803592)
			(xy 86.314026 -286.799274) (xy 86.289236 -286.79403) (xy 86.241499 -286.777048) (xy 86.196923 -286.752961)
			(xy 86.156558 -286.722338) (xy 86.121354 -286.685898) (xy 86.09214 -286.644501) (xy 86.069605 -286.599121)
			(xy 86.054278 -286.550828) (xy 86.046522 -286.500758) (xy 86.046056 -286.475424) (xy 2.509012 -286.475424)
			(xy 2.509012 -288.917126) (xy 88.395556 -288.917126) (xy 88.396056 -288.891781) (xy 88.403825 -288.84169)
			(xy 88.419169 -288.793377) (xy 88.441727 -288.747983) (xy 88.470967 -288.706576) (xy 88.506199 -288.670131)
			(xy 88.546595 -288.639509) (xy 88.591201 -288.61543) (xy 88.638966 -288.598461) (xy 88.66378 -288.593276)
			(xy 88.68664 -288.588958) (xy 88.891618 -288.233866) (xy 88.883744 -288.212022) (xy 88.875171 -288.185601)
			(xy 88.86597 -288.130828) (xy 88.865456 -288.103056) (xy 88.865964 -288.077169) (xy 88.874063 -288.026031)
			(xy 88.890062 -287.976791) (xy 88.913568 -287.930659) (xy 88.944 -287.888772) (xy 88.98061 -287.852162)
			(xy 89.022497 -287.82173) (xy 89.068629 -287.798224) (xy 89.117869 -287.782225) (xy 89.169007 -287.774126)
			(xy 89.220781 -287.774126) (xy 89.271919 -287.782225) (xy 89.321159 -287.798224) (xy 89.367291 -287.82173)
			(xy 89.409178 -287.852162) (xy 89.445788 -287.888772) (xy 89.47622 -287.930659) (xy 89.499726 -287.976791)
			(xy 89.515725 -288.026031) (xy 89.523824 -288.077169) (xy 89.524332 -288.103056) (xy 89.523874 -288.128391)
			(xy 89.516115 -288.178463) (xy 89.500786 -288.226759) (xy 89.47825 -288.272141) (xy 89.449037 -288.313542)
			(xy 89.413835 -288.349987) (xy 89.373471 -288.380617) (xy 89.328897 -288.404713) (xy 89.281162 -288.421706)
			(xy 89.256362 -288.426906) (xy 89.233502 -288.431224) (xy 89.028524 -288.786316) (xy 89.036398 -288.80816)
			(xy 89.045049 -288.834567) (xy 89.054366 -288.889344) (xy 89.05494 -288.917126) (xy 90.275156 -288.917126)
			(xy 90.275656 -288.891781) (xy 90.283425 -288.84169) (xy 90.298769 -288.793377) (xy 90.321327 -288.747983)
			(xy 90.350567 -288.706576) (xy 90.385799 -288.670131) (xy 90.426195 -288.639509) (xy 90.470801 -288.61543)
			(xy 90.518566 -288.598461) (xy 90.54338 -288.593276) (xy 90.56624 -288.588958) (xy 90.771218 -288.233866)
			(xy 90.763344 -288.212022) (xy 90.754771 -288.185601) (xy 90.74557 -288.130828) (xy 90.745056 -288.103056)
			(xy 90.745564 -288.077169) (xy 90.753663 -288.026031) (xy 90.769662 -287.976791) (xy 90.793168 -287.930659)
			(xy 90.8236 -287.888772) (xy 90.86021 -287.852162) (xy 90.902097 -287.82173) (xy 90.948229 -287.798224)
			(xy 90.997469 -287.782225) (xy 91.048607 -287.774126) (xy 91.100381 -287.774126) (xy 91.151519 -287.782225)
			(xy 91.200759 -287.798224) (xy 91.246891 -287.82173) (xy 91.288778 -287.852162) (xy 91.325388 -287.888772)
			(xy 91.35582 -287.930659) (xy 91.379326 -287.976791) (xy 91.395325 -288.026031) (xy 91.403424 -288.077169)
			(xy 91.403932 -288.103056) (xy 91.403474 -288.128391) (xy 91.395715 -288.178463) (xy 91.380386 -288.226759)
			(xy 91.35785 -288.272141) (xy 91.328637 -288.313542) (xy 91.293435 -288.349987) (xy 91.253071 -288.380617)
			(xy 91.208497 -288.404713) (xy 91.160762 -288.421706) (xy 91.135962 -288.426906) (xy 91.113102 -288.431224)
			(xy 90.908124 -288.786316) (xy 90.915998 -288.80816) (xy 90.924649 -288.834567) (xy 90.933966 -288.889344)
			(xy 90.93454 -288.917126) (xy 91.214956 -288.917126) (xy 91.215464 -288.891219) (xy 91.22357 -288.840042)
			(xy 91.239582 -288.790763) (xy 91.263105 -288.744596) (xy 91.293561 -288.702677) (xy 91.330199 -288.666039)
			(xy 91.372118 -288.635583) (xy 91.418285 -288.61206) (xy 91.467564 -288.596048) (xy 91.518741 -288.587942)
			(xy 91.570555 -288.587942) (xy 91.621732 -288.596048) (xy 91.671011 -288.61206) (xy 91.717178 -288.635583)
			(xy 91.759097 -288.666039) (xy 91.795735 -288.702677) (xy 91.826191 -288.744596) (xy 91.849714 -288.790763)
			(xy 91.865726 -288.840042) (xy 91.873832 -288.891219) (xy 91.87434 -288.917126) (xy 92.154756 -288.917126)
			(xy 92.155256 -288.891781) (xy 92.163025 -288.84169) (xy 92.178369 -288.793377) (xy 92.200927 -288.747983)
			(xy 92.230167 -288.706576) (xy 92.265399 -288.670131) (xy 92.305795 -288.639509) (xy 92.350401 -288.61543)
			(xy 92.398166 -288.598461) (xy 92.42298 -288.593276) (xy 92.44584 -288.588958) (xy 92.651072 -288.233866)
			(xy 92.643198 -288.211768) (xy 92.634576 -288.185419) (xy 92.625249 -288.130773) (xy 92.624656 -288.103056)
			(xy 92.625164 -288.077149) (xy 92.63327 -288.025972) (xy 92.649282 -287.976693) (xy 92.672805 -287.930526)
			(xy 92.703261 -287.888607) (xy 92.739899 -287.851969) (xy 92.781818 -287.821513) (xy 92.827985 -287.79799)
			(xy 92.877264 -287.781978) (xy 92.928441 -287.773872) (xy 92.980255 -287.773872) (xy 93.031432 -287.781978)
			(xy 93.080711 -287.79799) (xy 93.126878 -287.821513) (xy 93.168797 -287.851969) (xy 93.205435 -287.888607)
			(xy 93.235891 -287.930526) (xy 93.259414 -287.976693) (xy 93.275426 -288.025972) (xy 93.283532 -288.077149)
			(xy 93.28404 -288.103056) (xy 93.283618 -288.128404) (xy 93.275836 -288.178499) (xy 93.26048 -288.226813)
			(xy 93.237912 -288.272208) (xy 93.208662 -288.313614) (xy 93.173421 -288.350057) (xy 93.133018 -288.380678)
			(xy 93.088405 -288.404755) (xy 93.040632 -288.421722) (xy 93.015816 -288.426906) (xy 92.992956 -288.431224)
			(xy 92.787724 -288.786316) (xy 92.795598 -288.808414) (xy 92.80424 -288.834757) (xy 92.813554 -288.889407)
			(xy 92.81414 -288.917126) (xy 93.094556 -288.917126) (xy 93.095064 -288.891219) (xy 93.10317 -288.840042)
			(xy 93.119182 -288.790763) (xy 93.142705 -288.744596) (xy 93.173161 -288.702677) (xy 93.209799 -288.666039)
			(xy 93.251718 -288.635583) (xy 93.297885 -288.61206) (xy 93.347164 -288.596048) (xy 93.398341 -288.587942)
			(xy 93.450155 -288.587942) (xy 93.501332 -288.596048) (xy 93.550611 -288.61206) (xy 93.596778 -288.635583)
			(xy 93.638697 -288.666039) (xy 93.675335 -288.702677) (xy 93.705791 -288.744596) (xy 93.729314 -288.790763)
			(xy 93.745326 -288.840042) (xy 93.753432 -288.891219) (xy 93.75394 -288.917126) (xy 94.034356 -288.917126)
			(xy 94.034856 -288.891781) (xy 94.042625 -288.84169) (xy 94.057969 -288.793377) (xy 94.080527 -288.747983)
			(xy 94.109767 -288.706576) (xy 94.144999 -288.670131) (xy 94.185395 -288.639509) (xy 94.230001 -288.61543)
			(xy 94.277766 -288.598461) (xy 94.30258 -288.593276) (xy 94.32544 -288.588958) (xy 94.530672 -288.233866)
			(xy 94.522798 -288.211768) (xy 94.514176 -288.185419) (xy 94.504849 -288.130773) (xy 94.504256 -288.103056)
			(xy 94.504764 -288.077149) (xy 94.51287 -288.025972) (xy 94.528882 -287.976693) (xy 94.552405 -287.930526)
			(xy 94.582861 -287.888607) (xy 94.619499 -287.851969) (xy 94.661418 -287.821513) (xy 94.707585 -287.79799)
			(xy 94.756864 -287.781978) (xy 94.808041 -287.773872) (xy 94.859855 -287.773872) (xy 94.911032 -287.781978)
			(xy 94.960311 -287.79799) (xy 95.006478 -287.821513) (xy 95.048397 -287.851969) (xy 95.085035 -287.888607)
			(xy 95.115491 -287.930526) (xy 95.139014 -287.976693) (xy 95.155026 -288.025972) (xy 95.163132 -288.077149)
			(xy 95.16364 -288.103056) (xy 95.163218 -288.128404) (xy 95.155436 -288.178499) (xy 95.14008 -288.226813)
			(xy 95.117512 -288.272208) (xy 95.088262 -288.313614) (xy 95.053021 -288.350057) (xy 95.012618 -288.380678)
			(xy 94.968005 -288.404755) (xy 94.920232 -288.421722) (xy 94.895416 -288.426906) (xy 94.872556 -288.431224)
			(xy 94.667324 -288.786316) (xy 94.675198 -288.808414) (xy 94.68384 -288.834757) (xy 94.693154 -288.889407)
			(xy 94.69374 -288.917126) (xy 94.974156 -288.917126) (xy 94.974664 -288.891219) (xy 94.98277 -288.840042)
			(xy 94.998782 -288.790763) (xy 95.022305 -288.744596) (xy 95.052761 -288.702677) (xy 95.089399 -288.666039)
			(xy 95.131318 -288.635583) (xy 95.177485 -288.61206) (xy 95.226764 -288.596048) (xy 95.277941 -288.587942)
			(xy 95.329755 -288.587942) (xy 95.380932 -288.596048) (xy 95.430211 -288.61206) (xy 95.476378 -288.635583)
			(xy 95.518297 -288.666039) (xy 95.554935 -288.702677) (xy 95.585391 -288.744596) (xy 95.608914 -288.790763)
			(xy 95.624926 -288.840042) (xy 95.633032 -288.891219) (xy 95.63354 -288.917126) (xy 95.913956 -288.917126)
			(xy 95.914456 -288.891781) (xy 95.922225 -288.84169) (xy 95.937569 -288.793377) (xy 95.960127 -288.747983)
			(xy 95.989367 -288.706576) (xy 96.024599 -288.670131) (xy 96.064995 -288.639509) (xy 96.109601 -288.61543)
			(xy 96.157366 -288.598461) (xy 96.18218 -288.593276) (xy 96.20504 -288.588958) (xy 96.410272 -288.233866)
			(xy 96.402398 -288.211768) (xy 96.393776 -288.185419) (xy 96.384449 -288.130773) (xy 96.383856 -288.103056)
			(xy 96.384364 -288.077149) (xy 96.39247 -288.025972) (xy 96.408482 -287.976693) (xy 96.432005 -287.930526)
			(xy 96.462461 -287.888607) (xy 96.499099 -287.851969) (xy 96.541018 -287.821513) (xy 96.587185 -287.79799)
			(xy 96.636464 -287.781978) (xy 96.687641 -287.773872) (xy 96.739455 -287.773872) (xy 96.790632 -287.781978)
			(xy 96.839911 -287.79799) (xy 96.886078 -287.821513) (xy 96.927997 -287.851969) (xy 96.964635 -287.888607)
			(xy 96.995091 -287.930526) (xy 97.018614 -287.976693) (xy 97.034626 -288.025972) (xy 97.042732 -288.077149)
			(xy 97.04324 -288.103056) (xy 97.042818 -288.128404) (xy 97.035036 -288.178499) (xy 97.01968 -288.226813)
			(xy 96.997112 -288.272208) (xy 96.967862 -288.313614) (xy 96.932621 -288.350057) (xy 96.892218 -288.380678)
			(xy 96.847605 -288.404755) (xy 96.799832 -288.421722) (xy 96.775016 -288.426906) (xy 96.752156 -288.431224)
			(xy 96.546924 -288.786316) (xy 96.554798 -288.808414) (xy 96.56344 -288.834757) (xy 96.572754 -288.889407)
			(xy 96.57334 -288.917126) (xy 96.853756 -288.917126) (xy 96.854264 -288.891219) (xy 96.86237 -288.840042)
			(xy 96.878382 -288.790763) (xy 96.901905 -288.744596) (xy 96.932361 -288.702677) (xy 96.968999 -288.666039)
			(xy 97.010918 -288.635583) (xy 97.057085 -288.61206) (xy 97.106364 -288.596048) (xy 97.157541 -288.587942)
			(xy 97.209355 -288.587942) (xy 97.260532 -288.596048) (xy 97.309811 -288.61206) (xy 97.355978 -288.635583)
			(xy 97.397897 -288.666039) (xy 97.434535 -288.702677) (xy 97.464991 -288.744596) (xy 97.488514 -288.790763)
			(xy 97.504526 -288.840042) (xy 97.512632 -288.891219) (xy 97.51314 -288.917126) (xy 97.793556 -288.917126)
			(xy 97.794056 -288.891781) (xy 97.801825 -288.84169) (xy 97.817169 -288.793377) (xy 97.839727 -288.747983)
			(xy 97.868967 -288.706576) (xy 97.904199 -288.670131) (xy 97.944595 -288.639509) (xy 97.989201 -288.61543)
			(xy 98.036966 -288.598461) (xy 98.06178 -288.593276) (xy 98.08464 -288.588958) (xy 98.289872 -288.233866)
			(xy 98.281998 -288.211768) (xy 98.273376 -288.185419) (xy 98.264049 -288.130773) (xy 98.263456 -288.103056)
			(xy 98.263964 -288.077149) (xy 98.27207 -288.025972) (xy 98.288082 -287.976693) (xy 98.311605 -287.930526)
			(xy 98.342061 -287.888607) (xy 98.378699 -287.851969) (xy 98.420618 -287.821513) (xy 98.466785 -287.79799)
			(xy 98.516064 -287.781978) (xy 98.567241 -287.773872) (xy 98.619055 -287.773872) (xy 98.670232 -287.781978)
			(xy 98.719511 -287.79799) (xy 98.765678 -287.821513) (xy 98.807597 -287.851969) (xy 98.844235 -287.888607)
			(xy 98.874691 -287.930526) (xy 98.898214 -287.976693) (xy 98.914226 -288.025972) (xy 98.922332 -288.077149)
			(xy 98.92284 -288.103056) (xy 98.922418 -288.128404) (xy 98.914636 -288.178499) (xy 98.89928 -288.226813)
			(xy 98.876712 -288.272208) (xy 98.847462 -288.313614) (xy 98.812221 -288.350057) (xy 98.771818 -288.380678)
			(xy 98.727205 -288.404755) (xy 98.679432 -288.421722) (xy 98.654616 -288.426906) (xy 98.631756 -288.431224)
			(xy 98.426524 -288.786316) (xy 98.434398 -288.808414) (xy 98.44304 -288.834757) (xy 98.452354 -288.889407)
			(xy 98.45294 -288.917126) (xy 98.733356 -288.917126) (xy 98.733864 -288.891219) (xy 98.74197 -288.840042)
			(xy 98.757982 -288.790763) (xy 98.781505 -288.744596) (xy 98.811961 -288.702677) (xy 98.848599 -288.666039)
			(xy 98.890518 -288.635583) (xy 98.936685 -288.61206) (xy 98.985964 -288.596048) (xy 99.037141 -288.587942)
			(xy 99.088955 -288.587942) (xy 99.140132 -288.596048) (xy 99.189411 -288.61206) (xy 99.235578 -288.635583)
			(xy 99.277497 -288.666039) (xy 99.314135 -288.702677) (xy 99.344591 -288.744596) (xy 99.368114 -288.790763)
			(xy 99.384126 -288.840042) (xy 99.392232 -288.891219) (xy 99.39274 -288.917126) (xy 99.673156 -288.917126)
			(xy 99.673656 -288.891781) (xy 99.681425 -288.84169) (xy 99.696769 -288.793377) (xy 99.719327 -288.747983)
			(xy 99.748567 -288.706576) (xy 99.783799 -288.670131) (xy 99.824195 -288.639509) (xy 99.868801 -288.61543)
			(xy 99.916566 -288.598461) (xy 99.94138 -288.593276) (xy 99.96424 -288.588958) (xy 100.169472 -288.233866)
			(xy 100.161598 -288.211768) (xy 100.152976 -288.185419) (xy 100.143649 -288.130773) (xy 100.143056 -288.103056)
			(xy 100.143564 -288.077149) (xy 100.15167 -288.025972) (xy 100.167682 -287.976693) (xy 100.191205 -287.930526)
			(xy 100.221661 -287.888607) (xy 100.258299 -287.851969) (xy 100.300218 -287.821513) (xy 100.346385 -287.79799)
			(xy 100.395664 -287.781978) (xy 100.446841 -287.773872) (xy 100.498655 -287.773872) (xy 100.549832 -287.781978)
			(xy 100.599111 -287.79799) (xy 100.645278 -287.821513) (xy 100.687197 -287.851969) (xy 100.723835 -287.888607)
			(xy 100.754291 -287.930526) (xy 100.777814 -287.976693) (xy 100.793826 -288.025972) (xy 100.801932 -288.077149)
			(xy 100.80244 -288.103056) (xy 100.802018 -288.128404) (xy 100.794236 -288.178499) (xy 100.77888 -288.226813)
			(xy 100.756312 -288.272208) (xy 100.727062 -288.313614) (xy 100.691821 -288.350057) (xy 100.651418 -288.380678)
			(xy 100.606805 -288.404755) (xy 100.559032 -288.421722) (xy 100.534216 -288.426906) (xy 100.511356 -288.431224)
			(xy 100.306124 -288.786316) (xy 100.313998 -288.808414) (xy 100.32264 -288.834757) (xy 100.331954 -288.889407)
			(xy 100.33254 -288.917126) (xy 100.612956 -288.917126) (xy 100.613464 -288.891219) (xy 100.62157 -288.840042)
			(xy 100.637582 -288.790763) (xy 100.661105 -288.744596) (xy 100.691561 -288.702677) (xy 100.728199 -288.666039)
			(xy 100.770118 -288.635583) (xy 100.816285 -288.61206) (xy 100.865564 -288.596048) (xy 100.916741 -288.587942)
			(xy 100.968555 -288.587942) (xy 101.019732 -288.596048) (xy 101.069011 -288.61206) (xy 101.115178 -288.635583)
			(xy 101.157097 -288.666039) (xy 101.193735 -288.702677) (xy 101.224191 -288.744596) (xy 101.247714 -288.790763)
			(xy 101.263726 -288.840042) (xy 101.271832 -288.891219) (xy 101.27234 -288.917126) (xy 101.552756 -288.917126)
			(xy 101.553256 -288.891781) (xy 101.561025 -288.84169) (xy 101.576369 -288.793377) (xy 101.598927 -288.747983)
			(xy 101.628167 -288.706576) (xy 101.663399 -288.670131) (xy 101.703795 -288.639509) (xy 101.748401 -288.61543)
			(xy 101.796166 -288.598461) (xy 101.82098 -288.593276) (xy 101.84384 -288.588958) (xy 102.049072 -288.233866)
			(xy 102.041198 -288.211768) (xy 102.032576 -288.185419) (xy 102.023249 -288.130773) (xy 102.022656 -288.103056)
			(xy 102.023164 -288.077149) (xy 102.03127 -288.025972) (xy 102.047282 -287.976693) (xy 102.070805 -287.930526)
			(xy 102.101261 -287.888607) (xy 102.137899 -287.851969) (xy 102.179818 -287.821513) (xy 102.225985 -287.79799)
			(xy 102.275264 -287.781978) (xy 102.326441 -287.773872) (xy 102.378255 -287.773872) (xy 102.429432 -287.781978)
			(xy 102.478711 -287.79799) (xy 102.524878 -287.821513) (xy 102.566797 -287.851969) (xy 102.603435 -287.888607)
			(xy 102.633891 -287.930526) (xy 102.657414 -287.976693) (xy 102.673426 -288.025972) (xy 102.681532 -288.077149)
			(xy 102.68204 -288.103056) (xy 102.681618 -288.128404) (xy 102.673836 -288.178499) (xy 102.65848 -288.226813)
			(xy 102.635912 -288.272208) (xy 102.606662 -288.313614) (xy 102.571421 -288.350057) (xy 102.531018 -288.380678)
			(xy 102.486405 -288.404755) (xy 102.438632 -288.421722) (xy 102.413816 -288.426906) (xy 102.390956 -288.431224)
			(xy 102.185724 -288.786316) (xy 102.193598 -288.808414) (xy 102.20224 -288.834757) (xy 102.211554 -288.889407)
			(xy 102.21214 -288.917126) (xy 102.492556 -288.917126) (xy 102.493064 -288.891219) (xy 102.50117 -288.840042)
			(xy 102.517182 -288.790763) (xy 102.540705 -288.744596) (xy 102.571161 -288.702677) (xy 102.607799 -288.666039)
			(xy 102.649718 -288.635583) (xy 102.695885 -288.61206) (xy 102.745164 -288.596048) (xy 102.796341 -288.587942)
			(xy 102.848155 -288.587942) (xy 102.899332 -288.596048) (xy 102.948611 -288.61206) (xy 102.994778 -288.635583)
			(xy 103.036697 -288.666039) (xy 103.073335 -288.702677) (xy 103.103791 -288.744596) (xy 103.127314 -288.790763)
			(xy 103.143326 -288.840042) (xy 103.151432 -288.891219) (xy 103.15194 -288.917126) (xy 103.432356 -288.917126)
			(xy 103.432856 -288.891781) (xy 103.440625 -288.84169) (xy 103.455969 -288.793377) (xy 103.478527 -288.747983)
			(xy 103.507767 -288.706576) (xy 103.542999 -288.670131) (xy 103.583395 -288.639509) (xy 103.628001 -288.61543)
			(xy 103.675766 -288.598461) (xy 103.70058 -288.593276) (xy 103.72344 -288.588958) (xy 103.928672 -288.233866)
			(xy 103.920798 -288.211768) (xy 103.912176 -288.185419) (xy 103.902849 -288.130773) (xy 103.902256 -288.103056)
			(xy 103.902764 -288.077149) (xy 103.91087 -288.025972) (xy 103.926882 -287.976693) (xy 103.950405 -287.930526)
			(xy 103.980861 -287.888607) (xy 104.017499 -287.851969) (xy 104.059418 -287.821513) (xy 104.105585 -287.79799)
			(xy 104.154864 -287.781978) (xy 104.206041 -287.773872) (xy 104.257855 -287.773872) (xy 104.309032 -287.781978)
			(xy 104.358311 -287.79799) (xy 104.404478 -287.821513) (xy 104.446397 -287.851969) (xy 104.483035 -287.888607)
			(xy 104.513491 -287.930526) (xy 104.537014 -287.976693) (xy 104.553026 -288.025972) (xy 104.561132 -288.077149)
			(xy 104.56164 -288.103056) (xy 120.818656 -288.103056) (xy 120.819164 -288.077149) (xy 120.82727 -288.025972)
			(xy 120.843282 -287.976693) (xy 120.866805 -287.930526) (xy 120.897261 -287.888607) (xy 120.933899 -287.851969)
			(xy 120.975818 -287.821513) (xy 121.021985 -287.79799) (xy 121.071264 -287.781978) (xy 121.122441 -287.773872)
			(xy 121.174255 -287.773872) (xy 121.225432 -287.781978) (xy 121.274711 -287.79799) (xy 121.320878 -287.821513)
			(xy 121.362797 -287.851969) (xy 121.399435 -287.888607) (xy 121.429891 -287.930526) (xy 121.453414 -287.976693)
			(xy 121.469426 -288.025972) (xy 121.477532 -288.077149) (xy 121.47804 -288.103056) (xy 122.698256 -288.103056)
			(xy 122.698764 -288.077149) (xy 122.70687 -288.025972) (xy 122.722882 -287.976693) (xy 122.746405 -287.930526)
			(xy 122.776861 -287.888607) (xy 122.813499 -287.851969) (xy 122.855418 -287.821513) (xy 122.901585 -287.79799)
			(xy 122.950864 -287.781978) (xy 123.002041 -287.773872) (xy 123.053855 -287.773872) (xy 123.105032 -287.781978)
			(xy 123.154311 -287.79799) (xy 123.200478 -287.821513) (xy 123.242397 -287.851969) (xy 123.279035 -287.888607)
			(xy 123.309491 -287.930526) (xy 123.333014 -287.976693) (xy 123.349026 -288.025972) (xy 123.357132 -288.077149)
			(xy 123.35764 -288.103056) (xy 124.577856 -288.103056) (xy 124.578364 -288.077149) (xy 124.58647 -288.025972)
			(xy 124.602482 -287.976693) (xy 124.626005 -287.930526) (xy 124.656461 -287.888607) (xy 124.693099 -287.851969)
			(xy 124.735018 -287.821513) (xy 124.781185 -287.79799) (xy 124.830464 -287.781978) (xy 124.881641 -287.773872)
			(xy 124.933455 -287.773872) (xy 124.984632 -287.781978) (xy 125.033911 -287.79799) (xy 125.080078 -287.821513)
			(xy 125.121997 -287.851969) (xy 125.158635 -287.888607) (xy 125.189091 -287.930526) (xy 125.212614 -287.976693)
			(xy 125.228626 -288.025972) (xy 125.236732 -288.077149) (xy 125.23724 -288.103056) (xy 126.457456 -288.103056)
			(xy 126.457964 -288.077149) (xy 126.46607 -288.025972) (xy 126.482082 -287.976693) (xy 126.505605 -287.930526)
			(xy 126.536061 -287.888607) (xy 126.572699 -287.851969) (xy 126.614618 -287.821513) (xy 126.660785 -287.79799)
			(xy 126.710064 -287.781978) (xy 126.761241 -287.773872) (xy 126.813055 -287.773872) (xy 126.864232 -287.781978)
			(xy 126.913511 -287.79799) (xy 126.959678 -287.821513) (xy 127.001597 -287.851969) (xy 127.038235 -287.888607)
			(xy 127.068691 -287.930526) (xy 127.092214 -287.976693) (xy 127.108226 -288.025972) (xy 127.116332 -288.077149)
			(xy 127.11684 -288.103056) (xy 128.337056 -288.103056) (xy 128.337564 -288.077149) (xy 128.34567 -288.025972)
			(xy 128.361682 -287.976693) (xy 128.385205 -287.930526) (xy 128.415661 -287.888607) (xy 128.452299 -287.851969)
			(xy 128.494218 -287.821513) (xy 128.540385 -287.79799) (xy 128.589664 -287.781978) (xy 128.640841 -287.773872)
			(xy 128.692655 -287.773872) (xy 128.743832 -287.781978) (xy 128.793111 -287.79799) (xy 128.839278 -287.821513)
			(xy 128.881197 -287.851969) (xy 128.917835 -287.888607) (xy 128.948291 -287.930526) (xy 128.971814 -287.976693)
			(xy 128.987826 -288.025972) (xy 128.995932 -288.077149) (xy 128.99644 -288.103056) (xy 130.216656 -288.103056)
			(xy 130.217164 -288.077149) (xy 130.22527 -288.025972) (xy 130.241282 -287.976693) (xy 130.264805 -287.930526)
			(xy 130.295261 -287.888607) (xy 130.331899 -287.851969) (xy 130.373818 -287.821513) (xy 130.419985 -287.79799)
			(xy 130.469264 -287.781978) (xy 130.520441 -287.773872) (xy 130.572255 -287.773872) (xy 130.623432 -287.781978)
			(xy 130.672711 -287.79799) (xy 130.718878 -287.821513) (xy 130.760797 -287.851969) (xy 130.797435 -287.888607)
			(xy 130.827891 -287.930526) (xy 130.851414 -287.976693) (xy 130.867426 -288.025972) (xy 130.875532 -288.077149)
			(xy 130.87604 -288.103056) (xy 132.096256 -288.103056) (xy 132.096764 -288.077149) (xy 132.10487 -288.025972)
			(xy 132.120882 -287.976693) (xy 132.144405 -287.930526) (xy 132.174861 -287.888607) (xy 132.211499 -287.851969)
			(xy 132.253418 -287.821513) (xy 132.299585 -287.79799) (xy 132.348864 -287.781978) (xy 132.400041 -287.773872)
			(xy 132.451855 -287.773872) (xy 132.503032 -287.781978) (xy 132.552311 -287.79799) (xy 132.598478 -287.821513)
			(xy 132.640397 -287.851969) (xy 132.677035 -287.888607) (xy 132.707491 -287.930526) (xy 132.731014 -287.976693)
			(xy 132.747026 -288.025972) (xy 132.755132 -288.077149) (xy 132.75564 -288.103056) (xy 134.915656 -288.103056)
			(xy 134.916164 -288.077149) (xy 134.92427 -288.025972) (xy 134.940282 -287.976693) (xy 134.963805 -287.930526)
			(xy 134.994261 -287.888607) (xy 135.030899 -287.851969) (xy 135.072818 -287.821513) (xy 135.118985 -287.79799)
			(xy 135.168264 -287.781978) (xy 135.219441 -287.773872) (xy 135.271255 -287.773872) (xy 135.322432 -287.781978)
			(xy 135.371711 -287.79799) (xy 135.417878 -287.821513) (xy 135.459797 -287.851969) (xy 135.496435 -287.888607)
			(xy 135.526891 -287.930526) (xy 135.550414 -287.976693) (xy 135.566426 -288.025972) (xy 135.574532 -288.077149)
			(xy 135.57504 -288.103056) (xy 135.574438 -288.130773) (xy 135.56512 -288.18542) (xy 135.556498 -288.211768)
			(xy 135.548624 -288.233866) (xy 135.753856 -288.588958) (xy 135.776716 -288.593276) (xy 135.801527 -288.598486)
			(xy 135.849305 -288.615434) (xy 135.893924 -288.6395) (xy 135.934331 -288.670114) (xy 135.969573 -288.706556)
			(xy 135.998818 -288.747964) (xy 136.021377 -288.793363) (xy 136.036717 -288.841681) (xy 136.044477 -288.891779)
			(xy 136.04494 -288.917126) (xy 336.335624 -288.917126) (xy 336.336149 -288.891782) (xy 336.343918 -288.841693)
			(xy 336.359261 -288.793383) (xy 336.381816 -288.74799) (xy 336.411052 -288.706584) (xy 336.446281 -288.67014)
			(xy 336.486672 -288.639516) (xy 336.531274 -288.615435) (xy 336.579036 -288.598463) (xy 336.603848 -288.593276)
			(xy 336.626708 -288.588958) (xy 336.831686 -288.233866) (xy 336.823812 -288.212022) (xy 336.815238 -288.185602)
			(xy 336.806038 -288.130828) (xy 336.805524 -288.103056) (xy 336.806032 -288.077169) (xy 336.814131 -288.026031)
			(xy 336.83013 -287.976791) (xy 336.853636 -287.930659) (xy 336.884068 -287.888772) (xy 336.920678 -287.852162)
			(xy 336.962565 -287.82173) (xy 337.008697 -287.798224) (xy 337.057937 -287.782225) (xy 337.109075 -287.774126)
			(xy 337.160849 -287.774126) (xy 337.211987 -287.782225) (xy 337.261227 -287.798224) (xy 337.307359 -287.82173)
			(xy 337.349246 -287.852162) (xy 337.385856 -287.888772) (xy 337.416288 -287.930659) (xy 337.439794 -287.976791)
			(xy 337.455793 -288.026031) (xy 337.463892 -288.077169) (xy 337.4644 -288.103056) (xy 337.463968 -288.128392)
			(xy 337.456207 -288.178467) (xy 337.440877 -288.226765) (xy 337.418339 -288.272149) (xy 337.389123 -288.31355)
			(xy 337.353916 -288.349995) (xy 337.313549 -288.380624) (xy 337.268971 -288.404718) (xy 337.221232 -288.421708)
			(xy 337.19643 -288.426906) (xy 337.17357 -288.431224) (xy 336.968592 -288.786316) (xy 336.976466 -288.80816)
			(xy 336.985119 -288.834566) (xy 336.994435 -288.889344) (xy 336.995008 -288.917126) (xy 338.215224 -288.917126)
			(xy 338.215749 -288.891782) (xy 338.223518 -288.841693) (xy 338.238861 -288.793383) (xy 338.261416 -288.74799)
			(xy 338.290652 -288.706584) (xy 338.325881 -288.67014) (xy 338.366272 -288.639516) (xy 338.410874 -288.615435)
			(xy 338.458636 -288.598463) (xy 338.483448 -288.593276) (xy 338.506308 -288.588958) (xy 338.711286 -288.233866)
			(xy 338.703412 -288.212022) (xy 338.694838 -288.185602) (xy 338.685638 -288.130828) (xy 338.685124 -288.103056)
			(xy 338.685632 -288.077169) (xy 338.693731 -288.026031) (xy 338.70973 -287.976791) (xy 338.733236 -287.930659)
			(xy 338.763668 -287.888772) (xy 338.800278 -287.852162) (xy 338.842165 -287.82173) (xy 338.888297 -287.798224)
			(xy 338.937537 -287.782225) (xy 338.988675 -287.774126) (xy 339.040449 -287.774126) (xy 339.091587 -287.782225)
			(xy 339.140827 -287.798224) (xy 339.186959 -287.82173) (xy 339.228846 -287.852162) (xy 339.265456 -287.888772)
			(xy 339.295888 -287.930659) (xy 339.319394 -287.976791) (xy 339.335393 -288.026031) (xy 339.343492 -288.077169)
			(xy 339.344 -288.103056) (xy 339.343568 -288.128392) (xy 339.335807 -288.178467) (xy 339.320477 -288.226765)
			(xy 339.297939 -288.272149) (xy 339.268723 -288.31355) (xy 339.233516 -288.349995) (xy 339.193149 -288.380624)
			(xy 339.148571 -288.404718) (xy 339.100832 -288.421708) (xy 339.07603 -288.426906) (xy 339.05317 -288.431224)
			(xy 338.848192 -288.786316) (xy 338.856066 -288.80816) (xy 338.864719 -288.834566) (xy 338.874035 -288.889344)
			(xy 338.874608 -288.917126) (xy 339.155024 -288.917126) (xy 339.155532 -288.891219) (xy 339.163638 -288.840042)
			(xy 339.17965 -288.790763) (xy 339.203173 -288.744596) (xy 339.233629 -288.702677) (xy 339.270267 -288.666039)
			(xy 339.312186 -288.635583) (xy 339.358353 -288.61206) (xy 339.407632 -288.596048) (xy 339.458809 -288.587942)
			(xy 339.510623 -288.587942) (xy 339.5618 -288.596048) (xy 339.611079 -288.61206) (xy 339.657246 -288.635583)
			(xy 339.699165 -288.666039) (xy 339.735803 -288.702677) (xy 339.766259 -288.744596) (xy 339.789782 -288.790763)
			(xy 339.805794 -288.840042) (xy 339.8139 -288.891219) (xy 339.814408 -288.917126) (xy 340.094824 -288.917126)
			(xy 340.095349 -288.891782) (xy 340.103118 -288.841693) (xy 340.118461 -288.793383) (xy 340.141016 -288.74799)
			(xy 340.170252 -288.706584) (xy 340.205481 -288.67014) (xy 340.245872 -288.639516) (xy 340.290474 -288.615435)
			(xy 340.338236 -288.598463) (xy 340.363048 -288.593276) (xy 340.385908 -288.588958) (xy 340.59114 -288.233866)
			(xy 340.583266 -288.211768) (xy 340.574642 -288.185419) (xy 340.565317 -288.130773) (xy 340.564724 -288.103056)
			(xy 340.565232 -288.077149) (xy 340.573338 -288.025972) (xy 340.58935 -287.976693) (xy 340.612873 -287.930526)
			(xy 340.643329 -287.888607) (xy 340.679967 -287.851969) (xy 340.721886 -287.821513) (xy 340.768053 -287.79799)
			(xy 340.817332 -287.781978) (xy 340.868509 -287.773872) (xy 340.920323 -287.773872) (xy 340.9715 -287.781978)
			(xy 341.020779 -287.79799) (xy 341.066946 -287.821513) (xy 341.108865 -287.851969) (xy 341.145503 -287.888607)
			(xy 341.175959 -287.930526) (xy 341.199482 -287.976693) (xy 341.215494 -288.025972) (xy 341.2236 -288.077149)
			(xy 341.224108 -288.103056) (xy 341.223631 -288.128401) (xy 341.215851 -288.178491) (xy 341.200499 -288.2268)
			(xy 341.177936 -288.272192) (xy 341.148694 -288.313597) (xy 341.11346 -288.35004) (xy 341.073065 -288.380663)
			(xy 341.028461 -288.404744) (xy 340.980697 -288.421718) (xy 340.955884 -288.426906) (xy 340.933024 -288.431224)
			(xy 340.727792 -288.786316) (xy 340.735666 -288.808414) (xy 340.744307 -288.834758) (xy 340.753621 -288.889407)
			(xy 340.754208 -288.917126) (xy 341.034624 -288.917126) (xy 341.035132 -288.891219) (xy 341.043238 -288.840042)
			(xy 341.05925 -288.790763) (xy 341.082773 -288.744596) (xy 341.113229 -288.702677) (xy 341.149867 -288.666039)
			(xy 341.191786 -288.635583) (xy 341.237953 -288.61206) (xy 341.287232 -288.596048) (xy 341.338409 -288.587942)
			(xy 341.390223 -288.587942) (xy 341.4414 -288.596048) (xy 341.490679 -288.61206) (xy 341.536846 -288.635583)
			(xy 341.578765 -288.666039) (xy 341.615403 -288.702677) (xy 341.645859 -288.744596) (xy 341.669382 -288.790763)
			(xy 341.685394 -288.840042) (xy 341.6935 -288.891219) (xy 341.694008 -288.917126) (xy 341.974424 -288.917126)
			(xy 341.974949 -288.891782) (xy 341.982718 -288.841693) (xy 341.998061 -288.793383) (xy 342.020616 -288.74799)
			(xy 342.049852 -288.706584) (xy 342.085081 -288.67014) (xy 342.125472 -288.639516) (xy 342.170074 -288.615435)
			(xy 342.217836 -288.598463) (xy 342.242648 -288.593276) (xy 342.265508 -288.588958) (xy 342.47074 -288.233866)
			(xy 342.462866 -288.211768) (xy 342.454242 -288.185419) (xy 342.444917 -288.130773) (xy 342.444324 -288.103056)
			(xy 342.444832 -288.077149) (xy 342.452938 -288.025972) (xy 342.46895 -287.976693) (xy 342.492473 -287.930526)
			(xy 342.522929 -287.888607) (xy 342.559567 -287.851969) (xy 342.601486 -287.821513) (xy 342.647653 -287.79799)
			(xy 342.696932 -287.781978) (xy 342.748109 -287.773872) (xy 342.799923 -287.773872) (xy 342.8511 -287.781978)
			(xy 342.900379 -287.79799) (xy 342.946546 -287.821513) (xy 342.988465 -287.851969) (xy 343.025103 -287.888607)
			(xy 343.055559 -287.930526) (xy 343.079082 -287.976693) (xy 343.095094 -288.025972) (xy 343.1032 -288.077149)
			(xy 343.103708 -288.103056) (xy 343.103231 -288.128401) (xy 343.095451 -288.178491) (xy 343.080099 -288.2268)
			(xy 343.057536 -288.272192) (xy 343.028294 -288.313597) (xy 342.99306 -288.35004) (xy 342.952665 -288.380663)
			(xy 342.908061 -288.404744) (xy 342.860297 -288.421718) (xy 342.835484 -288.426906) (xy 342.812624 -288.431224)
			(xy 342.607392 -288.786316) (xy 342.615266 -288.808414) (xy 342.623907 -288.834758) (xy 342.633221 -288.889407)
			(xy 342.633808 -288.917126) (xy 342.914224 -288.917126) (xy 342.914732 -288.891219) (xy 342.922838 -288.840042)
			(xy 342.93885 -288.790763) (xy 342.962373 -288.744596) (xy 342.992829 -288.702677) (xy 343.029467 -288.666039)
			(xy 343.071386 -288.635583) (xy 343.117553 -288.61206) (xy 343.166832 -288.596048) (xy 343.218009 -288.587942)
			(xy 343.269823 -288.587942) (xy 343.321 -288.596048) (xy 343.370279 -288.61206) (xy 343.416446 -288.635583)
			(xy 343.458365 -288.666039) (xy 343.495003 -288.702677) (xy 343.525459 -288.744596) (xy 343.548982 -288.790763)
			(xy 343.564994 -288.840042) (xy 343.5731 -288.891219) (xy 343.573608 -288.917126) (xy 343.854024 -288.917126)
			(xy 343.854549 -288.891782) (xy 343.862318 -288.841693) (xy 343.877661 -288.793383) (xy 343.900216 -288.74799)
			(xy 343.929452 -288.706584) (xy 343.964681 -288.67014) (xy 344.005072 -288.639516) (xy 344.049674 -288.615435)
			(xy 344.097436 -288.598463) (xy 344.122248 -288.593276) (xy 344.145108 -288.588958) (xy 344.35034 -288.233866)
			(xy 344.342466 -288.211768) (xy 344.333842 -288.185419) (xy 344.324517 -288.130773) (xy 344.323924 -288.103056)
			(xy 344.324432 -288.077149) (xy 344.332538 -288.025972) (xy 344.34855 -287.976693) (xy 344.372073 -287.930526)
			(xy 344.402529 -287.888607) (xy 344.439167 -287.851969) (xy 344.481086 -287.821513) (xy 344.527253 -287.79799)
			(xy 344.576532 -287.781978) (xy 344.627709 -287.773872) (xy 344.679523 -287.773872) (xy 344.7307 -287.781978)
			(xy 344.779979 -287.79799) (xy 344.826146 -287.821513) (xy 344.868065 -287.851969) (xy 344.904703 -287.888607)
			(xy 344.935159 -287.930526) (xy 344.958682 -287.976693) (xy 344.974694 -288.025972) (xy 344.9828 -288.077149)
			(xy 344.983308 -288.103056) (xy 344.982831 -288.128401) (xy 344.975051 -288.178491) (xy 344.959699 -288.2268)
			(xy 344.937136 -288.272192) (xy 344.907894 -288.313597) (xy 344.87266 -288.35004) (xy 344.832265 -288.380663)
			(xy 344.787661 -288.404744) (xy 344.739897 -288.421718) (xy 344.715084 -288.426906) (xy 344.692224 -288.431224)
			(xy 344.486992 -288.786316) (xy 344.494866 -288.808414) (xy 344.503507 -288.834758) (xy 344.512821 -288.889407)
			(xy 344.513408 -288.917126) (xy 344.793824 -288.917126) (xy 344.794332 -288.891219) (xy 344.802438 -288.840042)
			(xy 344.81845 -288.790763) (xy 344.841973 -288.744596) (xy 344.872429 -288.702677) (xy 344.909067 -288.666039)
			(xy 344.950986 -288.635583) (xy 344.997153 -288.61206) (xy 345.046432 -288.596048) (xy 345.097609 -288.587942)
			(xy 345.149423 -288.587942) (xy 345.2006 -288.596048) (xy 345.249879 -288.61206) (xy 345.296046 -288.635583)
			(xy 345.337965 -288.666039) (xy 345.374603 -288.702677) (xy 345.405059 -288.744596) (xy 345.428582 -288.790763)
			(xy 345.444594 -288.840042) (xy 345.4527 -288.891219) (xy 345.453208 -288.917126) (xy 345.733624 -288.917126)
			(xy 345.734149 -288.891782) (xy 345.741918 -288.841693) (xy 345.757261 -288.793383) (xy 345.779816 -288.74799)
			(xy 345.809052 -288.706584) (xy 345.844281 -288.67014) (xy 345.884672 -288.639516) (xy 345.929274 -288.615435)
			(xy 345.977036 -288.598463) (xy 346.001848 -288.593276) (xy 346.024708 -288.588958) (xy 346.22994 -288.233866)
			(xy 346.222066 -288.211768) (xy 346.213442 -288.185419) (xy 346.204117 -288.130773) (xy 346.203524 -288.103056)
			(xy 346.204032 -288.077149) (xy 346.212138 -288.025972) (xy 346.22815 -287.976693) (xy 346.251673 -287.930526)
			(xy 346.282129 -287.888607) (xy 346.318767 -287.851969) (xy 346.360686 -287.821513) (xy 346.406853 -287.79799)
			(xy 346.456132 -287.781978) (xy 346.507309 -287.773872) (xy 346.559123 -287.773872) (xy 346.6103 -287.781978)
			(xy 346.659579 -287.79799) (xy 346.705746 -287.821513) (xy 346.747665 -287.851969) (xy 346.784303 -287.888607)
			(xy 346.814759 -287.930526) (xy 346.838282 -287.976693) (xy 346.854294 -288.025972) (xy 346.8624 -288.077149)
			(xy 346.862908 -288.103056) (xy 346.862431 -288.128401) (xy 346.854651 -288.178491) (xy 346.839299 -288.2268)
			(xy 346.816736 -288.272192) (xy 346.787494 -288.313597) (xy 346.75226 -288.35004) (xy 346.711865 -288.380663)
			(xy 346.667261 -288.404744) (xy 346.619497 -288.421718) (xy 346.594684 -288.426906) (xy 346.571824 -288.431224)
			(xy 346.366592 -288.786316) (xy 346.374466 -288.808414) (xy 346.383107 -288.834758) (xy 346.392421 -288.889407)
			(xy 346.393008 -288.917126) (xy 346.673424 -288.917126) (xy 346.673932 -288.891219) (xy 346.682038 -288.840042)
			(xy 346.69805 -288.790763) (xy 346.721573 -288.744596) (xy 346.752029 -288.702677) (xy 346.788667 -288.666039)
			(xy 346.830586 -288.635583) (xy 346.876753 -288.61206) (xy 346.926032 -288.596048) (xy 346.977209 -288.587942)
			(xy 347.029023 -288.587942) (xy 347.0802 -288.596048) (xy 347.129479 -288.61206) (xy 347.175646 -288.635583)
			(xy 347.217565 -288.666039) (xy 347.254203 -288.702677) (xy 347.284659 -288.744596) (xy 347.308182 -288.790763)
			(xy 347.324194 -288.840042) (xy 347.3323 -288.891219) (xy 347.332808 -288.917126) (xy 347.613224 -288.917126)
			(xy 347.613749 -288.891782) (xy 347.621518 -288.841693) (xy 347.636861 -288.793383) (xy 347.659416 -288.74799)
			(xy 347.688652 -288.706584) (xy 347.723881 -288.67014) (xy 347.764272 -288.639516) (xy 347.808874 -288.615435)
			(xy 347.856636 -288.598463) (xy 347.881448 -288.593276) (xy 347.904308 -288.588958) (xy 348.10954 -288.233866)
			(xy 348.101666 -288.211768) (xy 348.093042 -288.185419) (xy 348.083717 -288.130773) (xy 348.083124 -288.103056)
			(xy 348.083632 -288.077149) (xy 348.091738 -288.025972) (xy 348.10775 -287.976693) (xy 348.131273 -287.930526)
			(xy 348.161729 -287.888607) (xy 348.198367 -287.851969) (xy 348.240286 -287.821513) (xy 348.286453 -287.79799)
			(xy 348.335732 -287.781978) (xy 348.386909 -287.773872) (xy 348.438723 -287.773872) (xy 348.4899 -287.781978)
			(xy 348.539179 -287.79799) (xy 348.585346 -287.821513) (xy 348.627265 -287.851969) (xy 348.663903 -287.888607)
			(xy 348.694359 -287.930526) (xy 348.717882 -287.976693) (xy 348.733894 -288.025972) (xy 348.742 -288.077149)
			(xy 348.742508 -288.103056) (xy 348.742031 -288.128401) (xy 348.734251 -288.178491) (xy 348.718899 -288.2268)
			(xy 348.696336 -288.272192) (xy 348.667094 -288.313597) (xy 348.63186 -288.35004) (xy 348.591465 -288.380663)
			(xy 348.546861 -288.404744) (xy 348.499097 -288.421718) (xy 348.474284 -288.426906) (xy 348.451424 -288.431224)
			(xy 348.246192 -288.786316) (xy 348.254066 -288.808414) (xy 348.262707 -288.834758) (xy 348.272021 -288.889407)
			(xy 348.272608 -288.917126) (xy 348.553024 -288.917126) (xy 348.553532 -288.891219) (xy 348.561638 -288.840042)
			(xy 348.57765 -288.790763) (xy 348.601173 -288.744596) (xy 348.631629 -288.702677) (xy 348.668267 -288.666039)
			(xy 348.710186 -288.635583) (xy 348.756353 -288.61206) (xy 348.805632 -288.596048) (xy 348.856809 -288.587942)
			(xy 348.908623 -288.587942) (xy 348.9598 -288.596048) (xy 349.009079 -288.61206) (xy 349.055246 -288.635583)
			(xy 349.097165 -288.666039) (xy 349.133803 -288.702677) (xy 349.164259 -288.744596) (xy 349.187782 -288.790763)
			(xy 349.203794 -288.840042) (xy 349.2119 -288.891219) (xy 349.212408 -288.917126) (xy 349.492824 -288.917126)
			(xy 349.493349 -288.891782) (xy 349.501118 -288.841693) (xy 349.516461 -288.793383) (xy 349.539016 -288.74799)
			(xy 349.568252 -288.706584) (xy 349.603481 -288.67014) (xy 349.643872 -288.639516) (xy 349.688474 -288.615435)
			(xy 349.736236 -288.598463) (xy 349.761048 -288.593276) (xy 349.783908 -288.588958) (xy 349.98914 -288.233866)
			(xy 349.981266 -288.211768) (xy 349.972642 -288.185419) (xy 349.963317 -288.130773) (xy 349.962724 -288.103056)
			(xy 349.963232 -288.077149) (xy 349.971338 -288.025972) (xy 349.98735 -287.976693) (xy 350.010873 -287.930526)
			(xy 350.041329 -287.888607) (xy 350.077967 -287.851969) (xy 350.119886 -287.821513) (xy 350.166053 -287.79799)
			(xy 350.215332 -287.781978) (xy 350.266509 -287.773872) (xy 350.318323 -287.773872) (xy 350.3695 -287.781978)
			(xy 350.418779 -287.79799) (xy 350.464946 -287.821513) (xy 350.506865 -287.851969) (xy 350.543503 -287.888607)
			(xy 350.573959 -287.930526) (xy 350.597482 -287.976693) (xy 350.613494 -288.025972) (xy 350.6216 -288.077149)
			(xy 350.622108 -288.103056) (xy 350.621631 -288.128401) (xy 350.613851 -288.178491) (xy 350.598499 -288.2268)
			(xy 350.575936 -288.272192) (xy 350.546694 -288.313597) (xy 350.51146 -288.35004) (xy 350.471065 -288.380663)
			(xy 350.426461 -288.404744) (xy 350.378697 -288.421718) (xy 350.353884 -288.426906) (xy 350.331024 -288.431224)
			(xy 350.125792 -288.786316) (xy 350.133666 -288.808414) (xy 350.142307 -288.834758) (xy 350.151621 -288.889407)
			(xy 350.152208 -288.917126) (xy 350.432624 -288.917126) (xy 350.433132 -288.891219) (xy 350.441238 -288.840042)
			(xy 350.45725 -288.790763) (xy 350.480773 -288.744596) (xy 350.511229 -288.702677) (xy 350.547867 -288.666039)
			(xy 350.589786 -288.635583) (xy 350.635953 -288.61206) (xy 350.685232 -288.596048) (xy 350.736409 -288.587942)
			(xy 350.788223 -288.587942) (xy 350.8394 -288.596048) (xy 350.888679 -288.61206) (xy 350.934846 -288.635583)
			(xy 350.976765 -288.666039) (xy 351.013403 -288.702677) (xy 351.043859 -288.744596) (xy 351.067382 -288.790763)
			(xy 351.083394 -288.840042) (xy 351.0915 -288.891219) (xy 351.092008 -288.917126) (xy 351.372424 -288.917126)
			(xy 351.372949 -288.891782) (xy 351.380718 -288.841693) (xy 351.396061 -288.793383) (xy 351.418616 -288.74799)
			(xy 351.447852 -288.706584) (xy 351.483081 -288.67014) (xy 351.523472 -288.639516) (xy 351.568074 -288.615435)
			(xy 351.615836 -288.598463) (xy 351.640648 -288.593276) (xy 351.663508 -288.588958) (xy 351.86874 -288.233866)
			(xy 351.860866 -288.211768) (xy 351.852242 -288.185419) (xy 351.842917 -288.130773) (xy 351.842324 -288.103056)
			(xy 351.842832 -288.077149) (xy 351.850938 -288.025972) (xy 351.86695 -287.976693) (xy 351.890473 -287.930526)
			(xy 351.920929 -287.888607) (xy 351.957567 -287.851969) (xy 351.999486 -287.821513) (xy 352.045653 -287.79799)
			(xy 352.094932 -287.781978) (xy 352.146109 -287.773872) (xy 352.197923 -287.773872) (xy 352.2491 -287.781978)
			(xy 352.298379 -287.79799) (xy 352.344546 -287.821513) (xy 352.386465 -287.851969) (xy 352.423103 -287.888607)
			(xy 352.453559 -287.930526) (xy 352.477082 -287.976693) (xy 352.493094 -288.025972) (xy 352.5012 -288.077149)
			(xy 352.501708 -288.103056) (xy 368.758724 -288.103056) (xy 368.759232 -288.077149) (xy 368.767338 -288.025972)
			(xy 368.78335 -287.976693) (xy 368.806873 -287.930526) (xy 368.837329 -287.888607) (xy 368.873967 -287.851969)
			(xy 368.915886 -287.821513) (xy 368.962053 -287.79799) (xy 369.011332 -287.781978) (xy 369.062509 -287.773872)
			(xy 369.114323 -287.773872) (xy 369.1655 -287.781978) (xy 369.214779 -287.79799) (xy 369.260946 -287.821513)
			(xy 369.302865 -287.851969) (xy 369.339503 -287.888607) (xy 369.369959 -287.930526) (xy 369.393482 -287.976693)
			(xy 369.409494 -288.025972) (xy 369.4176 -288.077149) (xy 369.418108 -288.103056) (xy 370.638324 -288.103056)
			(xy 370.638832 -288.077149) (xy 370.646938 -288.025972) (xy 370.66295 -287.976693) (xy 370.686473 -287.930526)
			(xy 370.716929 -287.888607) (xy 370.753567 -287.851969) (xy 370.795486 -287.821513) (xy 370.841653 -287.79799)
			(xy 370.890932 -287.781978) (xy 370.942109 -287.773872) (xy 370.993923 -287.773872) (xy 371.0451 -287.781978)
			(xy 371.094379 -287.79799) (xy 371.140546 -287.821513) (xy 371.182465 -287.851969) (xy 371.219103 -287.888607)
			(xy 371.249559 -287.930526) (xy 371.273082 -287.976693) (xy 371.289094 -288.025972) (xy 371.2972 -288.077149)
			(xy 371.297708 -288.103056) (xy 372.517924 -288.103056) (xy 372.518432 -288.077149) (xy 372.526538 -288.025972)
			(xy 372.54255 -287.976693) (xy 372.566073 -287.930526) (xy 372.596529 -287.888607) (xy 372.633167 -287.851969)
			(xy 372.675086 -287.821513) (xy 372.721253 -287.79799) (xy 372.770532 -287.781978) (xy 372.821709 -287.773872)
			(xy 372.873523 -287.773872) (xy 372.9247 -287.781978) (xy 372.973979 -287.79799) (xy 373.020146 -287.821513)
			(xy 373.062065 -287.851969) (xy 373.098703 -287.888607) (xy 373.129159 -287.930526) (xy 373.152682 -287.976693)
			(xy 373.168694 -288.025972) (xy 373.1768 -288.077149) (xy 373.177308 -288.103056) (xy 374.397524 -288.103056)
			(xy 374.398032 -288.077149) (xy 374.406138 -288.025972) (xy 374.42215 -287.976693) (xy 374.445673 -287.930526)
			(xy 374.476129 -287.888607) (xy 374.512767 -287.851969) (xy 374.554686 -287.821513) (xy 374.600853 -287.79799)
			(xy 374.650132 -287.781978) (xy 374.701309 -287.773872) (xy 374.753123 -287.773872) (xy 374.8043 -287.781978)
			(xy 374.853579 -287.79799) (xy 374.899746 -287.821513) (xy 374.941665 -287.851969) (xy 374.978303 -287.888607)
			(xy 375.008759 -287.930526) (xy 375.032282 -287.976693) (xy 375.048294 -288.025972) (xy 375.0564 -288.077149)
			(xy 375.056908 -288.103056) (xy 376.277124 -288.103056) (xy 376.277632 -288.077149) (xy 376.285738 -288.025972)
			(xy 376.30175 -287.976693) (xy 376.325273 -287.930526) (xy 376.355729 -287.888607) (xy 376.392367 -287.851969)
			(xy 376.434286 -287.821513) (xy 376.480453 -287.79799) (xy 376.529732 -287.781978) (xy 376.580909 -287.773872)
			(xy 376.632723 -287.773872) (xy 376.6839 -287.781978) (xy 376.733179 -287.79799) (xy 376.779346 -287.821513)
			(xy 376.821265 -287.851969) (xy 376.857903 -287.888607) (xy 376.888359 -287.930526) (xy 376.911882 -287.976693)
			(xy 376.927894 -288.025972) (xy 376.936 -288.077149) (xy 376.936508 -288.103056) (xy 378.156724 -288.103056)
			(xy 378.157232 -288.077149) (xy 378.165338 -288.025972) (xy 378.18135 -287.976693) (xy 378.204873 -287.930526)
			(xy 378.235329 -287.888607) (xy 378.271967 -287.851969) (xy 378.313886 -287.821513) (xy 378.360053 -287.79799)
			(xy 378.409332 -287.781978) (xy 378.460509 -287.773872) (xy 378.512323 -287.773872) (xy 378.5635 -287.781978)
			(xy 378.612779 -287.79799) (xy 378.658946 -287.821513) (xy 378.700865 -287.851969) (xy 378.737503 -287.888607)
			(xy 378.767959 -287.930526) (xy 378.791482 -287.976693) (xy 378.807494 -288.025972) (xy 378.8156 -288.077149)
			(xy 378.816108 -288.103056) (xy 380.036324 -288.103056) (xy 380.036832 -288.077149) (xy 380.044938 -288.025972)
			(xy 380.06095 -287.976693) (xy 380.084473 -287.930526) (xy 380.114929 -287.888607) (xy 380.151567 -287.851969)
			(xy 380.193486 -287.821513) (xy 380.239653 -287.79799) (xy 380.288932 -287.781978) (xy 380.340109 -287.773872)
			(xy 380.391923 -287.773872) (xy 380.4431 -287.781978) (xy 380.492379 -287.79799) (xy 380.538546 -287.821513)
			(xy 380.580465 -287.851969) (xy 380.617103 -287.888607) (xy 380.647559 -287.930526) (xy 380.671082 -287.976693)
			(xy 380.687094 -288.025972) (xy 380.6952 -288.077149) (xy 380.695708 -288.103056) (xy 382.855724 -288.103056)
			(xy 382.856232 -288.077149) (xy 382.864338 -288.025972) (xy 382.88035 -287.976693) (xy 382.903873 -287.930526)
			(xy 382.934329 -287.888607) (xy 382.970967 -287.851969) (xy 383.012886 -287.821513) (xy 383.059053 -287.79799)
			(xy 383.108332 -287.781978) (xy 383.159509 -287.773872) (xy 383.211323 -287.773872) (xy 383.2625 -287.781978)
			(xy 383.311779 -287.79799) (xy 383.357946 -287.821513) (xy 383.399865 -287.851969) (xy 383.436503 -287.888607)
			(xy 383.466959 -287.930526) (xy 383.490482 -287.976693) (xy 383.506494 -288.025972) (xy 383.5146 -288.077149)
			(xy 383.515108 -288.103056) (xy 383.514503 -288.130773) (xy 383.505187 -288.185419) (xy 383.496566 -288.211768)
			(xy 383.488692 -288.233866) (xy 383.693924 -288.588958) (xy 383.716784 -288.593276) (xy 383.741606 -288.598437)
			(xy 383.789384 -288.615395) (xy 383.834001 -288.639469) (xy 383.874406 -288.67009) (xy 383.909646 -288.706538)
			(xy 383.93889 -288.747952) (xy 383.961447 -288.793355) (xy 383.976786 -288.841676) (xy 383.984545 -288.891777)
			(xy 383.985008 -288.917126) (xy 383.9845 -288.943033) (xy 383.976394 -288.99421) (xy 383.960382 -289.043489)
			(xy 383.936859 -289.089656) (xy 383.906403 -289.131575) (xy 383.869765 -289.168213) (xy 383.827846 -289.198669)
			(xy 383.781679 -289.222192) (xy 383.7324 -289.238204) (xy 383.681223 -289.24631) (xy 383.629409 -289.24631)
			(xy 383.578232 -289.238204) (xy 383.528953 -289.222192) (xy 383.482786 -289.198669) (xy 383.440867 -289.168213)
			(xy 383.404229 -289.131575) (xy 383.373773 -289.089656) (xy 383.35025 -289.043489) (xy 383.334238 -288.99421)
			(xy 383.326132 -288.943033) (xy 383.325624 -288.917126) (xy 383.326223 -288.889409) (xy 383.335543 -288.834762)
			(xy 383.344166 -288.808414) (xy 383.35204 -288.786316) (xy 383.146808 -288.431224) (xy 383.123948 -288.426906)
			(xy 383.099127 -288.421739) (xy 383.051348 -288.404784) (xy 383.006729 -288.380713) (xy 382.966322 -288.350092)
			(xy 382.931082 -288.313646) (xy 382.901838 -288.272232) (xy 382.879281 -288.226828) (xy 382.863943 -288.178506)
			(xy 382.856186 -288.128405) (xy 382.855724 -288.103056) (xy 380.695708 -288.103056) (xy 380.695103 -288.130773)
			(xy 380.685787 -288.185419) (xy 380.677166 -288.211768) (xy 380.669546 -288.233866) (xy 380.874524 -288.588958)
			(xy 380.897384 -288.593276) (xy 380.922206 -288.598437) (xy 380.969984 -288.615395) (xy 381.014601 -288.639469)
			(xy 381.055006 -288.67009) (xy 381.090246 -288.706538) (xy 381.11949 -288.747952) (xy 381.142047 -288.793355)
			(xy 381.157386 -288.841676) (xy 381.165145 -288.891777) (xy 381.165608 -288.917126) (xy 381.1651 -288.943033)
			(xy 381.156994 -288.99421) (xy 381.140982 -289.043489) (xy 381.117459 -289.089656) (xy 381.087003 -289.131575)
			(xy 381.050365 -289.168213) (xy 381.008446 -289.198669) (xy 380.962279 -289.222192) (xy 380.913 -289.238204)
			(xy 380.861823 -289.24631) (xy 380.810009 -289.24631) (xy 380.758832 -289.238204) (xy 380.709553 -289.222192)
			(xy 380.663386 -289.198669) (xy 380.621467 -289.168213) (xy 380.584829 -289.131575) (xy 380.554373 -289.089656)
			(xy 380.53085 -289.043489) (xy 380.514838 -288.99421) (xy 380.506732 -288.943033) (xy 380.506224 -288.917126)
			(xy 380.506823 -288.889409) (xy 380.516143 -288.834762) (xy 380.524766 -288.808414) (xy 380.53264 -288.786316)
			(xy 380.327662 -288.431224) (xy 380.304802 -288.426906) (xy 380.279961 -288.421779) (xy 380.232152 -288.40484)
			(xy 380.187502 -288.380778) (xy 380.147063 -288.350162) (xy 380.111791 -288.313713) (xy 380.082517 -288.272293)
			(xy 380.059933 -288.226877) (xy 380.044571 -288.178538) (xy 380.036794 -288.128417) (xy 380.036324 -288.103056)
			(xy 378.816108 -288.103056) (xy 378.815503 -288.130773) (xy 378.806187 -288.185419) (xy 378.797566 -288.211768)
			(xy 378.789946 -288.233866) (xy 378.994924 -288.588958) (xy 379.017784 -288.593276) (xy 379.042606 -288.598437)
			(xy 379.090384 -288.615395) (xy 379.135001 -288.639469) (xy 379.175406 -288.67009) (xy 379.210646 -288.706538)
			(xy 379.23989 -288.747952) (xy 379.262447 -288.793355) (xy 379.277786 -288.841676) (xy 379.285545 -288.891777)
			(xy 379.286008 -288.917126) (xy 379.2855 -288.943033) (xy 379.277394 -288.99421) (xy 379.261382 -289.043489)
			(xy 379.237859 -289.089656) (xy 379.207403 -289.131575) (xy 379.170765 -289.168213) (xy 379.128846 -289.198669)
			(xy 379.082679 -289.222192) (xy 379.0334 -289.238204) (xy 378.982223 -289.24631) (xy 378.930409 -289.24631)
			(xy 378.879232 -289.238204) (xy 378.829953 -289.222192) (xy 378.783786 -289.198669) (xy 378.741867 -289.168213)
			(xy 378.705229 -289.131575) (xy 378.674773 -289.089656) (xy 378.65125 -289.043489) (xy 378.635238 -288.99421)
			(xy 378.627132 -288.943033) (xy 378.626624 -288.917126) (xy 378.627223 -288.889409) (xy 378.636543 -288.834762)
			(xy 378.645166 -288.808414) (xy 378.65304 -288.786316) (xy 378.448062 -288.431224) (xy 378.425202 -288.426906)
			(xy 378.400361 -288.421779) (xy 378.352552 -288.40484) (xy 378.307902 -288.380778) (xy 378.267463 -288.350162)
			(xy 378.232191 -288.313713) (xy 378.202917 -288.272293) (xy 378.180333 -288.226877) (xy 378.164971 -288.178538)
			(xy 378.157194 -288.128417) (xy 378.156724 -288.103056) (xy 376.936508 -288.103056) (xy 376.935903 -288.130773)
			(xy 376.926587 -288.185419) (xy 376.917966 -288.211768) (xy 376.910346 -288.233866) (xy 377.115324 -288.588958)
			(xy 377.138184 -288.593276) (xy 377.163006 -288.598437) (xy 377.210784 -288.615395) (xy 377.255401 -288.639469)
			(xy 377.295806 -288.67009) (xy 377.331046 -288.706538) (xy 377.36029 -288.747952) (xy 377.382847 -288.793355)
			(xy 377.398186 -288.841676) (xy 377.405945 -288.891777) (xy 377.406408 -288.917126) (xy 377.4059 -288.943033)
			(xy 377.397794 -288.99421) (xy 377.381782 -289.043489) (xy 377.358259 -289.089656) (xy 377.327803 -289.131575)
			(xy 377.291165 -289.168213) (xy 377.249246 -289.198669) (xy 377.203079 -289.222192) (xy 377.1538 -289.238204)
			(xy 377.102623 -289.24631) (xy 377.050809 -289.24631) (xy 376.999632 -289.238204) (xy 376.950353 -289.222192)
			(xy 376.904186 -289.198669) (xy 376.862267 -289.168213) (xy 376.825629 -289.131575) (xy 376.795173 -289.089656)
			(xy 376.77165 -289.043489) (xy 376.755638 -288.99421) (xy 376.747532 -288.943033) (xy 376.747024 -288.917126)
			(xy 376.747623 -288.889409) (xy 376.756943 -288.834762) (xy 376.765566 -288.808414) (xy 376.77344 -288.786316)
			(xy 376.568462 -288.431224) (xy 376.545602 -288.426906) (xy 376.520761 -288.421779) (xy 376.472952 -288.40484)
			(xy 376.428302 -288.380778) (xy 376.387863 -288.350162) (xy 376.352591 -288.313713) (xy 376.323317 -288.272293)
			(xy 376.300733 -288.226877) (xy 376.285371 -288.178538) (xy 376.277594 -288.128417) (xy 376.277124 -288.103056)
			(xy 375.056908 -288.103056) (xy 375.056303 -288.130773) (xy 375.046987 -288.185419) (xy 375.038366 -288.211768)
			(xy 375.030746 -288.233866) (xy 375.235724 -288.588958) (xy 375.258584 -288.593276) (xy 375.283406 -288.598437)
			(xy 375.331184 -288.615395) (xy 375.375801 -288.639469) (xy 375.416206 -288.67009) (xy 375.451446 -288.706538)
			(xy 375.48069 -288.747952) (xy 375.503247 -288.793355) (xy 375.518586 -288.841676) (xy 375.526345 -288.891777)
			(xy 375.526808 -288.917126) (xy 375.5263 -288.943033) (xy 375.518194 -288.99421) (xy 375.502182 -289.043489)
			(xy 375.478659 -289.089656) (xy 375.448203 -289.131575) (xy 375.411565 -289.168213) (xy 375.369646 -289.198669)
			(xy 375.323479 -289.222192) (xy 375.2742 -289.238204) (xy 375.223023 -289.24631) (xy 375.171209 -289.24631)
			(xy 375.120032 -289.238204) (xy 375.070753 -289.222192) (xy 375.024586 -289.198669) (xy 374.982667 -289.168213)
			(xy 374.946029 -289.131575) (xy 374.915573 -289.089656) (xy 374.89205 -289.043489) (xy 374.876038 -288.99421)
			(xy 374.867932 -288.943033) (xy 374.867424 -288.917126) (xy 374.868023 -288.889409) (xy 374.877343 -288.834762)
			(xy 374.885966 -288.808414) (xy 374.89384 -288.786316) (xy 374.688862 -288.431224) (xy 374.666002 -288.426906)
			(xy 374.641161 -288.421779) (xy 374.593352 -288.40484) (xy 374.548702 -288.380778) (xy 374.508263 -288.350162)
			(xy 374.472991 -288.313713) (xy 374.443717 -288.272293) (xy 374.421133 -288.226877) (xy 374.405771 -288.178538)
			(xy 374.397994 -288.128417) (xy 374.397524 -288.103056) (xy 373.177308 -288.103056) (xy 373.176703 -288.130773)
			(xy 373.167387 -288.185419) (xy 373.158766 -288.211768) (xy 373.151146 -288.233866) (xy 373.356124 -288.588958)
			(xy 373.378984 -288.593276) (xy 373.403806 -288.598437) (xy 373.451584 -288.615395) (xy 373.496201 -288.639469)
			(xy 373.536606 -288.67009) (xy 373.571846 -288.706538) (xy 373.60109 -288.747952) (xy 373.623647 -288.793355)
			(xy 373.638986 -288.841676) (xy 373.646745 -288.891777) (xy 373.647208 -288.917126) (xy 373.6467 -288.943033)
			(xy 373.638594 -288.99421) (xy 373.622582 -289.043489) (xy 373.599059 -289.089656) (xy 373.568603 -289.131575)
			(xy 373.531965 -289.168213) (xy 373.490046 -289.198669) (xy 373.443879 -289.222192) (xy 373.3946 -289.238204)
			(xy 373.343423 -289.24631) (xy 373.291609 -289.24631) (xy 373.240432 -289.238204) (xy 373.191153 -289.222192)
			(xy 373.144986 -289.198669) (xy 373.103067 -289.168213) (xy 373.066429 -289.131575) (xy 373.035973 -289.089656)
			(xy 373.01245 -289.043489) (xy 372.996438 -288.99421) (xy 372.988332 -288.943033) (xy 372.987824 -288.917126)
			(xy 372.988423 -288.889409) (xy 372.997743 -288.834762) (xy 373.006366 -288.808414) (xy 373.01424 -288.786316)
			(xy 372.809262 -288.431224) (xy 372.786402 -288.426906) (xy 372.761561 -288.421779) (xy 372.713752 -288.40484)
			(xy 372.669102 -288.380778) (xy 372.628663 -288.350162) (xy 372.593391 -288.313713) (xy 372.564117 -288.272293)
			(xy 372.541533 -288.226877) (xy 372.526171 -288.178538) (xy 372.518394 -288.128417) (xy 372.517924 -288.103056)
			(xy 371.297708 -288.103056) (xy 371.297103 -288.130773) (xy 371.287787 -288.185419) (xy 371.279166 -288.211768)
			(xy 371.271546 -288.233866) (xy 371.476524 -288.588958) (xy 371.499384 -288.593276) (xy 371.524206 -288.598437)
			(xy 371.571984 -288.615395) (xy 371.616601 -288.639469) (xy 371.657006 -288.67009) (xy 371.692246 -288.706538)
			(xy 371.72149 -288.747952) (xy 371.744047 -288.793355) (xy 371.759386 -288.841676) (xy 371.767145 -288.891777)
			(xy 371.767608 -288.917126) (xy 371.7671 -288.943033) (xy 371.758994 -288.99421) (xy 371.742982 -289.043489)
			(xy 371.719459 -289.089656) (xy 371.689003 -289.131575) (xy 371.652365 -289.168213) (xy 371.610446 -289.198669)
			(xy 371.564279 -289.222192) (xy 371.515 -289.238204) (xy 371.463823 -289.24631) (xy 371.412009 -289.24631)
			(xy 371.360832 -289.238204) (xy 371.311553 -289.222192) (xy 371.265386 -289.198669) (xy 371.223467 -289.168213)
			(xy 371.186829 -289.131575) (xy 371.156373 -289.089656) (xy 371.13285 -289.043489) (xy 371.116838 -288.99421)
			(xy 371.108732 -288.943033) (xy 371.108224 -288.917126) (xy 371.108823 -288.889409) (xy 371.118143 -288.834762)
			(xy 371.126766 -288.808414) (xy 371.13464 -288.786316) (xy 370.929662 -288.431224) (xy 370.906802 -288.426906)
			(xy 370.881961 -288.421779) (xy 370.834152 -288.40484) (xy 370.789502 -288.380778) (xy 370.749063 -288.350162)
			(xy 370.713791 -288.313713) (xy 370.684517 -288.272293) (xy 370.661933 -288.226877) (xy 370.646571 -288.178538)
			(xy 370.638794 -288.128417) (xy 370.638324 -288.103056) (xy 369.418108 -288.103056) (xy 369.417503 -288.130773)
			(xy 369.408187 -288.185419) (xy 369.399566 -288.211768) (xy 369.391692 -288.233866) (xy 369.596924 -288.588958)
			(xy 369.619784 -288.593276) (xy 369.644606 -288.598437) (xy 369.692384 -288.615395) (xy 369.737001 -288.639469)
			(xy 369.777406 -288.67009) (xy 369.812646 -288.706538) (xy 369.84189 -288.747952) (xy 369.864447 -288.793355)
			(xy 369.879786 -288.841676) (xy 369.887545 -288.891777) (xy 369.888008 -288.917126) (xy 369.8875 -288.943033)
			(xy 369.879394 -288.99421) (xy 369.863382 -289.043489) (xy 369.839859 -289.089656) (xy 369.809403 -289.131575)
			(xy 369.772765 -289.168213) (xy 369.730846 -289.198669) (xy 369.684679 -289.222192) (xy 369.6354 -289.238204)
			(xy 369.584223 -289.24631) (xy 369.532409 -289.24631) (xy 369.481232 -289.238204) (xy 369.431953 -289.222192)
			(xy 369.385786 -289.198669) (xy 369.343867 -289.168213) (xy 369.307229 -289.131575) (xy 369.276773 -289.089656)
			(xy 369.25325 -289.043489) (xy 369.237238 -288.99421) (xy 369.229132 -288.943033) (xy 369.228624 -288.917126)
			(xy 369.229223 -288.889409) (xy 369.238543 -288.834762) (xy 369.247166 -288.808414) (xy 369.25504 -288.786316)
			(xy 369.049808 -288.431224) (xy 369.026948 -288.426906) (xy 369.002127 -288.421739) (xy 368.954348 -288.404784)
			(xy 368.909729 -288.380713) (xy 368.869322 -288.350092) (xy 368.834082 -288.313646) (xy 368.804838 -288.272232)
			(xy 368.782281 -288.226828) (xy 368.766943 -288.178506) (xy 368.759186 -288.128405) (xy 368.758724 -288.103056)
			(xy 352.501708 -288.103056) (xy 352.501231 -288.128401) (xy 352.493451 -288.178491) (xy 352.478099 -288.2268)
			(xy 352.455536 -288.272192) (xy 352.426294 -288.313597) (xy 352.39106 -288.35004) (xy 352.350665 -288.380663)
			(xy 352.306061 -288.404744) (xy 352.258297 -288.421718) (xy 352.233484 -288.426906) (xy 352.210624 -288.431224)
			(xy 352.005392 -288.786316) (xy 352.013266 -288.808414) (xy 352.021907 -288.834758) (xy 352.031221 -288.889407)
			(xy 352.031808 -288.917126) (xy 352.0313 -288.943033) (xy 352.023194 -288.99421) (xy 352.007182 -289.043489)
			(xy 351.983659 -289.089656) (xy 351.953203 -289.131575) (xy 351.916565 -289.168213) (xy 351.874646 -289.198669)
			(xy 351.828479 -289.222192) (xy 351.7792 -289.238204) (xy 351.728023 -289.24631) (xy 351.676209 -289.24631)
			(xy 351.625032 -289.238204) (xy 351.575753 -289.222192) (xy 351.529586 -289.198669) (xy 351.487667 -289.168213)
			(xy 351.451029 -289.131575) (xy 351.420573 -289.089656) (xy 351.39705 -289.043489) (xy 351.381038 -288.99421)
			(xy 351.372932 -288.943033) (xy 351.372424 -288.917126) (xy 351.092008 -288.917126) (xy 351.091589 -288.940067)
			(xy 351.08516 -288.985498) (xy 351.072513 -289.029604) (xy 351.06356 -289.05073) (xy 351.053654 -289.073336)
			(xy 351.267522 -289.478466) (xy 351.291652 -289.483038) (xy 351.316573 -289.488138) (xy 351.364584 -289.504939)
			(xy 351.409443 -289.528919) (xy 351.450084 -289.559507) (xy 351.485541 -289.595978) (xy 351.514973 -289.637465)
			(xy 351.537679 -289.682981) (xy 351.553121 -289.731446) (xy 351.560931 -289.781709) (xy 351.5614 -289.807142)
			(xy 367.818924 -289.807142) (xy 367.819411 -289.781712) (xy 367.827244 -289.73146) (xy 367.842699 -289.683005)
			(xy 367.86541 -289.637498) (xy 367.894839 -289.596018) (xy 367.930287 -289.559547) (xy 367.970914 -289.528951)
			(xy 368.015757 -289.504956) (xy 368.063753 -289.48813) (xy 368.088672 -289.483038) (xy 368.112802 -289.478466)
			(xy 368.327178 -289.073082) (xy 368.317272 -289.050476) (xy 368.308309 -289.029398) (xy 368.295664 -288.985377)
			(xy 368.289249 -288.940026) (xy 368.288824 -288.917126) (xy 368.289332 -288.891219) (xy 368.297438 -288.840042)
			(xy 368.31345 -288.790763) (xy 368.336973 -288.744596) (xy 368.367429 -288.702677) (xy 368.404067 -288.666039)
			(xy 368.445986 -288.635583) (xy 368.492153 -288.61206) (xy 368.541432 -288.596048) (xy 368.592609 -288.587942)
			(xy 368.644423 -288.587942) (xy 368.6956 -288.596048) (xy 368.744879 -288.61206) (xy 368.791046 -288.635583)
			(xy 368.832965 -288.666039) (xy 368.869603 -288.702677) (xy 368.900059 -288.744596) (xy 368.923582 -288.790763)
			(xy 368.939594 -288.840042) (xy 368.9477 -288.891219) (xy 368.948208 -288.917126) (xy 368.947753 -288.942575)
			(xy 368.939949 -288.992871) (xy 368.924499 -289.041367) (xy 368.901771 -289.086909) (xy 368.872307 -289.128411)
			(xy 368.836809 -289.164887) (xy 368.796121 -289.195466) (xy 368.751213 -289.21942) (xy 368.703153 -289.23618)
			(xy 368.678206 -289.24123) (xy 368.654076 -289.245802) (xy 368.4397 -289.651186) (xy 368.449606 -289.673792)
			(xy 368.458528 -289.694877) (xy 368.471078 -289.738907) (xy 368.47741 -289.78425) (xy 368.4778 -289.807142)
			(xy 369.698524 -289.807142) (xy 369.699011 -289.781712) (xy 369.706844 -289.73146) (xy 369.722299 -289.683005)
			(xy 369.74501 -289.637498) (xy 369.774439 -289.596018) (xy 369.809887 -289.559547) (xy 369.850514 -289.528951)
			(xy 369.895357 -289.504956) (xy 369.943353 -289.48813) (xy 369.968272 -289.483038) (xy 369.992402 -289.478466)
			(xy 370.206778 -289.073082) (xy 370.196872 -289.050476) (xy 370.187909 -289.029398) (xy 370.175264 -288.985377)
			(xy 370.168849 -288.940026) (xy 370.168424 -288.917126) (xy 370.168932 -288.891219) (xy 370.177038 -288.840042)
			(xy 370.19305 -288.790763) (xy 370.216573 -288.744596) (xy 370.247029 -288.702677) (xy 370.283667 -288.666039)
			(xy 370.325586 -288.635583) (xy 370.371753 -288.61206) (xy 370.421032 -288.596048) (xy 370.472209 -288.587942)
			(xy 370.524023 -288.587942) (xy 370.5752 -288.596048) (xy 370.624479 -288.61206) (xy 370.670646 -288.635583)
			(xy 370.712565 -288.666039) (xy 370.749203 -288.702677) (xy 370.779659 -288.744596) (xy 370.803182 -288.790763)
			(xy 370.819194 -288.840042) (xy 370.8273 -288.891219) (xy 370.827808 -288.917126) (xy 370.827353 -288.942575)
			(xy 370.819549 -288.992871) (xy 370.804099 -289.041367) (xy 370.781371 -289.086909) (xy 370.751907 -289.128411)
			(xy 370.716409 -289.164887) (xy 370.675721 -289.195466) (xy 370.630813 -289.21942) (xy 370.582753 -289.23618)
			(xy 370.557806 -289.24123) (xy 370.533676 -289.245802) (xy 370.3193 -289.651186) (xy 370.329206 -289.673792)
			(xy 370.338128 -289.694877) (xy 370.350678 -289.738907) (xy 370.35701 -289.78425) (xy 370.3574 -289.807142)
			(xy 371.578124 -289.807142) (xy 371.578611 -289.781712) (xy 371.586444 -289.73146) (xy 371.601899 -289.683005)
			(xy 371.62461 -289.637498) (xy 371.654039 -289.596018) (xy 371.689487 -289.559547) (xy 371.730114 -289.528951)
			(xy 371.774957 -289.504956) (xy 371.822953 -289.48813) (xy 371.847872 -289.483038) (xy 371.872002 -289.478466)
			(xy 372.086378 -289.073082) (xy 372.076472 -289.050476) (xy 372.067509 -289.029398) (xy 372.054864 -288.985377)
			(xy 372.048449 -288.940026) (xy 372.048024 -288.917126) (xy 372.048532 -288.891219) (xy 372.056638 -288.840042)
			(xy 372.07265 -288.790763) (xy 372.096173 -288.744596) (xy 372.126629 -288.702677) (xy 372.163267 -288.666039)
			(xy 372.205186 -288.635583) (xy 372.251353 -288.61206) (xy 372.300632 -288.596048) (xy 372.351809 -288.587942)
			(xy 372.403623 -288.587942) (xy 372.4548 -288.596048) (xy 372.504079 -288.61206) (xy 372.550246 -288.635583)
			(xy 372.592165 -288.666039) (xy 372.628803 -288.702677) (xy 372.659259 -288.744596) (xy 372.682782 -288.790763)
			(xy 372.698794 -288.840042) (xy 372.7069 -288.891219) (xy 372.707408 -288.917126) (xy 372.706953 -288.942575)
			(xy 372.699149 -288.992871) (xy 372.683699 -289.041367) (xy 372.660971 -289.086909) (xy 372.631507 -289.128411)
			(xy 372.596009 -289.164887) (xy 372.555321 -289.195466) (xy 372.510413 -289.21942) (xy 372.462353 -289.23618)
			(xy 372.437406 -289.24123) (xy 372.413276 -289.245802) (xy 372.1989 -289.651186) (xy 372.208806 -289.673792)
			(xy 372.217728 -289.694877) (xy 372.230278 -289.738907) (xy 372.23661 -289.78425) (xy 372.237 -289.807142)
			(xy 373.457724 -289.807142) (xy 373.458211 -289.781712) (xy 373.466044 -289.73146) (xy 373.481499 -289.683005)
			(xy 373.50421 -289.637498) (xy 373.533639 -289.596018) (xy 373.569087 -289.559547) (xy 373.609714 -289.528951)
			(xy 373.654557 -289.504956) (xy 373.702553 -289.48813) (xy 373.727472 -289.483038) (xy 373.751602 -289.478466)
			(xy 373.965978 -289.073082) (xy 373.956072 -289.050476) (xy 373.947109 -289.029398) (xy 373.934464 -288.985377)
			(xy 373.928049 -288.940026) (xy 373.927624 -288.917126) (xy 373.928132 -288.891219) (xy 373.936238 -288.840042)
			(xy 373.95225 -288.790763) (xy 373.975773 -288.744596) (xy 374.006229 -288.702677) (xy 374.042867 -288.666039)
			(xy 374.084786 -288.635583) (xy 374.130953 -288.61206) (xy 374.180232 -288.596048) (xy 374.231409 -288.587942)
			(xy 374.283223 -288.587942) (xy 374.3344 -288.596048) (xy 374.383679 -288.61206) (xy 374.429846 -288.635583)
			(xy 374.471765 -288.666039) (xy 374.508403 -288.702677) (xy 374.538859 -288.744596) (xy 374.562382 -288.790763)
			(xy 374.578394 -288.840042) (xy 374.5865 -288.891219) (xy 374.587008 -288.917126) (xy 374.586553 -288.942575)
			(xy 374.578749 -288.992871) (xy 374.563299 -289.041367) (xy 374.540571 -289.086909) (xy 374.511107 -289.128411)
			(xy 374.475609 -289.164887) (xy 374.434921 -289.195466) (xy 374.390013 -289.21942) (xy 374.341953 -289.23618)
			(xy 374.317006 -289.24123) (xy 374.292876 -289.245802) (xy 374.0785 -289.651186) (xy 374.088406 -289.673792)
			(xy 374.097328 -289.694877) (xy 374.109878 -289.738907) (xy 374.11621 -289.78425) (xy 374.1166 -289.807142)
			(xy 375.337324 -289.807142) (xy 375.337811 -289.781712) (xy 375.345644 -289.73146) (xy 375.361099 -289.683005)
			(xy 375.38381 -289.637498) (xy 375.413239 -289.596018) (xy 375.448687 -289.559547) (xy 375.489314 -289.528951)
			(xy 375.534157 -289.504956) (xy 375.582153 -289.48813) (xy 375.607072 -289.483038) (xy 375.631202 -289.478466)
			(xy 375.845578 -289.073082) (xy 375.835672 -289.050476) (xy 375.826709 -289.029398) (xy 375.814064 -288.985377)
			(xy 375.807649 -288.940026) (xy 375.807224 -288.917126) (xy 375.807732 -288.891219) (xy 375.815838 -288.840042)
			(xy 375.83185 -288.790763) (xy 375.855373 -288.744596) (xy 375.885829 -288.702677) (xy 375.922467 -288.666039)
			(xy 375.964386 -288.635583) (xy 376.010553 -288.61206) (xy 376.059832 -288.596048) (xy 376.111009 -288.587942)
			(xy 376.162823 -288.587942) (xy 376.214 -288.596048) (xy 376.263279 -288.61206) (xy 376.309446 -288.635583)
			(xy 376.351365 -288.666039) (xy 376.388003 -288.702677) (xy 376.418459 -288.744596) (xy 376.441982 -288.790763)
			(xy 376.457994 -288.840042) (xy 376.4661 -288.891219) (xy 376.466608 -288.917126) (xy 376.466153 -288.942575)
			(xy 376.458349 -288.992871) (xy 376.442899 -289.041367) (xy 376.420171 -289.086909) (xy 376.390707 -289.128411)
			(xy 376.355209 -289.164887) (xy 376.314521 -289.195466) (xy 376.269613 -289.21942) (xy 376.221553 -289.23618)
			(xy 376.196606 -289.24123) (xy 376.172476 -289.245802) (xy 375.9581 -289.651186) (xy 375.968006 -289.673792)
			(xy 375.976928 -289.694877) (xy 375.989478 -289.738907) (xy 375.99581 -289.78425) (xy 375.9962 -289.807142)
			(xy 377.216924 -289.807142) (xy 377.217411 -289.781712) (xy 377.225244 -289.73146) (xy 377.240699 -289.683005)
			(xy 377.26341 -289.637498) (xy 377.292839 -289.596018) (xy 377.328287 -289.559547) (xy 377.368914 -289.528951)
			(xy 377.413757 -289.504956) (xy 377.461753 -289.48813) (xy 377.486672 -289.483038) (xy 377.510802 -289.478466)
			(xy 377.725178 -289.073082) (xy 377.715272 -289.050476) (xy 377.706309 -289.029398) (xy 377.693664 -288.985377)
			(xy 377.687249 -288.940026) (xy 377.686824 -288.917126) (xy 377.687332 -288.891219) (xy 377.695438 -288.840042)
			(xy 377.71145 -288.790763) (xy 377.734973 -288.744596) (xy 377.765429 -288.702677) (xy 377.802067 -288.666039)
			(xy 377.843986 -288.635583) (xy 377.890153 -288.61206) (xy 377.939432 -288.596048) (xy 377.990609 -288.587942)
			(xy 378.042423 -288.587942) (xy 378.0936 -288.596048) (xy 378.142879 -288.61206) (xy 378.189046 -288.635583)
			(xy 378.230965 -288.666039) (xy 378.267603 -288.702677) (xy 378.298059 -288.744596) (xy 378.321582 -288.790763)
			(xy 378.337594 -288.840042) (xy 378.3457 -288.891219) (xy 378.346208 -288.917126) (xy 378.345753 -288.942575)
			(xy 378.337949 -288.992871) (xy 378.322499 -289.041367) (xy 378.299771 -289.086909) (xy 378.270307 -289.128411)
			(xy 378.234809 -289.164887) (xy 378.194121 -289.195466) (xy 378.149213 -289.21942) (xy 378.101153 -289.23618)
			(xy 378.076206 -289.24123) (xy 378.052076 -289.245802) (xy 377.8377 -289.651186) (xy 377.847606 -289.673792)
			(xy 377.856528 -289.694877) (xy 377.869078 -289.738907) (xy 377.87541 -289.78425) (xy 377.8758 -289.807142)
			(xy 379.096524 -289.807142) (xy 379.097011 -289.781712) (xy 379.104844 -289.73146) (xy 379.120299 -289.683005)
			(xy 379.14301 -289.637498) (xy 379.172439 -289.596018) (xy 379.207887 -289.559547) (xy 379.248514 -289.528951)
			(xy 379.293357 -289.504956) (xy 379.341353 -289.48813) (xy 379.366272 -289.483038) (xy 379.390402 -289.478466)
			(xy 379.604778 -289.073082) (xy 379.594872 -289.050476) (xy 379.585909 -289.029398) (xy 379.573264 -288.985377)
			(xy 379.566849 -288.940026) (xy 379.566424 -288.917126) (xy 379.566932 -288.891219) (xy 379.575038 -288.840042)
			(xy 379.59105 -288.790763) (xy 379.614573 -288.744596) (xy 379.645029 -288.702677) (xy 379.681667 -288.666039)
			(xy 379.723586 -288.635583) (xy 379.769753 -288.61206) (xy 379.819032 -288.596048) (xy 379.870209 -288.587942)
			(xy 379.922023 -288.587942) (xy 379.9732 -288.596048) (xy 380.022479 -288.61206) (xy 380.068646 -288.635583)
			(xy 380.110565 -288.666039) (xy 380.147203 -288.702677) (xy 380.177659 -288.744596) (xy 380.201182 -288.790763)
			(xy 380.217194 -288.840042) (xy 380.2253 -288.891219) (xy 380.225808 -288.917126) (xy 380.225353 -288.942575)
			(xy 380.217549 -288.992871) (xy 380.202099 -289.041367) (xy 380.179371 -289.086909) (xy 380.149907 -289.128411)
			(xy 380.114409 -289.164887) (xy 380.073721 -289.195466) (xy 380.028813 -289.21942) (xy 379.980753 -289.23618)
			(xy 379.955806 -289.24123) (xy 379.931676 -289.245802) (xy 379.7173 -289.651186) (xy 379.727206 -289.673792)
			(xy 379.736128 -289.694877) (xy 379.748678 -289.738907) (xy 379.75501 -289.78425) (xy 379.7554 -289.807142)
			(xy 380.976124 -289.807142) (xy 380.976611 -289.781712) (xy 380.984444 -289.73146) (xy 380.999899 -289.683005)
			(xy 381.02261 -289.637498) (xy 381.052039 -289.596018) (xy 381.087487 -289.559547) (xy 381.128114 -289.528951)
			(xy 381.172957 -289.504956) (xy 381.220953 -289.48813) (xy 381.245872 -289.483038) (xy 381.270002 -289.478466)
			(xy 381.484378 -289.073082) (xy 381.474472 -289.050476) (xy 381.465509 -289.029398) (xy 381.452864 -288.985377)
			(xy 381.446449 -288.940026) (xy 381.446024 -288.917126) (xy 381.446532 -288.891219) (xy 381.454638 -288.840042)
			(xy 381.47065 -288.790763) (xy 381.494173 -288.744596) (xy 381.524629 -288.702677) (xy 381.561267 -288.666039)
			(xy 381.603186 -288.635583) (xy 381.649353 -288.61206) (xy 381.698632 -288.596048) (xy 381.749809 -288.587942)
			(xy 381.801623 -288.587942) (xy 381.8528 -288.596048) (xy 381.902079 -288.61206) (xy 381.948246 -288.635583)
			(xy 381.990165 -288.666039) (xy 382.026803 -288.702677) (xy 382.057259 -288.744596) (xy 382.080782 -288.790763)
			(xy 382.096794 -288.840042) (xy 382.1049 -288.891219) (xy 382.105408 -288.917126) (xy 382.104953 -288.942575)
			(xy 382.097149 -288.992871) (xy 382.081699 -289.041367) (xy 382.058971 -289.086909) (xy 382.029507 -289.128411)
			(xy 381.994009 -289.164887) (xy 381.953321 -289.195466) (xy 381.908413 -289.21942) (xy 381.860353 -289.23618)
			(xy 381.835406 -289.24123) (xy 381.811276 -289.245802) (xy 381.5969 -289.651186) (xy 381.606806 -289.673792)
			(xy 381.615728 -289.694877) (xy 381.628278 -289.738907) (xy 381.63461 -289.78425) (xy 381.635 -289.807142)
			(xy 381.634492 -289.833029) (xy 381.626393 -289.884167) (xy 381.610394 -289.933407) (xy 381.586888 -289.979539)
			(xy 381.556456 -290.021426) (xy 381.519846 -290.058036) (xy 381.477959 -290.088468) (xy 381.431827 -290.111974)
			(xy 381.382587 -290.127973) (xy 381.331449 -290.136072) (xy 381.279675 -290.136072) (xy 381.228537 -290.127973)
			(xy 381.179297 -290.111974) (xy 381.133165 -290.088468) (xy 381.091278 -290.058036) (xy 381.054668 -290.021426)
			(xy 381.024236 -289.979539) (xy 381.00073 -289.933407) (xy 380.984731 -289.884167) (xy 380.976632 -289.833029)
			(xy 380.976124 -289.807142) (xy 379.7554 -289.807142) (xy 379.754892 -289.833029) (xy 379.746793 -289.884167)
			(xy 379.730794 -289.933407) (xy 379.707288 -289.979539) (xy 379.676856 -290.021426) (xy 379.640246 -290.058036)
			(xy 379.598359 -290.088468) (xy 379.552227 -290.111974) (xy 379.502987 -290.127973) (xy 379.451849 -290.136072)
			(xy 379.400075 -290.136072) (xy 379.348937 -290.127973) (xy 379.299697 -290.111974) (xy 379.253565 -290.088468)
			(xy 379.211678 -290.058036) (xy 379.175068 -290.021426) (xy 379.144636 -289.979539) (xy 379.12113 -289.933407)
			(xy 379.105131 -289.884167) (xy 379.097032 -289.833029) (xy 379.096524 -289.807142) (xy 377.8758 -289.807142)
			(xy 377.875292 -289.833029) (xy 377.867193 -289.884167) (xy 377.851194 -289.933407) (xy 377.827688 -289.979539)
			(xy 377.797256 -290.021426) (xy 377.760646 -290.058036) (xy 377.718759 -290.088468) (xy 377.672627 -290.111974)
			(xy 377.623387 -290.127973) (xy 377.572249 -290.136072) (xy 377.520475 -290.136072) (xy 377.469337 -290.127973)
			(xy 377.420097 -290.111974) (xy 377.373965 -290.088468) (xy 377.332078 -290.058036) (xy 377.295468 -290.021426)
			(xy 377.265036 -289.979539) (xy 377.24153 -289.933407) (xy 377.225531 -289.884167) (xy 377.217432 -289.833029)
			(xy 377.216924 -289.807142) (xy 375.9962 -289.807142) (xy 375.995692 -289.833029) (xy 375.987593 -289.884167)
			(xy 375.971594 -289.933407) (xy 375.948088 -289.979539) (xy 375.917656 -290.021426) (xy 375.881046 -290.058036)
			(xy 375.839159 -290.088468) (xy 375.793027 -290.111974) (xy 375.743787 -290.127973) (xy 375.692649 -290.136072)
			(xy 375.640875 -290.136072) (xy 375.589737 -290.127973) (xy 375.540497 -290.111974) (xy 375.494365 -290.088468)
			(xy 375.452478 -290.058036) (xy 375.415868 -290.021426) (xy 375.385436 -289.979539) (xy 375.36193 -289.933407)
			(xy 375.345931 -289.884167) (xy 375.337832 -289.833029) (xy 375.337324 -289.807142) (xy 374.1166 -289.807142)
			(xy 374.116092 -289.833029) (xy 374.107993 -289.884167) (xy 374.091994 -289.933407) (xy 374.068488 -289.979539)
			(xy 374.038056 -290.021426) (xy 374.001446 -290.058036) (xy 373.959559 -290.088468) (xy 373.913427 -290.111974)
			(xy 373.864187 -290.127973) (xy 373.813049 -290.136072) (xy 373.761275 -290.136072) (xy 373.710137 -290.127973)
			(xy 373.660897 -290.111974) (xy 373.614765 -290.088468) (xy 373.572878 -290.058036) (xy 373.536268 -290.021426)
			(xy 373.505836 -289.979539) (xy 373.48233 -289.933407) (xy 373.466331 -289.884167) (xy 373.458232 -289.833029)
			(xy 373.457724 -289.807142) (xy 372.237 -289.807142) (xy 372.236492 -289.833029) (xy 372.228393 -289.884167)
			(xy 372.212394 -289.933407) (xy 372.188888 -289.979539) (xy 372.158456 -290.021426) (xy 372.121846 -290.058036)
			(xy 372.079959 -290.088468) (xy 372.033827 -290.111974) (xy 371.984587 -290.127973) (xy 371.933449 -290.136072)
			(xy 371.881675 -290.136072) (xy 371.830537 -290.127973) (xy 371.781297 -290.111974) (xy 371.735165 -290.088468)
			(xy 371.693278 -290.058036) (xy 371.656668 -290.021426) (xy 371.626236 -289.979539) (xy 371.60273 -289.933407)
			(xy 371.586731 -289.884167) (xy 371.578632 -289.833029) (xy 371.578124 -289.807142) (xy 370.3574 -289.807142)
			(xy 370.356892 -289.833029) (xy 370.348793 -289.884167) (xy 370.332794 -289.933407) (xy 370.309288 -289.979539)
			(xy 370.278856 -290.021426) (xy 370.242246 -290.058036) (xy 370.200359 -290.088468) (xy 370.154227 -290.111974)
			(xy 370.104987 -290.127973) (xy 370.053849 -290.136072) (xy 370.002075 -290.136072) (xy 369.950937 -290.127973)
			(xy 369.901697 -290.111974) (xy 369.855565 -290.088468) (xy 369.813678 -290.058036) (xy 369.777068 -290.021426)
			(xy 369.746636 -289.979539) (xy 369.72313 -289.933407) (xy 369.707131 -289.884167) (xy 369.699032 -289.833029)
			(xy 369.698524 -289.807142) (xy 368.4778 -289.807142) (xy 368.477292 -289.833029) (xy 368.469193 -289.884167)
			(xy 368.453194 -289.933407) (xy 368.429688 -289.979539) (xy 368.399256 -290.021426) (xy 368.362646 -290.058036)
			(xy 368.320759 -290.088468) (xy 368.274627 -290.111974) (xy 368.225387 -290.127973) (xy 368.174249 -290.136072)
			(xy 368.122475 -290.136072) (xy 368.071337 -290.127973) (xy 368.022097 -290.111974) (xy 367.975965 -290.088468)
			(xy 367.934078 -290.058036) (xy 367.897468 -290.021426) (xy 367.867036 -289.979539) (xy 367.84353 -289.933407)
			(xy 367.827531 -289.884167) (xy 367.819432 -289.833029) (xy 367.818924 -289.807142) (xy 351.5614 -289.807142)
			(xy 351.560892 -289.833029) (xy 351.552793 -289.884167) (xy 351.536794 -289.933407) (xy 351.513288 -289.979539)
			(xy 351.482856 -290.021426) (xy 351.446246 -290.058036) (xy 351.404359 -290.088468) (xy 351.358227 -290.111974)
			(xy 351.308987 -290.127973) (xy 351.257849 -290.136072) (xy 351.206075 -290.136072) (xy 351.154937 -290.127973)
			(xy 351.105697 -290.111974) (xy 351.059565 -290.088468) (xy 351.017678 -290.058036) (xy 350.981068 -290.021426)
			(xy 350.950636 -289.979539) (xy 350.92713 -289.933407) (xy 350.911131 -289.884167) (xy 350.903032 -289.833029)
			(xy 350.902524 -289.807142) (xy 350.902524 -289.806634) (xy 350.902922 -289.783785) (xy 350.909275 -289.738531)
			(xy 350.921824 -289.694589) (xy 350.930718 -289.673538) (xy 350.940624 -289.650932) (xy 350.726756 -289.245802)
			(xy 350.702626 -289.24123) (xy 350.677682 -289.236182) (xy 350.629639 -289.219398) (xy 350.584746 -289.195428)
			(xy 350.544072 -289.164843) (xy 350.508582 -289.128369) (xy 350.479121 -289.086873) (xy 350.456389 -289.041341)
			(xy 350.440925 -288.992857) (xy 350.433099 -288.942571) (xy 350.432624 -288.917126) (xy 350.152208 -288.917126)
			(xy 350.1517 -288.943033) (xy 350.143594 -288.99421) (xy 350.127582 -289.043489) (xy 350.104059 -289.089656)
			(xy 350.073603 -289.131575) (xy 350.036965 -289.168213) (xy 349.995046 -289.198669) (xy 349.948879 -289.222192)
			(xy 349.8996 -289.238204) (xy 349.848423 -289.24631) (xy 349.796609 -289.24631) (xy 349.745432 -289.238204)
			(xy 349.696153 -289.222192) (xy 349.649986 -289.198669) (xy 349.608067 -289.168213) (xy 349.571429 -289.131575)
			(xy 349.540973 -289.089656) (xy 349.51745 -289.043489) (xy 349.501438 -288.99421) (xy 349.493332 -288.943033)
			(xy 349.492824 -288.917126) (xy 349.212408 -288.917126) (xy 349.211989 -288.940067) (xy 349.20556 -288.985498)
			(xy 349.192913 -289.029604) (xy 349.18396 -289.05073) (xy 349.174054 -289.073336) (xy 349.387922 -289.478466)
			(xy 349.412052 -289.483038) (xy 349.436973 -289.488138) (xy 349.484984 -289.504939) (xy 349.529843 -289.528919)
			(xy 349.570484 -289.559507) (xy 349.605941 -289.595978) (xy 349.635373 -289.637465) (xy 349.658079 -289.682981)
			(xy 349.673521 -289.731446) (xy 349.681331 -289.781709) (xy 349.6818 -289.807142) (xy 349.681292 -289.833029)
			(xy 349.673193 -289.884167) (xy 349.657194 -289.933407) (xy 349.633688 -289.979539) (xy 349.603256 -290.021426)
			(xy 349.566646 -290.058036) (xy 349.524759 -290.088468) (xy 349.478627 -290.111974) (xy 349.429387 -290.127973)
			(xy 349.378249 -290.136072) (xy 349.326475 -290.136072) (xy 349.275337 -290.127973) (xy 349.226097 -290.111974)
			(xy 349.179965 -290.088468) (xy 349.138078 -290.058036) (xy 349.101468 -290.021426) (xy 349.071036 -289.979539)
			(xy 349.04753 -289.933407) (xy 349.031531 -289.884167) (xy 349.023432 -289.833029) (xy 349.022924 -289.807142)
			(xy 349.022924 -289.806634) (xy 349.023322 -289.783785) (xy 349.029675 -289.738531) (xy 349.042224 -289.694589)
			(xy 349.051118 -289.673538) (xy 349.061024 -289.650932) (xy 348.847156 -289.245802) (xy 348.823026 -289.24123)
			(xy 348.798082 -289.236182) (xy 348.750039 -289.219398) (xy 348.705146 -289.195428) (xy 348.664472 -289.164843)
			(xy 348.628982 -289.128369) (xy 348.599521 -289.086873) (xy 348.576789 -289.041341) (xy 348.561325 -288.992857)
			(xy 348.553499 -288.942571) (xy 348.553024 -288.917126) (xy 348.272608 -288.917126) (xy 348.2721 -288.943033)
			(xy 348.263994 -288.99421) (xy 348.247982 -289.043489) (xy 348.224459 -289.089656) (xy 348.194003 -289.131575)
			(xy 348.157365 -289.168213) (xy 348.115446 -289.198669) (xy 348.069279 -289.222192) (xy 348.02 -289.238204)
			(xy 347.968823 -289.24631) (xy 347.917009 -289.24631) (xy 347.865832 -289.238204) (xy 347.816553 -289.222192)
			(xy 347.770386 -289.198669) (xy 347.728467 -289.168213) (xy 347.691829 -289.131575) (xy 347.661373 -289.089656)
			(xy 347.63785 -289.043489) (xy 347.621838 -288.99421) (xy 347.613732 -288.943033) (xy 347.613224 -288.917126)
			(xy 347.332808 -288.917126) (xy 347.332389 -288.940067) (xy 347.32596 -288.985498) (xy 347.313313 -289.029604)
			(xy 347.30436 -289.05073) (xy 347.294454 -289.073336) (xy 347.508322 -289.478466) (xy 347.532452 -289.483038)
			(xy 347.557373 -289.488138) (xy 347.605384 -289.504939) (xy 347.650243 -289.528919) (xy 347.690884 -289.559507)
			(xy 347.726341 -289.595978) (xy 347.755773 -289.637465) (xy 347.778479 -289.682981) (xy 347.793921 -289.731446)
			(xy 347.801731 -289.781709) (xy 347.8022 -289.807142) (xy 347.801692 -289.833029) (xy 347.793593 -289.884167)
			(xy 347.777594 -289.933407) (xy 347.754088 -289.979539) (xy 347.723656 -290.021426) (xy 347.687046 -290.058036)
			(xy 347.645159 -290.088468) (xy 347.599027 -290.111974) (xy 347.549787 -290.127973) (xy 347.498649 -290.136072)
			(xy 347.446875 -290.136072) (xy 347.395737 -290.127973) (xy 347.346497 -290.111974) (xy 347.300365 -290.088468)
			(xy 347.258478 -290.058036) (xy 347.221868 -290.021426) (xy 347.191436 -289.979539) (xy 347.16793 -289.933407)
			(xy 347.151931 -289.884167) (xy 347.143832 -289.833029) (xy 347.143324 -289.807142) (xy 347.143324 -289.806634)
			(xy 347.143722 -289.783785) (xy 347.150075 -289.738531) (xy 347.162624 -289.694589) (xy 347.171518 -289.673538)
			(xy 347.181424 -289.650932) (xy 346.967556 -289.245802) (xy 346.943426 -289.24123) (xy 346.918482 -289.236182)
			(xy 346.870439 -289.219398) (xy 346.825546 -289.195428) (xy 346.784872 -289.164843) (xy 346.749382 -289.128369)
			(xy 346.719921 -289.086873) (xy 346.697189 -289.041341) (xy 346.681725 -288.992857) (xy 346.673899 -288.942571)
			(xy 346.673424 -288.917126) (xy 346.393008 -288.917126) (xy 346.3925 -288.943033) (xy 346.384394 -288.99421)
			(xy 346.368382 -289.043489) (xy 346.344859 -289.089656) (xy 346.314403 -289.131575) (xy 346.277765 -289.168213)
			(xy 346.235846 -289.198669) (xy 346.189679 -289.222192) (xy 346.1404 -289.238204) (xy 346.089223 -289.24631)
			(xy 346.037409 -289.24631) (xy 345.986232 -289.238204) (xy 345.936953 -289.222192) (xy 345.890786 -289.198669)
			(xy 345.848867 -289.168213) (xy 345.812229 -289.131575) (xy 345.781773 -289.089656) (xy 345.75825 -289.043489)
			(xy 345.742238 -288.99421) (xy 345.734132 -288.943033) (xy 345.733624 -288.917126) (xy 345.453208 -288.917126)
			(xy 345.452789 -288.940067) (xy 345.44636 -288.985498) (xy 345.433713 -289.029604) (xy 345.42476 -289.05073)
			(xy 345.414854 -289.073336) (xy 345.628722 -289.478466) (xy 345.652852 -289.483038) (xy 345.677773 -289.488138)
			(xy 345.725784 -289.504939) (xy 345.770643 -289.528919) (xy 345.811284 -289.559507) (xy 345.846741 -289.595978)
			(xy 345.876173 -289.637465) (xy 345.898879 -289.682981) (xy 345.914321 -289.731446) (xy 345.922131 -289.781709)
			(xy 345.9226 -289.807142) (xy 345.922092 -289.833029) (xy 345.913993 -289.884167) (xy 345.897994 -289.933407)
			(xy 345.874488 -289.979539) (xy 345.844056 -290.021426) (xy 345.807446 -290.058036) (xy 345.765559 -290.088468)
			(xy 345.719427 -290.111974) (xy 345.670187 -290.127973) (xy 345.619049 -290.136072) (xy 345.567275 -290.136072)
			(xy 345.516137 -290.127973) (xy 345.466897 -290.111974) (xy 345.420765 -290.088468) (xy 345.378878 -290.058036)
			(xy 345.342268 -290.021426) (xy 345.311836 -289.979539) (xy 345.28833 -289.933407) (xy 345.272331 -289.884167)
			(xy 345.264232 -289.833029) (xy 345.263724 -289.807142) (xy 345.263724 -289.806634) (xy 345.264122 -289.783785)
			(xy 345.270475 -289.738531) (xy 345.283024 -289.694589) (xy 345.291918 -289.673538) (xy 345.301824 -289.650932)
			(xy 345.087956 -289.245802) (xy 345.063826 -289.24123) (xy 345.038882 -289.236182) (xy 344.990839 -289.219398)
			(xy 344.945946 -289.195428) (xy 344.905272 -289.164843) (xy 344.869782 -289.128369) (xy 344.840321 -289.086873)
			(xy 344.817589 -289.041341) (xy 344.802125 -288.992857) (xy 344.794299 -288.942571) (xy 344.793824 -288.917126)
			(xy 344.513408 -288.917126) (xy 344.5129 -288.943033) (xy 344.504794 -288.99421) (xy 344.488782 -289.043489)
			(xy 344.465259 -289.089656) (xy 344.434803 -289.131575) (xy 344.398165 -289.168213) (xy 344.356246 -289.198669)
			(xy 344.310079 -289.222192) (xy 344.2608 -289.238204) (xy 344.209623 -289.24631) (xy 344.157809 -289.24631)
			(xy 344.106632 -289.238204) (xy 344.057353 -289.222192) (xy 344.011186 -289.198669) (xy 343.969267 -289.168213)
			(xy 343.932629 -289.131575) (xy 343.902173 -289.089656) (xy 343.87865 -289.043489) (xy 343.862638 -288.99421)
			(xy 343.854532 -288.943033) (xy 343.854024 -288.917126) (xy 343.573608 -288.917126) (xy 343.573189 -288.940067)
			(xy 343.56676 -288.985498) (xy 343.554113 -289.029604) (xy 343.54516 -289.05073) (xy 343.535254 -289.073336)
			(xy 343.749122 -289.478466) (xy 343.773252 -289.483038) (xy 343.798173 -289.488138) (xy 343.846184 -289.504939)
			(xy 343.891043 -289.528919) (xy 343.931684 -289.559507) (xy 343.967141 -289.595978) (xy 343.996573 -289.637465)
			(xy 344.019279 -289.682981) (xy 344.034721 -289.731446) (xy 344.042531 -289.781709) (xy 344.043 -289.807142)
			(xy 344.042492 -289.833029) (xy 344.034393 -289.884167) (xy 344.018394 -289.933407) (xy 343.994888 -289.979539)
			(xy 343.964456 -290.021426) (xy 343.927846 -290.058036) (xy 343.885959 -290.088468) (xy 343.839827 -290.111974)
			(xy 343.790587 -290.127973) (xy 343.739449 -290.136072) (xy 343.687675 -290.136072) (xy 343.636537 -290.127973)
			(xy 343.587297 -290.111974) (xy 343.541165 -290.088468) (xy 343.499278 -290.058036) (xy 343.462668 -290.021426)
			(xy 343.432236 -289.979539) (xy 343.40873 -289.933407) (xy 343.392731 -289.884167) (xy 343.384632 -289.833029)
			(xy 343.384124 -289.807142) (xy 343.384124 -289.806634) (xy 343.384522 -289.783785) (xy 343.390875 -289.738531)
			(xy 343.403424 -289.694589) (xy 343.412318 -289.673538) (xy 343.422224 -289.650932) (xy 343.208356 -289.245802)
			(xy 343.184226 -289.24123) (xy 343.159282 -289.236182) (xy 343.111239 -289.219398) (xy 343.066346 -289.195428)
			(xy 343.025672 -289.164843) (xy 342.990182 -289.128369) (xy 342.960721 -289.086873) (xy 342.937989 -289.041341)
			(xy 342.922525 -288.992857) (xy 342.914699 -288.942571) (xy 342.914224 -288.917126) (xy 342.633808 -288.917126)
			(xy 342.6333 -288.943033) (xy 342.625194 -288.99421) (xy 342.609182 -289.043489) (xy 342.585659 -289.089656)
			(xy 342.555203 -289.131575) (xy 342.518565 -289.168213) (xy 342.476646 -289.198669) (xy 342.430479 -289.222192)
			(xy 342.3812 -289.238204) (xy 342.330023 -289.24631) (xy 342.278209 -289.24631) (xy 342.227032 -289.238204)
			(xy 342.177753 -289.222192) (xy 342.131586 -289.198669) (xy 342.089667 -289.168213) (xy 342.053029 -289.131575)
			(xy 342.022573 -289.089656) (xy 341.99905 -289.043489) (xy 341.983038 -288.99421) (xy 341.974932 -288.943033)
			(xy 341.974424 -288.917126) (xy 341.694008 -288.917126) (xy 341.693589 -288.940067) (xy 341.68716 -288.985498)
			(xy 341.674513 -289.029604) (xy 341.66556 -289.05073) (xy 341.655654 -289.073336) (xy 341.869522 -289.478466)
			(xy 341.893652 -289.483038) (xy 341.918573 -289.488138) (xy 341.966584 -289.504939) (xy 342.011443 -289.528919)
			(xy 342.052084 -289.559507) (xy 342.087541 -289.595978) (xy 342.116973 -289.637465) (xy 342.139679 -289.682981)
			(xy 342.155121 -289.731446) (xy 342.162931 -289.781709) (xy 342.1634 -289.807142) (xy 342.162892 -289.833029)
			(xy 342.154793 -289.884167) (xy 342.138794 -289.933407) (xy 342.115288 -289.979539) (xy 342.084856 -290.021426)
			(xy 342.048246 -290.058036) (xy 342.006359 -290.088468) (xy 341.960227 -290.111974) (xy 341.910987 -290.127973)
			(xy 341.859849 -290.136072) (xy 341.808075 -290.136072) (xy 341.756937 -290.127973) (xy 341.707697 -290.111974)
			(xy 341.661565 -290.088468) (xy 341.619678 -290.058036) (xy 341.583068 -290.021426) (xy 341.552636 -289.979539)
			(xy 341.52913 -289.933407) (xy 341.513131 -289.884167) (xy 341.505032 -289.833029) (xy 341.504524 -289.807142)
			(xy 341.504524 -289.806634) (xy 341.504922 -289.783785) (xy 341.511275 -289.738531) (xy 341.523824 -289.694589)
			(xy 341.532718 -289.673538) (xy 341.542624 -289.650932) (xy 341.328756 -289.245802) (xy 341.304626 -289.24123)
			(xy 341.279682 -289.236182) (xy 341.231639 -289.219398) (xy 341.186746 -289.195428) (xy 341.146072 -289.164843)
			(xy 341.110582 -289.128369) (xy 341.081121 -289.086873) (xy 341.058389 -289.041341) (xy 341.042925 -288.992857)
			(xy 341.035099 -288.942571) (xy 341.034624 -288.917126) (xy 340.754208 -288.917126) (xy 340.7537 -288.943033)
			(xy 340.745594 -288.99421) (xy 340.729582 -289.043489) (xy 340.706059 -289.089656) (xy 340.675603 -289.131575)
			(xy 340.638965 -289.168213) (xy 340.597046 -289.198669) (xy 340.550879 -289.222192) (xy 340.5016 -289.238204)
			(xy 340.450423 -289.24631) (xy 340.398609 -289.24631) (xy 340.347432 -289.238204) (xy 340.298153 -289.222192)
			(xy 340.251986 -289.198669) (xy 340.210067 -289.168213) (xy 340.173429 -289.131575) (xy 340.142973 -289.089656)
			(xy 340.11945 -289.043489) (xy 340.103438 -288.99421) (xy 340.095332 -288.943033) (xy 340.094824 -288.917126)
			(xy 339.814408 -288.917126) (xy 339.813989 -288.940067) (xy 339.80756 -288.985498) (xy 339.794913 -289.029604)
			(xy 339.78596 -289.05073) (xy 339.776054 -289.073336) (xy 339.989922 -289.478466) (xy 340.014052 -289.483038)
			(xy 340.038973 -289.488138) (xy 340.086984 -289.504939) (xy 340.131843 -289.528919) (xy 340.172484 -289.559507)
			(xy 340.207941 -289.595978) (xy 340.237373 -289.637465) (xy 340.260079 -289.682981) (xy 340.275521 -289.731446)
			(xy 340.283331 -289.781709) (xy 340.2838 -289.807142) (xy 340.283292 -289.833029) (xy 340.275193 -289.884167)
			(xy 340.259194 -289.933407) (xy 340.235688 -289.979539) (xy 340.205256 -290.021426) (xy 340.168646 -290.058036)
			(xy 340.126759 -290.088468) (xy 340.080627 -290.111974) (xy 340.031387 -290.127973) (xy 339.980249 -290.136072)
			(xy 339.928475 -290.136072) (xy 339.877337 -290.127973) (xy 339.828097 -290.111974) (xy 339.781965 -290.088468)
			(xy 339.740078 -290.058036) (xy 339.703468 -290.021426) (xy 339.673036 -289.979539) (xy 339.64953 -289.933407)
			(xy 339.633531 -289.884167) (xy 339.625432 -289.833029) (xy 339.624924 -289.807142) (xy 339.624924 -289.806634)
			(xy 339.625322 -289.783785) (xy 339.631675 -289.738531) (xy 339.644224 -289.694589) (xy 339.653118 -289.673538)
			(xy 339.663024 -289.650932) (xy 339.449156 -289.245802) (xy 339.425026 -289.24123) (xy 339.400082 -289.236182)
			(xy 339.352039 -289.219398) (xy 339.307146 -289.195428) (xy 339.266472 -289.164843) (xy 339.230982 -289.128369)
			(xy 339.201521 -289.086873) (xy 339.178789 -289.041341) (xy 339.163325 -288.992857) (xy 339.155499 -288.942571)
			(xy 339.155024 -288.917126) (xy 338.874608 -288.917126) (xy 338.8741 -288.943033) (xy 338.865994 -288.99421)
			(xy 338.849982 -289.043489) (xy 338.826459 -289.089656) (xy 338.796003 -289.131575) (xy 338.759365 -289.168213)
			(xy 338.717446 -289.198669) (xy 338.671279 -289.222192) (xy 338.622 -289.238204) (xy 338.570823 -289.24631)
			(xy 338.519009 -289.24631) (xy 338.467832 -289.238204) (xy 338.418553 -289.222192) (xy 338.372386 -289.198669)
			(xy 338.330467 -289.168213) (xy 338.293829 -289.131575) (xy 338.263373 -289.089656) (xy 338.23985 -289.043489)
			(xy 338.223838 -288.99421) (xy 338.215732 -288.943033) (xy 338.215224 -288.917126) (xy 336.995008 -288.917126)
			(xy 336.9945 -288.943033) (xy 336.986394 -288.99421) (xy 336.970382 -289.043489) (xy 336.946859 -289.089656)
			(xy 336.916403 -289.131575) (xy 336.879765 -289.168213) (xy 336.837846 -289.198669) (xy 336.791679 -289.222192)
			(xy 336.7424 -289.238204) (xy 336.691223 -289.24631) (xy 336.639409 -289.24631) (xy 336.588232 -289.238204)
			(xy 336.538953 -289.222192) (xy 336.492786 -289.198669) (xy 336.450867 -289.168213) (xy 336.414229 -289.131575)
			(xy 336.383773 -289.089656) (xy 336.36025 -289.043489) (xy 336.344238 -288.99421) (xy 336.336132 -288.943033)
			(xy 336.335624 -288.917126) (xy 136.04494 -288.917126) (xy 136.044432 -288.943033) (xy 136.036326 -288.99421)
			(xy 136.020314 -289.043489) (xy 135.996791 -289.089656) (xy 135.966335 -289.131575) (xy 135.929697 -289.168213)
			(xy 135.887778 -289.198669) (xy 135.841611 -289.222192) (xy 135.792332 -289.238204) (xy 135.741155 -289.24631)
			(xy 135.689341 -289.24631) (xy 135.638164 -289.238204) (xy 135.588885 -289.222192) (xy 135.542718 -289.198669)
			(xy 135.500799 -289.168213) (xy 135.464161 -289.131575) (xy 135.433705 -289.089656) (xy 135.410182 -289.043489)
			(xy 135.39417 -288.99421) (xy 135.386064 -288.943033) (xy 135.385556 -288.917126) (xy 135.386153 -288.889409)
			(xy 135.395474 -288.834762) (xy 135.404098 -288.808414) (xy 135.411972 -288.786316) (xy 135.20674 -288.431224)
			(xy 135.18388 -288.426906) (xy 135.159064 -288.421716) (xy 135.111285 -288.404766) (xy 135.066665 -288.380698)
			(xy 135.026258 -288.350081) (xy 134.991016 -288.313637) (xy 134.961772 -288.272226) (xy 134.939214 -288.226825)
			(xy 134.923875 -288.178504) (xy 134.916118 -288.128404) (xy 134.915656 -288.103056) (xy 132.75564 -288.103056)
			(xy 132.755038 -288.130773) (xy 132.74572 -288.18542) (xy 132.737098 -288.211768) (xy 132.729478 -288.233866)
			(xy 132.934456 -288.588958) (xy 132.957316 -288.593276) (xy 132.982127 -288.598486) (xy 133.029905 -288.615434)
			(xy 133.074524 -288.6395) (xy 133.114931 -288.670114) (xy 133.150173 -288.706556) (xy 133.179418 -288.747964)
			(xy 133.201977 -288.793363) (xy 133.217317 -288.841681) (xy 133.225077 -288.891779) (xy 133.22554 -288.917126)
			(xy 133.225032 -288.943033) (xy 133.216926 -288.99421) (xy 133.200914 -289.043489) (xy 133.177391 -289.089656)
			(xy 133.146935 -289.131575) (xy 133.110297 -289.168213) (xy 133.068378 -289.198669) (xy 133.022211 -289.222192)
			(xy 132.972932 -289.238204) (xy 132.921755 -289.24631) (xy 132.869941 -289.24631) (xy 132.818764 -289.238204)
			(xy 132.769485 -289.222192) (xy 132.723318 -289.198669) (xy 132.681399 -289.168213) (xy 132.644761 -289.131575)
			(xy 132.614305 -289.089656) (xy 132.590782 -289.043489) (xy 132.57477 -288.99421) (xy 132.566664 -288.943033)
			(xy 132.566156 -288.917126) (xy 132.566753 -288.889409) (xy 132.576074 -288.834762) (xy 132.584698 -288.808414)
			(xy 132.592572 -288.786316) (xy 132.387594 -288.431224) (xy 132.364734 -288.426906) (xy 132.339899 -288.421756)
			(xy 132.292089 -288.404821) (xy 132.247438 -288.380764) (xy 132.206999 -288.350151) (xy 132.171726 -288.313705)
			(xy 132.142451 -288.272287) (xy 132.119866 -288.226873) (xy 132.104504 -288.178536) (xy 132.096726 -288.128416)
			(xy 132.096256 -288.103056) (xy 130.87604 -288.103056) (xy 130.875438 -288.130773) (xy 130.86612 -288.18542)
			(xy 130.857498 -288.211768) (xy 130.849878 -288.233866) (xy 131.054856 -288.588958) (xy 131.077716 -288.593276)
			(xy 131.102527 -288.598486) (xy 131.150305 -288.615434) (xy 131.194924 -288.6395) (xy 131.235331 -288.670114)
			(xy 131.270573 -288.706556) (xy 131.299818 -288.747964) (xy 131.322377 -288.793363) (xy 131.337717 -288.841681)
			(xy 131.345477 -288.891779) (xy 131.34594 -288.917126) (xy 131.345432 -288.943033) (xy 131.337326 -288.99421)
			(xy 131.321314 -289.043489) (xy 131.297791 -289.089656) (xy 131.267335 -289.131575) (xy 131.230697 -289.168213)
			(xy 131.188778 -289.198669) (xy 131.142611 -289.222192) (xy 131.093332 -289.238204) (xy 131.042155 -289.24631)
			(xy 130.990341 -289.24631) (xy 130.939164 -289.238204) (xy 130.889885 -289.222192) (xy 130.843718 -289.198669)
			(xy 130.801799 -289.168213) (xy 130.765161 -289.131575) (xy 130.734705 -289.089656) (xy 130.711182 -289.043489)
			(xy 130.69517 -288.99421) (xy 130.687064 -288.943033) (xy 130.686556 -288.917126) (xy 130.687153 -288.889409)
			(xy 130.696474 -288.834762) (xy 130.705098 -288.808414) (xy 130.712972 -288.786316) (xy 130.507994 -288.431224)
			(xy 130.485134 -288.426906) (xy 130.460299 -288.421756) (xy 130.412489 -288.404821) (xy 130.367838 -288.380764)
			(xy 130.327399 -288.350151) (xy 130.292126 -288.313705) (xy 130.262851 -288.272287) (xy 130.240266 -288.226873)
			(xy 130.224904 -288.178536) (xy 130.217126 -288.128416) (xy 130.216656 -288.103056) (xy 128.99644 -288.103056)
			(xy 128.995838 -288.130773) (xy 128.98652 -288.18542) (xy 128.977898 -288.211768) (xy 128.970278 -288.233866)
			(xy 129.175256 -288.588958) (xy 129.198116 -288.593276) (xy 129.222927 -288.598486) (xy 129.270705 -288.615434)
			(xy 129.315324 -288.6395) (xy 129.355731 -288.670114) (xy 129.390973 -288.706556) (xy 129.420218 -288.747964)
			(xy 129.442777 -288.793363) (xy 129.458117 -288.841681) (xy 129.465877 -288.891779) (xy 129.46634 -288.917126)
			(xy 129.465832 -288.943033) (xy 129.457726 -288.99421) (xy 129.441714 -289.043489) (xy 129.418191 -289.089656)
			(xy 129.387735 -289.131575) (xy 129.351097 -289.168213) (xy 129.309178 -289.198669) (xy 129.263011 -289.222192)
			(xy 129.213732 -289.238204) (xy 129.162555 -289.24631) (xy 129.110741 -289.24631) (xy 129.059564 -289.238204)
			(xy 129.010285 -289.222192) (xy 128.964118 -289.198669) (xy 128.922199 -289.168213) (xy 128.885561 -289.131575)
			(xy 128.855105 -289.089656) (xy 128.831582 -289.043489) (xy 128.81557 -288.99421) (xy 128.807464 -288.943033)
			(xy 128.806956 -288.917126) (xy 128.807553 -288.889409) (xy 128.816874 -288.834762) (xy 128.825498 -288.808414)
			(xy 128.833372 -288.786316) (xy 128.628394 -288.431224) (xy 128.605534 -288.426906) (xy 128.580699 -288.421756)
			(xy 128.532889 -288.404821) (xy 128.488238 -288.380764) (xy 128.447799 -288.350151) (xy 128.412526 -288.313705)
			(xy 128.383251 -288.272287) (xy 128.360666 -288.226873) (xy 128.345304 -288.178536) (xy 128.337526 -288.128416)
			(xy 128.337056 -288.103056) (xy 127.11684 -288.103056) (xy 127.116238 -288.130773) (xy 127.10692 -288.18542)
			(xy 127.098298 -288.211768) (xy 127.090678 -288.233866) (xy 127.295656 -288.588958) (xy 127.318516 -288.593276)
			(xy 127.343327 -288.598486) (xy 127.391105 -288.615434) (xy 127.435724 -288.6395) (xy 127.476131 -288.670114)
			(xy 127.511373 -288.706556) (xy 127.540618 -288.747964) (xy 127.563177 -288.793363) (xy 127.578517 -288.841681)
			(xy 127.586277 -288.891779) (xy 127.58674 -288.917126) (xy 127.586232 -288.943033) (xy 127.578126 -288.99421)
			(xy 127.562114 -289.043489) (xy 127.538591 -289.089656) (xy 127.508135 -289.131575) (xy 127.471497 -289.168213)
			(xy 127.429578 -289.198669) (xy 127.383411 -289.222192) (xy 127.334132 -289.238204) (xy 127.282955 -289.24631)
			(xy 127.231141 -289.24631) (xy 127.179964 -289.238204) (xy 127.130685 -289.222192) (xy 127.084518 -289.198669)
			(xy 127.042599 -289.168213) (xy 127.005961 -289.131575) (xy 126.975505 -289.089656) (xy 126.951982 -289.043489)
			(xy 126.93597 -288.99421) (xy 126.927864 -288.943033) (xy 126.927356 -288.917126) (xy 126.927953 -288.889409)
			(xy 126.937274 -288.834762) (xy 126.945898 -288.808414) (xy 126.953772 -288.786316) (xy 126.748794 -288.431224)
			(xy 126.725934 -288.426906) (xy 126.701099 -288.421756) (xy 126.653289 -288.404821) (xy 126.608638 -288.380764)
			(xy 126.568199 -288.350151) (xy 126.532926 -288.313705) (xy 126.503651 -288.272287) (xy 126.481066 -288.226873)
			(xy 126.465704 -288.178536) (xy 126.457926 -288.128416) (xy 126.457456 -288.103056) (xy 125.23724 -288.103056)
			(xy 125.236638 -288.130773) (xy 125.22732 -288.18542) (xy 125.218698 -288.211768) (xy 125.211078 -288.233866)
			(xy 125.416056 -288.588958) (xy 125.438916 -288.593276) (xy 125.463727 -288.598486) (xy 125.511505 -288.615434)
			(xy 125.556124 -288.6395) (xy 125.596531 -288.670114) (xy 125.631773 -288.706556) (xy 125.661018 -288.747964)
			(xy 125.683577 -288.793363) (xy 125.698917 -288.841681) (xy 125.706677 -288.891779) (xy 125.70714 -288.917126)
			(xy 125.706632 -288.943033) (xy 125.698526 -288.99421) (xy 125.682514 -289.043489) (xy 125.658991 -289.089656)
			(xy 125.628535 -289.131575) (xy 125.591897 -289.168213) (xy 125.549978 -289.198669) (xy 125.503811 -289.222192)
			(xy 125.454532 -289.238204) (xy 125.403355 -289.24631) (xy 125.351541 -289.24631) (xy 125.300364 -289.238204)
			(xy 125.251085 -289.222192) (xy 125.204918 -289.198669) (xy 125.162999 -289.168213) (xy 125.126361 -289.131575)
			(xy 125.095905 -289.089656) (xy 125.072382 -289.043489) (xy 125.05637 -288.99421) (xy 125.048264 -288.943033)
			(xy 125.047756 -288.917126) (xy 125.048353 -288.889409) (xy 125.057674 -288.834762) (xy 125.066298 -288.808414)
			(xy 125.074172 -288.786316) (xy 124.869194 -288.431224) (xy 124.846334 -288.426906) (xy 124.821499 -288.421756)
			(xy 124.773689 -288.404821) (xy 124.729038 -288.380764) (xy 124.688599 -288.350151) (xy 124.653326 -288.313705)
			(xy 124.624051 -288.272287) (xy 124.601466 -288.226873) (xy 124.586104 -288.178536) (xy 124.578326 -288.128416)
			(xy 124.577856 -288.103056) (xy 123.35764 -288.103056) (xy 123.357038 -288.130773) (xy 123.34772 -288.18542)
			(xy 123.339098 -288.211768) (xy 123.331478 -288.233866) (xy 123.536456 -288.588958) (xy 123.559316 -288.593276)
			(xy 123.584127 -288.598486) (xy 123.631905 -288.615434) (xy 123.676524 -288.6395) (xy 123.716931 -288.670114)
			(xy 123.752173 -288.706556) (xy 123.781418 -288.747964) (xy 123.803977 -288.793363) (xy 123.819317 -288.841681)
			(xy 123.827077 -288.891779) (xy 123.82754 -288.917126) (xy 123.827032 -288.943033) (xy 123.818926 -288.99421)
			(xy 123.802914 -289.043489) (xy 123.779391 -289.089656) (xy 123.748935 -289.131575) (xy 123.712297 -289.168213)
			(xy 123.670378 -289.198669) (xy 123.624211 -289.222192) (xy 123.574932 -289.238204) (xy 123.523755 -289.24631)
			(xy 123.471941 -289.24631) (xy 123.420764 -289.238204) (xy 123.371485 -289.222192) (xy 123.325318 -289.198669)
			(xy 123.283399 -289.168213) (xy 123.246761 -289.131575) (xy 123.216305 -289.089656) (xy 123.192782 -289.043489)
			(xy 123.17677 -288.99421) (xy 123.168664 -288.943033) (xy 123.168156 -288.917126) (xy 123.168753 -288.889409)
			(xy 123.178074 -288.834762) (xy 123.186698 -288.808414) (xy 123.194572 -288.786316) (xy 122.989594 -288.431224)
			(xy 122.966734 -288.426906) (xy 122.941899 -288.421756) (xy 122.894089 -288.404821) (xy 122.849438 -288.380764)
			(xy 122.808999 -288.350151) (xy 122.773726 -288.313705) (xy 122.744451 -288.272287) (xy 122.721866 -288.226873)
			(xy 122.706504 -288.178536) (xy 122.698726 -288.128416) (xy 122.698256 -288.103056) (xy 121.47804 -288.103056)
			(xy 121.477438 -288.130773) (xy 121.46812 -288.18542) (xy 121.459498 -288.211768) (xy 121.451624 -288.233866)
			(xy 121.656856 -288.588958) (xy 121.679716 -288.593276) (xy 121.704527 -288.598486) (xy 121.752305 -288.615434)
			(xy 121.796924 -288.6395) (xy 121.837331 -288.670114) (xy 121.872573 -288.706556) (xy 121.901818 -288.747964)
			(xy 121.924377 -288.793363) (xy 121.939717 -288.841681) (xy 121.947477 -288.891779) (xy 121.94794 -288.917126)
			(xy 121.947432 -288.943033) (xy 121.939326 -288.99421) (xy 121.923314 -289.043489) (xy 121.899791 -289.089656)
			(xy 121.869335 -289.131575) (xy 121.832697 -289.168213) (xy 121.790778 -289.198669) (xy 121.744611 -289.222192)
			(xy 121.695332 -289.238204) (xy 121.644155 -289.24631) (xy 121.592341 -289.24631) (xy 121.541164 -289.238204)
			(xy 121.491885 -289.222192) (xy 121.445718 -289.198669) (xy 121.403799 -289.168213) (xy 121.367161 -289.131575)
			(xy 121.336705 -289.089656) (xy 121.313182 -289.043489) (xy 121.29717 -288.99421) (xy 121.289064 -288.943033)
			(xy 121.288556 -288.917126) (xy 121.289153 -288.889409) (xy 121.298474 -288.834762) (xy 121.307098 -288.808414)
			(xy 121.314972 -288.786316) (xy 121.10974 -288.431224) (xy 121.08688 -288.426906) (xy 121.062064 -288.421716)
			(xy 121.014285 -288.404766) (xy 120.969665 -288.380698) (xy 120.929258 -288.350081) (xy 120.894016 -288.313637)
			(xy 120.864772 -288.272226) (xy 120.842214 -288.226825) (xy 120.826875 -288.178504) (xy 120.819118 -288.128404)
			(xy 120.818656 -288.103056) (xy 104.56164 -288.103056) (xy 104.561218 -288.128404) (xy 104.553436 -288.178499)
			(xy 104.53808 -288.226813) (xy 104.515512 -288.272208) (xy 104.486262 -288.313614) (xy 104.451021 -288.350057)
			(xy 104.410618 -288.380678) (xy 104.366005 -288.404755) (xy 104.318232 -288.421722) (xy 104.293416 -288.426906)
			(xy 104.270556 -288.431224) (xy 104.065324 -288.786316) (xy 104.073198 -288.808414) (xy 104.08184 -288.834757)
			(xy 104.091154 -288.889407) (xy 104.09174 -288.917126) (xy 104.091232 -288.943033) (xy 104.083126 -288.99421)
			(xy 104.067114 -289.043489) (xy 104.043591 -289.089656) (xy 104.013135 -289.131575) (xy 103.976497 -289.168213)
			(xy 103.934578 -289.198669) (xy 103.888411 -289.222192) (xy 103.839132 -289.238204) (xy 103.787955 -289.24631)
			(xy 103.736141 -289.24631) (xy 103.684964 -289.238204) (xy 103.635685 -289.222192) (xy 103.589518 -289.198669)
			(xy 103.547599 -289.168213) (xy 103.510961 -289.131575) (xy 103.480505 -289.089656) (xy 103.456982 -289.043489)
			(xy 103.44097 -288.99421) (xy 103.432864 -288.943033) (xy 103.432356 -288.917126) (xy 103.15194 -288.917126)
			(xy 103.151518 -288.940067) (xy 103.14509 -288.985498) (xy 103.132444 -289.029604) (xy 103.123492 -289.05073)
			(xy 103.113586 -289.073336) (xy 103.327454 -289.478466) (xy 103.351584 -289.483038) (xy 103.37651 -289.488115)
			(xy 103.424521 -289.50492) (xy 103.469379 -289.528904) (xy 103.510019 -289.559496) (xy 103.545476 -289.59597)
			(xy 103.574906 -289.637459) (xy 103.597612 -289.682977) (xy 103.613053 -289.731444) (xy 103.620863 -289.781708)
			(xy 103.621332 -289.807142) (xy 119.878856 -289.807142) (xy 119.879399 -289.781715) (xy 119.887229 -289.731468)
			(xy 119.90268 -289.683018) (xy 119.925386 -289.637514) (xy 119.954808 -289.596036) (xy 119.990248 -289.559565)
			(xy 120.030867 -289.528967) (xy 120.075701 -289.504967) (xy 120.123688 -289.488134) (xy 120.148604 -289.483038)
			(xy 120.172734 -289.478466) (xy 120.38711 -289.073082) (xy 120.377204 -289.050476) (xy 120.368243 -289.029398)
			(xy 120.355596 -288.985377) (xy 120.349182 -288.940026) (xy 120.348756 -288.917126) (xy 120.349264 -288.891219)
			(xy 120.35737 -288.840042) (xy 120.373382 -288.790763) (xy 120.396905 -288.744596) (xy 120.427361 -288.702677)
			(xy 120.463999 -288.666039) (xy 120.505918 -288.635583) (xy 120.552085 -288.61206) (xy 120.601364 -288.596048)
			(xy 120.652541 -288.587942) (xy 120.704355 -288.587942) (xy 120.755532 -288.596048) (xy 120.804811 -288.61206)
			(xy 120.850978 -288.635583) (xy 120.892897 -288.666039) (xy 120.929535 -288.702677) (xy 120.959991 -288.744596)
			(xy 120.983514 -288.790763) (xy 120.999526 -288.840042) (xy 121.007632 -288.891219) (xy 121.00814 -288.917126)
			(xy 121.007659 -288.942574) (xy 120.999856 -288.992867) (xy 120.984408 -289.041361) (xy 120.961683 -289.086901)
			(xy 120.932222 -289.128403) (xy 120.896727 -289.164878) (xy 120.856043 -289.195458) (xy 120.811139 -289.219415)
			(xy 120.763084 -289.236178) (xy 120.738138 -289.24123) (xy 120.714008 -289.245802) (xy 120.499632 -289.651186)
			(xy 120.509538 -289.673792) (xy 120.518456 -289.694878) (xy 120.531008 -289.738907) (xy 120.537342 -289.78425)
			(xy 120.537732 -289.807142) (xy 121.758456 -289.807142) (xy 121.758999 -289.781715) (xy 121.766829 -289.731468)
			(xy 121.78228 -289.683018) (xy 121.804986 -289.637514) (xy 121.834408 -289.596036) (xy 121.869848 -289.559565)
			(xy 121.910467 -289.528967) (xy 121.955301 -289.504967) (xy 122.003288 -289.488134) (xy 122.028204 -289.483038)
			(xy 122.052334 -289.478466) (xy 122.26671 -289.073082) (xy 122.256804 -289.050476) (xy 122.247843 -289.029398)
			(xy 122.235196 -288.985377) (xy 122.228782 -288.940026) (xy 122.228356 -288.917126) (xy 122.228864 -288.891219)
			(xy 122.23697 -288.840042) (xy 122.252982 -288.790763) (xy 122.276505 -288.744596) (xy 122.306961 -288.702677)
			(xy 122.343599 -288.666039) (xy 122.385518 -288.635583) (xy 122.431685 -288.61206) (xy 122.480964 -288.596048)
			(xy 122.532141 -288.587942) (xy 122.583955 -288.587942) (xy 122.635132 -288.596048) (xy 122.684411 -288.61206)
			(xy 122.730578 -288.635583) (xy 122.772497 -288.666039) (xy 122.809135 -288.702677) (xy 122.839591 -288.744596)
			(xy 122.863114 -288.790763) (xy 122.879126 -288.840042) (xy 122.887232 -288.891219) (xy 122.88774 -288.917126)
			(xy 122.887259 -288.942574) (xy 122.879456 -288.992867) (xy 122.864008 -289.041361) (xy 122.841283 -289.086901)
			(xy 122.811822 -289.128403) (xy 122.776327 -289.164878) (xy 122.735643 -289.195458) (xy 122.690739 -289.219415)
			(xy 122.642684 -289.236178) (xy 122.617738 -289.24123) (xy 122.593608 -289.245802) (xy 122.379232 -289.651186)
			(xy 122.389138 -289.673792) (xy 122.398056 -289.694878) (xy 122.410608 -289.738907) (xy 122.416942 -289.78425)
			(xy 122.417332 -289.807142) (xy 123.638056 -289.807142) (xy 123.638599 -289.781715) (xy 123.646429 -289.731468)
			(xy 123.66188 -289.683018) (xy 123.684586 -289.637514) (xy 123.714008 -289.596036) (xy 123.749448 -289.559565)
			(xy 123.790067 -289.528967) (xy 123.834901 -289.504967) (xy 123.882888 -289.488134) (xy 123.907804 -289.483038)
			(xy 123.931934 -289.478466) (xy 124.14631 -289.073082) (xy 124.136404 -289.050476) (xy 124.127443 -289.029398)
			(xy 124.114796 -288.985377) (xy 124.108382 -288.940026) (xy 124.107956 -288.917126) (xy 124.108464 -288.891219)
			(xy 124.11657 -288.840042) (xy 124.132582 -288.790763) (xy 124.156105 -288.744596) (xy 124.186561 -288.702677)
			(xy 124.223199 -288.666039) (xy 124.265118 -288.635583) (xy 124.311285 -288.61206) (xy 124.360564 -288.596048)
			(xy 124.411741 -288.587942) (xy 124.463555 -288.587942) (xy 124.514732 -288.596048) (xy 124.564011 -288.61206)
			(xy 124.610178 -288.635583) (xy 124.652097 -288.666039) (xy 124.688735 -288.702677) (xy 124.719191 -288.744596)
			(xy 124.742714 -288.790763) (xy 124.758726 -288.840042) (xy 124.766832 -288.891219) (xy 124.76734 -288.917126)
			(xy 124.766859 -288.942574) (xy 124.759056 -288.992867) (xy 124.743608 -289.041361) (xy 124.720883 -289.086901)
			(xy 124.691422 -289.128403) (xy 124.655927 -289.164878) (xy 124.615243 -289.195458) (xy 124.570339 -289.219415)
			(xy 124.522284 -289.236178) (xy 124.497338 -289.24123) (xy 124.473208 -289.245802) (xy 124.258832 -289.651186)
			(xy 124.268738 -289.673792) (xy 124.277656 -289.694878) (xy 124.290208 -289.738907) (xy 124.296542 -289.78425)
			(xy 124.296932 -289.807142) (xy 125.517656 -289.807142) (xy 125.518199 -289.781715) (xy 125.526029 -289.731468)
			(xy 125.54148 -289.683018) (xy 125.564186 -289.637514) (xy 125.593608 -289.596036) (xy 125.629048 -289.559565)
			(xy 125.669667 -289.528967) (xy 125.714501 -289.504967) (xy 125.762488 -289.488134) (xy 125.787404 -289.483038)
			(xy 125.811534 -289.478466) (xy 126.02591 -289.073082) (xy 126.016004 -289.050476) (xy 126.007043 -289.029398)
			(xy 125.994396 -288.985377) (xy 125.987982 -288.940026) (xy 125.987556 -288.917126) (xy 125.988064 -288.891219)
			(xy 125.99617 -288.840042) (xy 126.012182 -288.790763) (xy 126.035705 -288.744596) (xy 126.066161 -288.702677)
			(xy 126.102799 -288.666039) (xy 126.144718 -288.635583) (xy 126.190885 -288.61206) (xy 126.240164 -288.596048)
			(xy 126.291341 -288.587942) (xy 126.343155 -288.587942) (xy 126.394332 -288.596048) (xy 126.443611 -288.61206)
			(xy 126.489778 -288.635583) (xy 126.531697 -288.666039) (xy 126.568335 -288.702677) (xy 126.598791 -288.744596)
			(xy 126.622314 -288.790763) (xy 126.638326 -288.840042) (xy 126.646432 -288.891219) (xy 126.64694 -288.917126)
			(xy 126.646459 -288.942574) (xy 126.638656 -288.992867) (xy 126.623208 -289.041361) (xy 126.600483 -289.086901)
			(xy 126.571022 -289.128403) (xy 126.535527 -289.164878) (xy 126.494843 -289.195458) (xy 126.449939 -289.219415)
			(xy 126.401884 -289.236178) (xy 126.376938 -289.24123) (xy 126.352808 -289.245802) (xy 126.138432 -289.651186)
			(xy 126.148338 -289.673792) (xy 126.157256 -289.694878) (xy 126.169808 -289.738907) (xy 126.176142 -289.78425)
			(xy 126.176532 -289.807142) (xy 127.397256 -289.807142) (xy 127.397799 -289.781715) (xy 127.405629 -289.731468)
			(xy 127.42108 -289.683018) (xy 127.443786 -289.637514) (xy 127.473208 -289.596036) (xy 127.508648 -289.559565)
			(xy 127.549267 -289.528967) (xy 127.594101 -289.504967) (xy 127.642088 -289.488134) (xy 127.667004 -289.483038)
			(xy 127.691134 -289.478466) (xy 127.90551 -289.073082) (xy 127.895604 -289.050476) (xy 127.886643 -289.029398)
			(xy 127.873996 -288.985377) (xy 127.867582 -288.940026) (xy 127.867156 -288.917126) (xy 127.867664 -288.891219)
			(xy 127.87577 -288.840042) (xy 127.891782 -288.790763) (xy 127.915305 -288.744596) (xy 127.945761 -288.702677)
			(xy 127.982399 -288.666039) (xy 128.024318 -288.635583) (xy 128.070485 -288.61206) (xy 128.119764 -288.596048)
			(xy 128.170941 -288.587942) (xy 128.222755 -288.587942) (xy 128.273932 -288.596048) (xy 128.323211 -288.61206)
			(xy 128.369378 -288.635583) (xy 128.411297 -288.666039) (xy 128.447935 -288.702677) (xy 128.478391 -288.744596)
			(xy 128.501914 -288.790763) (xy 128.517926 -288.840042) (xy 128.526032 -288.891219) (xy 128.52654 -288.917126)
			(xy 128.526059 -288.942574) (xy 128.518256 -288.992867) (xy 128.502808 -289.041361) (xy 128.480083 -289.086901)
			(xy 128.450622 -289.128403) (xy 128.415127 -289.164878) (xy 128.374443 -289.195458) (xy 128.329539 -289.219415)
			(xy 128.281484 -289.236178) (xy 128.256538 -289.24123) (xy 128.232408 -289.245802) (xy 128.018032 -289.651186)
			(xy 128.027938 -289.673792) (xy 128.036856 -289.694878) (xy 128.049408 -289.738907) (xy 128.055742 -289.78425)
			(xy 128.056132 -289.807142) (xy 129.276856 -289.807142) (xy 129.277399 -289.781715) (xy 129.285229 -289.731468)
			(xy 129.30068 -289.683018) (xy 129.323386 -289.637514) (xy 129.352808 -289.596036) (xy 129.388248 -289.559565)
			(xy 129.428867 -289.528967) (xy 129.473701 -289.504967) (xy 129.521688 -289.488134) (xy 129.546604 -289.483038)
			(xy 129.570734 -289.478466) (xy 129.78511 -289.073082) (xy 129.775204 -289.050476) (xy 129.766243 -289.029398)
			(xy 129.753596 -288.985377) (xy 129.747182 -288.940026) (xy 129.746756 -288.917126) (xy 129.747264 -288.891219)
			(xy 129.75537 -288.840042) (xy 129.771382 -288.790763) (xy 129.794905 -288.744596) (xy 129.825361 -288.702677)
			(xy 129.861999 -288.666039) (xy 129.903918 -288.635583) (xy 129.950085 -288.61206) (xy 129.999364 -288.596048)
			(xy 130.050541 -288.587942) (xy 130.102355 -288.587942) (xy 130.153532 -288.596048) (xy 130.202811 -288.61206)
			(xy 130.248978 -288.635583) (xy 130.290897 -288.666039) (xy 130.327535 -288.702677) (xy 130.357991 -288.744596)
			(xy 130.381514 -288.790763) (xy 130.397526 -288.840042) (xy 130.405632 -288.891219) (xy 130.40614 -288.917126)
			(xy 130.405659 -288.942574) (xy 130.397856 -288.992867) (xy 130.382408 -289.041361) (xy 130.359683 -289.086901)
			(xy 130.330222 -289.128403) (xy 130.294727 -289.164878) (xy 130.254043 -289.195458) (xy 130.209139 -289.219415)
			(xy 130.161084 -289.236178) (xy 130.136138 -289.24123) (xy 130.112008 -289.245802) (xy 129.897632 -289.651186)
			(xy 129.907538 -289.673792) (xy 129.916456 -289.694878) (xy 129.929008 -289.738907) (xy 129.935342 -289.78425)
			(xy 129.935732 -289.807142) (xy 131.156456 -289.807142) (xy 131.156999 -289.781715) (xy 131.164829 -289.731468)
			(xy 131.18028 -289.683018) (xy 131.202986 -289.637514) (xy 131.232408 -289.596036) (xy 131.267848 -289.559565)
			(xy 131.308467 -289.528967) (xy 131.353301 -289.504967) (xy 131.401288 -289.488134) (xy 131.426204 -289.483038)
			(xy 131.450334 -289.478466) (xy 131.66471 -289.073082) (xy 131.654804 -289.050476) (xy 131.645843 -289.029398)
			(xy 131.633196 -288.985377) (xy 131.626782 -288.940026) (xy 131.626356 -288.917126) (xy 131.626864 -288.891219)
			(xy 131.63497 -288.840042) (xy 131.650982 -288.790763) (xy 131.674505 -288.744596) (xy 131.704961 -288.702677)
			(xy 131.741599 -288.666039) (xy 131.783518 -288.635583) (xy 131.829685 -288.61206) (xy 131.878964 -288.596048)
			(xy 131.930141 -288.587942) (xy 131.981955 -288.587942) (xy 132.033132 -288.596048) (xy 132.082411 -288.61206)
			(xy 132.128578 -288.635583) (xy 132.170497 -288.666039) (xy 132.207135 -288.702677) (xy 132.237591 -288.744596)
			(xy 132.261114 -288.790763) (xy 132.277126 -288.840042) (xy 132.285232 -288.891219) (xy 132.28574 -288.917126)
			(xy 132.285259 -288.942574) (xy 132.277456 -288.992867) (xy 132.262008 -289.041361) (xy 132.239283 -289.086901)
			(xy 132.209822 -289.128403) (xy 132.174327 -289.164878) (xy 132.133643 -289.195458) (xy 132.088739 -289.219415)
			(xy 132.040684 -289.236178) (xy 132.015738 -289.24123) (xy 131.991608 -289.245802) (xy 131.777232 -289.651186)
			(xy 131.787138 -289.673792) (xy 131.796056 -289.694878) (xy 131.808608 -289.738907) (xy 131.814942 -289.78425)
			(xy 131.815332 -289.807142) (xy 133.036056 -289.807142) (xy 133.036599 -289.781715) (xy 133.044429 -289.731468)
			(xy 133.05988 -289.683018) (xy 133.082586 -289.637514) (xy 133.112008 -289.596036) (xy 133.147448 -289.559565)
			(xy 133.188067 -289.528967) (xy 133.232901 -289.504967) (xy 133.280888 -289.488134) (xy 133.305804 -289.483038)
			(xy 133.329934 -289.478466) (xy 133.54431 -289.073082) (xy 133.534404 -289.050476) (xy 133.525443 -289.029398)
			(xy 133.512796 -288.985377) (xy 133.506382 -288.940026) (xy 133.505956 -288.917126) (xy 133.506464 -288.891219)
			(xy 133.51457 -288.840042) (xy 133.530582 -288.790763) (xy 133.554105 -288.744596) (xy 133.584561 -288.702677)
			(xy 133.621199 -288.666039) (xy 133.663118 -288.635583) (xy 133.709285 -288.61206) (xy 133.758564 -288.596048)
			(xy 133.809741 -288.587942) (xy 133.861555 -288.587942) (xy 133.912732 -288.596048) (xy 133.962011 -288.61206)
			(xy 134.008178 -288.635583) (xy 134.050097 -288.666039) (xy 134.086735 -288.702677) (xy 134.117191 -288.744596)
			(xy 134.140714 -288.790763) (xy 134.156726 -288.840042) (xy 134.164832 -288.891219) (xy 134.16534 -288.917126)
			(xy 134.164859 -288.942574) (xy 134.157056 -288.992867) (xy 134.141608 -289.041361) (xy 134.118883 -289.086901)
			(xy 134.089422 -289.128403) (xy 134.053927 -289.164878) (xy 134.013243 -289.195458) (xy 133.968339 -289.219415)
			(xy 133.920284 -289.236178) (xy 133.895338 -289.24123) (xy 133.871208 -289.245802) (xy 133.656832 -289.651186)
			(xy 133.666738 -289.673792) (xy 133.675656 -289.694878) (xy 133.688208 -289.738907) (xy 133.694542 -289.78425)
			(xy 133.694932 -289.807142) (xy 133.694424 -289.833029) (xy 133.686325 -289.884167) (xy 133.670326 -289.933407)
			(xy 133.64682 -289.979539) (xy 133.616388 -290.021426) (xy 133.579778 -290.058036) (xy 133.537891 -290.088468)
			(xy 133.491759 -290.111974) (xy 133.442519 -290.127973) (xy 133.391381 -290.136072) (xy 133.339607 -290.136072)
			(xy 133.288469 -290.127973) (xy 133.239229 -290.111974) (xy 133.193097 -290.088468) (xy 133.15121 -290.058036)
			(xy 133.1146 -290.021426) (xy 133.084168 -289.979539) (xy 133.060662 -289.933407) (xy 133.044663 -289.884167)
			(xy 133.036564 -289.833029) (xy 133.036056 -289.807142) (xy 131.815332 -289.807142) (xy 131.814824 -289.833029)
			(xy 131.806725 -289.884167) (xy 131.790726 -289.933407) (xy 131.76722 -289.979539) (xy 131.736788 -290.021426)
			(xy 131.700178 -290.058036) (xy 131.658291 -290.088468) (xy 131.612159 -290.111974) (xy 131.562919 -290.127973)
			(xy 131.511781 -290.136072) (xy 131.460007 -290.136072) (xy 131.408869 -290.127973) (xy 131.359629 -290.111974)
			(xy 131.313497 -290.088468) (xy 131.27161 -290.058036) (xy 131.235 -290.021426) (xy 131.204568 -289.979539)
			(xy 131.181062 -289.933407) (xy 131.165063 -289.884167) (xy 131.156964 -289.833029) (xy 131.156456 -289.807142)
			(xy 129.935732 -289.807142) (xy 129.935224 -289.833029) (xy 129.927125 -289.884167) (xy 129.911126 -289.933407)
			(xy 129.88762 -289.979539) (xy 129.857188 -290.021426) (xy 129.820578 -290.058036) (xy 129.778691 -290.088468)
			(xy 129.732559 -290.111974) (xy 129.683319 -290.127973) (xy 129.632181 -290.136072) (xy 129.580407 -290.136072)
			(xy 129.529269 -290.127973) (xy 129.480029 -290.111974) (xy 129.433897 -290.088468) (xy 129.39201 -290.058036)
			(xy 129.3554 -290.021426) (xy 129.324968 -289.979539) (xy 129.301462 -289.933407) (xy 129.285463 -289.884167)
			(xy 129.277364 -289.833029) (xy 129.276856 -289.807142) (xy 128.056132 -289.807142) (xy 128.055624 -289.833029)
			(xy 128.047525 -289.884167) (xy 128.031526 -289.933407) (xy 128.00802 -289.979539) (xy 127.977588 -290.021426)
			(xy 127.940978 -290.058036) (xy 127.899091 -290.088468) (xy 127.852959 -290.111974) (xy 127.803719 -290.127973)
			(xy 127.752581 -290.136072) (xy 127.700807 -290.136072) (xy 127.649669 -290.127973) (xy 127.600429 -290.111974)
			(xy 127.554297 -290.088468) (xy 127.51241 -290.058036) (xy 127.4758 -290.021426) (xy 127.445368 -289.979539)
			(xy 127.421862 -289.933407) (xy 127.405863 -289.884167) (xy 127.397764 -289.833029) (xy 127.397256 -289.807142)
			(xy 126.176532 -289.807142) (xy 126.176024 -289.833029) (xy 126.167925 -289.884167) (xy 126.151926 -289.933407)
			(xy 126.12842 -289.979539) (xy 126.097988 -290.021426) (xy 126.061378 -290.058036) (xy 126.019491 -290.088468)
			(xy 125.973359 -290.111974) (xy 125.924119 -290.127973) (xy 125.872981 -290.136072) (xy 125.821207 -290.136072)
			(xy 125.770069 -290.127973) (xy 125.720829 -290.111974) (xy 125.674697 -290.088468) (xy 125.63281 -290.058036)
			(xy 125.5962 -290.021426) (xy 125.565768 -289.979539) (xy 125.542262 -289.933407) (xy 125.526263 -289.884167)
			(xy 125.518164 -289.833029) (xy 125.517656 -289.807142) (xy 124.296932 -289.807142) (xy 124.296424 -289.833029)
			(xy 124.288325 -289.884167) (xy 124.272326 -289.933407) (xy 124.24882 -289.979539) (xy 124.218388 -290.021426)
			(xy 124.181778 -290.058036) (xy 124.139891 -290.088468) (xy 124.093759 -290.111974) (xy 124.044519 -290.127973)
			(xy 123.993381 -290.136072) (xy 123.941607 -290.136072) (xy 123.890469 -290.127973) (xy 123.841229 -290.111974)
			(xy 123.795097 -290.088468) (xy 123.75321 -290.058036) (xy 123.7166 -290.021426) (xy 123.686168 -289.979539)
			(xy 123.662662 -289.933407) (xy 123.646663 -289.884167) (xy 123.638564 -289.833029) (xy 123.638056 -289.807142)
			(xy 122.417332 -289.807142) (xy 122.416824 -289.833029) (xy 122.408725 -289.884167) (xy 122.392726 -289.933407)
			(xy 122.36922 -289.979539) (xy 122.338788 -290.021426) (xy 122.302178 -290.058036) (xy 122.260291 -290.088468)
			(xy 122.214159 -290.111974) (xy 122.164919 -290.127973) (xy 122.113781 -290.136072) (xy 122.062007 -290.136072)
			(xy 122.010869 -290.127973) (xy 121.961629 -290.111974) (xy 121.915497 -290.088468) (xy 121.87361 -290.058036)
			(xy 121.837 -290.021426) (xy 121.806568 -289.979539) (xy 121.783062 -289.933407) (xy 121.767063 -289.884167)
			(xy 121.758964 -289.833029) (xy 121.758456 -289.807142) (xy 120.537732 -289.807142) (xy 120.537224 -289.833029)
			(xy 120.529125 -289.884167) (xy 120.513126 -289.933407) (xy 120.48962 -289.979539) (xy 120.459188 -290.021426)
			(xy 120.422578 -290.058036) (xy 120.380691 -290.088468) (xy 120.334559 -290.111974) (xy 120.285319 -290.127973)
			(xy 120.234181 -290.136072) (xy 120.182407 -290.136072) (xy 120.131269 -290.127973) (xy 120.082029 -290.111974)
			(xy 120.035897 -290.088468) (xy 119.99401 -290.058036) (xy 119.9574 -290.021426) (xy 119.926968 -289.979539)
			(xy 119.903462 -289.933407) (xy 119.887463 -289.884167) (xy 119.879364 -289.833029) (xy 119.878856 -289.807142)
			(xy 103.621332 -289.807142) (xy 103.620824 -289.833029) (xy 103.612725 -289.884167) (xy 103.596726 -289.933407)
			(xy 103.57322 -289.979539) (xy 103.542788 -290.021426) (xy 103.506178 -290.058036) (xy 103.464291 -290.088468)
			(xy 103.418159 -290.111974) (xy 103.368919 -290.127973) (xy 103.317781 -290.136072) (xy 103.266007 -290.136072)
			(xy 103.214869 -290.127973) (xy 103.165629 -290.111974) (xy 103.119497 -290.088468) (xy 103.07761 -290.058036)
			(xy 103.041 -290.021426) (xy 103.010568 -289.979539) (xy 102.987062 -289.933407) (xy 102.971063 -289.884167)
			(xy 102.962964 -289.833029) (xy 102.962456 -289.807142) (xy 102.962456 -289.806634) (xy 102.962859 -289.783785)
			(xy 102.969212 -289.738531) (xy 102.981758 -289.694589) (xy 102.99065 -289.673538) (xy 103.000556 -289.650932)
			(xy 102.786688 -289.245802) (xy 102.762558 -289.24123) (xy 102.737619 -289.236158) (xy 102.689576 -289.219379)
			(xy 102.644683 -289.195414) (xy 102.604007 -289.164832) (xy 102.568517 -289.12836) (xy 102.539055 -289.086867)
			(xy 102.516322 -289.041337) (xy 102.500858 -288.992854) (xy 102.493031 -288.942571) (xy 102.492556 -288.917126)
			(xy 102.21214 -288.917126) (xy 102.211632 -288.943033) (xy 102.203526 -288.99421) (xy 102.187514 -289.043489)
			(xy 102.163991 -289.089656) (xy 102.133535 -289.131575) (xy 102.096897 -289.168213) (xy 102.054978 -289.198669)
			(xy 102.008811 -289.222192) (xy 101.959532 -289.238204) (xy 101.908355 -289.24631) (xy 101.856541 -289.24631)
			(xy 101.805364 -289.238204) (xy 101.756085 -289.222192) (xy 101.709918 -289.198669) (xy 101.667999 -289.168213)
			(xy 101.631361 -289.131575) (xy 101.600905 -289.089656) (xy 101.577382 -289.043489) (xy 101.56137 -288.99421)
			(xy 101.553264 -288.943033) (xy 101.552756 -288.917126) (xy 101.27234 -288.917126) (xy 101.271918 -288.940067)
			(xy 101.26549 -288.985498) (xy 101.252844 -289.029604) (xy 101.243892 -289.05073) (xy 101.233986 -289.073336)
			(xy 101.447854 -289.478466) (xy 101.471984 -289.483038) (xy 101.49691 -289.488115) (xy 101.544921 -289.50492)
			(xy 101.589779 -289.528904) (xy 101.630419 -289.559496) (xy 101.665876 -289.59597) (xy 101.695306 -289.637459)
			(xy 101.718012 -289.682977) (xy 101.733453 -289.731444) (xy 101.741263 -289.781708) (xy 101.741732 -289.807142)
			(xy 101.741224 -289.833029) (xy 101.733125 -289.884167) (xy 101.717126 -289.933407) (xy 101.69362 -289.979539)
			(xy 101.663188 -290.021426) (xy 101.626578 -290.058036) (xy 101.584691 -290.088468) (xy 101.538559 -290.111974)
			(xy 101.489319 -290.127973) (xy 101.438181 -290.136072) (xy 101.386407 -290.136072) (xy 101.335269 -290.127973)
			(xy 101.286029 -290.111974) (xy 101.239897 -290.088468) (xy 101.19801 -290.058036) (xy 101.1614 -290.021426)
			(xy 101.130968 -289.979539) (xy 101.107462 -289.933407) (xy 101.091463 -289.884167) (xy 101.083364 -289.833029)
			(xy 101.082856 -289.807142) (xy 101.082856 -289.806634) (xy 101.083259 -289.783785) (xy 101.089612 -289.738531)
			(xy 101.102158 -289.694589) (xy 101.11105 -289.673538) (xy 101.120956 -289.650932) (xy 100.907088 -289.245802)
			(xy 100.882958 -289.24123) (xy 100.858019 -289.236158) (xy 100.809976 -289.219379) (xy 100.765083 -289.195414)
			(xy 100.724407 -289.164832) (xy 100.688917 -289.12836) (xy 100.659455 -289.086867) (xy 100.636722 -289.041337)
			(xy 100.621258 -288.992854) (xy 100.613431 -288.942571) (xy 100.612956 -288.917126) (xy 100.33254 -288.917126)
			(xy 100.332032 -288.943033) (xy 100.323926 -288.99421) (xy 100.307914 -289.043489) (xy 100.284391 -289.089656)
			(xy 100.253935 -289.131575) (xy 100.217297 -289.168213) (xy 100.175378 -289.198669) (xy 100.129211 -289.222192)
			(xy 100.079932 -289.238204) (xy 100.028755 -289.24631) (xy 99.976941 -289.24631) (xy 99.925764 -289.238204)
			(xy 99.876485 -289.222192) (xy 99.830318 -289.198669) (xy 99.788399 -289.168213) (xy 99.751761 -289.131575)
			(xy 99.721305 -289.089656) (xy 99.697782 -289.043489) (xy 99.68177 -288.99421) (xy 99.673664 -288.943033)
			(xy 99.673156 -288.917126) (xy 99.39274 -288.917126) (xy 99.392318 -288.940067) (xy 99.38589 -288.985498)
			(xy 99.373244 -289.029604) (xy 99.364292 -289.05073) (xy 99.354386 -289.073336) (xy 99.568254 -289.478466)
			(xy 99.592384 -289.483038) (xy 99.61731 -289.488115) (xy 99.665321 -289.50492) (xy 99.710179 -289.528904)
			(xy 99.750819 -289.559496) (xy 99.786276 -289.59597) (xy 99.815706 -289.637459) (xy 99.838412 -289.682977)
			(xy 99.853853 -289.731444) (xy 99.861663 -289.781708) (xy 99.862132 -289.807142) (xy 99.861624 -289.833029)
			(xy 99.853525 -289.884167) (xy 99.837526 -289.933407) (xy 99.81402 -289.979539) (xy 99.783588 -290.021426)
			(xy 99.746978 -290.058036) (xy 99.705091 -290.088468) (xy 99.658959 -290.111974) (xy 99.609719 -290.127973)
			(xy 99.558581 -290.136072) (xy 99.506807 -290.136072) (xy 99.455669 -290.127973) (xy 99.406429 -290.111974)
			(xy 99.360297 -290.088468) (xy 99.31841 -290.058036) (xy 99.2818 -290.021426) (xy 99.251368 -289.979539)
			(xy 99.227862 -289.933407) (xy 99.211863 -289.884167) (xy 99.203764 -289.833029) (xy 99.203256 -289.807142)
			(xy 99.203256 -289.806634) (xy 99.203659 -289.783785) (xy 99.210012 -289.738531) (xy 99.222558 -289.694589)
			(xy 99.23145 -289.673538) (xy 99.241356 -289.650932) (xy 99.027488 -289.245802) (xy 99.003358 -289.24123)
			(xy 98.978419 -289.236158) (xy 98.930376 -289.219379) (xy 98.885483 -289.195414) (xy 98.844807 -289.164832)
			(xy 98.809317 -289.12836) (xy 98.779855 -289.086867) (xy 98.757122 -289.041337) (xy 98.741658 -288.992854)
			(xy 98.733831 -288.942571) (xy 98.733356 -288.917126) (xy 98.45294 -288.917126) (xy 98.452432 -288.943033)
			(xy 98.444326 -288.99421) (xy 98.428314 -289.043489) (xy 98.404791 -289.089656) (xy 98.374335 -289.131575)
			(xy 98.337697 -289.168213) (xy 98.295778 -289.198669) (xy 98.249611 -289.222192) (xy 98.200332 -289.238204)
			(xy 98.149155 -289.24631) (xy 98.097341 -289.24631) (xy 98.046164 -289.238204) (xy 97.996885 -289.222192)
			(xy 97.950718 -289.198669) (xy 97.908799 -289.168213) (xy 97.872161 -289.131575) (xy 97.841705 -289.089656)
			(xy 97.818182 -289.043489) (xy 97.80217 -288.99421) (xy 97.794064 -288.943033) (xy 97.793556 -288.917126)
			(xy 97.51314 -288.917126) (xy 97.512718 -288.940067) (xy 97.50629 -288.985498) (xy 97.493644 -289.029604)
			(xy 97.484692 -289.05073) (xy 97.474786 -289.073336) (xy 97.688654 -289.478466) (xy 97.712784 -289.483038)
			(xy 97.73771 -289.488115) (xy 97.785721 -289.50492) (xy 97.830579 -289.528904) (xy 97.871219 -289.559496)
			(xy 97.906676 -289.59597) (xy 97.936106 -289.637459) (xy 97.958812 -289.682977) (xy 97.974253 -289.731444)
			(xy 97.982063 -289.781708) (xy 97.982532 -289.807142) (xy 97.982024 -289.833029) (xy 97.973925 -289.884167)
			(xy 97.957926 -289.933407) (xy 97.93442 -289.979539) (xy 97.903988 -290.021426) (xy 97.867378 -290.058036)
			(xy 97.825491 -290.088468) (xy 97.779359 -290.111974) (xy 97.730119 -290.127973) (xy 97.678981 -290.136072)
			(xy 97.627207 -290.136072) (xy 97.576069 -290.127973) (xy 97.526829 -290.111974) (xy 97.480697 -290.088468)
			(xy 97.43881 -290.058036) (xy 97.4022 -290.021426) (xy 97.371768 -289.979539) (xy 97.348262 -289.933407)
			(xy 97.332263 -289.884167) (xy 97.324164 -289.833029) (xy 97.323656 -289.807142) (xy 97.323656 -289.806634)
			(xy 97.324059 -289.783785) (xy 97.330412 -289.738531) (xy 97.342958 -289.694589) (xy 97.35185 -289.673538)
			(xy 97.361756 -289.650932) (xy 97.147888 -289.245802) (xy 97.123758 -289.24123) (xy 97.098819 -289.236158)
			(xy 97.050776 -289.219379) (xy 97.005883 -289.195414) (xy 96.965207 -289.164832) (xy 96.929717 -289.12836)
			(xy 96.900255 -289.086867) (xy 96.877522 -289.041337) (xy 96.862058 -288.992854) (xy 96.854231 -288.942571)
			(xy 96.853756 -288.917126) (xy 96.57334 -288.917126) (xy 96.572832 -288.943033) (xy 96.564726 -288.99421)
			(xy 96.548714 -289.043489) (xy 96.525191 -289.089656) (xy 96.494735 -289.131575) (xy 96.458097 -289.168213)
			(xy 96.416178 -289.198669) (xy 96.370011 -289.222192) (xy 96.320732 -289.238204) (xy 96.269555 -289.24631)
			(xy 96.217741 -289.24631) (xy 96.166564 -289.238204) (xy 96.117285 -289.222192) (xy 96.071118 -289.198669)
			(xy 96.029199 -289.168213) (xy 95.992561 -289.131575) (xy 95.962105 -289.089656) (xy 95.938582 -289.043489)
			(xy 95.92257 -288.99421) (xy 95.914464 -288.943033) (xy 95.913956 -288.917126) (xy 95.63354 -288.917126)
			(xy 95.633118 -288.940067) (xy 95.62669 -288.985498) (xy 95.614044 -289.029604) (xy 95.605092 -289.05073)
			(xy 95.595186 -289.073336) (xy 95.809054 -289.478466) (xy 95.833184 -289.483038) (xy 95.85811 -289.488115)
			(xy 95.906121 -289.50492) (xy 95.950979 -289.528904) (xy 95.991619 -289.559496) (xy 96.027076 -289.59597)
			(xy 96.056506 -289.637459) (xy 96.079212 -289.682977) (xy 96.094653 -289.731444) (xy 96.102463 -289.781708)
			(xy 96.102932 -289.807142) (xy 96.102424 -289.833029) (xy 96.094325 -289.884167) (xy 96.078326 -289.933407)
			(xy 96.05482 -289.979539) (xy 96.024388 -290.021426) (xy 95.987778 -290.058036) (xy 95.945891 -290.088468)
			(xy 95.899759 -290.111974) (xy 95.850519 -290.127973) (xy 95.799381 -290.136072) (xy 95.747607 -290.136072)
			(xy 95.696469 -290.127973) (xy 95.647229 -290.111974) (xy 95.601097 -290.088468) (xy 95.55921 -290.058036)
			(xy 95.5226 -290.021426) (xy 95.492168 -289.979539) (xy 95.468662 -289.933407) (xy 95.452663 -289.884167)
			(xy 95.444564 -289.833029) (xy 95.444056 -289.807142) (xy 95.444056 -289.806634) (xy 95.444459 -289.783785)
			(xy 95.450812 -289.738531) (xy 95.463358 -289.694589) (xy 95.47225 -289.673538) (xy 95.482156 -289.650932)
			(xy 95.268288 -289.245802) (xy 95.244158 -289.24123) (xy 95.219219 -289.236158) (xy 95.171176 -289.219379)
			(xy 95.126283 -289.195414) (xy 95.085607 -289.164832) (xy 95.050117 -289.12836) (xy 95.020655 -289.086867)
			(xy 94.997922 -289.041337) (xy 94.982458 -288.992854) (xy 94.974631 -288.942571) (xy 94.974156 -288.917126)
			(xy 94.69374 -288.917126) (xy 94.693232 -288.943033) (xy 94.685126 -288.99421) (xy 94.669114 -289.043489)
			(xy 94.645591 -289.089656) (xy 94.615135 -289.131575) (xy 94.578497 -289.168213) (xy 94.536578 -289.198669)
			(xy 94.490411 -289.222192) (xy 94.441132 -289.238204) (xy 94.389955 -289.24631) (xy 94.338141 -289.24631)
			(xy 94.286964 -289.238204) (xy 94.237685 -289.222192) (xy 94.191518 -289.198669) (xy 94.149599 -289.168213)
			(xy 94.112961 -289.131575) (xy 94.082505 -289.089656) (xy 94.058982 -289.043489) (xy 94.04297 -288.99421)
			(xy 94.034864 -288.943033) (xy 94.034356 -288.917126) (xy 93.75394 -288.917126) (xy 93.753518 -288.940067)
			(xy 93.74709 -288.985498) (xy 93.734444 -289.029604) (xy 93.725492 -289.05073) (xy 93.715586 -289.073336)
			(xy 93.929454 -289.478466) (xy 93.953584 -289.483038) (xy 93.97851 -289.488115) (xy 94.026521 -289.50492)
			(xy 94.071379 -289.528904) (xy 94.112019 -289.559496) (xy 94.147476 -289.59597) (xy 94.176906 -289.637459)
			(xy 94.199612 -289.682977) (xy 94.215053 -289.731444) (xy 94.222863 -289.781708) (xy 94.223332 -289.807142)
			(xy 94.222824 -289.833029) (xy 94.214725 -289.884167) (xy 94.198726 -289.933407) (xy 94.17522 -289.979539)
			(xy 94.144788 -290.021426) (xy 94.108178 -290.058036) (xy 94.066291 -290.088468) (xy 94.020159 -290.111974)
			(xy 93.970919 -290.127973) (xy 93.919781 -290.136072) (xy 93.868007 -290.136072) (xy 93.816869 -290.127973)
			(xy 93.767629 -290.111974) (xy 93.721497 -290.088468) (xy 93.67961 -290.058036) (xy 93.643 -290.021426)
			(xy 93.612568 -289.979539) (xy 93.589062 -289.933407) (xy 93.573063 -289.884167) (xy 93.564964 -289.833029)
			(xy 93.564456 -289.807142) (xy 93.564456 -289.806634) (xy 93.564859 -289.783785) (xy 93.571212 -289.738531)
			(xy 93.583758 -289.694589) (xy 93.59265 -289.673538) (xy 93.602556 -289.650932) (xy 93.388688 -289.245802)
			(xy 93.364558 -289.24123) (xy 93.339619 -289.236158) (xy 93.291576 -289.219379) (xy 93.246683 -289.195414)
			(xy 93.206007 -289.164832) (xy 93.170517 -289.12836) (xy 93.141055 -289.086867) (xy 93.118322 -289.041337)
			(xy 93.102858 -288.992854) (xy 93.095031 -288.942571) (xy 93.094556 -288.917126) (xy 92.81414 -288.917126)
			(xy 92.813632 -288.943033) (xy 92.805526 -288.99421) (xy 92.789514 -289.043489) (xy 92.765991 -289.089656)
			(xy 92.735535 -289.131575) (xy 92.698897 -289.168213) (xy 92.656978 -289.198669) (xy 92.610811 -289.222192)
			(xy 92.561532 -289.238204) (xy 92.510355 -289.24631) (xy 92.458541 -289.24631) (xy 92.407364 -289.238204)
			(xy 92.358085 -289.222192) (xy 92.311918 -289.198669) (xy 92.269999 -289.168213) (xy 92.233361 -289.131575)
			(xy 92.202905 -289.089656) (xy 92.179382 -289.043489) (xy 92.16337 -288.99421) (xy 92.155264 -288.943033)
			(xy 92.154756 -288.917126) (xy 91.87434 -288.917126) (xy 91.873918 -288.940067) (xy 91.86749 -288.985498)
			(xy 91.854844 -289.029604) (xy 91.845892 -289.05073) (xy 91.835986 -289.073336) (xy 92.049854 -289.478466)
			(xy 92.073984 -289.483038) (xy 92.09891 -289.488115) (xy 92.146921 -289.50492) (xy 92.191779 -289.528904)
			(xy 92.232419 -289.559496) (xy 92.267876 -289.59597) (xy 92.297306 -289.637459) (xy 92.320012 -289.682977)
			(xy 92.335453 -289.731444) (xy 92.343263 -289.781708) (xy 92.343732 -289.807142) (xy 92.343224 -289.833029)
			(xy 92.335125 -289.884167) (xy 92.319126 -289.933407) (xy 92.29562 -289.979539) (xy 92.265188 -290.021426)
			(xy 92.228578 -290.058036) (xy 92.186691 -290.088468) (xy 92.140559 -290.111974) (xy 92.091319 -290.127973)
			(xy 92.040181 -290.136072) (xy 91.988407 -290.136072) (xy 91.937269 -290.127973) (xy 91.888029 -290.111974)
			(xy 91.841897 -290.088468) (xy 91.80001 -290.058036) (xy 91.7634 -290.021426) (xy 91.732968 -289.979539)
			(xy 91.709462 -289.933407) (xy 91.693463 -289.884167) (xy 91.685364 -289.833029) (xy 91.684856 -289.807142)
			(xy 91.684856 -289.806634) (xy 91.685259 -289.783785) (xy 91.691612 -289.738531) (xy 91.704158 -289.694589)
			(xy 91.71305 -289.673538) (xy 91.722956 -289.650932) (xy 91.509088 -289.245802) (xy 91.484958 -289.24123)
			(xy 91.460019 -289.236158) (xy 91.411976 -289.219379) (xy 91.367083 -289.195414) (xy 91.326407 -289.164832)
			(xy 91.290917 -289.12836) (xy 91.261455 -289.086867) (xy 91.238722 -289.041337) (xy 91.223258 -288.992854)
			(xy 91.215431 -288.942571) (xy 91.214956 -288.917126) (xy 90.93454 -288.917126) (xy 90.934032 -288.943033)
			(xy 90.925926 -288.99421) (xy 90.909914 -289.043489) (xy 90.886391 -289.089656) (xy 90.855935 -289.131575)
			(xy 90.819297 -289.168213) (xy 90.777378 -289.198669) (xy 90.731211 -289.222192) (xy 90.681932 -289.238204)
			(xy 90.630755 -289.24631) (xy 90.578941 -289.24631) (xy 90.527764 -289.238204) (xy 90.478485 -289.222192)
			(xy 90.432318 -289.198669) (xy 90.390399 -289.168213) (xy 90.353761 -289.131575) (xy 90.323305 -289.089656)
			(xy 90.299782 -289.043489) (xy 90.28377 -288.99421) (xy 90.275664 -288.943033) (xy 90.275156 -288.917126)
			(xy 89.05494 -288.917126) (xy 89.054432 -288.943033) (xy 89.046326 -288.99421) (xy 89.030314 -289.043489)
			(xy 89.006791 -289.089656) (xy 88.976335 -289.131575) (xy 88.939697 -289.168213) (xy 88.897778 -289.198669)
			(xy 88.851611 -289.222192) (xy 88.802332 -289.238204) (xy 88.751155 -289.24631) (xy 88.699341 -289.24631)
			(xy 88.648164 -289.238204) (xy 88.598885 -289.222192) (xy 88.552718 -289.198669) (xy 88.510799 -289.168213)
			(xy 88.474161 -289.131575) (xy 88.443705 -289.089656) (xy 88.420182 -289.043489) (xy 88.40417 -288.99421)
			(xy 88.396064 -288.943033) (xy 88.395556 -288.917126) (xy 2.509012 -288.917126) (xy 2.509012 -297.515026)
			(xy 88.21548 -297.515026) (xy 88.219461 -297.382006) (xy 88.23139 -297.249461) (xy 88.251225 -297.117868)
			(xy 88.278894 -296.987696) (xy 88.314298 -296.859411) (xy 88.357311 -296.733474) (xy 88.407778 -296.610335)
			(xy 88.465519 -296.490434) (xy 88.530328 -296.374201) (xy 88.601972 -296.262051) (xy 88.680194 -296.154387)
			(xy 88.764715 -296.051594) (xy 88.855233 -295.954039) (xy 88.951422 -295.862073) (xy 89.05294 -295.776023)
			(xy 89.159421 -295.696199) (xy 89.270486 -295.622886) (xy 89.385737 -295.556346) (xy 89.504761 -295.496817)
			(xy 89.627132 -295.444513) (xy 89.752411 -295.399621) (xy 89.880152 -295.362302) (xy 90.009895 -295.332689)
			(xy 90.141177 -295.310888) (xy 90.273528 -295.296978) (xy 90.406474 -295.291007) (xy 90.539539 -295.292998)
			(xy 90.672247 -295.302943) (xy 90.804123 -295.320807) (xy 90.934694 -295.346525) (xy 91.063494 -295.380006)
			(xy 91.19006 -295.42113) (xy 91.313941 -295.46975) (xy 91.434692 -295.525691) (xy 91.551882 -295.588753)
			(xy 91.665091 -295.658711) (xy 91.773913 -295.735315) (xy 91.877959 -295.818289) (xy 91.976857 -295.907337)
			(xy 92.070252 -296.00214) (xy 92.15781 -296.102358) (xy 92.239219 -296.207634) (xy 92.314185 -296.31759)
			(xy 92.382442 -296.431832) (xy 92.443744 -296.549952) (xy 92.497873 -296.671527) (xy 92.544634 -296.796121)
			(xy 92.58386 -296.923289) (xy 92.61541 -297.052575) (xy 92.639173 -297.183516) (xy 92.655062 -297.315644)
			(xy 92.66302 -297.448486) (xy 92.663518 -297.515026) (xy 131.195582 -297.515026) (xy 131.199563 -297.382006)
			(xy 131.211492 -297.249461) (xy 131.231327 -297.117868) (xy 131.258996 -296.987696) (xy 131.2944 -296.859411)
			(xy 131.337413 -296.733474) (xy 131.38788 -296.610335) (xy 131.445621 -296.490434) (xy 131.51043 -296.374201)
			(xy 131.582074 -296.262051) (xy 131.660296 -296.154387) (xy 131.744817 -296.051594) (xy 131.835335 -295.954039)
			(xy 131.931524 -295.862073) (xy 132.033042 -295.776023) (xy 132.139523 -295.696199) (xy 132.250588 -295.622886)
			(xy 132.365839 -295.556346) (xy 132.484863 -295.496817) (xy 132.607234 -295.444513) (xy 132.732513 -295.399621)
			(xy 132.860254 -295.362302) (xy 132.989997 -295.332689) (xy 133.121279 -295.310888) (xy 133.25363 -295.296978)
			(xy 133.386576 -295.291007) (xy 133.519641 -295.292998) (xy 133.652349 -295.302943) (xy 133.784225 -295.320807)
			(xy 133.914796 -295.346525) (xy 134.043596 -295.380006) (xy 134.170162 -295.42113) (xy 134.294043 -295.46975)
			(xy 134.414794 -295.525691) (xy 134.531984 -295.588753) (xy 134.645193 -295.658711) (xy 134.754015 -295.735315)
			(xy 134.858061 -295.818289) (xy 134.956959 -295.907337) (xy 135.050354 -296.00214) (xy 135.137912 -296.102358)
			(xy 135.219321 -296.207634) (xy 135.294287 -296.31759) (xy 135.362544 -296.431832) (xy 135.423846 -296.549952)
			(xy 135.477975 -296.671527) (xy 135.524736 -296.796121) (xy 135.563962 -296.923289) (xy 135.595512 -297.052575)
			(xy 135.619275 -297.183516) (xy 135.635164 -297.315644) (xy 135.643122 -297.448486) (xy 135.64362 -297.515026)
			(xy 336.155548 -297.515026) (xy 336.159529 -297.382006) (xy 336.171458 -297.249461) (xy 336.191293 -297.117868)
			(xy 336.218962 -296.987696) (xy 336.254366 -296.859411) (xy 336.297379 -296.733474) (xy 336.347846 -296.610335)
			(xy 336.405587 -296.490434) (xy 336.470396 -296.374201) (xy 336.54204 -296.262051) (xy 336.620262 -296.154387)
			(xy 336.704783 -296.051594) (xy 336.795301 -295.954039) (xy 336.89149 -295.862073) (xy 336.993008 -295.776023)
			(xy 337.099489 -295.696199) (xy 337.210554 -295.622886) (xy 337.325805 -295.556346) (xy 337.444829 -295.496817)
			(xy 337.5672 -295.444513) (xy 337.692479 -295.399621) (xy 337.82022 -295.362302) (xy 337.949963 -295.332689)
			(xy 338.081245 -295.310888) (xy 338.213596 -295.296978) (xy 338.346542 -295.291007) (xy 338.479607 -295.292998)
			(xy 338.612315 -295.302943) (xy 338.744191 -295.320807) (xy 338.874762 -295.346525) (xy 339.003562 -295.380006)
			(xy 339.130128 -295.42113) (xy 339.254009 -295.46975) (xy 339.37476 -295.525691) (xy 339.49195 -295.588753)
			(xy 339.605159 -295.658711) (xy 339.713981 -295.735315) (xy 339.818027 -295.818289) (xy 339.916925 -295.907337)
			(xy 340.01032 -296.00214) (xy 340.097878 -296.102358) (xy 340.179287 -296.207634) (xy 340.254253 -296.31759)
			(xy 340.32251 -296.431832) (xy 340.383812 -296.549952) (xy 340.437941 -296.671527) (xy 340.484702 -296.796121)
			(xy 340.523928 -296.923289) (xy 340.555478 -297.052575) (xy 340.579241 -297.183516) (xy 340.59513 -297.315644)
			(xy 340.603088 -297.448486) (xy 340.603586 -297.515026) (xy 379.13565 -297.515026) (xy 379.139631 -297.382006)
			(xy 379.15156 -297.249461) (xy 379.171395 -297.117868) (xy 379.199064 -296.987696) (xy 379.234468 -296.859411)
			(xy 379.277481 -296.733474) (xy 379.327948 -296.610335) (xy 379.385689 -296.490434) (xy 379.450498 -296.374201)
			(xy 379.522142 -296.262051) (xy 379.600364 -296.154387) (xy 379.684885 -296.051594) (xy 379.775403 -295.954039)
			(xy 379.871592 -295.862073) (xy 379.97311 -295.776023) (xy 380.079591 -295.696199) (xy 380.190656 -295.622886)
			(xy 380.305907 -295.556346) (xy 380.424931 -295.496817) (xy 380.547302 -295.444513) (xy 380.672581 -295.399621)
			(xy 380.800322 -295.362302) (xy 380.930065 -295.332689) (xy 381.061347 -295.310888) (xy 381.193698 -295.296978)
			(xy 381.326644 -295.291007) (xy 381.459709 -295.292998) (xy 381.592417 -295.302943) (xy 381.724293 -295.320807)
			(xy 381.854864 -295.346525) (xy 381.983664 -295.380006) (xy 382.11023 -295.42113) (xy 382.234111 -295.46975)
			(xy 382.354862 -295.525691) (xy 382.472052 -295.588753) (xy 382.585261 -295.658711) (xy 382.694083 -295.735315)
			(xy 382.798129 -295.818289) (xy 382.897027 -295.907337) (xy 382.990422 -296.00214) (xy 383.07798 -296.102358)
			(xy 383.159389 -296.207634) (xy 383.234355 -296.31759) (xy 383.302612 -296.431832) (xy 383.363914 -296.549952)
			(xy 383.418043 -296.671527) (xy 383.464804 -296.796121) (xy 383.50403 -296.923289) (xy 383.53558 -297.052575)
			(xy 383.559343 -297.183516) (xy 383.575232 -297.315644) (xy 383.58319 -297.448486) (xy 383.583688 -297.515026)
			(xy 383.58319 -297.581566) (xy 383.575232 -297.714408) (xy 383.559343 -297.846536) (xy 383.53558 -297.977477)
			(xy 383.50403 -298.106763) (xy 383.464804 -298.233931) (xy 383.418043 -298.358525) (xy 383.363914 -298.4801)
			(xy 383.302612 -298.59822) (xy 383.234355 -298.712462) (xy 383.159389 -298.822418) (xy 383.07798 -298.927694)
			(xy 382.990422 -299.027912) (xy 382.897027 -299.122715) (xy 382.798129 -299.211763) (xy 382.694083 -299.294737)
			(xy 382.585261 -299.371341) (xy 382.472052 -299.441299) (xy 382.354862 -299.504361) (xy 382.234111 -299.560302)
			(xy 382.11023 -299.608922) (xy 381.983664 -299.650046) (xy 381.854864 -299.683527) (xy 381.724293 -299.709245)
			(xy 381.592417 -299.727109) (xy 381.459709 -299.737054) (xy 381.326644 -299.739045) (xy 381.193698 -299.733074)
			(xy 381.061347 -299.719164) (xy 380.930065 -299.697363) (xy 380.800322 -299.66775) (xy 380.672581 -299.630431)
			(xy 380.547302 -299.585539) (xy 380.424931 -299.533235) (xy 380.305907 -299.473706) (xy 380.190656 -299.407166)
			(xy 380.079591 -299.333853) (xy 379.97311 -299.254029) (xy 379.871592 -299.167979) (xy 379.775403 -299.076013)
			(xy 379.684885 -298.978458) (xy 379.600364 -298.875665) (xy 379.522142 -298.768001) (xy 379.450498 -298.655851)
			(xy 379.385689 -298.539618) (xy 379.327948 -298.419717) (xy 379.277481 -298.296578) (xy 379.234468 -298.170641)
			(xy 379.199064 -298.042356) (xy 379.171395 -297.912184) (xy 379.15156 -297.780591) (xy 379.139631 -297.648046)
			(xy 379.13565 -297.515026) (xy 340.603586 -297.515026) (xy 340.603088 -297.581566) (xy 340.59513 -297.714408)
			(xy 340.579241 -297.846536) (xy 340.555478 -297.977477) (xy 340.523928 -298.106763) (xy 340.484702 -298.233931)
			(xy 340.437941 -298.358525) (xy 340.383812 -298.4801) (xy 340.32251 -298.59822) (xy 340.254253 -298.712462)
			(xy 340.179287 -298.822418) (xy 340.097878 -298.927694) (xy 340.01032 -299.027912) (xy 339.916925 -299.122715)
			(xy 339.818027 -299.211763) (xy 339.713981 -299.294737) (xy 339.605159 -299.371341) (xy 339.49195 -299.441299)
			(xy 339.37476 -299.504361) (xy 339.254009 -299.560302) (xy 339.130128 -299.608922) (xy 339.003562 -299.650046)
			(xy 338.874762 -299.683527) (xy 338.744191 -299.709245) (xy 338.612315 -299.727109) (xy 338.479607 -299.737054)
			(xy 338.346542 -299.739045) (xy 338.213596 -299.733074) (xy 338.081245 -299.719164) (xy 337.949963 -299.697363)
			(xy 337.82022 -299.66775) (xy 337.692479 -299.630431) (xy 337.5672 -299.585539) (xy 337.444829 -299.533235)
			(xy 337.325805 -299.473706) (xy 337.210554 -299.407166) (xy 337.099489 -299.333853) (xy 336.993008 -299.254029)
			(xy 336.89149 -299.167979) (xy 336.795301 -299.076013) (xy 336.704783 -298.978458) (xy 336.620262 -298.875665)
			(xy 336.54204 -298.768001) (xy 336.470396 -298.655851) (xy 336.405587 -298.539618) (xy 336.347846 -298.419717)
			(xy 336.297379 -298.296578) (xy 336.254366 -298.170641) (xy 336.218962 -298.042356) (xy 336.191293 -297.912184)
			(xy 336.171458 -297.780591) (xy 336.159529 -297.648046) (xy 336.155548 -297.515026) (xy 135.64362 -297.515026)
			(xy 135.643122 -297.581566) (xy 135.635164 -297.714408) (xy 135.619275 -297.846536) (xy 135.595512 -297.977477)
			(xy 135.563962 -298.106763) (xy 135.524736 -298.233931) (xy 135.477975 -298.358525) (xy 135.423846 -298.4801)
			(xy 135.362544 -298.59822) (xy 135.294287 -298.712462) (xy 135.219321 -298.822418) (xy 135.137912 -298.927694)
			(xy 135.050354 -299.027912) (xy 134.956959 -299.122715) (xy 134.858061 -299.211763) (xy 134.754015 -299.294737)
			(xy 134.645193 -299.371341) (xy 134.531984 -299.441299) (xy 134.414794 -299.504361) (xy 134.294043 -299.560302)
			(xy 134.170162 -299.608922) (xy 134.043596 -299.650046) (xy 133.914796 -299.683527) (xy 133.784225 -299.709245)
			(xy 133.652349 -299.727109) (xy 133.519641 -299.737054) (xy 133.386576 -299.739045) (xy 133.25363 -299.733074)
			(xy 133.121279 -299.719164) (xy 132.989997 -299.697363) (xy 132.860254 -299.66775) (xy 132.732513 -299.630431)
			(xy 132.607234 -299.585539) (xy 132.484863 -299.533235) (xy 132.365839 -299.473706) (xy 132.250588 -299.407166)
			(xy 132.139523 -299.333853) (xy 132.033042 -299.254029) (xy 131.931524 -299.167979) (xy 131.835335 -299.076013)
			(xy 131.744817 -298.978458) (xy 131.660296 -298.875665) (xy 131.582074 -298.768001) (xy 131.51043 -298.655851)
			(xy 131.445621 -298.539618) (xy 131.38788 -298.419717) (xy 131.337413 -298.296578) (xy 131.2944 -298.170641)
			(xy 131.258996 -298.042356) (xy 131.231327 -297.912184) (xy 131.211492 -297.780591) (xy 131.199563 -297.648046)
			(xy 131.195582 -297.515026) (xy 92.663518 -297.515026) (xy 92.66302 -297.581566) (xy 92.655062 -297.714408)
			(xy 92.639173 -297.846536) (xy 92.61541 -297.977477) (xy 92.58386 -298.106763) (xy 92.544634 -298.233931)
			(xy 92.497873 -298.358525) (xy 92.443744 -298.4801) (xy 92.382442 -298.59822) (xy 92.314185 -298.712462)
			(xy 92.239219 -298.822418) (xy 92.15781 -298.927694) (xy 92.070252 -299.027912) (xy 91.976857 -299.122715)
			(xy 91.877959 -299.211763) (xy 91.773913 -299.294737) (xy 91.665091 -299.371341) (xy 91.551882 -299.441299)
			(xy 91.434692 -299.504361) (xy 91.313941 -299.560302) (xy 91.19006 -299.608922) (xy 91.063494 -299.650046)
			(xy 90.934694 -299.683527) (xy 90.804123 -299.709245) (xy 90.672247 -299.727109) (xy 90.539539 -299.737054)
			(xy 90.406474 -299.739045) (xy 90.273528 -299.733074) (xy 90.141177 -299.719164) (xy 90.009895 -299.697363)
			(xy 89.880152 -299.66775) (xy 89.752411 -299.630431) (xy 89.627132 -299.585539) (xy 89.504761 -299.533235)
			(xy 89.385737 -299.473706) (xy 89.270486 -299.407166) (xy 89.159421 -299.333853) (xy 89.05294 -299.254029)
			(xy 88.951422 -299.167979) (xy 88.855233 -299.076013) (xy 88.764715 -298.978458) (xy 88.680194 -298.875665)
			(xy 88.601972 -298.768001) (xy 88.530328 -298.655851) (xy 88.465519 -298.539618) (xy 88.407778 -298.419717)
			(xy 88.357311 -298.296578) (xy 88.314298 -298.170641) (xy 88.278894 -298.042356) (xy 88.251225 -297.912184)
			(xy 88.23139 -297.780591) (xy 88.219461 -297.648046) (xy 88.21548 -297.515026) (xy 2.509012 -297.515026)
			(xy 2.509012 -360.76382) (xy 4.226823 -360.76382) (xy 4.230819 -360.553934) (xy 4.242804 -360.344352)
			(xy 4.262758 -360.135378) (xy 4.290654 -359.927316) (xy 4.326451 -359.720466) (xy 4.370096 -359.515129)
			(xy 4.421528 -359.311603) (xy 4.48067 -359.110182) (xy 4.547438 -358.911159) (xy 4.621734 -358.714822)
			(xy 4.703452 -358.521456) (xy 4.792471 -358.331341) (xy 4.888664 -358.144753) (xy 4.991891 -357.961962)
			(xy 5.102002 -357.783234) (xy 5.218837 -357.608827) (xy 5.342227 -357.438995) (xy 5.471994 -357.273983)
			(xy 5.607948 -357.114032) (xy 5.749894 -356.959372) (xy 5.897624 -356.810228) (xy 6.050926 -356.666817)
			(xy 6.209576 -356.529346) (xy 6.373345 -356.398014) (xy 6.541995 -356.273013) (xy 6.715281 -356.154522)
			(xy 6.892953 -356.042715) (xy 7.074753 -355.937753) (xy 7.260417 -355.839788) (xy 7.449675 -355.748963)
			(xy 7.642255 -355.665409) (xy 7.837876 -355.589246) (xy 8.036254 -355.520587) (xy 8.237103 -355.45953)
			(xy 8.44013 -355.406163) (xy 8.645043 -355.360565) (xy 8.851542 -355.3228) (xy 9.059329 -355.292925)
			(xy 9.268104 -355.270982) (xy 9.477562 -355.257003) (xy 9.687401 -355.251008) (xy 9.897315 -355.253007)
			(xy 10.107002 -355.262995) (xy 10.316156 -355.28096) (xy 10.524474 -355.306874) (xy 10.731655 -355.340699)
			(xy 10.937399 -355.382388) (xy 11.141405 -355.43188) (xy 11.34338 -355.489102) (xy 11.54303 -355.553972)
			(xy 11.740065 -355.626396) (xy 11.934201 -355.706269) (xy 12.125154 -355.793475) (xy 12.31265 -355.887887)
			(xy 12.496415 -355.989369) (xy 12.676183 -356.097773) (xy 12.851694 -356.212943) (xy 13.022693 -356.334711)
			(xy 13.188933 -356.4629) (xy 13.350172 -356.597326) (xy 13.506176 -356.737793) (xy 13.656719 -356.884097)
			(xy 13.801583 -357.036026) (xy 13.940558 -357.19336) (xy 14.073443 -357.355871) (xy 14.200044 -357.523324)
			(xy 14.320179 -357.695474) (xy 14.433673 -357.872074) (xy 14.540361 -358.052866) (xy 14.640088 -358.237589)
			(xy 14.732711 -358.425975) (xy 14.818095 -358.61775) (xy 14.896116 -358.812637) (xy 14.966661 -359.010353)
			(xy 15.029628 -359.210611) (xy 15.084925 -359.413121) (xy 15.132472 -359.61759) (xy 15.1722 -359.823721)
			(xy 15.204052 -360.031214) (xy 15.227982 -360.23977) (xy 15.243954 -360.449086) (xy 15.251946 -360.658858)
			(xy 15.252446 -360.76382) (xy 15.251946 -360.868782) (xy 15.243954 -361.078554) (xy 15.239789 -361.133136)
			(xy 121.446286 -361.133136) (xy 121.450375 -361.077254) (xy 121.462558 -361.022564) (xy 121.482574 -360.97023)
			(xy 121.509997 -360.921368) (xy 121.544242 -360.87702) (xy 121.584578 -360.83813) (xy 121.630148 -360.805528)
			(xy 121.679979 -360.779909) (xy 121.733009 -360.761817) (xy 121.788107 -360.75164) (xy 121.844101 -360.749594)
			(xy 121.899796 -360.755722) (xy 121.930771 -360.76382) (xy 211.161635 -360.76382) (xy 211.16566 -360.621628)
			(xy 211.177723 -360.479892) (xy 211.197786 -360.339066) (xy 211.225784 -360.1996) (xy 211.261628 -360.061941)
			(xy 211.305202 -359.926531) (xy 211.356367 -359.793803) (xy 211.41496 -359.664182) (xy 211.480791 -359.538084)
			(xy 211.553652 -359.415912) (xy 211.633307 -359.298058) (xy 211.719503 -359.184899) (xy 211.811962 -359.076797)
			(xy 211.91039 -358.9741) (xy 212.014469 -358.877136) (xy 212.123868 -358.786216) (xy 212.238236 -358.70163)
			(xy 212.357205 -358.62365) (xy 212.480396 -358.552526) (xy 212.607413 -358.488485) (xy 212.73785 -358.431733)
			(xy 212.871289 -358.382451) (xy 213.007302 -358.340797) (xy 213.145454 -358.306905) (xy 213.285303 -358.280884)
			(xy 213.426399 -358.262816) (xy 213.568291 -358.252759) (xy 213.710526 -358.250746) (xy 213.852646 -358.256783)
			(xy 213.994197 -358.270851) (xy 214.134726 -358.292905) (xy 214.273781 -358.322874) (xy 214.410919 -358.360662)
			(xy 214.545699 -358.406148) (xy 214.67769 -358.459186) (xy 214.806469 -358.519607) (xy 214.931623 -358.587216)
			(xy 215.052751 -358.661798) (xy 215.169467 -358.743114) (xy 215.281395 -358.830902) (xy 215.388177 -358.924882)
			(xy 215.489471 -359.024752) (xy 215.584952 -359.130194) (xy 215.674316 -359.240868) (xy 215.757274 -359.356421)
			(xy 215.833563 -359.476482) (xy 215.902937 -359.600667) (xy 215.965174 -359.728578) (xy 216.020075 -359.859805)
			(xy 216.067463 -359.993928) (xy 216.107188 -360.130517) (xy 216.139121 -360.269135) (xy 216.163162 -360.409337)
			(xy 216.179231 -360.550675) (xy 216.187279 -360.692696) (xy 216.187782 -360.76382) (xy 255.611635 -360.76382)
			(xy 255.61566 -360.621628) (xy 255.627723 -360.479892) (xy 255.647786 -360.339066) (xy 255.675784 -360.1996)
			(xy 255.711628 -360.061941) (xy 255.755202 -359.926531) (xy 255.806367 -359.793803) (xy 255.86496 -359.664182)
			(xy 255.930791 -359.538084) (xy 256.003652 -359.415912) (xy 256.083307 -359.298058) (xy 256.169503 -359.184899)
			(xy 256.261962 -359.076797) (xy 256.36039 -358.9741) (xy 256.464469 -358.877136) (xy 256.573868 -358.786216)
			(xy 256.688236 -358.70163) (xy 256.807205 -358.62365) (xy 256.930396 -358.552526) (xy 257.057413 -358.488485)
			(xy 257.18785 -358.431733) (xy 257.321289 -358.382451) (xy 257.457302 -358.340797) (xy 257.595454 -358.306905)
			(xy 257.735303 -358.280884) (xy 257.876399 -358.262816) (xy 258.018291 -358.252759) (xy 258.160526 -358.250746)
			(xy 258.302646 -358.256783) (xy 258.444197 -358.270851) (xy 258.584726 -358.292905) (xy 258.723781 -358.322874)
			(xy 258.860919 -358.360662) (xy 258.995699 -358.406148) (xy 259.12769 -358.459186) (xy 259.256469 -358.519607)
			(xy 259.381623 -358.587216) (xy 259.502751 -358.661798) (xy 259.619467 -358.743114) (xy 259.731395 -358.830902)
			(xy 259.838177 -358.924882) (xy 259.939471 -359.024752) (xy 260.034952 -359.130194) (xy 260.124316 -359.240868)
			(xy 260.207274 -359.356421) (xy 260.283563 -359.476482) (xy 260.352937 -359.600667) (xy 260.415174 -359.728578)
			(xy 260.470075 -359.859805) (xy 260.517463 -359.993928) (xy 260.557188 -360.130517) (xy 260.589121 -360.269135)
			(xy 260.613162 -360.409337) (xy 260.629231 -360.550675) (xy 260.637279 -360.692696) (xy 260.637782 -360.76382)
			(xy 260.637279 -360.834944) (xy 260.629231 -360.976965) (xy 260.613162 -361.118303) (xy 260.610619 -361.133136)
			(xy 369.3861 -361.133136) (xy 369.390189 -361.077254) (xy 369.402372 -361.022564) (xy 369.422388 -360.97023)
			(xy 369.449811 -360.921368) (xy 369.484056 -360.87702) (xy 369.524392 -360.83813) (xy 369.569962 -360.805528)
			(xy 369.619793 -360.779909) (xy 369.672823 -360.761817) (xy 369.727921 -360.75164) (xy 369.783915 -360.749594)
			(xy 369.83961 -360.755722) (xy 369.870585 -360.76382) (xy 456.565771 -360.76382) (xy 456.569767 -360.553934)
			(xy 456.581752 -360.344352) (xy 456.601706 -360.135378) (xy 456.629602 -359.927316) (xy 456.665399 -359.720466)
			(xy 456.709044 -359.515129) (xy 456.760476 -359.311603) (xy 456.819618 -359.110182) (xy 456.886386 -358.911159)
			(xy 456.960682 -358.714822) (xy 457.0424 -358.521456) (xy 457.131419 -358.331341) (xy 457.227612 -358.144753)
			(xy 457.330839 -357.961962) (xy 457.44095 -357.783234) (xy 457.557785 -357.608827) (xy 457.681175 -357.438995)
			(xy 457.810942 -357.273983) (xy 457.946896 -357.114032) (xy 458.088842 -356.959372) (xy 458.236572 -356.810228)
			(xy 458.389874 -356.666817) (xy 458.548524 -356.529346) (xy 458.712293 -356.398014) (xy 458.880943 -356.273013)
			(xy 459.054229 -356.154522) (xy 459.231901 -356.042715) (xy 459.413701 -355.937753) (xy 459.599365 -355.839788)
			(xy 459.788623 -355.748963) (xy 459.981203 -355.665409) (xy 460.176824 -355.589246) (xy 460.375202 -355.520587)
			(xy 460.576051 -355.45953) (xy 460.779078 -355.406163) (xy 460.983991 -355.360565) (xy 461.19049 -355.3228)
			(xy 461.398277 -355.292925) (xy 461.607052 -355.270982) (xy 461.81651 -355.257003) (xy 462.026349 -355.251008)
			(xy 462.236263 -355.253007) (xy 462.44595 -355.262995) (xy 462.655104 -355.28096) (xy 462.863422 -355.306874)
			(xy 463.070603 -355.340699) (xy 463.276347 -355.382388) (xy 463.480353 -355.43188) (xy 463.682328 -355.489102)
			(xy 463.881978 -355.553972) (xy 464.079013 -355.626396) (xy 464.273149 -355.706269) (xy 464.464102 -355.793475)
			(xy 464.651598 -355.887887) (xy 464.835363 -355.989369) (xy 465.015131 -356.097773) (xy 465.190642 -356.212943)
			(xy 465.361641 -356.334711) (xy 465.527881 -356.4629) (xy 465.68912 -356.597326) (xy 465.845124 -356.737793)
			(xy 465.995667 -356.884097) (xy 466.140531 -357.036026) (xy 466.279506 -357.19336) (xy 466.412391 -357.355871)
			(xy 466.538992 -357.523324) (xy 466.659127 -357.695474) (xy 466.772621 -357.872074) (xy 466.879309 -358.052866)
			(xy 466.979036 -358.237589) (xy 467.071659 -358.425975) (xy 467.157043 -358.61775) (xy 467.235064 -358.812637)
			(xy 467.305609 -359.010353) (xy 467.368576 -359.210611) (xy 467.423873 -359.413121) (xy 467.47142 -359.61759)
			(xy 467.511148 -359.823721) (xy 467.543 -360.031214) (xy 467.56693 -360.23977) (xy 467.582902 -360.449086)
			(xy 467.590894 -360.658858) (xy 467.591394 -360.76382) (xy 467.590894 -360.868782) (xy 467.582902 -361.078554)
			(xy 467.56693 -361.28787) (xy 467.543 -361.496426) (xy 467.511148 -361.703919) (xy 467.47142 -361.91005)
			(xy 467.423873 -362.114519) (xy 467.368576 -362.317029) (xy 467.305609 -362.517287) (xy 467.235064 -362.715003)
			(xy 467.157043 -362.90989) (xy 467.071659 -363.101665) (xy 466.979036 -363.290051) (xy 466.879309 -363.474774)
			(xy 466.772621 -363.655566) (xy 466.659127 -363.832166) (xy 466.538992 -364.004316) (xy 466.412391 -364.171769)
			(xy 466.279506 -364.33428) (xy 466.140531 -364.491614) (xy 465.995667 -364.643543) (xy 465.845124 -364.789847)
			(xy 465.68912 -364.930314) (xy 465.527881 -365.06474) (xy 465.361641 -365.192929) (xy 465.190642 -365.314697)
			(xy 465.015131 -365.429867) (xy 464.835363 -365.538271) (xy 464.651598 -365.639753) (xy 464.464102 -365.734165)
			(xy 464.273149 -365.821371) (xy 464.079013 -365.901244) (xy 463.881978 -365.973668) (xy 463.682328 -366.038538)
			(xy 463.480353 -366.09576) (xy 463.276347 -366.145252) (xy 463.070603 -366.186941) (xy 462.863422 -366.220766)
			(xy 462.655104 -366.24668) (xy 462.44595 -366.264645) (xy 462.236263 -366.274633) (xy 462.026349 -366.276632)
			(xy 461.81651 -366.270637) (xy 461.607052 -366.256658) (xy 461.398277 -366.234715) (xy 461.19049 -366.20484)
			(xy 460.983991 -366.167075) (xy 460.779078 -366.121477) (xy 460.576051 -366.06811) (xy 460.375202 -366.007053)
			(xy 460.176824 -365.938394) (xy 459.981203 -365.862231) (xy 459.788623 -365.778677) (xy 459.599365 -365.687852)
			(xy 459.413701 -365.589887) (xy 459.231901 -365.484925) (xy 459.054229 -365.373118) (xy 458.880943 -365.254627)
			(xy 458.712293 -365.129626) (xy 458.548524 -364.998294) (xy 458.389874 -364.860823) (xy 458.236572 -364.717412)
			(xy 458.088842 -364.568268) (xy 457.946896 -364.413608) (xy 457.810942 -364.253657) (xy 457.681175 -364.088645)
			(xy 457.557785 -363.918813) (xy 457.44095 -363.744406) (xy 457.330839 -363.565678) (xy 457.227612 -363.382887)
			(xy 457.131419 -363.196299) (xy 457.0424 -363.006184) (xy 456.960682 -362.812818) (xy 456.886386 -362.616481)
			(xy 456.819618 -362.417458) (xy 456.760476 -362.216037) (xy 456.709044 -362.012511) (xy 456.665399 -361.807174)
			(xy 456.629602 -361.600324) (xy 456.601706 -361.392262) (xy 456.581752 -361.183288) (xy 456.569767 -360.973706)
			(xy 456.565771 -360.76382) (xy 369.870585 -360.76382) (xy 369.893819 -360.769894) (xy 369.945387 -360.791808)
			(xy 369.993215 -360.820997) (xy 370.036283 -360.856838) (xy 370.073673 -360.898568) (xy 370.104589 -360.945298)
			(xy 370.128372 -360.996031) (xy 370.144514 -361.049687) (xy 370.152673 -361.105121) (xy 370.153184 -361.133136)
			(xy 370.152673 -361.161151) (xy 370.144514 -361.216585) (xy 370.128372 -361.270241) (xy 370.104589 -361.320974)
			(xy 370.073673 -361.367704) (xy 370.036283 -361.409434) (xy 369.993215 -361.445275) (xy 369.945387 -361.474464)
			(xy 369.893819 -361.496378) (xy 369.83961 -361.51055) (xy 369.783915 -361.516678) (xy 369.727921 -361.514632)
			(xy 369.672823 -361.504455) (xy 369.619793 -361.486363) (xy 369.569962 -361.460744) (xy 369.524392 -361.428142)
			(xy 369.484056 -361.389252) (xy 369.449811 -361.344904) (xy 369.422388 -361.296042) (xy 369.402372 -361.243708)
			(xy 369.390189 -361.189018) (xy 369.3861 -361.133136) (xy 260.610619 -361.133136) (xy 260.589121 -361.258505)
			(xy 260.557188 -361.397123) (xy 260.517463 -361.533712) (xy 260.470075 -361.667835) (xy 260.415174 -361.799062)
			(xy 260.352937 -361.926973) (xy 260.283563 -362.051158) (xy 260.207274 -362.171219) (xy 260.124316 -362.286772)
			(xy 260.034952 -362.397446) (xy 259.939471 -362.502888) (xy 259.838177 -362.602758) (xy 259.731395 -362.696738)
			(xy 259.619467 -362.784526) (xy 259.502751 -362.865842) (xy 259.381623 -362.940424) (xy 259.256469 -363.008033)
			(xy 259.12769 -363.068454) (xy 258.995699 -363.121492) (xy 258.860919 -363.166978) (xy 258.723781 -363.204766)
			(xy 258.584726 -363.234735) (xy 258.444197 -363.256789) (xy 258.302646 -363.270857) (xy 258.160526 -363.276894)
			(xy 258.018291 -363.274881) (xy 257.876399 -363.264824) (xy 257.735303 -363.246756) (xy 257.595454 -363.220735)
			(xy 257.457302 -363.186843) (xy 257.321289 -363.145189) (xy 257.18785 -363.095907) (xy 257.057413 -363.039155)
			(xy 256.930396 -362.975114) (xy 256.807205 -362.90399) (xy 256.688236 -362.82601) (xy 256.573868 -362.741424)
			(xy 256.464469 -362.650504) (xy 256.36039 -362.55354) (xy 256.261962 -362.450843) (xy 256.169503 -362.342741)
			(xy 256.083307 -362.229582) (xy 256.003652 -362.111728) (xy 255.930791 -361.989556) (xy 255.86496 -361.863458)
			(xy 255.806367 -361.733837) (xy 255.755202 -361.601109) (xy 255.711628 -361.465699) (xy 255.675784 -361.32804)
			(xy 255.647786 -361.188574) (xy 255.627723 -361.047748) (xy 255.61566 -360.906012) (xy 255.611635 -360.76382)
			(xy 216.187782 -360.76382) (xy 216.187279 -360.834944) (xy 216.179231 -360.976965) (xy 216.163162 -361.118303)
			(xy 216.139121 -361.258505) (xy 216.107188 -361.397123) (xy 216.067463 -361.533712) (xy 216.020075 -361.667835)
			(xy 215.965174 -361.799062) (xy 215.902937 -361.926973) (xy 215.833563 -362.051158) (xy 215.757274 -362.171219)
			(xy 215.674316 -362.286772) (xy 215.584952 -362.397446) (xy 215.489471 -362.502888) (xy 215.388177 -362.602758)
			(xy 215.281395 -362.696738) (xy 215.169467 -362.784526) (xy 215.052751 -362.865842) (xy 214.931623 -362.940424)
			(xy 214.806469 -363.008033) (xy 214.67769 -363.068454) (xy 214.545699 -363.121492) (xy 214.410919 -363.166978)
			(xy 214.273781 -363.204766) (xy 214.134726 -363.234735) (xy 213.994197 -363.256789) (xy 213.852646 -363.270857)
			(xy 213.710526 -363.276894) (xy 213.568291 -363.274881) (xy 213.426399 -363.264824) (xy 213.285303 -363.246756)
			(xy 213.145454 -363.220735) (xy 213.007302 -363.186843) (xy 212.871289 -363.145189) (xy 212.73785 -363.095907)
			(xy 212.607413 -363.039155) (xy 212.480396 -362.975114) (xy 212.357205 -362.90399) (xy 212.238236 -362.82601)
			(xy 212.123868 -362.741424) (xy 212.014469 -362.650504) (xy 211.91039 -362.55354) (xy 211.811962 -362.450843)
			(xy 211.719503 -362.342741) (xy 211.633307 -362.229582) (xy 211.553652 -362.111728) (xy 211.480791 -361.989556)
			(xy 211.41496 -361.863458) (xy 211.356367 -361.733837) (xy 211.305202 -361.601109) (xy 211.261628 -361.465699)
			(xy 211.225784 -361.32804) (xy 211.197786 -361.188574) (xy 211.177723 -361.047748) (xy 211.16566 -360.906012)
			(xy 211.161635 -360.76382) (xy 121.930771 -360.76382) (xy 121.954005 -360.769894) (xy 122.005573 -360.791808)
			(xy 122.053401 -360.820997) (xy 122.096469 -360.856838) (xy 122.133859 -360.898568) (xy 122.164775 -360.945298)
			(xy 122.188558 -360.996031) (xy 122.2047 -361.049687) (xy 122.212859 -361.105121) (xy 122.21337 -361.133136)
			(xy 122.212859 -361.161151) (xy 122.2047 -361.216585) (xy 122.188558 -361.270241) (xy 122.164775 -361.320974)
			(xy 122.133859 -361.367704) (xy 122.096469 -361.409434) (xy 122.053401 -361.445275) (xy 122.005573 -361.474464)
			(xy 121.954005 -361.496378) (xy 121.899796 -361.51055) (xy 121.844101 -361.516678) (xy 121.788107 -361.514632)
			(xy 121.733009 -361.504455) (xy 121.679979 -361.486363) (xy 121.630148 -361.460744) (xy 121.584578 -361.428142)
			(xy 121.544242 -361.389252) (xy 121.509997 -361.344904) (xy 121.482574 -361.296042) (xy 121.462558 -361.243708)
			(xy 121.450375 -361.189018) (xy 121.446286 -361.133136) (xy 15.239789 -361.133136) (xy 15.227982 -361.28787)
			(xy 15.204052 -361.496426) (xy 15.1722 -361.703919) (xy 15.132472 -361.91005) (xy 15.084925 -362.114519)
			(xy 15.029628 -362.317029) (xy 14.966661 -362.517287) (xy 14.896116 -362.715003) (xy 14.818095 -362.90989)
			(xy 14.732711 -363.101665) (xy 14.640088 -363.290051) (xy 14.540361 -363.474774) (xy 14.433673 -363.655566)
			(xy 14.320179 -363.832166) (xy 14.200044 -364.004316) (xy 14.073443 -364.171769) (xy 13.940558 -364.33428)
			(xy 13.801583 -364.491614) (xy 13.656719 -364.643543) (xy 13.506176 -364.789847) (xy 13.350172 -364.930314)
			(xy 13.188933 -365.06474) (xy 13.022693 -365.192929) (xy 12.851694 -365.314697) (xy 12.676183 -365.429867)
			(xy 12.496415 -365.538271) (xy 12.31265 -365.639753) (xy 12.125154 -365.734165) (xy 11.934201 -365.821371)
			(xy 11.740065 -365.901244) (xy 11.54303 -365.973668) (xy 11.34338 -366.038538) (xy 11.141405 -366.09576)
			(xy 10.937399 -366.145252) (xy 10.731655 -366.186941) (xy 10.524474 -366.220766) (xy 10.316156 -366.24668)
			(xy 10.107002 -366.264645) (xy 9.897315 -366.274633) (xy 9.687401 -366.276632) (xy 9.477562 -366.270637)
			(xy 9.268104 -366.256658) (xy 9.059329 -366.234715) (xy 8.851542 -366.20484) (xy 8.645043 -366.167075)
			(xy 8.44013 -366.121477) (xy 8.237103 -366.06811) (xy 8.036254 -366.007053) (xy 7.837876 -365.938394)
			(xy 7.642255 -365.862231) (xy 7.449675 -365.778677) (xy 7.260417 -365.687852) (xy 7.074753 -365.589887)
			(xy 6.892953 -365.484925) (xy 6.715281 -365.373118) (xy 6.541995 -365.254627) (xy 6.373345 -365.129626)
			(xy 6.209576 -364.998294) (xy 6.050926 -364.860823) (xy 5.897624 -364.717412) (xy 5.749894 -364.568268)
			(xy 5.607948 -364.413608) (xy 5.471994 -364.253657) (xy 5.342227 -364.088645) (xy 5.218837 -363.918813)
			(xy 5.102002 -363.744406) (xy 4.991891 -363.565678) (xy 4.888664 -363.382887) (xy 4.792471 -363.196299)
			(xy 4.703452 -363.006184) (xy 4.621734 -362.812818) (xy 4.547438 -362.616481) (xy 4.48067 -362.417458)
			(xy 4.421528 -362.216037) (xy 4.370096 -362.012511) (xy 4.326451 -361.807174) (xy 4.290654 -361.600324)
			(xy 4.262758 -361.392262) (xy 4.242804 -361.183288) (xy 4.230819 -360.973706) (xy 4.226823 -360.76382)
			(xy 2.509012 -360.76382) (xy 2.509012 -383.932484) (xy 8.539215 -383.932484) (xy 8.539215 -383.803344)
			(xy 8.547165 -383.674449) (xy 8.563035 -383.546289) (xy 8.586764 -383.419348) (xy 8.618263 -383.294109)
			(xy 8.657412 -383.171046) (xy 8.704063 -383.050627) (xy 8.758038 -382.933308) (xy 8.819133 -382.819534)
			(xy 8.887116 -382.709737) (xy 8.96173 -382.604334) (xy 9.042691 -382.503724) (xy 9.129691 -382.408289)
			(xy 9.222402 -382.31839) (xy 9.320472 -382.234369) (xy 9.423527 -382.156545) (xy 9.531178 -382.085213)
			(xy 9.643017 -382.020643) (xy 9.758618 -381.963081) (xy 9.877543 -381.912744) (xy 9.999342 -381.869824)
			(xy 10.123552 -381.834483) (xy 10.249701 -381.806856) (xy 10.377313 -381.787047) (xy 10.505902 -381.775131)
			(xy 10.63498 -381.771155) (xy 10.764058 -381.775131) (xy 10.892647 -381.787047) (xy 11.020259 -381.806856)
			(xy 11.146408 -381.834483) (xy 11.270618 -381.869824) (xy 11.392417 -381.912744) (xy 11.511342 -381.963081)
			(xy 11.626943 -382.020643) (xy 11.738782 -382.085213) (xy 11.846433 -382.156545) (xy 11.949488 -382.234369)
			(xy 12.047558 -382.31839) (xy 12.140269 -382.408289) (xy 12.227269 -382.503724) (xy 12.30823 -382.604334)
			(xy 12.382844 -382.709737) (xy 12.450827 -382.819534) (xy 12.505341 -382.921052) (xy 19.016679 -382.921052)
			(xy 19.016679 -382.866548) (xy 19.024437 -382.812598) (xy 19.039793 -382.760301) (xy 19.062436 -382.710722)
			(xy 19.091904 -382.664871) (xy 19.127599 -382.62368) (xy 19.168792 -382.587989) (xy 19.214645 -382.558523)
			(xy 19.264226 -382.535884) (xy 19.316523 -382.520531) (xy 19.370474 -382.512778) (xy 19.397726 -382.512316)
			(xy 20.261326 -382.512316) (xy 20.288578 -382.512756) (xy 20.342526 -382.520516) (xy 20.394821 -382.535874)
			(xy 20.444398 -382.558518) (xy 20.490248 -382.587987) (xy 20.531438 -382.623681) (xy 20.567129 -382.664873)
			(xy 20.596594 -382.710725) (xy 20.619235 -382.760303) (xy 20.63459 -382.812599) (xy 20.642346 -382.866548)
			(xy 20.642346 -382.921052) (xy 20.636681 -382.960459) (xy 22.291788 -382.960459) (xy 22.291788 -382.905921)
			(xy 22.29955 -382.851938) (xy 22.314915 -382.79961) (xy 22.337571 -382.75) (xy 22.367056 -382.70412)
			(xy 22.40277 -382.662903) (xy 22.443987 -382.627188) (xy 22.489867 -382.597702) (xy 22.539476 -382.575046)
			(xy 22.591804 -382.559681) (xy 22.645787 -382.551919) (xy 22.673056 -382.551432) (xy 23.536656 -382.551432)
			(xy 23.563927 -382.551887) (xy 23.617915 -382.559649) (xy 23.670249 -382.575015) (xy 23.719863 -382.597673)
			(xy 23.765748 -382.62716) (xy 23.806969 -382.662878) (xy 23.842687 -382.704099) (xy 23.872175 -382.749983)
			(xy 23.894834 -382.799597) (xy 23.9102 -382.851931) (xy 23.917962 -382.905919) (xy 23.917962 -382.960461)
			(xy 23.9102 -383.014449) (xy 23.894834 -383.066783) (xy 23.872175 -383.116397) (xy 23.842687 -383.162281)
			(xy 23.806969 -383.203502) (xy 23.765748 -383.23922) (xy 23.719863 -383.268707) (xy 23.670249 -383.291365)
			(xy 23.617915 -383.306731) (xy 23.563927 -383.314493) (xy 23.536656 -383.314956) (xy 22.673056 -383.314956)
			(xy 22.645787 -383.314461) (xy 22.591804 -383.306699) (xy 22.539476 -383.291334) (xy 22.489867 -383.268678)
			(xy 22.443987 -383.239192) (xy 22.40277 -383.203477) (xy 22.367056 -383.16226) (xy 22.337571 -383.11638)
			(xy 22.314915 -383.06677) (xy 22.29955 -383.014442) (xy 22.291788 -382.960459) (xy 20.636681 -382.960459)
			(xy 20.63459 -382.975001) (xy 20.619235 -383.027297) (xy 20.596594 -383.076875) (xy 20.567129 -383.122727)
			(xy 20.531438 -383.163919) (xy 20.490248 -383.199613) (xy 20.444398 -383.229082) (xy 20.394821 -383.251726)
			(xy 20.342526 -383.267084) (xy 20.288578 -383.274844) (xy 20.261326 -383.275332) (xy 19.397726 -383.275332)
			(xy 19.370474 -383.274822) (xy 19.316523 -383.267069) (xy 19.264226 -383.251716) (xy 19.214645 -383.229077)
			(xy 19.168792 -383.199611) (xy 19.127599 -383.16392) (xy 19.091904 -383.122729) (xy 19.062436 -383.076878)
			(xy 19.039793 -383.027299) (xy 19.024437 -382.975002) (xy 19.016679 -382.921052) (xy 12.505341 -382.921052)
			(xy 12.511922 -382.933308) (xy 12.565897 -383.050627) (xy 12.612548 -383.171046) (xy 12.651697 -383.294109)
			(xy 12.683196 -383.419348) (xy 12.706925 -383.546289) (xy 12.722795 -383.674449) (xy 12.730745 -383.803344)
			(xy 12.731242 -383.867914) (xy 12.730745 -383.932484) (xy 12.722795 -384.061379) (xy 12.706925 -384.189539)
			(xy 12.683196 -384.31648) (xy 12.651697 -384.441719) (xy 12.612548 -384.564782) (xy 12.565897 -384.685201)
			(xy 12.511922 -384.80252) (xy 12.450827 -384.916294) (xy 12.382844 -385.026091) (xy 12.30823 -385.131494)
			(xy 12.227269 -385.232104) (xy 12.140269 -385.327539) (xy 12.047558 -385.417438) (xy 11.949488 -385.501459)
			(xy 11.846433 -385.579283) (xy 11.738782 -385.650615) (xy 11.626943 -385.715185) (xy 11.511342 -385.772747)
			(xy 11.483943 -385.784344) (xy 19.460972 -385.784344) (xy 19.460972 -384.920744) (xy 19.461458 -384.893493)
			(xy 19.469214 -384.839545) (xy 19.484569 -384.78725) (xy 19.507211 -384.737673) (xy 19.536677 -384.691823)
			(xy 19.572368 -384.650632) (xy 19.613559 -384.614941) (xy 19.659409 -384.585475) (xy 19.708986 -384.562833)
			(xy 19.761281 -384.547478) (xy 19.815229 -384.539722) (xy 19.869731 -384.539722) (xy 19.923679 -384.547478)
			(xy 19.975974 -384.562833) (xy 20.025551 -384.585475) (xy 20.071401 -384.614941) (xy 20.112592 -384.650632)
			(xy 20.148283 -384.691823) (xy 20.177749 -384.737673) (xy 20.200391 -384.78725) (xy 20.215746 -384.839545)
			(xy 20.223502 -384.893493) (xy 20.223988 -384.920744) (xy 20.223988 -385.784344) (xy 20.22353 -385.809998)
			(xy 22.731984 -385.809998) (xy 22.731984 -384.946398) (xy 22.73247 -384.919147) (xy 22.740226 -384.865199)
			(xy 22.755581 -384.812904) (xy 22.778223 -384.763327) (xy 22.807689 -384.717477) (xy 22.84338 -384.676286)
			(xy 22.884571 -384.640595) (xy 22.930421 -384.611129) (xy 22.979998 -384.588487) (xy 23.032293 -384.573132)
			(xy 23.086241 -384.565376) (xy 23.140743 -384.565376) (xy 23.194691 -384.573132) (xy 23.246986 -384.588487)
			(xy 23.296563 -384.611129) (xy 23.342413 -384.640595) (xy 23.383604 -384.676286) (xy 23.419295 -384.717477)
			(xy 23.448761 -384.763327) (xy 23.471403 -384.812904) (xy 23.486758 -384.865199) (xy 23.494514 -384.919147)
			(xy 23.495 -384.946398) (xy 23.495 -385.440249) (xy 36.585674 -385.440249) (xy 36.585674 -385.385751)
			(xy 36.593429 -385.331807) (xy 36.608782 -385.279515) (xy 36.63142 -385.229941) (xy 36.660882 -385.184092)
			(xy 36.696569 -385.142903) (xy 36.737753 -385.107211) (xy 36.783598 -385.077743) (xy 36.83317 -385.055099)
			(xy 36.88546 -385.039739) (xy 36.939403 -385.031977) (xy 36.966652 -385.031488) (xy 37.830252 -385.031488)
			(xy 37.857507 -385.031956) (xy 37.911462 -385.039707) (xy 37.963765 -385.055059) (xy 38.013351 -385.077699)
			(xy 38.05921 -385.107165) (xy 38.100408 -385.142858) (xy 38.136106 -385.184052) (xy 38.165578 -385.229907)
			(xy 38.188224 -385.27949) (xy 38.203582 -385.331791) (xy 38.211341 -385.385745) (xy 38.211341 -385.440255)
			(xy 38.203582 -385.494209) (xy 38.188224 -385.54651) (xy 38.165578 -385.596093) (xy 38.16123 -385.602858)
			(xy 41.455211 -385.602858) (xy 41.455211 -385.548342) (xy 41.46297 -385.494381) (xy 41.47833 -385.442074)
			(xy 41.500978 -385.392486) (xy 41.530453 -385.346625) (xy 41.566155 -385.305427) (xy 41.607357 -385.269729)
			(xy 41.653221 -385.240259) (xy 41.702812 -385.217616) (xy 41.755121 -385.202261) (xy 41.809082 -385.194508)
			(xy 41.83634 -385.194048) (xy 42.69994 -385.194048) (xy 42.727186 -385.194625) (xy 42.781123 -385.202385)
			(xy 42.833407 -385.217742) (xy 42.882974 -385.240383) (xy 42.928814 -385.269847) (xy 42.969994 -385.305534)
			(xy 43.005677 -385.346718) (xy 43.035136 -385.392562) (xy 43.057772 -385.44213) (xy 43.073123 -385.494416)
			(xy 43.080878 -385.548354) (xy 43.080878 -385.602846) (xy 43.073123 -385.656784) (xy 43.057772 -385.70907)
			(xy 43.035136 -385.758638) (xy 43.005677 -385.804482) (xy 42.969994 -385.845666) (xy 42.928814 -385.881353)
			(xy 42.882974 -385.910817) (xy 42.833407 -385.933458) (xy 42.781123 -385.948815) (xy 42.727186 -385.956575)
			(xy 42.69994 -385.957064) (xy 41.83634 -385.957064) (xy 41.809082 -385.956692) (xy 41.755121 -385.948939)
			(xy 41.702812 -385.933584) (xy 41.653221 -385.910941) (xy 41.607357 -385.881471) (xy 41.566155 -385.845773)
			(xy 41.530453 -385.804575) (xy 41.500978 -385.758714) (xy 41.47833 -385.709126) (xy 41.46297 -385.656819)
			(xy 41.455211 -385.602858) (xy 38.16123 -385.602858) (xy 38.136106 -385.641948) (xy 38.100408 -385.683142)
			(xy 38.05921 -385.718835) (xy 38.013351 -385.748301) (xy 37.963765 -385.770941) (xy 37.911462 -385.786293)
			(xy 37.857507 -385.794044) (xy 37.830252 -385.794504) (xy 36.966652 -385.794504) (xy 36.939403 -385.794023)
			(xy 36.88546 -385.786261) (xy 36.83317 -385.770901) (xy 36.783598 -385.748257) (xy 36.737753 -385.718789)
			(xy 36.696569 -385.683097) (xy 36.660882 -385.641908) (xy 36.63142 -385.596059) (xy 36.608782 -385.546485)
			(xy 36.593429 -385.494193) (xy 36.585674 -385.440249) (xy 23.495 -385.440249) (xy 23.495 -385.809998)
			(xy 23.494514 -385.837249) (xy 23.486758 -385.891197) (xy 23.471403 -385.943492) (xy 23.448761 -385.993069)
			(xy 23.419295 -386.038919) (xy 23.383604 -386.08011) (xy 23.342413 -386.115801) (xy 23.296563 -386.145267)
			(xy 23.246986 -386.167909) (xy 23.194691 -386.183264) (xy 23.140743 -386.19102) (xy 23.086241 -386.19102)
			(xy 23.032293 -386.183264) (xy 22.979998 -386.167909) (xy 22.930421 -386.145267) (xy 22.884571 -386.115801)
			(xy 22.84338 -386.08011) (xy 22.807689 -386.038919) (xy 22.778223 -385.993069) (xy 22.755581 -385.943492)
			(xy 22.740226 -385.891197) (xy 22.73247 -385.837249) (xy 22.731984 -385.809998) (xy 20.22353 -385.809998)
			(xy 20.223502 -385.811595) (xy 20.215746 -385.865543) (xy 20.200391 -385.917838) (xy 20.177749 -385.967415)
			(xy 20.148283 -386.013265) (xy 20.112592 -386.054456) (xy 20.071401 -386.090147) (xy 20.025551 -386.119613)
			(xy 19.975974 -386.142255) (xy 19.923679 -386.15761) (xy 19.869731 -386.165366) (xy 19.815229 -386.165366)
			(xy 19.761281 -386.15761) (xy 19.708986 -386.142255) (xy 19.659409 -386.119613) (xy 19.613559 -386.090147)
			(xy 19.572368 -386.054456) (xy 19.536677 -386.013265) (xy 19.507211 -385.967415) (xy 19.484569 -385.917838)
			(xy 19.469214 -385.865543) (xy 19.461458 -385.811595) (xy 19.460972 -385.784344) (xy 11.483943 -385.784344)
			(xy 11.392417 -385.823084) (xy 11.270618 -385.866004) (xy 11.146408 -385.901345) (xy 11.020259 -385.928972)
			(xy 10.892647 -385.948781) (xy 10.764058 -385.960697) (xy 10.63498 -385.964674) (xy 10.505902 -385.960697)
			(xy 10.377313 -385.948781) (xy 10.249701 -385.928972) (xy 10.123552 -385.901345) (xy 9.999342 -385.866004)
			(xy 9.877543 -385.823084) (xy 9.758618 -385.772747) (xy 9.643017 -385.715185) (xy 9.531178 -385.650615)
			(xy 9.423527 -385.579283) (xy 9.320472 -385.501459) (xy 9.222402 -385.417438) (xy 9.129691 -385.327539)
			(xy 9.042691 -385.232104) (xy 8.96173 -385.131494) (xy 8.887116 -385.026091) (xy 8.819133 -384.916294)
			(xy 8.758038 -384.80252) (xy 8.704063 -384.685201) (xy 8.657412 -384.564782) (xy 8.618263 -384.441719)
			(xy 8.586764 -384.31648) (xy 8.563035 -384.189539) (xy 8.547165 -384.061379) (xy 8.539215 -383.932484)
			(xy 2.509012 -383.932484) (xy 2.509012 -389.402275) (xy 286.566098 -389.402275) (xy 286.566098 -389.317529)
			(xy 286.574154 -389.233168) (xy 286.590192 -389.149954) (xy 286.614067 -389.068641) (xy 286.645564 -388.989966)
			(xy 286.684397 -388.914642) (xy 286.730213 -388.843349) (xy 286.7826 -388.776735) (xy 286.84108 -388.715402)
			(xy 286.905127 -388.659906) (xy 286.974158 -388.610748) (xy 287.04755 -388.568376) (xy 287.124637 -388.533171)
			(xy 287.204721 -388.505454) (xy 287.287078 -388.485474) (xy 287.370961 -388.473414) (xy 287.45561 -388.469382)
			(xy 287.540259 -388.473414) (xy 287.624142 -388.485474) (xy 287.706499 -388.505454) (xy 287.786583 -388.533171)
			(xy 287.86367 -388.568376) (xy 287.937062 -388.610748) (xy 288.006093 -388.659906) (xy 288.07014 -388.715402)
			(xy 288.12862 -388.776735) (xy 288.181007 -388.843349) (xy 288.226823 -388.914642) (xy 288.265656 -388.989966)
			(xy 288.297153 -389.068641) (xy 288.321028 -389.149954) (xy 288.337066 -389.233168) (xy 288.345122 -389.317529)
			(xy 288.345626 -389.359902) (xy 288.345122 -389.402275) (xy 297.615098 -389.402275) (xy 297.615098 -389.317529)
			(xy 297.623154 -389.233168) (xy 297.639192 -389.149954) (xy 297.663067 -389.068641) (xy 297.694564 -388.989966)
			(xy 297.733397 -388.914642) (xy 297.779213 -388.843349) (xy 297.8316 -388.776735) (xy 297.89008 -388.715402)
			(xy 297.954127 -388.659906) (xy 298.023158 -388.610748) (xy 298.09655 -388.568376) (xy 298.173637 -388.533171)
			(xy 298.253721 -388.505454) (xy 298.336078 -388.485474) (xy 298.419961 -388.473414) (xy 298.50461 -388.469382)
			(xy 298.589259 -388.473414) (xy 298.673142 -388.485474) (xy 298.755499 -388.505454) (xy 298.835583 -388.533171)
			(xy 298.91267 -388.568376) (xy 298.986062 -388.610748) (xy 299.055093 -388.659906) (xy 299.11914 -388.715402)
			(xy 299.17762 -388.776735) (xy 299.230007 -388.843349) (xy 299.275823 -388.914642) (xy 299.314656 -388.989966)
			(xy 299.346153 -389.068641) (xy 299.370028 -389.149954) (xy 299.386066 -389.233168) (xy 299.394122 -389.317529)
			(xy 299.394626 -389.359902) (xy 299.394122 -389.402275) (xy 299.386066 -389.486636) (xy 299.370028 -389.56985)
			(xy 299.346153 -389.651163) (xy 299.314656 -389.729838) (xy 299.275823 -389.805162) (xy 299.230007 -389.876455)
			(xy 299.17762 -389.943069) (xy 299.11914 -390.004402) (xy 299.055093 -390.059898) (xy 298.986062 -390.109056)
			(xy 298.91267 -390.151428) (xy 298.835583 -390.186633) (xy 298.755499 -390.21435) (xy 298.673142 -390.23433)
			(xy 298.589259 -390.24639) (xy 298.50461 -390.250423) (xy 298.419961 -390.24639) (xy 298.336078 -390.23433)
			(xy 298.253721 -390.21435) (xy 298.173637 -390.186633) (xy 298.09655 -390.151428) (xy 298.023158 -390.109056)
			(xy 297.954127 -390.059898) (xy 297.89008 -390.004402) (xy 297.8316 -389.943069) (xy 297.779213 -389.876455)
			(xy 297.733397 -389.805162) (xy 297.694564 -389.729838) (xy 297.663067 -389.651163) (xy 297.639192 -389.56985)
			(xy 297.623154 -389.486636) (xy 297.615098 -389.402275) (xy 288.345122 -389.402275) (xy 288.337066 -389.486636)
			(xy 288.321028 -389.56985) (xy 288.297153 -389.651163) (xy 288.265656 -389.729838) (xy 288.226823 -389.805162)
			(xy 288.181007 -389.876455) (xy 288.12862 -389.943069) (xy 288.07014 -390.004402) (xy 288.006093 -390.059898)
			(xy 287.937062 -390.109056) (xy 287.86367 -390.151428) (xy 287.786583 -390.186633) (xy 287.706499 -390.21435)
			(xy 287.624142 -390.23433) (xy 287.540259 -390.24639) (xy 287.45561 -390.250423) (xy 287.370961 -390.24639)
			(xy 287.287078 -390.23433) (xy 287.204721 -390.21435) (xy 287.124637 -390.186633) (xy 287.04755 -390.151428)
			(xy 286.974158 -390.109056) (xy 286.905127 -390.059898) (xy 286.84108 -390.004402) (xy 286.7826 -389.943069)
			(xy 286.730213 -389.876455) (xy 286.684397 -389.805162) (xy 286.645564 -389.729838) (xy 286.614067 -389.651163)
			(xy 286.590192 -389.56985) (xy 286.574154 -389.486636) (xy 286.566098 -389.402275) (xy 2.509012 -389.402275)
			(xy 2.509012 -390.74852) (xy 289.828732 -390.74852) (xy 289.829157 -390.717787) (xy 289.836564 -390.656768)
			(xy 289.851272 -390.597088) (xy 289.873068 -390.539615) (xy 289.901633 -390.485189) (xy 289.93655 -390.434604)
			(xy 289.97731 -390.388596) (xy 290.023319 -390.347837) (xy 290.073907 -390.312922) (xy 290.128334 -390.28436)
			(xy 290.185807 -390.262566) (xy 290.245488 -390.24786) (xy 290.306507 -390.240455) (xy 290.33724 -390.240012)
			(xy 290.369283 -390.240508) (xy 290.432859 -390.248584) (xy 290.494917 -390.264579) (xy 290.554476 -390.288239)
			(xy 290.610594 -390.31919) (xy 290.662381 -390.356941) (xy 290.709019 -390.400896) (xy 290.749768 -390.450359)
			(xy 290.783985 -390.504546) (xy 290.811128 -390.562601) (xy 290.830767 -390.623604) (xy 290.842591 -390.686591)
			(xy 290.844986 -390.718548) (xy 290.846452 -390.733661) (xy 290.857061 -390.762093) (xy 290.875562 -390.786147)
			(xy 290.900318 -390.803698) (xy 290.929141 -390.813192) (xy 290.9443 -390.814052) (xy 290.977155 -390.815239)
			(xy 291.042167 -390.825028) (xy 291.105376 -390.843112) (xy 291.165728 -390.86919) (xy 291.222216 -390.902827)
			(xy 291.2739 -390.943462) (xy 291.319917 -390.990417) (xy 291.359501 -391.04291) (xy 291.391992 -391.100065)
			(xy 291.416847 -391.160931) (xy 291.433653 -391.224491) (xy 291.442129 -391.289688) (xy 291.442648 -391.32256)
			(xy 291.442106 -391.353289) (xy 291.434703 -391.414298) (xy 291.42 -391.473971) (xy 291.398212 -391.531436)
			(xy 291.369656 -391.585856) (xy 291.334748 -391.636437) (xy 291.293998 -391.682441) (xy 291.248 -391.723199)
			(xy 291.197424 -391.758114) (xy 291.143009 -391.786679) (xy 291.085547 -391.808477) (xy 291.025877 -391.823189)
			(xy 290.964869 -391.830602) (xy 290.93414 -391.831068) (xy 290.902098 -391.830516) (xy 290.838523 -391.822449)
			(xy 290.776465 -391.806463) (xy 290.716905 -391.78281) (xy 290.660787 -391.751866) (xy 290.608999 -391.71412)
			(xy 290.56236 -391.670169) (xy 290.521609 -391.620711) (xy 290.487392 -391.566526) (xy 290.460249 -391.508474)
			(xy 290.440611 -391.447473) (xy 290.428788 -391.384488) (xy 290.426394 -391.352532) (xy 290.424962 -391.337414)
			(xy 290.414346 -391.308979) (xy 290.395837 -391.284924) (xy 290.371072 -391.267376) (xy 290.342242 -391.257886)
			(xy 290.32708 -391.257028) (xy 290.294229 -391.25578) (xy 290.229223 -391.24599) (xy 290.166019 -391.227907)
			(xy 290.105673 -391.201832) (xy 290.049188 -391.1682) (xy 289.997507 -391.127571) (xy 289.95149 -391.080623)
			(xy 289.911906 -391.028137) (xy 289.879413 -390.97099) (xy 289.854553 -390.910132) (xy 289.837741 -390.846579)
			(xy 289.829256 -390.78139) (xy 289.828732 -390.74852) (xy 2.509012 -390.74852) (xy 2.509012 -394.8085)
			(xy 243.179528 -394.8085) (xy 243.183558 -394.723892) (xy 243.195613 -394.640051) (xy 243.215583 -394.557735)
			(xy 243.243287 -394.47769) (xy 243.278475 -394.400641) (xy 243.320827 -394.327286) (xy 243.36996 -394.258289)
			(xy 243.42543 -394.194274) (xy 243.486733 -394.135823) (xy 243.553315 -394.083463) (xy 243.624573 -394.03767)
			(xy 243.699861 -393.998857) (xy 243.778498 -393.967377) (xy 243.859771 -393.943515) (xy 243.942944 -393.927486)
			(xy 244.027264 -393.919435) (xy 244.069616 -393.918948) (xy 244.11084 -393.919417) (xy 244.192933 -393.927053)
			(xy 244.273968 -393.94225) (xy 244.35325 -393.964876) (xy 244.430099 -393.994739) (xy 244.503857 -394.031582)
			(xy 244.573891 -394.075088) (xy 244.639601 -394.124886) (xy 244.670326 -394.152374) (xy 244.677558 -394.158461)
			(xy 244.695171 -394.165287) (xy 244.714061 -394.165287) (xy 244.731674 -394.158461) (xy 244.738906 -394.152374)
			(xy 244.769639 -394.124894) (xy 244.835341 -394.075085) (xy 244.905371 -394.03157) (xy 244.979128 -393.994723)
			(xy 245.055977 -393.964858) (xy 245.13526 -393.942233) (xy 245.216297 -393.927041) (xy 245.298392 -393.919413)
			(xy 245.339616 -393.918948) (xy 245.380184 -393.919416) (xy 245.460981 -393.926807) (xy 245.54077 -393.941524)
			(xy 245.618888 -393.963447) (xy 245.694684 -393.992392) (xy 245.767529 -394.02812) (xy 245.836818 -394.070333)
			(xy 245.901975 -394.118681) (xy 245.962458 -394.172761) (xy 246.017765 -394.232125) (xy 246.067436 -394.296278)
			(xy 246.111059 -394.364689) (xy 246.130064 -394.400532) (xy 246.157157 -394.401367) (xy 246.21073 -394.409598)
			(xy 246.262601 -394.42532) (xy 246.31173 -394.448214) (xy 246.357129 -394.477824) (xy 246.397887 -394.513553)
			(xy 246.433186 -394.554684) (xy 246.462317 -394.600391) (xy 246.484695 -394.649758) (xy 246.499871 -394.701791)
			(xy 246.507539 -394.755447) (xy 246.508016 -394.782548) (xy 246.507582 -394.8085) (xy 249.114543 -394.8085)
			(xy 249.118574 -394.723896) (xy 249.130628 -394.640058) (xy 249.150596 -394.557746) (xy 249.178298 -394.477704)
			(xy 249.213483 -394.400658) (xy 249.255833 -394.327305) (xy 249.304963 -394.25831) (xy 249.360429 -394.194298)
			(xy 249.421729 -394.135847) (xy 249.488307 -394.083488) (xy 249.55956 -394.037695) (xy 249.634844 -393.998882)
			(xy 249.713476 -393.967401) (xy 249.794745 -393.943537) (xy 249.877914 -393.927506) (xy 249.96223 -393.919453)
			(xy 250.00458 -393.918948) (xy 250.045803 -393.919439) (xy 250.127896 -393.927072) (xy 250.20893 -393.942266)
			(xy 250.288212 -393.964889) (xy 250.365061 -393.994749) (xy 250.438819 -394.031588) (xy 250.508854 -394.075092)
			(xy 250.574564 -394.124887) (xy 250.60529 -394.152374) (xy 250.612522 -394.158461) (xy 250.630135 -394.165287)
			(xy 250.649025 -394.165287) (xy 250.666638 -394.158461) (xy 250.67387 -394.152374) (xy 250.704576 -394.124863)
			(xy 250.770283 -394.075057) (xy 250.840317 -394.031545) (xy 250.914078 -393.994701) (xy 250.990931 -393.96484)
			(xy 251.070218 -393.942219) (xy 251.151257 -393.927032) (xy 251.233355 -393.91941) (xy 251.27458 -393.918948)
			(xy 251.315219 -393.919386) (xy 251.396157 -393.926808) (xy 251.47608 -393.941582) (xy 251.554323 -393.963585)
			(xy 251.630232 -393.992634) (xy 251.703174 -394.028487) (xy 251.772542 -394.070844) (xy 251.837756 -394.119353)
			(xy 251.898274 -394.173608) (xy 251.95359 -394.233158) (xy 252.003243 -394.297505) (xy 252.046819 -394.366114)
			(xy 252.06579 -394.402056) (xy 252.086364 -394.401548) (xy 252.113582 -394.401996) (xy 252.167464 -394.409739)
			(xy 252.219695 -394.425073) (xy 252.269213 -394.447684) (xy 252.315007 -394.477114) (xy 252.356147 -394.512762)
			(xy 252.391793 -394.553902) (xy 252.421221 -394.599698) (xy 252.443832 -394.649216) (xy 252.459163 -394.701448)
			(xy 252.466905 -394.75533) (xy 252.467364 -394.782548) (xy 252.466916 -394.8085) (xy 255.049428 -394.8085)
			(xy 255.053459 -394.723891) (xy 255.065514 -394.640048) (xy 255.085484 -394.55773) (xy 255.11319 -394.477684)
			(xy 255.148379 -394.400634) (xy 255.190732 -394.327277) (xy 255.239868 -394.258279) (xy 255.295339 -394.194265)
			(xy 255.356645 -394.135813) (xy 255.423229 -394.083453) (xy 255.494489 -394.03766) (xy 255.56978 -393.998849)
			(xy 255.648419 -393.96737) (xy 255.729694 -393.943509) (xy 255.812869 -393.927482) (xy 255.897191 -393.919434)
			(xy 255.939544 -393.918948) (xy 255.980768 -393.919399) (xy 256.062862 -393.927038) (xy 256.143897 -393.942237)
			(xy 256.223179 -393.964866) (xy 256.300029 -393.994731) (xy 256.373786 -394.031576) (xy 256.44382 -394.075085)
			(xy 256.509529 -394.124885) (xy 256.540254 -394.152374) (xy 256.547486 -394.158461) (xy 256.565099 -394.165287)
			(xy 256.583989 -394.165287) (xy 256.601602 -394.158461) (xy 256.608834 -394.152374) (xy 256.639555 -394.12488)
			(xy 256.70526 -394.075073) (xy 256.775292 -394.031559) (xy 256.849049 -393.994713) (xy 256.925901 -393.96485)
			(xy 257.005185 -393.942227) (xy 257.086223 -393.927037) (xy 257.168319 -393.919412) (xy 257.209544 -393.918948)
			(xy 257.250365 -393.919407) (xy 257.331665 -393.926876) (xy 257.411938 -393.941765) (xy 257.490509 -393.963948)
			(xy 257.566715 -393.993239) (xy 257.639917 -394.029392) (xy 257.709496 -394.072102) (xy 257.774868 -394.121009)
			(xy 257.835483 -394.175702) (xy 257.890829 -394.235721) (xy 257.940442 -394.300559) (xy 257.983902 -394.369672)
			(xy 258.002786 -394.405866) (xy 258.01873 -394.403337) (xy 258.050905 -394.400664) (xy 258.067048 -394.400532)
			(xy 258.094337 -394.400926) (xy 258.148358 -394.408699) (xy 258.200723 -394.424081) (xy 258.250366 -394.446758)
			(xy 258.296278 -394.476268) (xy 258.337522 -394.512012) (xy 258.37326 -394.553261) (xy 258.402765 -394.599176)
			(xy 258.425436 -394.648822) (xy 258.440811 -394.701189) (xy 258.448577 -394.755211) (xy 258.448577 -394.8085)
			(xy 260.984428 -394.8085) (xy 260.988458 -394.723893) (xy 261.000513 -394.640052) (xy 261.020483 -394.557736)
			(xy 261.048186 -394.477692) (xy 261.083374 -394.400643) (xy 261.125725 -394.327288) (xy 261.174858 -394.258291)
			(xy 261.230327 -394.194277) (xy 261.29163 -394.135826) (xy 261.358212 -394.083466) (xy 261.429469 -394.037672)
			(xy 261.504756 -393.99886) (xy 261.583392 -393.967379) (xy 261.664664 -393.943516) (xy 261.747837 -393.927487)
			(xy 261.832156 -393.919436) (xy 261.874508 -393.918948) (xy 261.915732 -393.919422) (xy 261.997825 -393.927057)
			(xy 262.078859 -393.942253) (xy 262.158141 -393.964879) (xy 262.234991 -393.994741) (xy 262.308749 -394.031583)
			(xy 262.378783 -394.075089) (xy 262.444493 -394.124886) (xy 262.475218 -394.152374) (xy 262.48245 -394.158461)
			(xy 262.500063 -394.165287) (xy 262.518953 -394.165287) (xy 262.536566 -394.158461) (xy 262.543798 -394.152374)
			(xy 262.574534 -394.124897) (xy 262.640236 -394.075089) (xy 262.710266 -394.031574) (xy 262.784021 -393.994725)
			(xy 262.86087 -393.96486) (xy 262.940153 -393.942234) (xy 263.021189 -393.927042) (xy 263.103284 -393.919413)
			(xy 263.144508 -393.918948) (xy 263.185239 -393.919443) (xy 263.26636 -393.9269) (xy 263.346458 -393.941743)
			(xy 263.424865 -393.963847) (xy 263.500922 -393.993026) (xy 263.573993 -394.029037) (xy 263.643465 -394.071577)
			(xy 263.708758 -394.120291) (xy 263.769323 -394.174771) (xy 263.824654 -394.234559) (xy 263.874287 -394.299155)
			(xy 263.917806 -394.368019) (xy 263.936734 -394.404088) (xy 263.947933 -394.402872) (xy 263.970427 -394.401601)
			(xy 263.981692 -394.401548) (xy 264.008912 -394.401914) (xy 264.062799 -394.409661) (xy 264.115035 -394.424998)
			(xy 264.164556 -394.447612) (xy 264.210355 -394.477045) (xy 264.251499 -394.512695) (xy 264.287151 -394.553838)
			(xy 264.316584 -394.599637) (xy 264.3392 -394.649158) (xy 264.354537 -394.701393) (xy 264.362285 -394.75528)
			(xy 264.362285 -394.8085) (xy 266.919443 -394.8085) (xy 266.923474 -394.723896) (xy 266.935527 -394.640059)
			(xy 266.955496 -394.557747) (xy 266.983198 -394.477706) (xy 267.018382 -394.40066) (xy 267.060731 -394.327308)
			(xy 267.109861 -394.258313) (xy 267.165326 -394.194301) (xy 267.226625 -394.13585) (xy 267.293203 -394.083491)
			(xy 267.364456 -394.037698) (xy 267.439739 -393.998885) (xy 267.51837 -393.967403) (xy 267.599638 -393.943538)
			(xy 267.682807 -393.927507) (xy 267.767122 -393.919453) (xy 267.809472 -393.918948) (xy 267.850695 -393.919444)
			(xy 267.932787 -393.927077) (xy 268.013822 -393.942269) (xy 268.093103 -393.964892) (xy 268.169953 -393.994751)
			(xy 268.243711 -394.03159) (xy 268.313746 -394.075093) (xy 268.379456 -394.124888) (xy 268.410182 -394.152374)
			(xy 268.417414 -394.158461) (xy 268.435027 -394.165287) (xy 268.453917 -394.165287) (xy 268.47153 -394.158461)
			(xy 268.478762 -394.152374) (xy 268.509471 -394.124866) (xy 268.575178 -394.07506) (xy 268.645212 -394.031548)
			(xy 268.718971 -393.994703) (xy 268.795824 -393.964842) (xy 268.87511 -393.942221) (xy 268.95615 -393.927033)
			(xy 269.038247 -393.91941) (xy 269.079472 -393.918948) (xy 269.120039 -393.919454) (xy 269.200835 -393.92684)
			(xy 269.280624 -393.941554) (xy 269.35874 -393.963472) (xy 269.434536 -393.992414) (xy 269.507381 -394.028138)
			(xy 269.576671 -394.070348) (xy 269.641828 -394.118693) (xy 269.702312 -394.17277) (xy 269.757619 -394.232131)
			(xy 269.807291 -394.296282) (xy 269.850914 -394.36469) (xy 269.86992 -394.400532) (xy 269.897015 -394.401316)
			(xy 269.95059 -394.409555) (xy 270.002462 -394.425283) (xy 270.051591 -394.448184) (xy 270.096989 -394.477799)
			(xy 270.137747 -394.513533) (xy 270.173045 -394.554669) (xy 270.202175 -394.60038) (xy 270.224552 -394.64975)
			(xy 270.239727 -394.701787) (xy 270.247395 -394.755446) (xy 270.247872 -394.782548) (xy 270.24739 -394.8085)
			(xy 272.854328 -394.8085) (xy 272.858359 -394.723891) (xy 272.870414 -394.640048) (xy 272.890384 -394.557731)
			(xy 272.918089 -394.477686) (xy 272.953277 -394.400636) (xy 272.995631 -394.32728) (xy 273.044766 -394.258282)
			(xy 273.100237 -394.194267) (xy 273.161542 -394.135816) (xy 273.228125 -394.083456) (xy 273.299385 -394.037663)
			(xy 273.374675 -393.998851) (xy 273.453313 -393.967372) (xy 273.534587 -393.943511) (xy 273.617762 -393.927483)
			(xy 273.702084 -393.919434) (xy 273.744436 -393.918948) (xy 273.78566 -393.919404) (xy 273.867754 -393.927042)
			(xy 273.948789 -393.942241) (xy 274.028071 -393.964869) (xy 274.10492 -393.994734) (xy 274.178678 -394.031578)
			(xy 274.248712 -394.075086) (xy 274.314421 -394.124886) (xy 274.345146 -394.152374) (xy 274.352378 -394.158461)
			(xy 274.369991 -394.165287) (xy 274.388881 -394.165287) (xy 274.406494 -394.158461) (xy 274.413726 -394.152374)
			(xy 274.44445 -394.124884) (xy 274.510154 -394.075076) (xy 274.580186 -394.031562) (xy 274.653943 -393.994716)
			(xy 274.730794 -393.964852) (xy 274.810078 -393.942228) (xy 274.891116 -393.927038) (xy 274.973211 -393.919412)
			(xy 275.014436 -393.918948) (xy 275.055004 -393.9194) (xy 275.135802 -393.926792) (xy 275.215592 -393.941511)
			(xy 275.293709 -393.963435) (xy 275.369506 -393.992382) (xy 275.442351 -394.028112) (xy 275.51164 -394.070326)
			(xy 275.576797 -394.118675) (xy 275.63728 -394.172757) (xy 275.692586 -394.232122) (xy 275.742257 -394.296277)
			(xy 275.785879 -394.364688) (xy 275.804884 -394.400532) (xy 275.831978 -394.401349) (xy 275.885551 -394.409583)
			(xy 275.937423 -394.425306) (xy 275.986552 -394.448204) (xy 276.031951 -394.477815) (xy 276.072709 -394.513546)
			(xy 276.108007 -394.554678) (xy 276.137138 -394.600387) (xy 276.159515 -394.649755) (xy 276.174691 -394.70179)
			(xy 276.182359 -394.755447) (xy 276.182836 -394.782548) (xy 276.182385 -394.808456) (xy 278.916892 -394.808456)
			(xy 278.917356 -394.766262) (xy 278.925335 -394.682252) (xy 278.941234 -394.599376) (xy 278.964912 -394.518378)
			(xy 278.996156 -394.439987) (xy 279.034684 -394.364908) (xy 279.08015 -394.293815) (xy 279.132146 -394.227349)
			(xy 279.190203 -394.166106) (xy 279.2538 -394.110638) (xy 279.322365 -394.061443) (xy 279.395282 -394.018964)
			(xy 279.471894 -393.983582) (xy 279.551513 -393.955615) (xy 279.633423 -393.935316) (xy 279.675082 -393.9286)
			(xy 279.689459 -393.925944) (xy 279.715949 -393.913606) (xy 279.737852 -393.894262) (xy 279.753368 -393.869499)
			(xy 279.761223 -393.841352) (xy 279.760772 -393.812133) (xy 279.75687 -393.798044) (xy 279.744165 -393.755179)
			(xy 279.726399 -393.667554) (xy 279.717507 -393.578589) (xy 279.716992 -393.533884) (xy 279.717496 -393.491536)
			(xy 279.725547 -393.407222) (xy 279.741576 -393.324056) (xy 279.765437 -393.242789) (xy 279.796916 -393.164159)
			(xy 279.835727 -393.088878) (xy 279.881517 -393.017626) (xy 279.933873 -392.95105) (xy 279.992321 -392.889752)
			(xy 280.056331 -392.834287) (xy 280.125323 -392.785158) (xy 280.198673 -392.742809) (xy 280.275716 -392.707625)
			(xy 280.355755 -392.679923) (xy 280.438064 -392.659955) (xy 280.521899 -392.647902) (xy 280.6065 -392.643872)
			(xy 280.691101 -392.647902) (xy 280.774936 -392.659955) (xy 280.857245 -392.679923) (xy 280.937284 -392.707625)
			(xy 281.014327 -392.742809) (xy 281.087677 -392.785158) (xy 281.156669 -392.834287) (xy 281.220679 -392.889752)
			(xy 281.279127 -392.95105) (xy 281.331483 -393.017626) (xy 281.377273 -393.088878) (xy 281.416084 -393.164159)
			(xy 281.447563 -393.242789) (xy 281.471424 -393.324056) (xy 281.487453 -393.407222) (xy 281.495504 -393.491536)
			(xy 281.496008 -393.533884) (xy 281.495487 -393.576077) (xy 281.487514 -393.660085) (xy 281.47162 -393.74296)
			(xy 281.461756 -393.776708) (xy 289.471608 -393.776708) (xy 289.471608 -393.776454) (xy 289.47211 -393.744493)
			(xy 289.480121 -393.681075) (xy 289.496018 -393.619161) (xy 289.51955 -393.559728) (xy 289.550344 -393.503713)
			(xy 289.587917 -393.451998) (xy 289.631674 -393.405401) (xy 289.680927 -393.364656) (xy 289.734898 -393.330405)
			(xy 289.792737 -393.303188) (xy 289.85353 -393.283435) (xy 289.91632 -393.271457) (xy 289.980116 -393.267444)
			(xy 290.043912 -393.271457) (xy 290.106702 -393.283435) (xy 290.167495 -393.303188) (xy 290.225334 -393.330405)
			(xy 290.279305 -393.364656) (xy 290.328558 -393.405401) (xy 290.372315 -393.451998) (xy 290.409888 -393.503713)
			(xy 290.440682 -393.559728) (xy 290.464214 -393.619161) (xy 290.480111 -393.681075) (xy 290.488122 -393.744493)
			(xy 290.488624 -393.776454) (xy 290.488624 -393.7765) (xy 291.470768 -393.7765) (xy 291.474784 -393.712663)
			(xy 291.48677 -393.649832) (xy 291.506536 -393.589) (xy 291.533771 -393.531124) (xy 291.568045 -393.477118)
			(xy 291.608817 -393.427834) (xy 291.655445 -393.384049) (xy 291.707193 -393.346453) (xy 291.763245 -393.315639)
			(xy 291.822717 -393.292094) (xy 291.884671 -393.276188) (xy 291.94813 -393.268172) (xy 291.980112 -393.267692)
			(xy 292.010658 -393.268138) (xy 292.071311 -393.275449) (xy 292.13065 -393.289975) (xy 292.187822 -393.311508)
			(xy 292.242001 -393.339737) (xy 292.292406 -393.374254) (xy 292.338312 -393.414564) (xy 292.379057 -393.460084)
			(xy 292.396926 -393.484862) (xy 292.405296 -393.496027) (xy 292.426903 -393.51367) (xy 292.452477 -393.52481)
			(xy 292.480111 -393.528618) (xy 292.507745 -393.52481) (xy 292.533319 -393.51367) (xy 292.554926 -393.496027)
			(xy 292.563296 -393.484862) (xy 292.582389 -393.458454) (xy 292.626241 -393.410247) (xy 292.675892 -393.368039)
			(xy 292.730528 -393.332518) (xy 292.789254 -393.304269) (xy 292.851108 -393.283754) (xy 292.915076 -393.271309)
			(xy 292.98011 -393.267138) (xy 293.045144 -393.271309) (xy 293.109112 -393.283754) (xy 293.170966 -393.304269)
			(xy 293.229692 -393.332518) (xy 293.284328 -393.368039) (xy 293.333979 -393.410247) (xy 293.377831 -393.458454)
			(xy 293.396924 -393.484862) (xy 293.405294 -393.496027) (xy 293.426901 -393.51367) (xy 293.452475 -393.52481)
			(xy 293.480109 -393.528618) (xy 293.507743 -393.52481) (xy 293.533317 -393.51367) (xy 293.554924 -393.496027)
			(xy 293.563294 -393.484862) (xy 293.582387 -393.458454) (xy 293.626239 -393.410247) (xy 293.67589 -393.368039)
			(xy 293.730526 -393.332518) (xy 293.789252 -393.304269) (xy 293.851106 -393.283754) (xy 293.915074 -393.271309)
			(xy 293.980108 -393.267138) (xy 294.045142 -393.271309) (xy 294.10911 -393.283754) (xy 294.170964 -393.304269)
			(xy 294.22969 -393.332518) (xy 294.284326 -393.368039) (xy 294.333977 -393.410247) (xy 294.377829 -393.458454)
			(xy 294.396922 -393.484862) (xy 294.405292 -393.496027) (xy 294.426899 -393.51367) (xy 294.452473 -393.52481)
			(xy 294.480107 -393.528618) (xy 294.507741 -393.52481) (xy 294.533315 -393.51367) (xy 294.554922 -393.496027)
			(xy 294.563292 -393.484862) (xy 294.582385 -393.458454) (xy 294.626237 -393.410247) (xy 294.675888 -393.368039)
			(xy 294.730524 -393.332518) (xy 294.78925 -393.304269) (xy 294.851104 -393.283754) (xy 294.915072 -393.271309)
			(xy 294.980106 -393.267138) (xy 295.04514 -393.271309) (xy 295.109108 -393.283754) (xy 295.170962 -393.304269)
			(xy 295.229688 -393.332518) (xy 295.284324 -393.368039) (xy 295.333975 -393.410247) (xy 295.377827 -393.458454)
			(xy 295.39692 -393.484862) (xy 295.40529 -393.496027) (xy 295.426897 -393.51367) (xy 295.452471 -393.52481)
			(xy 295.480105 -393.528618) (xy 295.507739 -393.52481) (xy 295.533313 -393.51367) (xy 295.55492 -393.496027)
			(xy 295.56329 -393.484862) (xy 295.582383 -393.458454) (xy 295.626235 -393.410247) (xy 295.675886 -393.368039)
			(xy 295.730522 -393.332518) (xy 295.789248 -393.304269) (xy 295.851102 -393.283754) (xy 295.91507 -393.271309)
			(xy 295.980104 -393.267138) (xy 296.045138 -393.271309) (xy 296.109106 -393.283754) (xy 296.17096 -393.304269)
			(xy 296.229686 -393.332518) (xy 296.284322 -393.368039) (xy 296.333973 -393.410247) (xy 296.377825 -393.458454)
			(xy 296.396918 -393.484862) (xy 296.405288 -393.496027) (xy 296.426895 -393.51367) (xy 296.452469 -393.52481)
			(xy 296.480103 -393.528618) (xy 296.507737 -393.52481) (xy 296.533311 -393.51367) (xy 296.554918 -393.496027)
			(xy 296.563288 -393.484862) (xy 296.581151 -393.46008) (xy 296.621903 -393.414568) (xy 296.667813 -393.374265)
			(xy 296.71822 -393.339752) (xy 296.772399 -393.311525) (xy 296.829568 -393.289992) (xy 296.888906 -393.275462)
			(xy 296.949557 -393.268144) (xy 296.980102 -393.267692) (xy 297.012076 -393.268286) (xy 297.07552 -393.276301)
			(xy 297.137459 -393.292204) (xy 297.196916 -393.315745) (xy 297.252954 -393.346553) (xy 297.304689 -393.384141)
			(xy 297.351305 -393.427916) (xy 297.392067 -393.477189) (xy 297.426332 -393.531182) (xy 297.45356 -393.589044)
			(xy 297.473321 -393.649863) (xy 297.485304 -393.712678) (xy 297.489319 -393.7765) (xy 297.485304 -393.840322)
			(xy 297.473321 -393.903137) (xy 297.45356 -393.963956) (xy 297.426332 -394.021818) (xy 297.392067 -394.075811)
			(xy 297.351305 -394.125084) (xy 297.304689 -394.168859) (xy 297.252954 -394.206447) (xy 297.196916 -394.237255)
			(xy 297.137459 -394.260796) (xy 297.07552 -394.276699) (xy 297.012076 -394.284714) (xy 296.980102 -394.285216)
			(xy 296.949556 -394.284756) (xy 296.888904 -394.277447) (xy 296.829565 -394.262922) (xy 296.772394 -394.241392)
			(xy 296.718215 -394.213165) (xy 296.667809 -394.178649) (xy 296.621903 -394.138341) (xy 296.581158 -394.092823)
			(xy 296.563288 -394.068046) (xy 296.554946 -394.056837) (xy 296.53336 -394.03911) (xy 296.507771 -394.027912)
			(xy 296.480103 -394.024083) (xy 296.452435 -394.027912) (xy 296.426846 -394.03911) (xy 296.40526 -394.056837)
			(xy 296.396918 -394.068046) (xy 296.377825 -394.094454) (xy 296.333973 -394.142661) (xy 296.284322 -394.184869)
			(xy 296.229686 -394.22039) (xy 296.17096 -394.248639) (xy 296.109106 -394.269154) (xy 296.045138 -394.281599)
			(xy 295.980104 -394.28577) (xy 295.91507 -394.281599) (xy 295.851102 -394.269154) (xy 295.789248 -394.248639)
			(xy 295.730522 -394.22039) (xy 295.675886 -394.184869) (xy 295.626235 -394.142661) (xy 295.582383 -394.094454)
			(xy 295.56329 -394.068046) (xy 295.554948 -394.056837) (xy 295.533362 -394.03911) (xy 295.507773 -394.027912)
			(xy 295.480105 -394.024083) (xy 295.452437 -394.027912) (xy 295.426848 -394.03911) (xy 295.405262 -394.056837)
			(xy 295.39692 -394.068046) (xy 295.377827 -394.094454) (xy 295.333975 -394.142661) (xy 295.284324 -394.184869)
			(xy 295.229688 -394.22039) (xy 295.170962 -394.248639) (xy 295.109108 -394.269154) (xy 295.04514 -394.281599)
			(xy 294.980106 -394.28577) (xy 294.915072 -394.281599) (xy 294.851104 -394.269154) (xy 294.78925 -394.248639)
			(xy 294.730524 -394.22039) (xy 294.675888 -394.184869) (xy 294.626237 -394.142661) (xy 294.582385 -394.094454)
			(xy 294.563292 -394.068046) (xy 294.55495 -394.056837) (xy 294.533364 -394.03911) (xy 294.507775 -394.027912)
			(xy 294.480107 -394.024083) (xy 294.452439 -394.027912) (xy 294.42685 -394.03911) (xy 294.405264 -394.056837)
			(xy 294.396922 -394.068046) (xy 294.377829 -394.094454) (xy 294.333977 -394.142661) (xy 294.284326 -394.184869)
			(xy 294.22969 -394.22039) (xy 294.170964 -394.248639) (xy 294.10911 -394.269154) (xy 294.045142 -394.281599)
			(xy 293.980108 -394.28577) (xy 293.915074 -394.281599) (xy 293.851106 -394.269154) (xy 293.789252 -394.248639)
			(xy 293.730526 -394.22039) (xy 293.67589 -394.184869) (xy 293.626239 -394.142661) (xy 293.582387 -394.094454)
			(xy 293.563294 -394.068046) (xy 293.554952 -394.056837) (xy 293.533366 -394.03911) (xy 293.507777 -394.027912)
			(xy 293.480109 -394.024083) (xy 293.452441 -394.027912) (xy 293.426852 -394.03911) (xy 293.405266 -394.056837)
			(xy 293.396924 -394.068046) (xy 293.377831 -394.094454) (xy 293.333979 -394.142661) (xy 293.284328 -394.184869)
			(xy 293.229692 -394.22039) (xy 293.170966 -394.248639) (xy 293.109112 -394.269154) (xy 293.045144 -394.281599)
			(xy 292.98011 -394.28577) (xy 292.915076 -394.281599) (xy 292.851108 -394.269154) (xy 292.789254 -394.248639)
			(xy 292.730528 -394.22039) (xy 292.675892 -394.184869) (xy 292.626241 -394.142661) (xy 292.582389 -394.094454)
			(xy 292.563296 -394.068046) (xy 292.554954 -394.056837) (xy 292.533368 -394.03911) (xy 292.507779 -394.027912)
			(xy 292.480111 -394.024083) (xy 292.452443 -394.027912) (xy 292.426854 -394.03911) (xy 292.405268 -394.056837)
			(xy 292.396926 -394.068046) (xy 292.379057 -394.092823) (xy 292.338306 -394.138335) (xy 292.292396 -394.178638)
			(xy 292.24199 -394.213151) (xy 292.187812 -394.241378) (xy 292.130644 -394.262913) (xy 292.071307 -394.277444)
			(xy 292.010657 -394.284763) (xy 291.980112 -394.285216) (xy 291.94813 -394.284828) (xy 291.884671 -394.276812)
			(xy 291.822717 -394.260906) (xy 291.763245 -394.237361) (xy 291.707193 -394.206547) (xy 291.655445 -394.168951)
			(xy 291.608817 -394.125166) (xy 291.568045 -394.075882) (xy 291.533771 -394.021876) (xy 291.506536 -393.964)
			(xy 291.48677 -393.903168) (xy 291.474784 -393.840337) (xy 291.470768 -393.7765) (xy 290.488624 -393.7765)
			(xy 290.488624 -393.776962) (xy 290.488202 -393.806564) (xy 290.481324 -393.865367) (xy 290.467658 -393.922971)
			(xy 290.447389 -393.978597) (xy 290.420792 -394.03149) (xy 290.388226 -394.080932) (xy 290.369498 -394.10386)
			(xy 290.389588 -394.127178) (xy 290.424612 -394.17779) (xy 290.453267 -394.232263) (xy 290.475133 -394.289797)
			(xy 290.48989 -394.349552) (xy 290.497321 -394.410651) (xy 290.497768 -394.441426) (xy 290.497768 -394.44168)
			(xy 290.497266 -394.473641) (xy 290.489255 -394.537059) (xy 290.473358 -394.598973) (xy 290.449826 -394.658406)
			(xy 290.419032 -394.714421) (xy 290.381459 -394.766136) (xy 290.337702 -394.812733) (xy 290.288449 -394.853478)
			(xy 290.234478 -394.887729) (xy 290.176639 -394.914946) (xy 290.115846 -394.934699) (xy 290.053056 -394.946677)
			(xy 289.98926 -394.950691) (xy 289.925464 -394.946677) (xy 289.862674 -394.934699) (xy 289.801881 -394.914946)
			(xy 289.744042 -394.887729) (xy 289.690071 -394.853478) (xy 289.640818 -394.812733) (xy 289.597061 -394.766136)
			(xy 289.559488 -394.714421) (xy 289.528694 -394.658406) (xy 289.505162 -394.598973) (xy 289.489265 -394.537059)
			(xy 289.481254 -394.473641) (xy 289.480752 -394.44168) (xy 289.480752 -394.441172) (xy 289.481141 -394.411569)
			(xy 289.488026 -394.352765) (xy 289.501699 -394.29516) (xy 289.521974 -394.239535) (xy 289.548577 -394.186643)
			(xy 289.581148 -394.137202) (xy 289.599878 -394.114274) (xy 289.579769 -394.090972) (xy 289.544745 -394.040357)
			(xy 289.516091 -393.985882) (xy 289.494228 -393.928344) (xy 289.479476 -393.868586) (xy 289.472051 -393.807484)
			(xy 289.471608 -393.776708) (xy 281.461756 -393.776708) (xy 281.447947 -393.823957) (xy 281.416708 -393.902348)
			(xy 281.378185 -393.977427) (xy 281.332723 -394.04852) (xy 281.280732 -394.114986) (xy 281.222678 -394.176229)
			(xy 281.159084 -394.231698) (xy 281.090523 -394.280894) (xy 281.017609 -394.323374) (xy 280.941 -394.358757)
			(xy 280.861383 -394.386724) (xy 280.779476 -394.407024) (xy 280.737818 -394.41374) (xy 280.72343 -394.416347)
			(xy 280.696933 -394.428691) (xy 280.675026 -394.448046) (xy 280.659511 -394.472819) (xy 280.651661 -394.500977)
			(xy 280.652122 -394.530204) (xy 280.65603 -394.544296) (xy 280.668744 -394.587158) (xy 280.686507 -394.674785)
			(xy 280.695395 -394.763751) (xy 280.695908 -394.808456) (xy 280.695404 -394.850804) (xy 280.687353 -394.935118)
			(xy 280.671324 -395.018284) (xy 280.647463 -395.099551) (xy 280.615984 -395.178181) (xy 280.577173 -395.253462)
			(xy 280.531383 -395.324714) (xy 280.479027 -395.39129) (xy 280.420579 -395.452588) (xy 280.356569 -395.508053)
			(xy 280.287577 -395.557182) (xy 280.214227 -395.599531) (xy 280.137184 -395.634715) (xy 280.057145 -395.662417)
			(xy 279.974836 -395.682385) (xy 279.891001 -395.694438) (xy 279.8064 -395.698469) (xy 279.721799 -395.694438)
			(xy 279.637964 -395.682385) (xy 279.555655 -395.662417) (xy 279.475616 -395.634715) (xy 279.398573 -395.599531)
			(xy 279.325223 -395.557182) (xy 279.256231 -395.508053) (xy 279.192221 -395.452588) (xy 279.133773 -395.39129)
			(xy 279.081417 -395.324714) (xy 279.035627 -395.253462) (xy 278.996816 -395.178181) (xy 278.965337 -395.099551)
			(xy 278.941476 -395.018284) (xy 278.925447 -394.935118) (xy 278.917396 -394.850804) (xy 278.916892 -394.808456)
			(xy 276.182385 -394.808456) (xy 276.182339 -394.81111) (xy 276.173854 -394.867601) (xy 276.157051 -394.922198)
			(xy 276.132304 -394.973684) (xy 276.100165 -395.02091) (xy 276.061351 -395.062822) (xy 276.016728 -395.098487)
			(xy 275.967291 -395.127109) (xy 275.914142 -395.148048) (xy 275.858468 -395.160839) (xy 275.83003 -395.163548)
			(xy 275.812369 -395.202766) (xy 275.770577 -395.277947) (xy 275.721724 -395.348744) (xy 275.666266 -395.414494)
			(xy 275.60472 -395.474584) (xy 275.537661 -395.528453) (xy 275.465716 -395.575598) (xy 275.389556 -395.615578)
			(xy 275.309893 -395.648021) (xy 275.22747 -395.672622) (xy 275.143058 -395.689153) (xy 275.057444 -395.697459)
			(xy 275.014436 -395.697964) (xy 274.973213 -395.69746) (xy 274.891121 -395.689828) (xy 274.810087 -395.674636)
			(xy 274.730806 -395.652015) (xy 274.653956 -395.622157) (xy 274.580198 -395.585319) (xy 274.510163 -395.541817)
			(xy 274.444452 -395.492024) (xy 274.413726 -395.464538) (xy 274.406494 -395.458451) (xy 274.388881 -395.451625)
			(xy 274.369991 -395.451625) (xy 274.352378 -395.458451) (xy 274.345146 -395.464538) (xy 274.314435 -395.492044)
			(xy 274.248729 -395.54185) (xy 274.178695 -395.585362) (xy 274.104936 -395.622207) (xy 274.028083 -395.652068)
			(xy 273.948797 -395.67469) (xy 273.867758 -395.689878) (xy 273.785661 -395.697501) (xy 273.744436 -395.697964)
			(xy 273.702084 -395.697566) (xy 273.617762 -395.689517) (xy 273.534587 -395.673489) (xy 273.453313 -395.649628)
			(xy 273.374675 -395.618149) (xy 273.299385 -395.579337) (xy 273.228125 -395.533544) (xy 273.161542 -395.481184)
			(xy 273.100237 -395.422733) (xy 273.044766 -395.358718) (xy 272.995631 -395.28972) (xy 272.953277 -395.216364)
			(xy 272.918089 -395.139314) (xy 272.890384 -395.059269) (xy 272.870414 -394.976952) (xy 272.858359 -394.893109)
			(xy 272.854328 -394.8085) (xy 270.24739 -394.8085) (xy 270.247342 -394.811109) (xy 270.238858 -394.867596)
			(xy 270.222057 -394.922191) (xy 270.197312 -394.973674) (xy 270.165177 -395.020899) (xy 270.126367 -395.062811)
			(xy 270.081748 -395.098476) (xy 270.032316 -395.127099) (xy 269.979172 -395.148042) (xy 269.923503 -395.160836)
			(xy 269.895066 -395.163548) (xy 269.877376 -395.202752) (xy 269.835586 -395.277933) (xy 269.786736 -395.348729)
			(xy 269.73128 -395.414479) (xy 269.669737 -395.474569) (xy 269.602681 -395.528439) (xy 269.530739 -395.575585)
			(xy 269.454582 -395.615566) (xy 269.374921 -395.648011) (xy 269.292501 -395.672615) (xy 269.208091 -395.689148)
			(xy 269.122479 -395.697457) (xy 269.079472 -395.697964) (xy 269.038248 -395.6975) (xy 268.956155 -395.689862)
			(xy 268.87512 -395.674665) (xy 268.795838 -395.652037) (xy 268.718989 -395.622174) (xy 268.645231 -395.585331)
			(xy 268.575197 -395.541824) (xy 268.509487 -395.492026) (xy 268.478762 -395.464538) (xy 268.47153 -395.458451)
			(xy 268.453917 -395.451625) (xy 268.435027 -395.451625) (xy 268.417414 -395.458451) (xy 268.410182 -395.464538)
			(xy 268.379456 -395.492026) (xy 268.313752 -395.541834) (xy 268.243721 -395.585348) (xy 268.169964 -395.622194)
			(xy 268.093113 -395.652058) (xy 268.013829 -395.674682) (xy 267.932792 -395.689873) (xy 267.850696 -395.6975)
			(xy 267.809472 -395.697964) (xy 267.767122 -395.697547) (xy 267.682807 -395.689493) (xy 267.599638 -395.673462)
			(xy 267.51837 -395.649597) (xy 267.439739 -395.618115) (xy 267.364456 -395.579302) (xy 267.293203 -395.533509)
			(xy 267.226625 -395.48115) (xy 267.165326 -395.422699) (xy 267.109861 -395.358687) (xy 267.060731 -395.289692)
			(xy 267.018382 -395.21634) (xy 266.983198 -395.139294) (xy 266.955496 -395.059253) (xy 266.935527 -394.976941)
			(xy 266.923474 -394.893104) (xy 266.919443 -394.8085) (xy 264.362285 -394.8085) (xy 264.362285 -394.80972)
			(xy 264.354537 -394.863607) (xy 264.3392 -394.915842) (xy 264.316584 -394.965363) (xy 264.287151 -395.011162)
			(xy 264.251499 -395.052305) (xy 264.210355 -395.087955) (xy 264.164556 -395.117388) (xy 264.115035 -395.140002)
			(xy 264.062799 -395.155339) (xy 264.008912 -395.163086) (xy 263.981692 -395.163548) (xy 263.960356 -395.16304)
			(xy 263.942674 -395.202274) (xy 263.9009 -395.277517) (xy 263.852055 -395.348375) (xy 263.796597 -395.414185)
			(xy 263.735042 -395.474332) (xy 263.667968 -395.528254) (xy 263.596 -395.575447) (xy 263.519811 -395.61547)
			(xy 263.440113 -395.647949) (xy 263.357652 -395.67258) (xy 263.273197 -395.689134) (xy 263.187539 -395.697455)
			(xy 263.144508 -395.697964) (xy 263.103285 -395.697477) (xy 263.021192 -395.689843) (xy 262.940158 -395.674649)
			(xy 262.860876 -395.652025) (xy 262.784027 -395.622164) (xy 262.710269 -395.585324) (xy 262.640234 -395.54182)
			(xy 262.574524 -395.492025) (xy 262.543798 -395.464538) (xy 262.536566 -395.458451) (xy 262.518953 -395.451625)
			(xy 262.500063 -395.451625) (xy 262.48245 -395.458451) (xy 262.475218 -395.464538) (xy 262.444477 -395.492009)
			(xy 262.378775 -395.541818) (xy 262.308747 -395.585333) (xy 262.234992 -395.622182) (xy 262.158144 -395.652048)
			(xy 262.078861 -395.674675) (xy 261.997826 -395.689868) (xy 261.915732 -395.697498) (xy 261.874508 -395.697964)
			(xy 261.832156 -395.697564) (xy 261.747837 -395.689513) (xy 261.664664 -395.673484) (xy 261.583392 -395.649621)
			(xy 261.504756 -395.61814) (xy 261.429469 -395.579328) (xy 261.358212 -395.533534) (xy 261.29163 -395.481174)
			(xy 261.230327 -395.422723) (xy 261.174858 -395.358709) (xy 261.125725 -395.289712) (xy 261.083374 -395.216357)
			(xy 261.048186 -395.139308) (xy 261.020483 -395.059264) (xy 261.000513 -394.976948) (xy 260.988458 -394.893107)
			(xy 260.984428 -394.8085) (xy 258.448577 -394.8085) (xy 258.448577 -394.809789) (xy 258.440811 -394.863811)
			(xy 258.425436 -394.916178) (xy 258.402765 -394.965824) (xy 258.37326 -395.011739) (xy 258.337522 -395.052988)
			(xy 258.296278 -395.088732) (xy 258.250366 -395.118242) (xy 258.200723 -395.140919) (xy 258.148358 -395.156301)
			(xy 258.094337 -395.164074) (xy 258.067048 -395.164564) (xy 258.056676 -395.164479) (xy 258.035964 -395.163337)
			(xy 258.025646 -395.162278) (xy 258.008 -395.201564) (xy 257.966267 -395.276906) (xy 257.917448 -395.347861)
			(xy 257.861999 -395.413765) (xy 257.80044 -395.474001) (xy 257.733346 -395.528004) (xy 257.661347 -395.575269)
			(xy 257.585116 -395.615354) (xy 257.505368 -395.647883) (xy 257.422848 -395.672551) (xy 257.338331 -395.689127)
			(xy 257.252608 -395.697456) (xy 257.209544 -395.697964) (xy 257.168321 -395.697455) (xy 257.08623 -395.689824)
			(xy 257.005196 -395.674633) (xy 256.925914 -395.652012) (xy 256.849065 -395.622155) (xy 256.775306 -395.585317)
			(xy 256.705271 -395.541816) (xy 256.63956 -395.492023) (xy 256.608834 -395.464538) (xy 256.601602 -395.458451)
			(xy 256.583989 -395.451625) (xy 256.565099 -395.451625) (xy 256.547486 -395.458451) (xy 256.540254 -395.464538)
			(xy 256.50954 -395.49204) (xy 256.443834 -395.541846) (xy 256.373801 -395.585359) (xy 256.300042 -395.622204)
			(xy 256.22319 -395.652066) (xy 256.143904 -395.674688) (xy 256.062865 -395.689877) (xy 255.980769 -395.697501)
			(xy 255.939544 -395.697964) (xy 255.897191 -395.697566) (xy 255.812869 -395.689518) (xy 255.729694 -395.673491)
			(xy 255.648419 -395.64963) (xy 255.56978 -395.618151) (xy 255.494489 -395.57934) (xy 255.423229 -395.533547)
			(xy 255.356645 -395.481187) (xy 255.295339 -395.422735) (xy 255.239868 -395.358721) (xy 255.190732 -395.289723)
			(xy 255.148379 -395.216366) (xy 255.11319 -395.139316) (xy 255.085484 -395.05927) (xy 255.065514 -394.976952)
			(xy 255.053459 -394.893109) (xy 255.049428 -394.8085) (xy 252.466916 -394.8085) (xy 252.466897 -394.809592)
			(xy 252.459254 -394.863136) (xy 252.444116 -394.915061) (xy 252.421785 -394.964324) (xy 252.392711 -395.009932)
			(xy 252.357479 -395.05097) (xy 252.316797 -395.086613) (xy 252.271483 -395.116143) (xy 252.222447 -395.138967)
			(xy 252.170677 -395.154627) (xy 252.117212 -395.162807) (xy 252.090174 -395.163548) (xy 252.072477 -395.202749)
			(xy 252.030688 -395.27793) (xy 251.981838 -395.348725) (xy 251.926383 -395.414475) (xy 251.864841 -395.474566)
			(xy 251.797785 -395.528436) (xy 251.725844 -395.575582) (xy 251.649687 -395.615564) (xy 251.570027 -395.648009)
			(xy 251.487608 -395.672613) (xy 251.403198 -395.689147) (xy 251.317587 -395.697457) (xy 251.27458 -395.697964)
			(xy 251.233356 -395.697495) (xy 251.151263 -395.689858) (xy 251.070228 -395.674661) (xy 250.990947 -395.652035)
			(xy 250.914097 -395.622172) (xy 250.840339 -395.58533) (xy 250.770305 -395.541823) (xy 250.704595 -395.492026)
			(xy 250.67387 -395.464538) (xy 250.666638 -395.458451) (xy 250.649025 -395.451625) (xy 250.630135 -395.451625)
			(xy 250.612522 -395.458451) (xy 250.60529 -395.464538) (xy 250.574561 -395.492023) (xy 250.508857 -395.54183)
			(xy 250.438827 -395.585344) (xy 250.36507 -395.622192) (xy 250.28822 -395.652056) (xy 250.208936 -395.67468)
			(xy 250.127899 -395.689872) (xy 250.045804 -395.697499) (xy 250.00458 -395.697964) (xy 249.96223 -395.697547)
			(xy 249.877914 -395.689494) (xy 249.794745 -395.673463) (xy 249.713476 -395.649599) (xy 249.634844 -395.618118)
			(xy 249.55956 -395.579305) (xy 249.488307 -395.533512) (xy 249.421729 -395.481153) (xy 249.360429 -395.422702)
			(xy 249.304963 -395.35869) (xy 249.255833 -395.289695) (xy 249.213483 -395.216342) (xy 249.178298 -395.139296)
			(xy 249.150596 -395.059254) (xy 249.130628 -394.976942) (xy 249.118574 -394.893104) (xy 249.114543 -394.8085)
			(xy 246.507582 -394.8085) (xy 246.507538 -394.811111) (xy 246.499052 -394.867604) (xy 246.482248 -394.922202)
			(xy 246.457499 -394.973689) (xy 246.425358 -395.020916) (xy 246.386542 -395.062829) (xy 246.341916 -395.098493)
			(xy 246.292476 -395.127114) (xy 246.239326 -395.148052) (xy 246.183649 -395.16084) (xy 246.15521 -395.163548)
			(xy 246.137565 -395.202774) (xy 246.095772 -395.277955) (xy 246.046918 -395.348752) (xy 245.991458 -395.414502)
			(xy 245.929911 -395.474592) (xy 245.86285 -395.528461) (xy 245.790904 -395.575605) (xy 245.714742 -395.615585)
			(xy 245.635078 -395.648026) (xy 245.552653 -395.672626) (xy 245.46824 -395.689156) (xy 245.382624 -395.69746)
			(xy 245.339616 -395.697964) (xy 245.298393 -395.697472) (xy 245.216301 -395.689839) (xy 245.135266 -395.674645)
			(xy 245.055985 -395.652022) (xy 244.979135 -395.622162) (xy 244.905377 -395.585323) (xy 244.835342 -395.541819)
			(xy 244.769632 -395.492024) (xy 244.738906 -395.464538) (xy 244.731674 -395.458451) (xy 244.714061 -395.451625)
			(xy 244.695171 -395.451625) (xy 244.677558 -395.458451) (xy 244.670326 -395.464538) (xy 244.639624 -395.492053)
			(xy 244.573916 -395.541859) (xy 244.503881 -395.58537) (xy 244.43012 -395.622214) (xy 244.353266 -395.652074)
			(xy 244.273979 -395.674694) (xy 244.192939 -395.68988) (xy 244.110841 -395.697502) (xy 244.069616 -395.697964)
			(xy 244.027264 -395.697565) (xy 243.942944 -395.689514) (xy 243.859771 -395.673485) (xy 243.778498 -395.649623)
			(xy 243.699861 -395.618143) (xy 243.624573 -395.57933) (xy 243.553315 -395.533537) (xy 243.486733 -395.481177)
			(xy 243.42543 -395.422726) (xy 243.36996 -395.358711) (xy 243.320827 -395.289714) (xy 243.278475 -395.216359)
			(xy 243.243287 -395.13931) (xy 243.215583 -395.059265) (xy 243.195613 -394.976949) (xy 243.183558 -394.893108)
			(xy 243.179528 -394.8085) (xy 2.509012 -394.8085) (xy 2.509012 -396.842996) (xy 18.90268 -396.842996)
			(xy 18.90268 -395.979396) (xy 18.903166 -395.952145) (xy 18.910922 -395.898197) (xy 18.926277 -395.845902)
			(xy 18.948919 -395.796325) (xy 18.978385 -395.750475) (xy 19.014076 -395.709284) (xy 19.055267 -395.673593)
			(xy 19.101117 -395.644127) (xy 19.150694 -395.621485) (xy 19.202989 -395.60613) (xy 19.256937 -395.598374)
			(xy 19.311439 -395.598374) (xy 19.365387 -395.60613) (xy 19.417682 -395.621485) (xy 19.467259 -395.644127)
			(xy 19.513109 -395.673593) (xy 19.5543 -395.709284) (xy 19.589991 -395.750475) (xy 19.601933 -395.769057)
			(xy 288.471858 -395.769057) (xy 288.471858 -395.705103) (xy 288.479873 -395.641653) (xy 288.495778 -395.579708)
			(xy 288.519321 -395.520246) (xy 288.550131 -395.464202) (xy 288.587723 -395.412462) (xy 288.631502 -395.365842)
			(xy 288.68078 -395.325076) (xy 288.734778 -395.290808) (xy 288.792645 -395.263577) (xy 288.853469 -395.243814)
			(xy 288.91629 -395.231831) (xy 288.980118 -395.227815) (xy 289.043946 -395.231831) (xy 289.106767 -395.243814)
			(xy 289.167591 -395.263577) (xy 289.225458 -395.290808) (xy 289.279456 -395.325076) (xy 289.328734 -395.365842)
			(xy 289.372513 -395.412462) (xy 289.410105 -395.464202) (xy 289.440915 -395.520246) (xy 289.464458 -395.579708)
			(xy 289.480363 -395.641653) (xy 289.488378 -395.705103) (xy 289.48888 -395.73708) (xy 289.488378 -395.769057)
			(xy 289.480363 -395.832507) (xy 289.464458 -395.894452) (xy 289.440915 -395.953914) (xy 289.410105 -396.009958)
			(xy 289.372513 -396.061698) (xy 289.328734 -396.108318) (xy 289.279456 -396.149084) (xy 289.225458 -396.183352)
			(xy 289.167591 -396.210583) (xy 289.106767 -396.230346) (xy 289.043946 -396.242329) (xy 288.980118 -396.246345)
			(xy 288.91629 -396.242329) (xy 288.853469 -396.230346) (xy 288.792645 -396.210583) (xy 288.734778 -396.183352)
			(xy 288.68078 -396.149084) (xy 288.631502 -396.108318) (xy 288.587723 -396.061698) (xy 288.550131 -396.009958)
			(xy 288.519321 -395.953914) (xy 288.495778 -395.894452) (xy 288.479873 -395.832507) (xy 288.471858 -395.769057)
			(xy 19.601933 -395.769057) (xy 19.619457 -395.796325) (xy 19.642099 -395.845902) (xy 19.657454 -395.898197)
			(xy 19.66521 -395.952145) (xy 19.665696 -395.979396) (xy 19.665696 -396.842996) (xy 19.66521 -396.870247)
			(xy 19.657454 -396.924195) (xy 19.642099 -396.97649) (xy 19.619457 -397.026067) (xy 19.589991 -397.071917)
			(xy 19.5543 -397.113108) (xy 19.513109 -397.148799) (xy 19.467259 -397.178265) (xy 19.417682 -397.200907)
			(xy 19.365387 -397.216262) (xy 19.311439 -397.224018) (xy 19.256937 -397.224018) (xy 19.202989 -397.216262)
			(xy 19.150694 -397.200907) (xy 19.101117 -397.178265) (xy 19.055267 -397.148799) (xy 19.014076 -397.113108)
			(xy 18.978385 -397.071917) (xy 18.948919 -397.026067) (xy 18.926277 -396.97649) (xy 18.910922 -396.924195)
			(xy 18.903166 -396.870247) (xy 18.90268 -396.842996) (xy 2.509012 -396.842996) (xy 2.509012 -397.606012)
			(xy 24.954992 -397.606012) (xy 24.954992 -396.742412) (xy 24.955478 -396.715161) (xy 24.963234 -396.661213)
			(xy 24.978589 -396.608918) (xy 25.001231 -396.559341) (xy 25.030697 -396.513491) (xy 25.066388 -396.4723)
			(xy 25.107579 -396.436609) (xy 25.153429 -396.407143) (xy 25.203006 -396.384501) (xy 25.255301 -396.369146)
			(xy 25.309249 -396.36139) (xy 25.363751 -396.36139) (xy 25.417699 -396.369146) (xy 25.469994 -396.384501)
			(xy 25.519571 -396.407143) (xy 25.565421 -396.436609) (xy 25.606612 -396.4723) (xy 25.642303 -396.513491)
			(xy 25.671769 -396.559341) (xy 25.694411 -396.608918) (xy 25.709766 -396.661213) (xy 25.717522 -396.715161)
			(xy 25.718008 -396.742412) (xy 25.718008 -397.606012) (xy 25.717522 -397.633263) (xy 25.709766 -397.687211)
			(xy 25.694411 -397.739506) (xy 25.671769 -397.789083) (xy 25.642303 -397.834933) (xy 25.606612 -397.876124)
			(xy 25.565421 -397.911815) (xy 25.519571 -397.941281) (xy 25.469994 -397.963923) (xy 25.417699 -397.979278)
			(xy 25.363751 -397.987034) (xy 25.309249 -397.987034) (xy 25.255301 -397.979278) (xy 25.203006 -397.963923)
			(xy 25.153429 -397.941281) (xy 25.107579 -397.911815) (xy 25.066388 -397.876124) (xy 25.030697 -397.834933)
			(xy 25.001231 -397.789083) (xy 24.978589 -397.739506) (xy 24.963234 -397.687211) (xy 24.955478 -397.633263)
			(xy 24.954992 -397.606012) (xy 2.509012 -397.606012) (xy 2.509012 -398.68657) (xy 36.781952 -398.68657)
			(xy 36.781952 -398.63203) (xy 36.789714 -398.578046) (xy 36.805081 -398.525717) (xy 36.827739 -398.476107)
			(xy 36.857227 -398.430227) (xy 36.892945 -398.389011) (xy 36.934165 -398.353298) (xy 36.980049 -398.323816)
			(xy 37.029662 -398.301164) (xy 37.081993 -398.285804) (xy 37.135978 -398.278048) (xy 37.163248 -398.277588)
			(xy 38.026848 -398.277588) (xy 38.054119 -398.277978) (xy 38.108104 -398.285746) (xy 38.160435 -398.301118)
			(xy 38.210045 -398.323779) (xy 38.255926 -398.353271) (xy 38.297144 -398.38899) (xy 38.332858 -398.430212)
			(xy 38.362344 -398.476097) (xy 38.384999 -398.52571) (xy 38.400364 -398.578043) (xy 38.408126 -398.632029)
			(xy 38.408126 -398.686571) (xy 38.400364 -398.740557) (xy 38.384999 -398.79289) (xy 38.38214 -398.799152)
			(xy 42.10455 -398.799152) (xy 42.10455 -398.744648) (xy 42.112306 -398.6907) (xy 42.12766 -398.638404)
			(xy 42.150301 -398.588826) (xy 42.179766 -398.542974) (xy 42.215456 -398.501781) (xy 42.256645 -398.466087)
			(xy 42.302494 -398.436618) (xy 42.35207 -398.413973) (xy 42.404365 -398.398614) (xy 42.458312 -398.390852)
			(xy 42.485564 -398.390364) (xy 43.349164 -398.390364) (xy 43.376417 -398.390881) (xy 43.430367 -398.398633)
			(xy 43.482666 -398.413985) (xy 43.532247 -398.436624) (xy 43.578101 -398.466088) (xy 43.619295 -398.50178)
			(xy 43.65499 -398.54297) (xy 43.684459 -398.588822) (xy 43.707103 -398.638401) (xy 43.722459 -398.690697)
			(xy 43.730217 -398.744648) (xy 43.730217 -398.799152) (xy 43.722459 -398.853103) (xy 43.707103 -398.9054)
			(xy 43.684459 -398.954978) (xy 43.65499 -399.00083) (xy 43.619295 -399.04202) (xy 43.578101 -399.077712)
			(xy 43.532247 -399.107176) (xy 43.482666 -399.129815) (xy 43.430367 -399.145167) (xy 43.376417 -399.152919)
			(xy 43.349164 -399.15338) (xy 42.485564 -399.15338) (xy 42.458312 -399.152948) (xy 42.404365 -399.145186)
			(xy 42.35207 -399.129827) (xy 42.302494 -399.107182) (xy 42.256645 -399.077713) (xy 42.215456 -399.042019)
			(xy 42.179766 -399.000826) (xy 42.150301 -398.954974) (xy 42.12766 -398.905396) (xy 42.112306 -398.8531)
			(xy 42.10455 -398.799152) (xy 38.38214 -398.799152) (xy 38.362344 -398.842503) (xy 38.332858 -398.888388)
			(xy 38.297144 -398.92961) (xy 38.255926 -398.965329) (xy 38.210045 -398.994821) (xy 38.160435 -399.017482)
			(xy 38.108104 -399.032854) (xy 38.054119 -399.040622) (xy 38.026848 -399.041112) (xy 37.163248 -399.041112)
			(xy 37.135978 -399.040552) (xy 37.081993 -399.032796) (xy 37.029662 -399.017436) (xy 36.980049 -398.994784)
			(xy 36.934165 -398.965302) (xy 36.892945 -398.929589) (xy 36.857227 -398.888373) (xy 36.827739 -398.842493)
			(xy 36.805081 -398.792883) (xy 36.789714 -398.740554) (xy 36.781952 -398.68657) (xy 2.509012 -398.68657)
			(xy 2.509012 -399.443249) (xy 18.470394 -399.443249) (xy 18.470394 -399.388751) (xy 18.47815 -399.334808)
			(xy 18.493503 -399.282518) (xy 18.516141 -399.232945) (xy 18.545603 -399.187098) (xy 18.58129 -399.14591)
			(xy 18.622475 -399.11022) (xy 18.66832 -399.080754) (xy 18.717892 -399.058112) (xy 18.770181 -399.042756)
			(xy 18.824123 -399.034996) (xy 18.851372 -399.034508) (xy 19.714972 -399.034508) (xy 19.742227 -399.034937)
			(xy 19.796184 -399.042691) (xy 19.848487 -399.058045) (xy 19.898073 -399.080687) (xy 19.943931 -399.110156)
			(xy 19.985129 -399.145851) (xy 20.020827 -399.187046) (xy 20.050299 -399.232903) (xy 20.072945 -399.282487)
			(xy 20.088303 -399.334789) (xy 20.096061 -399.388745) (xy 20.096061 -399.443255) (xy 20.088303 -399.497211)
			(xy 20.072945 -399.549513) (xy 20.050299 -399.599097) (xy 20.020828 -399.644954) (xy 19.985129 -399.686149)
			(xy 19.943931 -399.721844) (xy 19.898073 -399.751313) (xy 19.848487 -399.773955) (xy 19.796184 -399.789309)
			(xy 19.742227 -399.797063) (xy 19.714972 -399.797524) (xy 18.851372 -399.797524) (xy 18.824123 -399.797004)
			(xy 18.770181 -399.789244) (xy 18.717892 -399.773888) (xy 18.66832 -399.751246) (xy 18.622475 -399.72178)
			(xy 18.58129 -399.68609) (xy 18.545603 -399.644902) (xy 18.516141 -399.599055) (xy 18.493503 -399.549482)
			(xy 18.47815 -399.497192) (xy 18.470394 -399.443249) (xy 2.509012 -399.443249) (xy 2.509012 -400.459248)
			(xy 25.590794 -400.459248) (xy 25.590794 -400.404752) (xy 25.598549 -400.350811) (xy 25.613901 -400.298522)
			(xy 25.636538 -400.24895) (xy 25.665999 -400.203104) (xy 25.701684 -400.161916) (xy 25.742867 -400.126226)
			(xy 25.788709 -400.09676) (xy 25.838279 -400.074117) (xy 25.890566 -400.058759) (xy 25.944506 -400.050997)
			(xy 25.971754 -400.050508) (xy 26.835354 -400.050508) (xy 26.86261 -400.050936) (xy 26.916568 -400.058688)
			(xy 26.968874 -400.07404) (xy 27.018462 -400.096681) (xy 27.064323 -400.126149) (xy 27.105523 -400.161845)
			(xy 27.141223 -400.20304) (xy 27.170697 -400.248897) (xy 27.193343 -400.298483) (xy 27.208702 -400.350787)
			(xy 27.216461 -400.404744) (xy 27.216461 -400.459256) (xy 27.208702 -400.513213) (xy 27.193343 -400.565517)
			(xy 27.170697 -400.615103) (xy 27.141223 -400.66096) (xy 27.105523 -400.702155) (xy 27.064323 -400.737851)
			(xy 27.018462 -400.767319) (xy 26.968874 -400.78996) (xy 26.916568 -400.805312) (xy 26.86261 -400.813064)
			(xy 26.835354 -400.813524) (xy 25.971754 -400.813524) (xy 25.944506 -400.813003) (xy 25.890566 -400.805241)
			(xy 25.838279 -400.789883) (xy 25.788709 -400.76724) (xy 25.742867 -400.737774) (xy 25.701684 -400.702084)
			(xy 25.665999 -400.660896) (xy 25.636538 -400.61505) (xy 25.613901 -400.565478) (xy 25.598549 -400.513189)
			(xy 25.590794 -400.459248) (xy 2.509012 -400.459248) (xy 2.509012 -400.885453) (xy 47.598783 -400.885453)
			(xy 47.598783 -400.830947) (xy 47.606541 -400.776997) (xy 47.621898 -400.7247) (xy 47.644541 -400.675121)
			(xy 47.674011 -400.629269) (xy 47.709706 -400.588079) (xy 47.7509 -400.552388) (xy 47.796754 -400.522923)
			(xy 47.846336 -400.500284) (xy 47.898634 -400.484933) (xy 47.952585 -400.477181) (xy 47.979838 -400.47672)
			(xy 48.843438 -400.47672) (xy 48.870689 -400.477152) (xy 48.924637 -400.484914) (xy 48.976931 -400.500273)
			(xy 49.026507 -400.522918) (xy 49.072356 -400.552388) (xy 49.113545 -400.588082) (xy 49.149235 -400.629274)
			(xy 49.1787 -400.675126) (xy 49.20134 -400.724705) (xy 49.216694 -400.777) (xy 49.22445 -400.830948)
			(xy 49.22445 -400.885448) (xy 50.662106 -400.885448) (xy 50.662106 -400.830952) (xy 50.669862 -400.77701)
			(xy 50.685214 -400.724721) (xy 50.707852 -400.675149) (xy 50.737314 -400.629303) (xy 50.773001 -400.588116)
			(xy 50.814185 -400.552427) (xy 50.86003 -400.522963) (xy 50.9096 -400.500322) (xy 50.961888 -400.484966)
			(xy 51.01583 -400.477208) (xy 51.043078 -400.47672) (xy 51.906678 -400.47672) (xy 51.933934 -400.477125)
			(xy 51.987891 -400.48488) (xy 52.040196 -400.500236) (xy 52.089782 -400.522879) (xy 52.135642 -400.552348)
			(xy 52.17684 -400.588045) (xy 52.212539 -400.629241) (xy 52.242011 -400.675098) (xy 52.264657 -400.724684)
			(xy 52.280015 -400.776987) (xy 52.287773 -400.830944) (xy 52.287773 -400.885452) (xy 53.725283 -400.885452)
			(xy 53.725283 -400.830948) (xy 53.73304 -400.777) (xy 53.748396 -400.724704) (xy 53.771038 -400.675127)
			(xy 53.800506 -400.629276) (xy 53.836199 -400.588086) (xy 53.87739 -400.552395) (xy 53.923242 -400.52293)
			(xy 53.972821 -400.50029) (xy 54.025117 -400.484936) (xy 54.079066 -400.477182) (xy 54.106318 -400.47672)
			(xy 54.969918 -400.47672) (xy 54.99717 -400.477151) (xy 55.05112 -400.48491) (xy 55.103417 -400.500268)
			(xy 55.152995 -400.522912) (xy 55.198847 -400.552381) (xy 55.240038 -400.588075) (xy 55.27573 -400.629268)
			(xy 55.305197 -400.675121) (xy 55.327838 -400.7247) (xy 55.343194 -400.776997) (xy 55.35095 -400.830948)
			(xy 55.35095 -400.885447) (xy 56.788606 -400.885447) (xy 56.788606 -400.830953) (xy 56.796361 -400.777013)
			(xy 56.811713 -400.724725) (xy 56.834349 -400.675154) (xy 56.863809 -400.629309) (xy 56.899494 -400.588123)
			(xy 56.940676 -400.552435) (xy 56.986518 -400.522969) (xy 57.036086 -400.500327) (xy 57.088372 -400.48497)
			(xy 57.142311 -400.477209) (xy 57.169558 -400.47672) (xy 58.033158 -400.47672) (xy 58.060415 -400.477124)
			(xy 58.114374 -400.484877) (xy 58.166681 -400.50023) (xy 58.21627 -400.522872) (xy 58.262132 -400.552341)
			(xy 58.303333 -400.588037) (xy 58.339034 -400.629234) (xy 58.368508 -400.675093) (xy 58.391155 -400.724679)
			(xy 58.406514 -400.776985) (xy 58.414273 -400.830943) (xy 58.414273 -400.885449) (xy 59.851806 -400.885449)
			(xy 59.851806 -400.830951) (xy 59.859562 -400.777007) (xy 59.874916 -400.724717) (xy 59.897555 -400.675143)
			(xy 59.927019 -400.629296) (xy 59.962708 -400.588109) (xy 60.003895 -400.55242) (xy 60.049742 -400.522956)
			(xy 60.099315 -400.500317) (xy 60.151605 -400.484963) (xy 60.205549 -400.477206) (xy 60.232798 -400.47672)
			(xy 61.096398 -400.47672) (xy 61.123653 -400.477127) (xy 61.177608 -400.484884) (xy 61.22991 -400.500241)
			(xy 61.279494 -400.522885) (xy 61.325351 -400.552355) (xy 61.366547 -400.588052) (xy 61.402243 -400.629247)
			(xy 61.431714 -400.675104) (xy 61.454358 -400.724688) (xy 61.469715 -400.77699) (xy 61.477473 -400.830945)
			(xy 61.477473 -400.885453) (xy 62.914983 -400.885453) (xy 62.914983 -400.830947) (xy 62.922741 -400.776997)
			(xy 62.938098 -400.7247) (xy 62.960741 -400.675121) (xy 62.990211 -400.629269) (xy 63.025906 -400.588079)
			(xy 63.0671 -400.552388) (xy 63.112954 -400.522923) (xy 63.162536 -400.500284) (xy 63.214834 -400.484933)
			(xy 63.268785 -400.477181) (xy 63.296038 -400.47672) (xy 64.159638 -400.47672) (xy 64.186889 -400.477152)
			(xy 64.240837 -400.484914) (xy 64.293131 -400.500273) (xy 64.342707 -400.522918) (xy 64.388556 -400.552388)
			(xy 64.429745 -400.588082) (xy 64.465435 -400.629274) (xy 64.4949 -400.675126) (xy 64.51754 -400.724705)
			(xy 64.532894 -400.777) (xy 64.54065 -400.830948) (xy 64.54065 -400.885448) (xy 65.978306 -400.885448)
			(xy 65.978306 -400.830952) (xy 65.986062 -400.77701) (xy 66.001414 -400.724721) (xy 66.024052 -400.675149)
			(xy 66.053514 -400.629303) (xy 66.089201 -400.588116) (xy 66.130385 -400.552427) (xy 66.17623 -400.522963)
			(xy 66.2258 -400.500322) (xy 66.278088 -400.484966) (xy 66.33203 -400.477208) (xy 66.359278 -400.47672)
			(xy 67.222878 -400.47672) (xy 67.250134 -400.477125) (xy 67.304091 -400.48488) (xy 67.356396 -400.500236)
			(xy 67.405982 -400.522879) (xy 67.451842 -400.552348) (xy 67.49304 -400.588045) (xy 67.528739 -400.629241)
			(xy 67.558211 -400.675098) (xy 67.580857 -400.724684) (xy 67.596215 -400.776987) (xy 67.603973 -400.830944)
			(xy 67.603973 -400.885452) (xy 69.041483 -400.885452) (xy 69.041483 -400.830948) (xy 69.04924 -400.777)
			(xy 69.064596 -400.724704) (xy 69.087238 -400.675127) (xy 69.116706 -400.629276) (xy 69.152399 -400.588086)
			(xy 69.19359 -400.552395) (xy 69.239442 -400.52293) (xy 69.289021 -400.50029) (xy 69.341317 -400.484936)
			(xy 69.395266 -400.477182) (xy 69.422518 -400.47672) (xy 70.286118 -400.47672) (xy 70.31337 -400.477151)
			(xy 70.36732 -400.48491) (xy 70.419617 -400.500268) (xy 70.469195 -400.522912) (xy 70.515047 -400.552381)
			(xy 70.556238 -400.588075) (xy 70.59193 -400.629268) (xy 70.621397 -400.675121) (xy 70.644038 -400.7247)
			(xy 70.659394 -400.776997) (xy 70.66715 -400.830948) (xy 70.66715 -400.885447) (xy 72.104806 -400.885447)
			(xy 72.104806 -400.830953) (xy 72.112561 -400.777013) (xy 72.127913 -400.724725) (xy 72.150549 -400.675154)
			(xy 72.180009 -400.629309) (xy 72.215694 -400.588123) (xy 72.256876 -400.552435) (xy 72.302718 -400.522969)
			(xy 72.352286 -400.500327) (xy 72.404572 -400.48497) (xy 72.458511 -400.477209) (xy 72.485758 -400.47672)
			(xy 73.349358 -400.47672) (xy 73.376615 -400.477124) (xy 73.430574 -400.484877) (xy 73.482881 -400.50023)
			(xy 73.53247 -400.522872) (xy 73.578332 -400.552341) (xy 73.619533 -400.588037) (xy 73.655234 -400.629234)
			(xy 73.684708 -400.675093) (xy 73.707355 -400.724679) (xy 73.722714 -400.776985) (xy 73.730473 -400.830943)
			(xy 73.730473 -400.885449) (xy 75.168006 -400.885449) (xy 75.168006 -400.830951) (xy 75.175762 -400.777007)
			(xy 75.191116 -400.724717) (xy 75.213755 -400.675143) (xy 75.243219 -400.629296) (xy 75.278908 -400.588109)
			(xy 75.320095 -400.55242) (xy 75.365942 -400.522956) (xy 75.415515 -400.500317) (xy 75.467805 -400.484963)
			(xy 75.521749 -400.477206) (xy 75.548998 -400.47672) (xy 76.412598 -400.47672) (xy 76.439853 -400.477127)
			(xy 76.493808 -400.484884) (xy 76.54611 -400.500241) (xy 76.595694 -400.522885) (xy 76.641551 -400.552355)
			(xy 76.682747 -400.588052) (xy 76.718443 -400.629247) (xy 76.747914 -400.675104) (xy 76.770558 -400.724688)
			(xy 76.785915 -400.77699) (xy 76.793673 -400.830945) (xy 76.793673 -400.885453) (xy 78.231183 -400.885453)
			(xy 78.231183 -400.830947) (xy 78.238941 -400.776997) (xy 78.254298 -400.7247) (xy 78.276941 -400.675121)
			(xy 78.306411 -400.629269) (xy 78.342106 -400.588079) (xy 78.3833 -400.552388) (xy 78.429154 -400.522923)
			(xy 78.478736 -400.500284) (xy 78.531034 -400.484933) (xy 78.584985 -400.477181) (xy 78.612238 -400.47672)
			(xy 79.475838 -400.47672) (xy 79.503089 -400.477152) (xy 79.557037 -400.484914) (xy 79.609331 -400.500273)
			(xy 79.658907 -400.522918) (xy 79.704756 -400.552388) (xy 79.745945 -400.588082) (xy 79.781635 -400.629274)
			(xy 79.8111 -400.675126) (xy 79.83374 -400.724705) (xy 79.849094 -400.777) (xy 79.85685 -400.830948)
			(xy 79.85685 -400.885448) (xy 81.294506 -400.885448) (xy 81.294506 -400.830952) (xy 81.302262 -400.77701)
			(xy 81.317614 -400.724721) (xy 81.340252 -400.675149) (xy 81.369714 -400.629303) (xy 81.405401 -400.588116)
			(xy 81.446585 -400.552427) (xy 81.49243 -400.522963) (xy 81.542 -400.500322) (xy 81.594288 -400.484966)
			(xy 81.64823 -400.477208) (xy 81.675478 -400.47672) (xy 82.539078 -400.47672) (xy 82.566334 -400.477125)
			(xy 82.620291 -400.48488) (xy 82.672596 -400.500236) (xy 82.722182 -400.522879) (xy 82.768042 -400.552348)
			(xy 82.80924 -400.588045) (xy 82.844939 -400.629241) (xy 82.874411 -400.675098) (xy 82.897057 -400.724684)
			(xy 82.912415 -400.776987) (xy 82.920173 -400.830944) (xy 82.920173 -400.885452) (xy 84.357683 -400.885452)
			(xy 84.357683 -400.830948) (xy 84.36544 -400.777) (xy 84.380796 -400.724704) (xy 84.403438 -400.675127)
			(xy 84.432906 -400.629276) (xy 84.468599 -400.588086) (xy 84.50979 -400.552395) (xy 84.555642 -400.52293)
			(xy 84.605221 -400.50029) (xy 84.657517 -400.484936) (xy 84.711466 -400.477182) (xy 84.738718 -400.47672)
			(xy 85.602318 -400.47672) (xy 85.62957 -400.477151) (xy 85.68352 -400.48491) (xy 85.735817 -400.500268)
			(xy 85.785395 -400.522912) (xy 85.831247 -400.552381) (xy 85.872438 -400.588075) (xy 85.90813 -400.629268)
			(xy 85.937597 -400.675121) (xy 85.960238 -400.7247) (xy 85.975594 -400.776997) (xy 85.98335 -400.830948)
			(xy 85.98335 -400.885447) (xy 87.421006 -400.885447) (xy 87.421006 -400.830953) (xy 87.428761 -400.777013)
			(xy 87.444113 -400.724725) (xy 87.466749 -400.675154) (xy 87.496209 -400.629309) (xy 87.531894 -400.588123)
			(xy 87.573076 -400.552435) (xy 87.618918 -400.522969) (xy 87.668486 -400.500327) (xy 87.720772 -400.48497)
			(xy 87.774711 -400.477209) (xy 87.801958 -400.47672) (xy 88.665558 -400.47672) (xy 88.692815 -400.477124)
			(xy 88.746774 -400.484877) (xy 88.799081 -400.50023) (xy 88.84867 -400.522872) (xy 88.894532 -400.552341)
			(xy 88.935733 -400.588037) (xy 88.971434 -400.629234) (xy 89.000908 -400.675093) (xy 89.023555 -400.724679)
			(xy 89.038914 -400.776985) (xy 89.046673 -400.830943) (xy 89.046673 -400.885449) (xy 90.484206 -400.885449)
			(xy 90.484206 -400.830951) (xy 90.491962 -400.777007) (xy 90.507316 -400.724717) (xy 90.529955 -400.675143)
			(xy 90.559419 -400.629296) (xy 90.595108 -400.588109) (xy 90.636295 -400.55242) (xy 90.682142 -400.522956)
			(xy 90.731715 -400.500317) (xy 90.784005 -400.484963) (xy 90.837949 -400.477206) (xy 90.865198 -400.47672)
			(xy 91.728798 -400.47672) (xy 91.756053 -400.477127) (xy 91.810008 -400.484884) (xy 91.86231 -400.500241)
			(xy 91.911894 -400.522885) (xy 91.957751 -400.552355) (xy 91.998947 -400.588052) (xy 92.034643 -400.629247)
			(xy 92.064114 -400.675104) (xy 92.086758 -400.724688) (xy 92.102115 -400.77699) (xy 92.109873 -400.830945)
			(xy 92.109873 -400.885453) (xy 93.547383 -400.885453) (xy 93.547383 -400.830947) (xy 93.555141 -400.776997)
			(xy 93.570498 -400.7247) (xy 93.593141 -400.675121) (xy 93.622611 -400.629269) (xy 93.658306 -400.588079)
			(xy 93.6995 -400.552388) (xy 93.745354 -400.522923) (xy 93.794936 -400.500284) (xy 93.847234 -400.484933)
			(xy 93.901185 -400.477181) (xy 93.928438 -400.47672) (xy 94.792038 -400.47672) (xy 94.819289 -400.477152)
			(xy 94.873237 -400.484914) (xy 94.925531 -400.500273) (xy 94.975107 -400.522918) (xy 95.020956 -400.552388)
			(xy 95.062145 -400.588082) (xy 95.097835 -400.629274) (xy 95.1273 -400.675126) (xy 95.14994 -400.724705)
			(xy 95.165294 -400.777) (xy 95.17305 -400.830948) (xy 95.17305 -400.885447) (xy 119.774006 -400.885447)
			(xy 119.774006 -400.830953) (xy 119.781761 -400.777013) (xy 119.797112 -400.724726) (xy 119.819749 -400.675156)
			(xy 119.849208 -400.629311) (xy 119.884892 -400.588125) (xy 119.926074 -400.552436) (xy 119.971915 -400.522971)
			(xy 120.021483 -400.500329) (xy 120.073768 -400.484971) (xy 120.127707 -400.477209) (xy 120.154954 -400.47672)
			(xy 121.018554 -400.47672) (xy 121.045811 -400.477124) (xy 121.099771 -400.484876) (xy 121.152078 -400.500229)
			(xy 121.201668 -400.522871) (xy 121.24753 -400.55234) (xy 121.288731 -400.588036) (xy 121.324433 -400.629233)
			(xy 121.353907 -400.675092) (xy 121.376555 -400.724679) (xy 121.391914 -400.776984) (xy 121.399673 -400.830943)
			(xy 121.399673 -400.885449) (xy 122.837206 -400.885449) (xy 122.837206 -400.830951) (xy 122.844962 -400.777008)
			(xy 122.860316 -400.724717) (xy 122.882955 -400.675144) (xy 122.912418 -400.629298) (xy 122.948106 -400.588111)
			(xy 122.989293 -400.552422) (xy 123.035139 -400.522958) (xy 123.084712 -400.500318) (xy 123.137002 -400.484963)
			(xy 123.190945 -400.477207) (xy 123.218194 -400.47672) (xy 124.081794 -400.47672) (xy 124.109049 -400.477127)
			(xy 124.163005 -400.484883) (xy 124.215307 -400.50024) (xy 124.264892 -400.522884) (xy 124.310749 -400.552354)
			(xy 124.351946 -400.58805) (xy 124.387643 -400.629246) (xy 124.417113 -400.675103) (xy 124.439758 -400.724687)
			(xy 124.455115 -400.776989) (xy 124.462873 -400.830945) (xy 124.462873 -400.885452) (xy 125.900383 -400.885452)
			(xy 125.900383 -400.830948) (xy 125.908141 -400.776998) (xy 125.923497 -400.724701) (xy 125.946141 -400.675122)
			(xy 125.97561 -400.629271) (xy 126.011304 -400.58808) (xy 126.052498 -400.552389) (xy 126.098352 -400.522924)
			(xy 126.147933 -400.500285) (xy 126.200231 -400.484933) (xy 126.254182 -400.477181) (xy 126.281434 -400.47672)
			(xy 127.145034 -400.47672) (xy 127.172286 -400.477152) (xy 127.226234 -400.484913) (xy 127.278528 -400.500272)
			(xy 127.328105 -400.522917) (xy 127.373954 -400.552386) (xy 127.415143 -400.588081) (xy 127.450834 -400.629273)
			(xy 127.480299 -400.675125) (xy 127.50294 -400.724704) (xy 127.518294 -400.777) (xy 127.52605 -400.830948)
			(xy 127.52605 -400.885448) (xy 128.963706 -400.885448) (xy 128.963706 -400.830952) (xy 128.971461 -400.777011)
			(xy 128.986814 -400.724722) (xy 129.009452 -400.67515) (xy 129.038913 -400.629304) (xy 129.074599 -400.588118)
			(xy 129.115783 -400.552429) (xy 129.161627 -400.522964) (xy 129.211197 -400.500323) (xy 129.263485 -400.484967)
			(xy 129.317426 -400.477208) (xy 129.344674 -400.47672) (xy 130.208274 -400.47672) (xy 130.23553 -400.477125)
			(xy 130.289488 -400.48488) (xy 130.341793 -400.500235) (xy 130.39138 -400.522877) (xy 130.43724 -400.552347)
			(xy 130.478438 -400.588043) (xy 130.514138 -400.62924) (xy 130.54361 -400.675097) (xy 130.566256 -400.724683)
			(xy 130.581615 -400.776987) (xy 130.589373 -400.830944) (xy 130.589373 -400.885451) (xy 132.026883 -400.885451)
			(xy 132.026883 -400.830949) (xy 132.03464 -400.777) (xy 132.049996 -400.724705) (xy 132.072638 -400.675128)
			(xy 132.102105 -400.629277) (xy 132.137797 -400.588087) (xy 132.178989 -400.552396) (xy 132.22484 -400.522931)
			(xy 132.274418 -400.500291) (xy 132.326714 -400.484937) (xy 132.380662 -400.477182) (xy 132.407914 -400.47672)
			(xy 133.271514 -400.47672) (xy 133.298767 -400.477151) (xy 133.352717 -400.48491) (xy 133.405014 -400.500267)
			(xy 133.454593 -400.522911) (xy 133.500445 -400.552379) (xy 133.541636 -400.588074) (xy 133.577329 -400.629266)
			(xy 133.606796 -400.67512) (xy 133.629438 -400.724699) (xy 133.644793 -400.776997) (xy 133.65255 -400.830947)
			(xy 133.65255 -400.885447) (xy 135.090206 -400.885447) (xy 135.090206 -400.830953) (xy 135.097961 -400.777013)
			(xy 135.113312 -400.724726) (xy 135.135949 -400.675156) (xy 135.165408 -400.629311) (xy 135.201092 -400.588125)
			(xy 135.242274 -400.552436) (xy 135.288115 -400.522971) (xy 135.337683 -400.500329) (xy 135.389968 -400.484971)
			(xy 135.443907 -400.477209) (xy 135.471154 -400.47672) (xy 136.334754 -400.47672) (xy 136.362011 -400.477124)
			(xy 136.415971 -400.484876) (xy 136.468278 -400.500229) (xy 136.517868 -400.522871) (xy 136.56373 -400.55234)
			(xy 136.604931 -400.588036) (xy 136.640633 -400.629233) (xy 136.670107 -400.675092) (xy 136.692755 -400.724679)
			(xy 136.708114 -400.776984) (xy 136.715873 -400.830943) (xy 136.715873 -400.885449) (xy 138.153406 -400.885449)
			(xy 138.153406 -400.830951) (xy 138.161162 -400.777008) (xy 138.176516 -400.724717) (xy 138.199155 -400.675144)
			(xy 138.228618 -400.629298) (xy 138.264306 -400.588111) (xy 138.305493 -400.552422) (xy 138.351339 -400.522958)
			(xy 138.400912 -400.500318) (xy 138.453202 -400.484963) (xy 138.507145 -400.477207) (xy 138.534394 -400.47672)
			(xy 139.397994 -400.47672) (xy 139.425249 -400.477127) (xy 139.479205 -400.484883) (xy 139.531507 -400.50024)
			(xy 139.581092 -400.522884) (xy 139.626949 -400.552354) (xy 139.668146 -400.58805) (xy 139.703843 -400.629246)
			(xy 139.733313 -400.675103) (xy 139.755958 -400.724687) (xy 139.771315 -400.776989) (xy 139.779073 -400.830945)
			(xy 139.779073 -400.885452) (xy 141.216583 -400.885452) (xy 141.216583 -400.830948) (xy 141.224341 -400.776998)
			(xy 141.239697 -400.724701) (xy 141.262341 -400.675122) (xy 141.29181 -400.629271) (xy 141.327504 -400.58808)
			(xy 141.368698 -400.552389) (xy 141.414552 -400.522924) (xy 141.464133 -400.500285) (xy 141.516431 -400.484933)
			(xy 141.570382 -400.477181) (xy 141.597634 -400.47672) (xy 142.461234 -400.47672) (xy 142.488486 -400.477152)
			(xy 142.542434 -400.484913) (xy 142.594728 -400.500272) (xy 142.644305 -400.522917) (xy 142.690154 -400.552386)
			(xy 142.731343 -400.588081) (xy 142.767034 -400.629273) (xy 142.796499 -400.675125) (xy 142.81914 -400.724704)
			(xy 142.834494 -400.777) (xy 142.84225 -400.830948) (xy 142.84225 -400.885448) (xy 144.279906 -400.885448)
			(xy 144.279906 -400.830952) (xy 144.287661 -400.777011) (xy 144.303014 -400.724722) (xy 144.325652 -400.67515)
			(xy 144.355113 -400.629304) (xy 144.390799 -400.588118) (xy 144.431983 -400.552429) (xy 144.477827 -400.522964)
			(xy 144.527397 -400.500323) (xy 144.579685 -400.484967) (xy 144.633626 -400.477208) (xy 144.660874 -400.47672)
			(xy 145.524474 -400.47672) (xy 145.55173 -400.477125) (xy 145.605688 -400.48488) (xy 145.657993 -400.500235)
			(xy 145.70758 -400.522877) (xy 145.75344 -400.552347) (xy 145.794638 -400.588043) (xy 145.830338 -400.62924)
			(xy 145.85981 -400.675097) (xy 145.882456 -400.724683) (xy 145.897815 -400.776987) (xy 145.905573 -400.830944)
			(xy 145.905573 -400.885451) (xy 147.343083 -400.885451) (xy 147.343083 -400.830949) (xy 147.35084 -400.777)
			(xy 147.366196 -400.724705) (xy 147.388838 -400.675128) (xy 147.418305 -400.629277) (xy 147.453997 -400.588087)
			(xy 147.495189 -400.552396) (xy 147.54104 -400.522931) (xy 147.590618 -400.500291) (xy 147.642914 -400.484937)
			(xy 147.696862 -400.477182) (xy 147.724114 -400.47672) (xy 148.587714 -400.47672) (xy 148.614967 -400.477151)
			(xy 148.668917 -400.48491) (xy 148.721214 -400.500267) (xy 148.770793 -400.522911) (xy 148.816645 -400.552379)
			(xy 148.857836 -400.588074) (xy 148.893529 -400.629266) (xy 148.922996 -400.67512) (xy 148.945638 -400.724699)
			(xy 148.960993 -400.776997) (xy 148.96875 -400.830947) (xy 148.96875 -400.885447) (xy 150.406406 -400.885447)
			(xy 150.406406 -400.830953) (xy 150.414161 -400.777013) (xy 150.429512 -400.724726) (xy 150.452149 -400.675156)
			(xy 150.481608 -400.629311) (xy 150.517292 -400.588125) (xy 150.558474 -400.552436) (xy 150.604315 -400.522971)
			(xy 150.653883 -400.500329) (xy 150.706168 -400.484971) (xy 150.760107 -400.477209) (xy 150.787354 -400.47672)
			(xy 151.650954 -400.47672) (xy 151.678211 -400.477124) (xy 151.732171 -400.484876) (xy 151.784478 -400.500229)
			(xy 151.834068 -400.522871) (xy 151.87993 -400.55234) (xy 151.921131 -400.588036) (xy 151.956833 -400.629233)
			(xy 151.986307 -400.675092) (xy 152.008955 -400.724679) (xy 152.024314 -400.776984) (xy 152.032073 -400.830943)
			(xy 152.032073 -400.885449) (xy 153.469606 -400.885449) (xy 153.469606 -400.830951) (xy 153.477362 -400.777008)
			(xy 153.492716 -400.724717) (xy 153.515355 -400.675144) (xy 153.544818 -400.629298) (xy 153.580506 -400.588111)
			(xy 153.621693 -400.552422) (xy 153.667539 -400.522958) (xy 153.717112 -400.500318) (xy 153.769402 -400.484963)
			(xy 153.823345 -400.477207) (xy 153.850594 -400.47672) (xy 154.714194 -400.47672) (xy 154.741449 -400.477127)
			(xy 154.795405 -400.484883) (xy 154.847707 -400.50024) (xy 154.897292 -400.522884) (xy 154.943149 -400.552354)
			(xy 154.984346 -400.58805) (xy 155.020043 -400.629246) (xy 155.049513 -400.675103) (xy 155.072158 -400.724687)
			(xy 155.087515 -400.776989) (xy 155.095273 -400.830945) (xy 155.095273 -400.885452) (xy 156.532783 -400.885452)
			(xy 156.532783 -400.830948) (xy 156.540541 -400.776998) (xy 156.555897 -400.724701) (xy 156.578541 -400.675122)
			(xy 156.60801 -400.629271) (xy 156.643704 -400.58808) (xy 156.684898 -400.552389) (xy 156.730752 -400.522924)
			(xy 156.780333 -400.500285) (xy 156.832631 -400.484933) (xy 156.886582 -400.477181) (xy 156.913834 -400.47672)
			(xy 157.777434 -400.47672) (xy 157.804686 -400.477152) (xy 157.858634 -400.484913) (xy 157.910928 -400.500272)
			(xy 157.960505 -400.522917) (xy 158.006354 -400.552386) (xy 158.047543 -400.588081) (xy 158.083234 -400.629273)
			(xy 158.112699 -400.675125) (xy 158.13534 -400.724704) (xy 158.150694 -400.777) (xy 158.15845 -400.830948)
			(xy 158.15845 -400.885448) (xy 159.596106 -400.885448) (xy 159.596106 -400.830952) (xy 159.603861 -400.777011)
			(xy 159.619214 -400.724722) (xy 159.641852 -400.67515) (xy 159.671313 -400.629304) (xy 159.706999 -400.588118)
			(xy 159.748183 -400.552429) (xy 159.794027 -400.522964) (xy 159.843597 -400.500323) (xy 159.895885 -400.484967)
			(xy 159.949826 -400.477208) (xy 159.977074 -400.47672) (xy 160.840674 -400.47672) (xy 160.86793 -400.477125)
			(xy 160.921888 -400.48488) (xy 160.974193 -400.500235) (xy 161.02378 -400.522877) (xy 161.06964 -400.552347)
			(xy 161.110838 -400.588043) (xy 161.146538 -400.62924) (xy 161.17601 -400.675097) (xy 161.198656 -400.724683)
			(xy 161.214015 -400.776987) (xy 161.221773 -400.830944) (xy 161.221773 -400.885451) (xy 162.659283 -400.885451)
			(xy 162.659283 -400.830949) (xy 162.66704 -400.777) (xy 162.682396 -400.724705) (xy 162.705038 -400.675128)
			(xy 162.734505 -400.629277) (xy 162.770197 -400.588087) (xy 162.811389 -400.552396) (xy 162.85724 -400.522931)
			(xy 162.906818 -400.500291) (xy 162.959114 -400.484937) (xy 163.013062 -400.477182) (xy 163.040314 -400.47672)
			(xy 163.903914 -400.47672) (xy 163.931167 -400.477151) (xy 163.985117 -400.48491) (xy 164.037414 -400.500267)
			(xy 164.086993 -400.522911) (xy 164.132845 -400.552379) (xy 164.174036 -400.588074) (xy 164.209729 -400.629266)
			(xy 164.239196 -400.67512) (xy 164.261838 -400.724699) (xy 164.277193 -400.776997) (xy 164.28495 -400.830947)
			(xy 164.28495 -400.885447) (xy 165.722606 -400.885447) (xy 165.722606 -400.830953) (xy 165.730361 -400.777013)
			(xy 165.745712 -400.724726) (xy 165.768349 -400.675156) (xy 165.797808 -400.629311) (xy 165.833492 -400.588125)
			(xy 165.874674 -400.552436) (xy 165.920515 -400.522971) (xy 165.970083 -400.500329) (xy 166.022368 -400.484971)
			(xy 166.076307 -400.477209) (xy 166.103554 -400.47672) (xy 166.967154 -400.47672) (xy 166.994411 -400.477124)
			(xy 167.048371 -400.484876) (xy 167.100678 -400.500229) (xy 167.150268 -400.522871) (xy 167.19613 -400.55234)
			(xy 167.237331 -400.588036) (xy 167.273033 -400.629233) (xy 167.302507 -400.675092) (xy 167.325155 -400.724679)
			(xy 167.340514 -400.776984) (xy 167.348273 -400.830943) (xy 167.348273 -400.885457) (xy 167.340514 -400.939416)
			(xy 167.325155 -400.991721) (xy 167.302507 -401.041308) (xy 167.273033 -401.087167) (xy 167.237331 -401.128364)
			(xy 167.19613 -401.16406) (xy 167.150268 -401.193529) (xy 167.100678 -401.216171) (xy 167.048371 -401.231524)
			(xy 166.994411 -401.239276) (xy 166.967154 -401.239736) (xy 166.103554 -401.239736) (xy 166.076307 -401.239191)
			(xy 166.022368 -401.231429) (xy 165.970083 -401.216071) (xy 165.920515 -401.193429) (xy 165.874674 -401.163964)
			(xy 165.833492 -401.128275) (xy 165.797808 -401.087089) (xy 165.768349 -401.041244) (xy 165.745712 -400.991674)
			(xy 165.730361 -400.939387) (xy 165.722606 -400.885447) (xy 164.28495 -400.885447) (xy 164.28495 -400.885453)
			(xy 164.277193 -400.939403) (xy 164.261838 -400.991701) (xy 164.239196 -401.04128) (xy 164.209729 -401.087134)
			(xy 164.174036 -401.128326) (xy 164.132845 -401.164021) (xy 164.086993 -401.193489) (xy 164.037414 -401.216133)
			(xy 163.985117 -401.23149) (xy 163.931167 -401.239249) (xy 163.903914 -401.239736) (xy 163.040314 -401.239736)
			(xy 163.013062 -401.239218) (xy 162.959114 -401.231463) (xy 162.906818 -401.216109) (xy 162.85724 -401.193469)
			(xy 162.811389 -401.164004) (xy 162.770197 -401.128313) (xy 162.734505 -401.087123) (xy 162.705038 -401.041272)
			(xy 162.682396 -400.991695) (xy 162.66704 -400.9394) (xy 162.659283 -400.885451) (xy 161.221773 -400.885451)
			(xy 161.221773 -400.885456) (xy 161.214015 -400.939413) (xy 161.198656 -400.991717) (xy 161.17601 -401.041303)
			(xy 161.146538 -401.08716) (xy 161.110838 -401.128357) (xy 161.06964 -401.164053) (xy 161.02378 -401.193523)
			(xy 160.974193 -401.216165) (xy 160.921888 -401.23152) (xy 160.86793 -401.239275) (xy 160.840674 -401.239736)
			(xy 159.977074 -401.239736) (xy 159.949826 -401.239192) (xy 159.895885 -401.231433) (xy 159.843597 -401.216077)
			(xy 159.794027 -401.193436) (xy 159.748183 -401.163971) (xy 159.706999 -401.128282) (xy 159.671313 -401.087096)
			(xy 159.641852 -401.04125) (xy 159.619214 -400.991678) (xy 159.603861 -400.939389) (xy 159.596106 -400.885448)
			(xy 158.15845 -400.885448) (xy 158.15845 -400.885452) (xy 158.150694 -400.9394) (xy 158.13534 -400.991696)
			(xy 158.112699 -401.041275) (xy 158.083234 -401.087127) (xy 158.047543 -401.128319) (xy 158.006354 -401.164014)
			(xy 157.960505 -401.193483) (xy 157.910928 -401.216128) (xy 157.858634 -401.231487) (xy 157.804686 -401.239248)
			(xy 157.777434 -401.239736) (xy 156.913834 -401.239736) (xy 156.886582 -401.239219) (xy 156.832631 -401.231467)
			(xy 156.780333 -401.216115) (xy 156.730752 -401.193476) (xy 156.684898 -401.164011) (xy 156.643704 -401.12832)
			(xy 156.60801 -401.087129) (xy 156.578541 -401.041278) (xy 156.555897 -400.991699) (xy 156.540541 -400.939402)
			(xy 156.532783 -400.885452) (xy 155.095273 -400.885452) (xy 155.095273 -400.885455) (xy 155.087515 -400.939411)
			(xy 155.072158 -400.991713) (xy 155.049513 -401.041297) (xy 155.020043 -401.087154) (xy 154.984346 -401.12835)
			(xy 154.943149 -401.164046) (xy 154.897292 -401.193516) (xy 154.847707 -401.21616) (xy 154.795405 -401.231517)
			(xy 154.741449 -401.239273) (xy 154.714194 -401.239736) (xy 153.850594 -401.239736) (xy 153.823345 -401.239193)
			(xy 153.769402 -401.231437) (xy 153.717112 -401.216082) (xy 153.667539 -401.193442) (xy 153.621693 -401.163978)
			(xy 153.580506 -401.128289) (xy 153.544818 -401.087102) (xy 153.515355 -401.041256) (xy 153.492716 -400.991683)
			(xy 153.477362 -400.939392) (xy 153.469606 -400.885449) (xy 152.032073 -400.885449) (xy 152.032073 -400.885457)
			(xy 152.024314 -400.939416) (xy 152.008955 -400.991721) (xy 151.986307 -401.041308) (xy 151.956833 -401.087167)
			(xy 151.921131 -401.128364) (xy 151.87993 -401.16406) (xy 151.834068 -401.193529) (xy 151.784478 -401.216171)
			(xy 151.732171 -401.231524) (xy 151.678211 -401.239276) (xy 151.650954 -401.239736) (xy 150.787354 -401.239736)
			(xy 150.760107 -401.239191) (xy 150.706168 -401.231429) (xy 150.653883 -401.216071) (xy 150.604315 -401.193429)
			(xy 150.558474 -401.163964) (xy 150.517292 -401.128275) (xy 150.481608 -401.087089) (xy 150.452149 -401.041244)
			(xy 150.429512 -400.991674) (xy 150.414161 -400.939387) (xy 150.406406 -400.885447) (xy 148.96875 -400.885447)
			(xy 148.96875 -400.885453) (xy 148.960993 -400.939403) (xy 148.945638 -400.991701) (xy 148.922996 -401.04128)
			(xy 148.893529 -401.087134) (xy 148.857836 -401.128326) (xy 148.816645 -401.164021) (xy 148.770793 -401.193489)
			(xy 148.721214 -401.216133) (xy 148.668917 -401.23149) (xy 148.614967 -401.239249) (xy 148.587714 -401.239736)
			(xy 147.724114 -401.239736) (xy 147.696862 -401.239218) (xy 147.642914 -401.231463) (xy 147.590618 -401.216109)
			(xy 147.54104 -401.193469) (xy 147.495189 -401.164004) (xy 147.453997 -401.128313) (xy 147.418305 -401.087123)
			(xy 147.388838 -401.041272) (xy 147.366196 -400.991695) (xy 147.35084 -400.9394) (xy 147.343083 -400.885451)
			(xy 145.905573 -400.885451) (xy 145.905573 -400.885456) (xy 145.897815 -400.939413) (xy 145.882456 -400.991717)
			(xy 145.85981 -401.041303) (xy 145.830338 -401.08716) (xy 145.794638 -401.128357) (xy 145.75344 -401.164053)
			(xy 145.70758 -401.193523) (xy 145.657993 -401.216165) (xy 145.605688 -401.23152) (xy 145.55173 -401.239275)
			(xy 145.524474 -401.239736) (xy 144.660874 -401.239736) (xy 144.633626 -401.239192) (xy 144.579685 -401.231433)
			(xy 144.527397 -401.216077) (xy 144.477827 -401.193436) (xy 144.431983 -401.163971) (xy 144.390799 -401.128282)
			(xy 144.355113 -401.087096) (xy 144.325652 -401.04125) (xy 144.303014 -400.991678) (xy 144.287661 -400.939389)
			(xy 144.279906 -400.885448) (xy 142.84225 -400.885448) (xy 142.84225 -400.885452) (xy 142.834494 -400.9394)
			(xy 142.81914 -400.991696) (xy 142.796499 -401.041275) (xy 142.767034 -401.087127) (xy 142.731343 -401.128319)
			(xy 142.690154 -401.164014) (xy 142.644305 -401.193483) (xy 142.594728 -401.216128) (xy 142.542434 -401.231487)
			(xy 142.488486 -401.239248) (xy 142.461234 -401.239736) (xy 141.597634 -401.239736) (xy 141.570382 -401.239219)
			(xy 141.516431 -401.231467) (xy 141.464133 -401.216115) (xy 141.414552 -401.193476) (xy 141.368698 -401.164011)
			(xy 141.327504 -401.12832) (xy 141.29181 -401.087129) (xy 141.262341 -401.041278) (xy 141.239697 -400.991699)
			(xy 141.224341 -400.939402) (xy 141.216583 -400.885452) (xy 139.779073 -400.885452) (xy 139.779073 -400.885455)
			(xy 139.771315 -400.939411) (xy 139.755958 -400.991713) (xy 139.733313 -401.041297) (xy 139.703843 -401.087154)
			(xy 139.668146 -401.12835) (xy 139.626949 -401.164046) (xy 139.581092 -401.193516) (xy 139.531507 -401.21616)
			(xy 139.479205 -401.231517) (xy 139.425249 -401.239273) (xy 139.397994 -401.239736) (xy 138.534394 -401.239736)
			(xy 138.507145 -401.239193) (xy 138.453202 -401.231437) (xy 138.400912 -401.216082) (xy 138.351339 -401.193442)
			(xy 138.305493 -401.163978) (xy 138.264306 -401.128289) (xy 138.228618 -401.087102) (xy 138.199155 -401.041256)
			(xy 138.176516 -400.991683) (xy 138.161162 -400.939392) (xy 138.153406 -400.885449) (xy 136.715873 -400.885449)
			(xy 136.715873 -400.885457) (xy 136.708114 -400.939416) (xy 136.692755 -400.991721) (xy 136.670107 -401.041308)
			(xy 136.640633 -401.087167) (xy 136.604931 -401.128364) (xy 136.56373 -401.16406) (xy 136.517868 -401.193529)
			(xy 136.468278 -401.216171) (xy 136.415971 -401.231524) (xy 136.362011 -401.239276) (xy 136.334754 -401.239736)
			(xy 135.471154 -401.239736) (xy 135.443907 -401.239191) (xy 135.389968 -401.231429) (xy 135.337683 -401.216071)
			(xy 135.288115 -401.193429) (xy 135.242274 -401.163964) (xy 135.201092 -401.128275) (xy 135.165408 -401.087089)
			(xy 135.135949 -401.041244) (xy 135.113312 -400.991674) (xy 135.097961 -400.939387) (xy 135.090206 -400.885447)
			(xy 133.65255 -400.885447) (xy 133.65255 -400.885453) (xy 133.644793 -400.939403) (xy 133.629438 -400.991701)
			(xy 133.606796 -401.04128) (xy 133.577329 -401.087134) (xy 133.541636 -401.128326) (xy 133.500445 -401.164021)
			(xy 133.454593 -401.193489) (xy 133.405014 -401.216133) (xy 133.352717 -401.23149) (xy 133.298767 -401.239249)
			(xy 133.271514 -401.239736) (xy 132.407914 -401.239736) (xy 132.380662 -401.239218) (xy 132.326714 -401.231463)
			(xy 132.274418 -401.216109) (xy 132.22484 -401.193469) (xy 132.178989 -401.164004) (xy 132.137797 -401.128313)
			(xy 132.102105 -401.087123) (xy 132.072638 -401.041272) (xy 132.049996 -400.991695) (xy 132.03464 -400.9394)
			(xy 132.026883 -400.885451) (xy 130.589373 -400.885451) (xy 130.589373 -400.885456) (xy 130.581615 -400.939413)
			(xy 130.566256 -400.991717) (xy 130.54361 -401.041303) (xy 130.514138 -401.08716) (xy 130.478438 -401.128357)
			(xy 130.43724 -401.164053) (xy 130.39138 -401.193523) (xy 130.341793 -401.216165) (xy 130.289488 -401.23152)
			(xy 130.23553 -401.239275) (xy 130.208274 -401.239736) (xy 129.344674 -401.239736) (xy 129.317426 -401.239192)
			(xy 129.263485 -401.231433) (xy 129.211197 -401.216077) (xy 129.161627 -401.193436) (xy 129.115783 -401.163971)
			(xy 129.074599 -401.128282) (xy 129.038913 -401.087096) (xy 129.009452 -401.04125) (xy 128.986814 -400.991678)
			(xy 128.971461 -400.939389) (xy 128.963706 -400.885448) (xy 127.52605 -400.885448) (xy 127.52605 -400.885452)
			(xy 127.518294 -400.9394) (xy 127.50294 -400.991696) (xy 127.480299 -401.041275) (xy 127.450834 -401.087127)
			(xy 127.415143 -401.128319) (xy 127.373954 -401.164014) (xy 127.328105 -401.193483) (xy 127.278528 -401.216128)
			(xy 127.226234 -401.231487) (xy 127.172286 -401.239248) (xy 127.145034 -401.239736) (xy 126.281434 -401.239736)
			(xy 126.254182 -401.239219) (xy 126.200231 -401.231467) (xy 126.147933 -401.216115) (xy 126.098352 -401.193476)
			(xy 126.052498 -401.164011) (xy 126.011304 -401.12832) (xy 125.97561 -401.087129) (xy 125.946141 -401.041278)
			(xy 125.923497 -400.991699) (xy 125.908141 -400.939402) (xy 125.900383 -400.885452) (xy 124.462873 -400.885452)
			(xy 124.462873 -400.885455) (xy 124.455115 -400.939411) (xy 124.439758 -400.991713) (xy 124.417113 -401.041297)
			(xy 124.387643 -401.087154) (xy 124.351946 -401.12835) (xy 124.310749 -401.164046) (xy 124.264892 -401.193516)
			(xy 124.215307 -401.21616) (xy 124.163005 -401.231517) (xy 124.109049 -401.239273) (xy 124.081794 -401.239736)
			(xy 123.218194 -401.239736) (xy 123.190945 -401.239193) (xy 123.137002 -401.231437) (xy 123.084712 -401.216082)
			(xy 123.035139 -401.193442) (xy 122.989293 -401.163978) (xy 122.948106 -401.128289) (xy 122.912418 -401.087102)
			(xy 122.882955 -401.041256) (xy 122.860316 -400.991683) (xy 122.844962 -400.939392) (xy 122.837206 -400.885449)
			(xy 121.399673 -400.885449) (xy 121.399673 -400.885457) (xy 121.391914 -400.939416) (xy 121.376555 -400.991721)
			(xy 121.353907 -401.041308) (xy 121.324433 -401.087167) (xy 121.288731 -401.128364) (xy 121.24753 -401.16406)
			(xy 121.201668 -401.193529) (xy 121.152078 -401.216171) (xy 121.099771 -401.231524) (xy 121.045811 -401.239276)
			(xy 121.018554 -401.239736) (xy 120.154954 -401.239736) (xy 120.127707 -401.239191) (xy 120.073768 -401.231429)
			(xy 120.021483 -401.216071) (xy 119.971915 -401.193429) (xy 119.926074 -401.163964) (xy 119.884892 -401.128275)
			(xy 119.849208 -401.087089) (xy 119.819749 -401.041244) (xy 119.797112 -400.991674) (xy 119.781761 -400.939387)
			(xy 119.774006 -400.885447) (xy 95.17305 -400.885447) (xy 95.17305 -400.885452) (xy 95.165294 -400.9394)
			(xy 95.14994 -400.991695) (xy 95.1273 -401.041274) (xy 95.097835 -401.087126) (xy 95.062145 -401.128318)
			(xy 95.020956 -401.164012) (xy 94.975107 -401.193482) (xy 94.925531 -401.216127) (xy 94.873237 -401.231486)
			(xy 94.819289 -401.239248) (xy 94.792038 -401.239736) (xy 93.928438 -401.239736) (xy 93.901185 -401.239219)
			(xy 93.847234 -401.231467) (xy 93.794936 -401.216116) (xy 93.745354 -401.193477) (xy 93.6995 -401.164012)
			(xy 93.658306 -401.128321) (xy 93.622611 -401.087131) (xy 93.593141 -401.041279) (xy 93.570498 -400.9917)
			(xy 93.555141 -400.939403) (xy 93.547383 -400.885453) (xy 92.109873 -400.885453) (xy 92.109873 -400.885455)
			(xy 92.102115 -400.93941) (xy 92.086758 -400.991712) (xy 92.064114 -401.041296) (xy 92.034643 -401.087153)
			(xy 91.998947 -401.128348) (xy 91.957751 -401.164045) (xy 91.911894 -401.193515) (xy 91.86231 -401.216159)
			(xy 91.810008 -401.231516) (xy 91.756053 -401.239273) (xy 91.728798 -401.239736) (xy 90.865198 -401.239736)
			(xy 90.837949 -401.239194) (xy 90.784005 -401.231437) (xy 90.731715 -401.216083) (xy 90.682142 -401.193444)
			(xy 90.636295 -401.16398) (xy 90.595108 -401.128291) (xy 90.559419 -401.087104) (xy 90.529955 -401.041257)
			(xy 90.507316 -400.991683) (xy 90.491962 -400.939393) (xy 90.484206 -400.885449) (xy 89.046673 -400.885449)
			(xy 89.046673 -400.885457) (xy 89.038914 -400.939415) (xy 89.023555 -400.991721) (xy 89.000908 -401.041307)
			(xy 88.971434 -401.087166) (xy 88.935733 -401.128363) (xy 88.894532 -401.164059) (xy 88.84867 -401.193528)
			(xy 88.799081 -401.21617) (xy 88.746774 -401.231523) (xy 88.692815 -401.239276) (xy 88.665558 -401.239736)
			(xy 87.801958 -401.239736) (xy 87.774711 -401.239191) (xy 87.720772 -401.23143) (xy 87.668486 -401.216073)
			(xy 87.618918 -401.193431) (xy 87.573076 -401.163965) (xy 87.531894 -401.128277) (xy 87.496209 -401.087091)
			(xy 87.466749 -401.041246) (xy 87.444113 -400.991675) (xy 87.428761 -400.939387) (xy 87.421006 -400.885447)
			(xy 85.98335 -400.885447) (xy 85.98335 -400.885452) (xy 85.975594 -400.939403) (xy 85.960238 -400.9917)
			(xy 85.937597 -401.041279) (xy 85.90813 -401.087132) (xy 85.872438 -401.128325) (xy 85.831247 -401.164019)
			(xy 85.785395 -401.193488) (xy 85.735817 -401.216132) (xy 85.68352 -401.23149) (xy 85.62957 -401.239249)
			(xy 85.602318 -401.239736) (xy 84.738718 -401.239736) (xy 84.711466 -401.239218) (xy 84.657517 -401.231464)
			(xy 84.605221 -401.21611) (xy 84.555642 -401.19347) (xy 84.50979 -401.164005) (xy 84.468599 -401.128314)
			(xy 84.432906 -401.087124) (xy 84.403438 -401.041273) (xy 84.380796 -400.991696) (xy 84.36544 -400.9394)
			(xy 84.357683 -400.885452) (xy 82.920173 -400.885452) (xy 82.920173 -400.885456) (xy 82.912415 -400.939413)
			(xy 82.897057 -400.991716) (xy 82.874411 -401.041302) (xy 82.844939 -401.087159) (xy 82.80924 -401.128355)
			(xy 82.768042 -401.164052) (xy 82.722182 -401.193521) (xy 82.672596 -401.216164) (xy 82.620291 -401.23152)
			(xy 82.566334 -401.239275) (xy 82.539078 -401.239736) (xy 81.675478 -401.239736) (xy 81.64823 -401.239192)
			(xy 81.594288 -401.231434) (xy 81.542 -401.216078) (xy 81.49243 -401.193437) (xy 81.446585 -401.163973)
			(xy 81.405401 -401.128284) (xy 81.369714 -401.087097) (xy 81.340252 -401.041251) (xy 81.317614 -400.991679)
			(xy 81.302262 -400.93939) (xy 81.294506 -400.885448) (xy 79.85685 -400.885448) (xy 79.85685 -400.885452)
			(xy 79.849094 -400.9394) (xy 79.83374 -400.991695) (xy 79.8111 -401.041274) (xy 79.781635 -401.087126)
			(xy 79.745945 -401.128318) (xy 79.704756 -401.164012) (xy 79.658907 -401.193482) (xy 79.609331 -401.216127)
			(xy 79.557037 -401.231486) (xy 79.503089 -401.239248) (xy 79.475838 -401.239736) (xy 78.612238 -401.239736)
			(xy 78.584985 -401.239219) (xy 78.531034 -401.231467) (xy 78.478736 -401.216116) (xy 78.429154 -401.193477)
			(xy 78.3833 -401.164012) (xy 78.342106 -401.128321) (xy 78.306411 -401.087131) (xy 78.276941 -401.041279)
			(xy 78.254298 -400.9917) (xy 78.238941 -400.939403) (xy 78.231183 -400.885453) (xy 76.793673 -400.885453)
			(xy 76.793673 -400.885455) (xy 76.785915 -400.93941) (xy 76.770558 -400.991712) (xy 76.747914 -401.041296)
			(xy 76.718443 -401.087153) (xy 76.682747 -401.128348) (xy 76.641551 -401.164045) (xy 76.595694 -401.193515)
			(xy 76.54611 -401.216159) (xy 76.493808 -401.231516) (xy 76.439853 -401.239273) (xy 76.412598 -401.239736)
			(xy 75.548998 -401.239736) (xy 75.521749 -401.239194) (xy 75.467805 -401.231437) (xy 75.415515 -401.216083)
			(xy 75.365942 -401.193444) (xy 75.320095 -401.16398) (xy 75.278908 -401.128291) (xy 75.243219 -401.087104)
			(xy 75.213755 -401.041257) (xy 75.191116 -400.991683) (xy 75.175762 -400.939393) (xy 75.168006 -400.885449)
			(xy 73.730473 -400.885449) (xy 73.730473 -400.885457) (xy 73.722714 -400.939415) (xy 73.707355 -400.991721)
			(xy 73.684708 -401.041307) (xy 73.655234 -401.087166) (xy 73.619533 -401.128363) (xy 73.578332 -401.164059)
			(xy 73.53247 -401.193528) (xy 73.482881 -401.21617) (xy 73.430574 -401.231523) (xy 73.376615 -401.239276)
			(xy 73.349358 -401.239736) (xy 72.485758 -401.239736) (xy 72.458511 -401.239191) (xy 72.404572 -401.23143)
			(xy 72.352286 -401.216073) (xy 72.302718 -401.193431) (xy 72.256876 -401.163965) (xy 72.215694 -401.128277)
			(xy 72.180009 -401.087091) (xy 72.150549 -401.041246) (xy 72.127913 -400.991675) (xy 72.112561 -400.939387)
			(xy 72.104806 -400.885447) (xy 70.66715 -400.885447) (xy 70.66715 -400.885452) (xy 70.659394 -400.939403)
			(xy 70.644038 -400.9917) (xy 70.621397 -401.041279) (xy 70.59193 -401.087132) (xy 70.556238 -401.128325)
			(xy 70.515047 -401.164019) (xy 70.469195 -401.193488) (xy 70.419617 -401.216132) (xy 70.36732 -401.23149)
			(xy 70.31337 -401.239249) (xy 70.286118 -401.239736) (xy 69.422518 -401.239736) (xy 69.395266 -401.239218)
			(xy 69.341317 -401.231464) (xy 69.289021 -401.21611) (xy 69.239442 -401.19347) (xy 69.19359 -401.164005)
			(xy 69.152399 -401.128314) (xy 69.116706 -401.087124) (xy 69.087238 -401.041273) (xy 69.064596 -400.991696)
			(xy 69.04924 -400.9394) (xy 69.041483 -400.885452) (xy 67.603973 -400.885452) (xy 67.603973 -400.885456)
			(xy 67.596215 -400.939413) (xy 67.580857 -400.991716) (xy 67.558211 -401.041302) (xy 67.528739 -401.087159)
			(xy 67.49304 -401.128355) (xy 67.451842 -401.164052) (xy 67.405982 -401.193521) (xy 67.356396 -401.216164)
			(xy 67.304091 -401.23152) (xy 67.250134 -401.239275) (xy 67.222878 -401.239736) (xy 66.359278 -401.239736)
			(xy 66.33203 -401.239192) (xy 66.278088 -401.231434) (xy 66.2258 -401.216078) (xy 66.17623 -401.193437)
			(xy 66.130385 -401.163973) (xy 66.089201 -401.128284) (xy 66.053514 -401.087097) (xy 66.024052 -401.041251)
			(xy 66.001414 -400.991679) (xy 65.986062 -400.93939) (xy 65.978306 -400.885448) (xy 64.54065 -400.885448)
			(xy 64.54065 -400.885452) (xy 64.532894 -400.9394) (xy 64.51754 -400.991695) (xy 64.4949 -401.041274)
			(xy 64.465435 -401.087126) (xy 64.429745 -401.128318) (xy 64.388556 -401.164012) (xy 64.342707 -401.193482)
			(xy 64.293131 -401.216127) (xy 64.240837 -401.231486) (xy 64.186889 -401.239248) (xy 64.159638 -401.239736)
			(xy 63.296038 -401.239736) (xy 63.268785 -401.239219) (xy 63.214834 -401.231467) (xy 63.162536 -401.216116)
			(xy 63.112954 -401.193477) (xy 63.0671 -401.164012) (xy 63.025906 -401.128321) (xy 62.990211 -401.087131)
			(xy 62.960741 -401.041279) (xy 62.938098 -400.9917) (xy 62.922741 -400.939403) (xy 62.914983 -400.885453)
			(xy 61.477473 -400.885453) (xy 61.477473 -400.885455) (xy 61.469715 -400.93941) (xy 61.454358 -400.991712)
			(xy 61.431714 -401.041296) (xy 61.402243 -401.087153) (xy 61.366547 -401.128348) (xy 61.325351 -401.164045)
			(xy 61.279494 -401.193515) (xy 61.22991 -401.216159) (xy 61.177608 -401.231516) (xy 61.123653 -401.239273)
			(xy 61.096398 -401.239736) (xy 60.232798 -401.239736) (xy 60.205549 -401.239194) (xy 60.151605 -401.231437)
			(xy 60.099315 -401.216083) (xy 60.049742 -401.193444) (xy 60.003895 -401.16398) (xy 59.962708 -401.128291)
			(xy 59.927019 -401.087104) (xy 59.897555 -401.041257) (xy 59.874916 -400.991683) (xy 59.859562 -400.939393)
			(xy 59.851806 -400.885449) (xy 58.414273 -400.885449) (xy 58.414273 -400.885457) (xy 58.406514 -400.939415)
			(xy 58.391155 -400.991721) (xy 58.368508 -401.041307) (xy 58.339034 -401.087166) (xy 58.303333 -401.128363)
			(xy 58.262132 -401.164059) (xy 58.21627 -401.193528) (xy 58.166681 -401.21617) (xy 58.114374 -401.231523)
			(xy 58.060415 -401.239276) (xy 58.033158 -401.239736) (xy 57.169558 -401.239736) (xy 57.142311 -401.239191)
			(xy 57.088372 -401.23143) (xy 57.036086 -401.216073) (xy 56.986518 -401.193431) (xy 56.940676 -401.163965)
			(xy 56.899494 -401.128277) (xy 56.863809 -401.087091) (xy 56.834349 -401.041246) (xy 56.811713 -400.991675)
			(xy 56.796361 -400.939387) (xy 56.788606 -400.885447) (xy 55.35095 -400.885447) (xy 55.35095 -400.885452)
			(xy 55.343194 -400.939403) (xy 55.327838 -400.9917) (xy 55.305197 -401.041279) (xy 55.27573 -401.087132)
			(xy 55.240038 -401.128325) (xy 55.198847 -401.164019) (xy 55.152995 -401.193488) (xy 55.103417 -401.216132)
			(xy 55.05112 -401.23149) (xy 54.99717 -401.239249) (xy 54.969918 -401.239736) (xy 54.106318 -401.239736)
			(xy 54.079066 -401.239218) (xy 54.025117 -401.231464) (xy 53.972821 -401.21611) (xy 53.923242 -401.19347)
			(xy 53.87739 -401.164005) (xy 53.836199 -401.128314) (xy 53.800506 -401.087124) (xy 53.771038 -401.041273)
			(xy 53.748396 -400.991696) (xy 53.73304 -400.9394) (xy 53.725283 -400.885452) (xy 52.287773 -400.885452)
			(xy 52.287773 -400.885456) (xy 52.280015 -400.939413) (xy 52.264657 -400.991716) (xy 52.242011 -401.041302)
			(xy 52.212539 -401.087159) (xy 52.17684 -401.128355) (xy 52.135642 -401.164052) (xy 52.089782 -401.193521)
			(xy 52.040196 -401.216164) (xy 51.987891 -401.23152) (xy 51.933934 -401.239275) (xy 51.906678 -401.239736)
			(xy 51.043078 -401.239736) (xy 51.01583 -401.239192) (xy 50.961888 -401.231434) (xy 50.9096 -401.216078)
			(xy 50.86003 -401.193437) (xy 50.814185 -401.163973) (xy 50.773001 -401.128284) (xy 50.737314 -401.087097)
			(xy 50.707852 -401.041251) (xy 50.685214 -400.991679) (xy 50.669862 -400.93939) (xy 50.662106 -400.885448)
			(xy 49.22445 -400.885448) (xy 49.22445 -400.885452) (xy 49.216694 -400.9394) (xy 49.20134 -400.991695)
			(xy 49.1787 -401.041274) (xy 49.149235 -401.087126) (xy 49.113545 -401.128318) (xy 49.072356 -401.164012)
			(xy 49.026507 -401.193482) (xy 48.976931 -401.216127) (xy 48.924637 -401.231486) (xy 48.870689 -401.239248)
			(xy 48.843438 -401.239736) (xy 47.979838 -401.239736) (xy 47.952585 -401.239219) (xy 47.898634 -401.231467)
			(xy 47.846336 -401.216116) (xy 47.796754 -401.193477) (xy 47.7509 -401.164012) (xy 47.709706 -401.128321)
			(xy 47.674011 -401.087131) (xy 47.644541 -401.041279) (xy 47.621898 -400.9917) (xy 47.606541 -400.939403)
			(xy 47.598783 -400.885453) (xy 2.509012 -400.885453) (xy 2.509012 -402.10994) (xy 239.42294 -402.10994)
			(xy 239.42294 -397.53286) (xy 239.423521 -397.5079) (xy 239.433246 -397.458937) (xy 239.452353 -397.412819)
			(xy 239.480105 -397.371324) (xy 239.497362 -397.353282) (xy 239.885982 -396.964662) (xy 239.904032 -396.947415)
			(xy 239.945531 -396.919673) (xy 239.991645 -396.900562) (xy 240.040601 -396.890815) (xy 240.06556 -396.89024)
			(xy 280.24074 -396.89024) (xy 280.2657 -396.890821) (xy 280.314663 -396.900546) (xy 280.360781 -396.919653)
			(xy 280.402276 -396.947405) (xy 280.420318 -396.964662) (xy 280.689558 -397.233902) (xy 280.706818 -397.25194)
			(xy 280.734556 -397.293444) (xy 280.753664 -397.339561) (xy 280.763407 -397.38852) (xy 280.76398 -397.41348)
			(xy 280.76398 -398.65534) (xy 457.185003 -398.65534) (xy 457.185003 -398.5262) (xy 457.192953 -398.397305)
			(xy 457.208823 -398.269145) (xy 457.232552 -398.142204) (xy 457.264051 -398.016965) (xy 457.3032 -397.893902)
			(xy 457.349851 -397.773483) (xy 457.403826 -397.656164) (xy 457.464921 -397.54239) (xy 457.532904 -397.432593)
			(xy 457.607518 -397.32719) (xy 457.688479 -397.22658) (xy 457.775479 -397.131145) (xy 457.86819 -397.041246)
			(xy 457.96626 -396.957225) (xy 458.069315 -396.879401) (xy 458.176966 -396.808069) (xy 458.288805 -396.743499)
			(xy 458.404406 -396.685937) (xy 458.523331 -396.6356) (xy 458.64513 -396.59268) (xy 458.76934 -396.557339)
			(xy 458.895489 -396.529712) (xy 459.023101 -396.509903) (xy 459.15169 -396.497987) (xy 459.280768 -396.494011)
			(xy 459.409846 -396.497987) (xy 459.538435 -396.509903) (xy 459.666047 -396.529712) (xy 459.792196 -396.557339)
			(xy 459.916406 -396.59268) (xy 460.038205 -396.6356) (xy 460.15713 -396.685937) (xy 460.272731 -396.743499)
			(xy 460.38457 -396.808069) (xy 460.492221 -396.879401) (xy 460.595276 -396.957225) (xy 460.693346 -397.041246)
			(xy 460.786057 -397.131145) (xy 460.873057 -397.22658) (xy 460.954018 -397.32719) (xy 461.028632 -397.432593)
			(xy 461.096615 -397.54239) (xy 461.15771 -397.656164) (xy 461.211685 -397.773483) (xy 461.258336 -397.893902)
			(xy 461.297485 -398.016965) (xy 461.328984 -398.142204) (xy 461.352713 -398.269145) (xy 461.368583 -398.397305)
			(xy 461.376533 -398.5262) (xy 461.37703 -398.59077) (xy 461.376533 -398.65534) (xy 461.368583 -398.784235)
			(xy 461.352713 -398.912395) (xy 461.328984 -399.039336) (xy 461.297485 -399.164575) (xy 461.258336 -399.287638)
			(xy 461.211685 -399.408057) (xy 461.15771 -399.525376) (xy 461.096615 -399.63915) (xy 461.028632 -399.748947)
			(xy 460.954018 -399.85435) (xy 460.873057 -399.95496) (xy 460.786057 -400.050395) (xy 460.693346 -400.140294)
			(xy 460.595276 -400.224315) (xy 460.492221 -400.302139) (xy 460.38457 -400.373471) (xy 460.272731 -400.438041)
			(xy 460.15713 -400.495603) (xy 460.038205 -400.54594) (xy 459.916406 -400.58886) (xy 459.792196 -400.624201)
			(xy 459.666047 -400.651828) (xy 459.538435 -400.671637) (xy 459.409846 -400.683553) (xy 459.280768 -400.68753)
			(xy 459.15169 -400.683553) (xy 459.023101 -400.671637) (xy 458.895489 -400.651828) (xy 458.76934 -400.624201)
			(xy 458.64513 -400.58886) (xy 458.523331 -400.54594) (xy 458.404406 -400.495603) (xy 458.288805 -400.438041)
			(xy 458.176966 -400.373471) (xy 458.069315 -400.302139) (xy 457.96626 -400.224315) (xy 457.86819 -400.140294)
			(xy 457.775479 -400.050395) (xy 457.688479 -399.95496) (xy 457.607518 -399.85435) (xy 457.532904 -399.748947)
			(xy 457.464921 -399.63915) (xy 457.403826 -399.525376) (xy 457.349851 -399.408057) (xy 457.3032 -399.287638)
			(xy 457.264051 -399.164575) (xy 457.232552 -399.039336) (xy 457.208823 -398.912395) (xy 457.192953 -398.784235)
			(xy 457.185003 -398.65534) (xy 280.76398 -398.65534) (xy 280.76398 -399.9835) (xy 289.606441 -399.9835)
			(xy 289.610455 -399.919698) (xy 289.622434 -399.856902) (xy 289.642189 -399.796103) (xy 289.669408 -399.73826)
			(xy 289.703662 -399.684283) (xy 289.744411 -399.635026) (xy 289.791013 -399.591264) (xy 289.842731 -399.553688)
			(xy 289.898752 -399.52289) (xy 289.958191 -399.499357) (xy 290.02011 -399.483458) (xy 290.083534 -399.475446)
			(xy 290.115498 -399.474944) (xy 290.115752 -399.474944) (xy 290.147498 -399.475464) (xy 290.210494 -399.483393)
			(xy 290.272014 -399.499096) (xy 290.331102 -399.52233) (xy 290.386842 -399.552733) (xy 290.438367 -399.589834)
			(xy 290.461954 -399.611088) (xy 290.469217 -399.617272) (xy 290.486967 -399.624223) (xy 290.506029 -399.624223)
			(xy 290.523779 -399.617272) (xy 290.531042 -399.611088) (xy 290.554631 -399.589832) (xy 290.60614 -399.5527)
			(xy 290.661874 -399.522276) (xy 290.720965 -399.499035) (xy 290.782492 -399.483338) (xy 290.845495 -399.475431)
			(xy 290.877244 -399.474944) (xy 290.877498 -399.474944) (xy 290.909457 -399.475521) (xy 290.972872 -399.483532)
			(xy 291.034783 -399.499427) (xy 291.094213 -399.522957) (xy 291.150226 -399.55375) (xy 291.201937 -399.591321)
			(xy 291.248532 -399.635076) (xy 291.289276 -399.684326) (xy 291.323525 -399.738295) (xy 291.350741 -399.79613)
			(xy 291.370493 -399.856921) (xy 291.38247 -399.919707) (xy 291.386484 -399.9835) (xy 292.146441 -399.9835)
			(xy 292.150455 -399.919698) (xy 292.162434 -399.856902) (xy 292.182189 -399.796103) (xy 292.209408 -399.73826)
			(xy 292.243662 -399.684283) (xy 292.284411 -399.635026) (xy 292.331013 -399.591264) (xy 292.382731 -399.553688)
			(xy 292.438752 -399.52289) (xy 292.498191 -399.499357) (xy 292.56011 -399.483458) (xy 292.623534 -399.475446)
			(xy 292.655498 -399.474944) (xy 292.655752 -399.474944) (xy 292.687498 -399.475464) (xy 292.750494 -399.483393)
			(xy 292.812014 -399.499096) (xy 292.871102 -399.52233) (xy 292.926842 -399.552733) (xy 292.978367 -399.589834)
			(xy 293.001954 -399.611088) (xy 293.009217 -399.617272) (xy 293.026967 -399.624223) (xy 293.046029 -399.624223)
			(xy 293.063779 -399.617272) (xy 293.071042 -399.611088) (xy 293.094631 -399.589832) (xy 293.14614 -399.5527)
			(xy 293.201874 -399.522276) (xy 293.260965 -399.499035) (xy 293.322492 -399.483338) (xy 293.385495 -399.475431)
			(xy 293.417244 -399.474944) (xy 293.417498 -399.474944) (xy 293.449457 -399.475521) (xy 293.512872 -399.483532)
			(xy 293.574783 -399.499427) (xy 293.634213 -399.522957) (xy 293.690226 -399.55375) (xy 293.741937 -399.591321)
			(xy 293.788532 -399.635076) (xy 293.829276 -399.684326) (xy 293.863525 -399.738295) (xy 293.890741 -399.79613)
			(xy 293.910493 -399.856921) (xy 293.92247 -399.919707) (xy 293.926484 -399.9835) (xy 294.53602 -399.9835)
			(xy 294.540035 -399.919693) (xy 294.552015 -399.856892) (xy 294.571773 -399.796089) (xy 294.598995 -399.738241)
			(xy 294.633253 -399.684261) (xy 294.674007 -399.635001) (xy 294.720613 -399.591237) (xy 294.772338 -399.55366)
			(xy 294.828364 -399.522862) (xy 294.887809 -399.499329) (xy 294.949734 -399.483433) (xy 295.013163 -399.475423)
			(xy 295.04513 -399.474944) (xy 295.045384 -399.474944) (xy 295.077131 -399.475444) (xy 295.140127 -399.483377)
			(xy 295.201647 -399.499084) (xy 295.260736 -399.522322) (xy 295.316476 -399.552728) (xy 295.368 -399.589832)
			(xy 295.391586 -399.611088) (xy 295.398849 -399.617272) (xy 295.416599 -399.624223) (xy 295.435661 -399.624223)
			(xy 295.453411 -399.617272) (xy 295.460674 -399.611088) (xy 295.48425 -399.589817) (xy 295.535761 -399.552686)
			(xy 295.591498 -399.522265) (xy 295.650592 -399.499026) (xy 295.712121 -399.483332) (xy 295.775126 -399.475429)
			(xy 295.806876 -399.474944) (xy 295.80713 -399.474944) (xy 295.839087 -399.475544) (xy 295.902496 -399.483558)
			(xy 295.964401 -399.499455) (xy 296.023825 -399.522986) (xy 296.079832 -399.553779) (xy 296.131538 -399.591348)
			(xy 296.178128 -399.635102) (xy 296.218866 -399.684349) (xy 296.253112 -399.738314) (xy 296.280324 -399.796145)
			(xy 296.300074 -399.856931) (xy 296.312049 -399.919712) (xy 296.316063 -399.9835) (xy 297.07602 -399.9835)
			(xy 297.080035 -399.919693) (xy 297.092015 -399.856892) (xy 297.111773 -399.796089) (xy 297.138995 -399.738241)
			(xy 297.173253 -399.684261) (xy 297.214007 -399.635001) (xy 297.260613 -399.591237) (xy 297.312338 -399.55366)
			(xy 297.368364 -399.522862) (xy 297.427809 -399.499329) (xy 297.489734 -399.483433) (xy 297.553163 -399.475423)
			(xy 297.58513 -399.474944) (xy 297.585384 -399.474944) (xy 297.617131 -399.475444) (xy 297.680127 -399.483377)
			(xy 297.741647 -399.499084) (xy 297.800736 -399.522322) (xy 297.856476 -399.552728) (xy 297.908 -399.589832)
			(xy 297.931586 -399.611088) (xy 297.938849 -399.617272) (xy 297.956599 -399.624223) (xy 297.975661 -399.624223)
			(xy 297.993411 -399.617272) (xy 298.000674 -399.611088) (xy 298.02425 -399.589817) (xy 298.075761 -399.552686)
			(xy 298.131498 -399.522265) (xy 298.190592 -399.499026) (xy 298.252121 -399.483332) (xy 298.315126 -399.475429)
			(xy 298.346876 -399.474944) (xy 298.34713 -399.474944) (xy 298.379087 -399.475544) (xy 298.442496 -399.483558)
			(xy 298.504401 -399.499455) (xy 298.563825 -399.522986) (xy 298.619832 -399.553779) (xy 298.671538 -399.591348)
			(xy 298.718128 -399.635102) (xy 298.758866 -399.684349) (xy 298.793112 -399.738314) (xy 298.820324 -399.796145)
			(xy 298.840074 -399.856931) (xy 298.852049 -399.919712) (xy 298.856063 -399.9835) (xy 298.852049 -400.047288)
			(xy 298.840074 -400.110069) (xy 298.820324 -400.170855) (xy 298.793112 -400.228686) (xy 298.758866 -400.282651)
			(xy 298.718128 -400.331898) (xy 298.671538 -400.375652) (xy 298.619832 -400.413221) (xy 298.563825 -400.444014)
			(xy 298.504401 -400.467545) (xy 298.442496 -400.483442) (xy 298.379087 -400.491456) (xy 298.34713 -400.49196)
			(xy 298.346876 -400.49196) (xy 298.315131 -400.491422) (xy 298.252136 -400.483497) (xy 298.190616 -400.467797)
			(xy 298.131527 -400.444566) (xy 298.075787 -400.414166) (xy 298.024261 -400.377069) (xy 298.000674 -400.355816)
			(xy 297.993411 -400.349632) (xy 297.975661 -400.342681) (xy 297.956599 -400.342681) (xy 297.938849 -400.349632)
			(xy 297.931586 -400.355816) (xy 297.908028 -400.377107) (xy 297.856512 -400.414235) (xy 297.800771 -400.444654)
			(xy 297.741674 -400.467889) (xy 297.680142 -400.483579) (xy 297.617135 -400.491478) (xy 297.585384 -400.49196)
			(xy 297.58513 -400.49196) (xy 297.553163 -400.491577) (xy 297.489734 -400.483567) (xy 297.427809 -400.467671)
			(xy 297.368364 -400.444138) (xy 297.312338 -400.41334) (xy 297.260613 -400.375763) (xy 297.214007 -400.331999)
			(xy 297.173253 -400.282739) (xy 297.138995 -400.228759) (xy 297.111773 -400.170911) (xy 297.092015 -400.110108)
			(xy 297.080035 -400.047307) (xy 297.07602 -399.9835) (xy 296.316063 -399.9835) (xy 296.312049 -400.047288)
			(xy 296.300074 -400.110069) (xy 296.280324 -400.170855) (xy 296.253112 -400.228686) (xy 296.218866 -400.282651)
			(xy 296.178128 -400.331898) (xy 296.131538 -400.375652) (xy 296.079832 -400.413221) (xy 296.023825 -400.444014)
			(xy 295.964401 -400.467545) (xy 295.902496 -400.483442) (xy 295.839087 -400.491456) (xy 295.80713 -400.49196)
			(xy 295.806876 -400.49196) (xy 295.775131 -400.491422) (xy 295.712136 -400.483497) (xy 295.650616 -400.467797)
			(xy 295.591527 -400.444566) (xy 295.535787 -400.414166) (xy 295.484261 -400.377069) (xy 295.460674 -400.355816)
			(xy 295.453411 -400.349632) (xy 295.435661 -400.342681) (xy 295.416599 -400.342681) (xy 295.398849 -400.349632)
			(xy 295.391586 -400.355816) (xy 295.368028 -400.377107) (xy 295.316512 -400.414235) (xy 295.260771 -400.444654)
			(xy 295.201674 -400.467889) (xy 295.140142 -400.483579) (xy 295.077135 -400.491478) (xy 295.045384 -400.49196)
			(xy 295.04513 -400.49196) (xy 295.013163 -400.491577) (xy 294.949734 -400.483567) (xy 294.887809 -400.467671)
			(xy 294.828364 -400.444138) (xy 294.772338 -400.41334) (xy 294.720613 -400.375763) (xy 294.674007 -400.331999)
			(xy 294.633253 -400.282739) (xy 294.598995 -400.228759) (xy 294.571773 -400.170911) (xy 294.552015 -400.110108)
			(xy 294.540035 -400.047307) (xy 294.53602 -399.9835) (xy 293.926484 -399.9835) (xy 293.92247 -400.047293)
			(xy 293.910493 -400.110079) (xy 293.890741 -400.17087) (xy 293.863525 -400.228705) (xy 293.829276 -400.282674)
			(xy 293.788532 -400.331924) (xy 293.741937 -400.375679) (xy 293.690226 -400.41325) (xy 293.634213 -400.444043)
			(xy 293.574783 -400.467573) (xy 293.512872 -400.483468) (xy 293.449457 -400.491479) (xy 293.417498 -400.49196)
			(xy 293.417244 -400.49196) (xy 293.385498 -400.491442) (xy 293.322502 -400.483512) (xy 293.260982 -400.467809)
			(xy 293.201894 -400.444575) (xy 293.146154 -400.414171) (xy 293.094629 -400.37707) (xy 293.071042 -400.355816)
			(xy 293.063779 -400.349632) (xy 293.046029 -400.342681) (xy 293.026967 -400.342681) (xy 293.009217 -400.349632)
			(xy 293.001954 -400.355816) (xy 292.978367 -400.377074) (xy 292.926858 -400.414206) (xy 292.871123 -400.44463)
			(xy 292.812032 -400.467871) (xy 292.750504 -400.483567) (xy 292.687501 -400.491474) (xy 292.655752 -400.49196)
			(xy 292.655498 -400.49196) (xy 292.623534 -400.491554) (xy 292.56011 -400.483542) (xy 292.498191 -400.467643)
			(xy 292.438752 -400.44411) (xy 292.382731 -400.413312) (xy 292.331013 -400.375736) (xy 292.284411 -400.331974)
			(xy 292.243662 -400.282717) (xy 292.209408 -400.22874) (xy 292.182189 -400.170897) (xy 292.162434 -400.110098)
			(xy 292.150455 -400.047302) (xy 292.146441 -399.9835) (xy 291.386484 -399.9835) (xy 291.38247 -400.047293)
			(xy 291.370493 -400.110079) (xy 291.350741 -400.17087) (xy 291.323525 -400.228705) (xy 291.289276 -400.282674)
			(xy 291.248532 -400.331924) (xy 291.201937 -400.375679) (xy 291.150226 -400.41325) (xy 291.094213 -400.444043)
			(xy 291.034783 -400.467573) (xy 290.972872 -400.483468) (xy 290.909457 -400.491479) (xy 290.877498 -400.49196)
			(xy 290.877244 -400.49196) (xy 290.845498 -400.491442) (xy 290.782502 -400.483512) (xy 290.720982 -400.467809)
			(xy 290.661894 -400.444575) (xy 290.606154 -400.414171) (xy 290.554629 -400.37707) (xy 290.531042 -400.355816)
			(xy 290.523779 -400.349632) (xy 290.506029 -400.342681) (xy 290.486967 -400.342681) (xy 290.469217 -400.349632)
			(xy 290.461954 -400.355816) (xy 290.438367 -400.377074) (xy 290.386858 -400.414206) (xy 290.331123 -400.44463)
			(xy 290.272032 -400.467871) (xy 290.210504 -400.483567) (xy 290.147501 -400.491474) (xy 290.115752 -400.49196)
			(xy 290.115498 -400.49196) (xy 290.083534 -400.491554) (xy 290.02011 -400.483542) (xy 289.958191 -400.467643)
			(xy 289.898752 -400.44411) (xy 289.842731 -400.413312) (xy 289.791013 -400.375736) (xy 289.744411 -400.331974)
			(xy 289.703662 -400.282717) (xy 289.669408 -400.22874) (xy 289.642189 -400.170897) (xy 289.622434 -400.110098)
			(xy 289.610455 -400.047302) (xy 289.606441 -399.9835) (xy 280.76398 -399.9835) (xy 280.76398 -400.885449)
			(xy 303.599106 -400.885449) (xy 303.599106 -400.830951) (xy 303.606862 -400.777009) (xy 303.622215 -400.724719)
			(xy 303.644854 -400.675146) (xy 303.674317 -400.6293) (xy 303.710004 -400.588113) (xy 303.75119 -400.552424)
			(xy 303.797036 -400.52296) (xy 303.846608 -400.500319) (xy 303.898897 -400.484964) (xy 303.952839 -400.477207)
			(xy 303.980088 -400.47672) (xy 304.843688 -400.47672) (xy 304.870943 -400.477126) (xy 304.9249 -400.484882)
			(xy 304.977203 -400.500238) (xy 305.026788 -400.522882) (xy 305.072646 -400.552352) (xy 305.113843 -400.588048)
			(xy 305.149541 -400.629244) (xy 305.179012 -400.675101) (xy 305.201657 -400.724686) (xy 305.217015 -400.776989)
			(xy 305.224773 -400.830945) (xy 305.224773 -400.885452) (xy 306.662283 -400.885452) (xy 306.662283 -400.830948)
			(xy 306.67004 -400.776998) (xy 306.685397 -400.724702) (xy 306.70804 -400.675124) (xy 306.737508 -400.629273)
			(xy 306.773202 -400.588082) (xy 306.814395 -400.552391) (xy 306.860248 -400.522926) (xy 306.909828 -400.500287)
			(xy 306.962126 -400.484935) (xy 307.016076 -400.477181) (xy 307.043328 -400.47672) (xy 307.906928 -400.47672)
			(xy 307.93418 -400.477152) (xy 307.988129 -400.484912) (xy 308.040424 -400.500271) (xy 308.090001 -400.522915)
			(xy 308.135851 -400.552384) (xy 308.177041 -400.588079) (xy 308.212732 -400.629271) (xy 308.242198 -400.675123)
			(xy 308.264839 -400.724702) (xy 308.280194 -400.776999) (xy 308.28795 -400.830948) (xy 308.28795 -400.885448)
			(xy 309.725606 -400.885448) (xy 309.725606 -400.830952) (xy 309.733361 -400.777011) (xy 309.748714 -400.724723)
			(xy 309.771351 -400.675152) (xy 309.800812 -400.629306) (xy 309.836497 -400.58812) (xy 309.877681 -400.552431)
			(xy 309.923524 -400.522966) (xy 309.973093 -400.500325) (xy 310.02538 -400.484968) (xy 310.07932 -400.477208)
			(xy 310.106568 -400.47672) (xy 310.970168 -400.47672) (xy 310.997424 -400.477125) (xy 311.051383 -400.484879)
			(xy 311.103688 -400.500233) (xy 311.153276 -400.522875) (xy 311.199137 -400.552345) (xy 311.240336 -400.588041)
			(xy 311.276036 -400.629238) (xy 311.305509 -400.675096) (xy 311.328156 -400.724682) (xy 311.343515 -400.776986)
			(xy 311.351273 -400.830944) (xy 311.351273 -400.885451) (xy 312.788783 -400.885451) (xy 312.788783 -400.830949)
			(xy 312.79654 -400.777001) (xy 312.811895 -400.724706) (xy 312.834537 -400.675129) (xy 312.864003 -400.629279)
			(xy 312.899695 -400.588089) (xy 312.940886 -400.552398) (xy 312.986736 -400.522933) (xy 313.036314 -400.500292)
			(xy 313.088609 -400.484938) (xy 313.142557 -400.477183) (xy 313.169808 -400.47672) (xy 314.033408 -400.47672)
			(xy 314.060661 -400.47715) (xy 314.114612 -400.484908) (xy 314.166909 -400.500265) (xy 314.216489 -400.522909)
			(xy 314.262342 -400.552377) (xy 314.303534 -400.588071) (xy 314.339228 -400.629264) (xy 314.368695 -400.675118)
			(xy 314.391337 -400.724698) (xy 314.406693 -400.776996) (xy 314.41445 -400.830947) (xy 314.41445 -400.885453)
			(xy 315.851983 -400.885453) (xy 315.851983 -400.830947) (xy 315.859741 -400.776996) (xy 315.875098 -400.724698)
			(xy 315.897743 -400.675118) (xy 315.927213 -400.629266) (xy 315.962909 -400.588075) (xy 316.004105 -400.552384)
			(xy 316.04996 -400.52292) (xy 316.099543 -400.500282) (xy 316.151843 -400.484931) (xy 316.205795 -400.47718)
			(xy 316.233048 -400.47672) (xy 317.096648 -400.47672) (xy 317.123899 -400.477153) (xy 317.177846 -400.484916)
			(xy 317.230138 -400.500276) (xy 317.279713 -400.522922) (xy 317.325561 -400.552391) (xy 317.366748 -400.588086)
			(xy 317.402437 -400.629278) (xy 317.431901 -400.675129) (xy 317.454541 -400.724707) (xy 317.469894 -400.777001)
			(xy 317.47765 -400.830949) (xy 317.47765 -400.885449) (xy 318.915306 -400.885449) (xy 318.915306 -400.830951)
			(xy 318.923062 -400.777009) (xy 318.938415 -400.724719) (xy 318.961054 -400.675146) (xy 318.990517 -400.6293)
			(xy 319.026204 -400.588113) (xy 319.06739 -400.552424) (xy 319.113236 -400.52296) (xy 319.162808 -400.500319)
			(xy 319.215097 -400.484964) (xy 319.269039 -400.477207) (xy 319.296288 -400.47672) (xy 320.159888 -400.47672)
			(xy 320.187143 -400.477126) (xy 320.2411 -400.484882) (xy 320.293403 -400.500238) (xy 320.342988 -400.522882)
			(xy 320.388846 -400.552352) (xy 320.430043 -400.588048) (xy 320.465741 -400.629244) (xy 320.495212 -400.675101)
			(xy 320.517857 -400.724686) (xy 320.533215 -400.776989) (xy 320.540973 -400.830945) (xy 320.540973 -400.885452)
			(xy 321.978483 -400.885452) (xy 321.978483 -400.830948) (xy 321.98624 -400.776998) (xy 322.001597 -400.724702)
			(xy 322.02424 -400.675124) (xy 322.053708 -400.629273) (xy 322.089402 -400.588082) (xy 322.130595 -400.552391)
			(xy 322.176448 -400.522926) (xy 322.226028 -400.500287) (xy 322.278326 -400.484935) (xy 322.332276 -400.477181)
			(xy 322.359528 -400.47672) (xy 323.223128 -400.47672) (xy 323.25038 -400.477152) (xy 323.304329 -400.484912)
			(xy 323.356624 -400.500271) (xy 323.406201 -400.522915) (xy 323.452051 -400.552384) (xy 323.493241 -400.588079)
			(xy 323.528932 -400.629271) (xy 323.558398 -400.675123) (xy 323.581039 -400.724702) (xy 323.596394 -400.776999)
			(xy 323.60415 -400.830948) (xy 323.60415 -400.885448) (xy 325.041806 -400.885448) (xy 325.041806 -400.830952)
			(xy 325.049561 -400.777011) (xy 325.064914 -400.724723) (xy 325.087551 -400.675152) (xy 325.117012 -400.629306)
			(xy 325.152697 -400.58812) (xy 325.193881 -400.552431) (xy 325.239724 -400.522966) (xy 325.289293 -400.500325)
			(xy 325.34158 -400.484968) (xy 325.39552 -400.477208) (xy 325.422768 -400.47672) (xy 326.286368 -400.47672)
			(xy 326.313624 -400.477125) (xy 326.367583 -400.484879) (xy 326.419888 -400.500233) (xy 326.469476 -400.522875)
			(xy 326.515337 -400.552345) (xy 326.556536 -400.588041) (xy 326.592236 -400.629238) (xy 326.621709 -400.675096)
			(xy 326.644356 -400.724682) (xy 326.659715 -400.776986) (xy 326.667473 -400.830944) (xy 326.667473 -400.885451)
			(xy 328.104983 -400.885451) (xy 328.104983 -400.830949) (xy 328.11274 -400.777001) (xy 328.128095 -400.724706)
			(xy 328.150737 -400.675129) (xy 328.180203 -400.629279) (xy 328.215895 -400.588089) (xy 328.257086 -400.552398)
			(xy 328.302936 -400.522933) (xy 328.352514 -400.500292) (xy 328.404809 -400.484938) (xy 328.458757 -400.477183)
			(xy 328.486008 -400.47672) (xy 329.349608 -400.47672) (xy 329.376861 -400.47715) (xy 329.430812 -400.484908)
			(xy 329.483109 -400.500265) (xy 329.532689 -400.522909) (xy 329.578542 -400.552377) (xy 329.619734 -400.588071)
			(xy 329.655428 -400.629264) (xy 329.684895 -400.675118) (xy 329.707537 -400.724698) (xy 329.722893 -400.776996)
			(xy 329.73065 -400.830947) (xy 329.73065 -400.885453) (xy 331.168183 -400.885453) (xy 331.168183 -400.830947)
			(xy 331.175941 -400.776996) (xy 331.191298 -400.724698) (xy 331.213943 -400.675118) (xy 331.243413 -400.629266)
			(xy 331.279109 -400.588075) (xy 331.320305 -400.552384) (xy 331.36616 -400.52292) (xy 331.415743 -400.500282)
			(xy 331.468043 -400.484931) (xy 331.521995 -400.47718) (xy 331.549248 -400.47672) (xy 332.412848 -400.47672)
			(xy 332.440099 -400.477153) (xy 332.494046 -400.484916) (xy 332.546338 -400.500276) (xy 332.595913 -400.522922)
			(xy 332.641761 -400.552391) (xy 332.682948 -400.588086) (xy 332.718637 -400.629278) (xy 332.748101 -400.675129)
			(xy 332.770741 -400.724707) (xy 332.786094 -400.777001) (xy 332.79385 -400.830949) (xy 332.79385 -400.885449)
			(xy 334.231506 -400.885449) (xy 334.231506 -400.830951) (xy 334.239262 -400.777009) (xy 334.254615 -400.724719)
			(xy 334.277254 -400.675146) (xy 334.306717 -400.6293) (xy 334.342404 -400.588113) (xy 334.38359 -400.552424)
			(xy 334.429436 -400.52296) (xy 334.479008 -400.500319) (xy 334.531297 -400.484964) (xy 334.585239 -400.477207)
			(xy 334.612488 -400.47672) (xy 335.476088 -400.47672) (xy 335.503343 -400.477126) (xy 335.5573 -400.484882)
			(xy 335.609603 -400.500238) (xy 335.659188 -400.522882) (xy 335.705046 -400.552352) (xy 335.746243 -400.588048)
			(xy 335.781941 -400.629244) (xy 335.811412 -400.675101) (xy 335.834057 -400.724686) (xy 335.849415 -400.776989)
			(xy 335.857173 -400.830945) (xy 335.857173 -400.885452) (xy 337.294683 -400.885452) (xy 337.294683 -400.830948)
			(xy 337.30244 -400.776998) (xy 337.317797 -400.724702) (xy 337.34044 -400.675124) (xy 337.369908 -400.629273)
			(xy 337.405602 -400.588082) (xy 337.446795 -400.552391) (xy 337.492648 -400.522926) (xy 337.542228 -400.500287)
			(xy 337.594526 -400.484935) (xy 337.648476 -400.477181) (xy 337.675728 -400.47672) (xy 338.539328 -400.47672)
			(xy 338.56658 -400.477152) (xy 338.620529 -400.484912) (xy 338.672824 -400.500271) (xy 338.722401 -400.522915)
			(xy 338.768251 -400.552384) (xy 338.809441 -400.588079) (xy 338.845132 -400.629271) (xy 338.874598 -400.675123)
			(xy 338.897239 -400.724702) (xy 338.912594 -400.776999) (xy 338.92035 -400.830948) (xy 338.92035 -400.885448)
			(xy 340.358006 -400.885448) (xy 340.358006 -400.830952) (xy 340.365761 -400.777011) (xy 340.381114 -400.724723)
			(xy 340.403751 -400.675152) (xy 340.433212 -400.629306) (xy 340.468897 -400.58812) (xy 340.510081 -400.552431)
			(xy 340.555924 -400.522966) (xy 340.605493 -400.500325) (xy 340.65778 -400.484968) (xy 340.71172 -400.477208)
			(xy 340.738968 -400.47672) (xy 341.602568 -400.47672) (xy 341.629824 -400.477125) (xy 341.683783 -400.484879)
			(xy 341.736088 -400.500233) (xy 341.785676 -400.522875) (xy 341.831537 -400.552345) (xy 341.872736 -400.588041)
			(xy 341.908436 -400.629238) (xy 341.937909 -400.675096) (xy 341.960556 -400.724682) (xy 341.975915 -400.776986)
			(xy 341.983673 -400.830944) (xy 341.983673 -400.885451) (xy 343.421183 -400.885451) (xy 343.421183 -400.830949)
			(xy 343.42894 -400.777001) (xy 343.444295 -400.724706) (xy 343.466937 -400.675129) (xy 343.496403 -400.629279)
			(xy 343.532095 -400.588089) (xy 343.573286 -400.552398) (xy 343.619136 -400.522933) (xy 343.668714 -400.500292)
			(xy 343.721009 -400.484938) (xy 343.774957 -400.477183) (xy 343.802208 -400.47672) (xy 344.665808 -400.47672)
			(xy 344.693061 -400.47715) (xy 344.747012 -400.484908) (xy 344.799309 -400.500265) (xy 344.848889 -400.522909)
			(xy 344.894742 -400.552377) (xy 344.935934 -400.588071) (xy 344.971628 -400.629264) (xy 345.001095 -400.675118)
			(xy 345.023737 -400.724698) (xy 345.039093 -400.776996) (xy 345.04685 -400.830947) (xy 345.04685 -400.885453)
			(xy 346.484383 -400.885453) (xy 346.484383 -400.830947) (xy 346.492141 -400.776996) (xy 346.507498 -400.724698)
			(xy 346.530143 -400.675118) (xy 346.559613 -400.629266) (xy 346.595309 -400.588075) (xy 346.636505 -400.552384)
			(xy 346.68236 -400.52292) (xy 346.731943 -400.500282) (xy 346.784243 -400.484931) (xy 346.838195 -400.47718)
			(xy 346.865448 -400.47672) (xy 347.729048 -400.47672) (xy 347.756299 -400.477153) (xy 347.810246 -400.484916)
			(xy 347.862538 -400.500276) (xy 347.912113 -400.522922) (xy 347.957961 -400.552391) (xy 347.999148 -400.588086)
			(xy 348.034837 -400.629278) (xy 348.064301 -400.675129) (xy 348.086941 -400.724707) (xy 348.102294 -400.777001)
			(xy 348.11005 -400.830949) (xy 348.11005 -400.885449) (xy 349.547706 -400.885449) (xy 349.547706 -400.830951)
			(xy 349.555462 -400.777009) (xy 349.570815 -400.724719) (xy 349.593454 -400.675146) (xy 349.622917 -400.6293)
			(xy 349.658604 -400.588113) (xy 349.69979 -400.552424) (xy 349.745636 -400.52296) (xy 349.795208 -400.500319)
			(xy 349.847497 -400.484964) (xy 349.901439 -400.477207) (xy 349.928688 -400.47672) (xy 350.792288 -400.47672)
			(xy 350.819543 -400.477126) (xy 350.8735 -400.484882) (xy 350.925803 -400.500238) (xy 350.975388 -400.522882)
			(xy 351.021246 -400.552352) (xy 351.062443 -400.588048) (xy 351.098141 -400.629244) (xy 351.127612 -400.675101)
			(xy 351.150257 -400.724686) (xy 351.165615 -400.776989) (xy 351.173373 -400.830945) (xy 351.173373 -400.885452)
			(xy 371.041883 -400.885452) (xy 371.041883 -400.830948) (xy 371.049641 -400.776998) (xy 371.064997 -400.724702)
			(xy 371.08764 -400.675123) (xy 371.117109 -400.629272) (xy 371.152803 -400.588082) (xy 371.193996 -400.552391)
			(xy 371.23985 -400.522926) (xy 371.28943 -400.500286) (xy 371.341728 -400.484934) (xy 371.395678 -400.477181)
			(xy 371.42293 -400.47672) (xy 372.28653 -400.47672) (xy 372.313782 -400.477152) (xy 372.36773 -400.484912)
			(xy 372.420025 -400.500271) (xy 372.469602 -400.522916) (xy 372.515452 -400.552385) (xy 372.556642 -400.588079)
			(xy 372.592333 -400.629272) (xy 372.621799 -400.675124) (xy 372.644439 -400.724703) (xy 372.659794 -400.776999)
			(xy 372.66755 -400.830948) (xy 372.66755 -400.885448) (xy 374.105206 -400.885448) (xy 374.105206 -400.830952)
			(xy 374.112961 -400.777011) (xy 374.128314 -400.724723) (xy 374.150951 -400.675151) (xy 374.180412 -400.629306)
			(xy 374.216098 -400.588119) (xy 374.257281 -400.55243) (xy 374.303125 -400.522965) (xy 374.352694 -400.500324)
			(xy 374.404982 -400.484968) (xy 374.458922 -400.477208) (xy 374.48617 -400.47672) (xy 375.34977 -400.47672)
			(xy 375.377026 -400.477125) (xy 375.430984 -400.484879) (xy 375.48329 -400.500234) (xy 375.532877 -400.522876)
			(xy 375.578738 -400.552345) (xy 375.619937 -400.588042) (xy 375.655637 -400.629238) (xy 375.68511 -400.675096)
			(xy 375.707756 -400.724682) (xy 375.723115 -400.776986) (xy 375.730873 -400.830944) (xy 375.730873 -400.885451)
			(xy 377.168383 -400.885451) (xy 377.168383 -400.830949) (xy 377.17614 -400.777001) (xy 377.191495 -400.724706)
			(xy 377.214137 -400.675129) (xy 377.243604 -400.629279) (xy 377.279296 -400.588089) (xy 377.320487 -400.552398)
			(xy 377.366338 -400.522932) (xy 377.415915 -400.500292) (xy 377.468211 -400.484938) (xy 377.522159 -400.477183)
			(xy 377.54941 -400.47672) (xy 378.41301 -400.47672) (xy 378.440263 -400.477151) (xy 378.494213 -400.484909)
			(xy 378.546511 -400.500266) (xy 378.59609 -400.522909) (xy 378.641943 -400.552378) (xy 378.683135 -400.588072)
			(xy 378.718828 -400.629265) (xy 378.748296 -400.675118) (xy 378.770938 -400.724699) (xy 378.786293 -400.776996)
			(xy 378.79405 -400.830947) (xy 378.79405 -400.885447) (xy 380.231706 -400.885447) (xy 380.231706 -400.830953)
			(xy 380.239461 -400.777014) (xy 380.254812 -400.724727) (xy 380.277448 -400.675157) (xy 380.306907 -400.629312)
			(xy 380.342591 -400.588126) (xy 380.383772 -400.552437) (xy 380.429613 -400.522972) (xy 380.47918 -400.50033)
			(xy 380.531465 -400.484971) (xy 380.585403 -400.47721) (xy 380.61265 -400.47672) (xy 381.47625 -400.47672)
			(xy 381.503507 -400.477124) (xy 381.557468 -400.484875) (xy 381.609775 -400.500228) (xy 381.659365 -400.522869)
			(xy 381.705228 -400.552338) (xy 381.74643 -400.588035) (xy 381.782132 -400.629232) (xy 381.811607 -400.675091)
			(xy 381.834254 -400.724678) (xy 381.849614 -400.776983) (xy 381.857373 -400.830943) (xy 381.857373 -400.885449)
			(xy 383.294906 -400.885449) (xy 383.294906 -400.830951) (xy 383.302662 -400.777008) (xy 383.318015 -400.724718)
			(xy 383.340654 -400.675145) (xy 383.370117 -400.629299) (xy 383.405805 -400.588112) (xy 383.446991 -400.552423)
			(xy 383.492837 -400.522959) (xy 383.542409 -400.500319) (xy 383.594699 -400.484964) (xy 383.648641 -400.477207)
			(xy 383.67589 -400.47672) (xy 384.53949 -400.47672) (xy 384.566745 -400.477126) (xy 384.620701 -400.484883)
			(xy 384.673004 -400.500239) (xy 384.722589 -400.522883) (xy 384.768447 -400.552352) (xy 384.809644 -400.588049)
			(xy 384.845342 -400.629245) (xy 384.874813 -400.675102) (xy 384.897458 -400.724686) (xy 384.912815 -400.776989)
			(xy 384.920573 -400.830945) (xy 384.920573 -400.885452) (xy 386.358083 -400.885452) (xy 386.358083 -400.830948)
			(xy 386.365841 -400.776998) (xy 386.381197 -400.724702) (xy 386.40384 -400.675123) (xy 386.433309 -400.629272)
			(xy 386.469003 -400.588082) (xy 386.510196 -400.552391) (xy 386.55605 -400.522926) (xy 386.60563 -400.500286)
			(xy 386.657928 -400.484934) (xy 386.711878 -400.477181) (xy 386.73913 -400.47672) (xy 387.60273 -400.47672)
			(xy 387.629982 -400.477152) (xy 387.68393 -400.484912) (xy 387.736225 -400.500271) (xy 387.785802 -400.522916)
			(xy 387.831652 -400.552385) (xy 387.872842 -400.588079) (xy 387.908533 -400.629272) (xy 387.937999 -400.675124)
			(xy 387.960639 -400.724703) (xy 387.975994 -400.776999) (xy 387.98375 -400.830948) (xy 387.98375 -400.885448)
			(xy 389.421406 -400.885448) (xy 389.421406 -400.830952) (xy 389.429161 -400.777011) (xy 389.444514 -400.724723)
			(xy 389.467151 -400.675151) (xy 389.496612 -400.629306) (xy 389.532298 -400.588119) (xy 389.573481 -400.55243)
			(xy 389.619325 -400.522965) (xy 389.668894 -400.500324) (xy 389.721182 -400.484968) (xy 389.775122 -400.477208)
			(xy 389.80237 -400.47672) (xy 390.66597 -400.47672) (xy 390.693226 -400.477125) (xy 390.747184 -400.484879)
			(xy 390.79949 -400.500234) (xy 390.849077 -400.522876) (xy 390.894938 -400.552345) (xy 390.936137 -400.588042)
			(xy 390.971837 -400.629238) (xy 391.00131 -400.675096) (xy 391.023956 -400.724682) (xy 391.039315 -400.776986)
			(xy 391.047073 -400.830944) (xy 391.047073 -400.885451) (xy 392.484583 -400.885451) (xy 392.484583 -400.830949)
			(xy 392.49234 -400.777001) (xy 392.507695 -400.724706) (xy 392.530337 -400.675129) (xy 392.559804 -400.629279)
			(xy 392.595496 -400.588089) (xy 392.636687 -400.552398) (xy 392.682538 -400.522932) (xy 392.732115 -400.500292)
			(xy 392.784411 -400.484938) (xy 392.838359 -400.477183) (xy 392.86561 -400.47672) (xy 393.72921 -400.47672)
			(xy 393.756463 -400.477151) (xy 393.810413 -400.484909) (xy 393.862711 -400.500266) (xy 393.91229 -400.522909)
			(xy 393.958143 -400.552378) (xy 393.999335 -400.588072) (xy 394.035028 -400.629265) (xy 394.064496 -400.675118)
			(xy 394.087138 -400.724699) (xy 394.102493 -400.776996) (xy 394.11025 -400.830947) (xy 394.11025 -400.885447)
			(xy 395.547906 -400.885447) (xy 395.547906 -400.830953) (xy 395.555661 -400.777014) (xy 395.571012 -400.724727)
			(xy 395.593648 -400.675157) (xy 395.623107 -400.629312) (xy 395.658791 -400.588126) (xy 395.699972 -400.552437)
			(xy 395.745813 -400.522972) (xy 395.79538 -400.50033) (xy 395.847665 -400.484971) (xy 395.901603 -400.47721)
			(xy 395.92885 -400.47672) (xy 396.79245 -400.47672) (xy 396.819707 -400.477124) (xy 396.873668 -400.484875)
			(xy 396.925975 -400.500228) (xy 396.975565 -400.522869) (xy 397.021428 -400.552338) (xy 397.06263 -400.588035)
			(xy 397.098332 -400.629232) (xy 397.127807 -400.675091) (xy 397.150454 -400.724678) (xy 397.165814 -400.776983)
			(xy 397.173573 -400.830943) (xy 397.173573 -400.885449) (xy 398.611106 -400.885449) (xy 398.611106 -400.830951)
			(xy 398.618862 -400.777008) (xy 398.634215 -400.724718) (xy 398.656854 -400.675145) (xy 398.686317 -400.629299)
			(xy 398.722005 -400.588112) (xy 398.763191 -400.552423) (xy 398.809037 -400.522959) (xy 398.858609 -400.500319)
			(xy 398.910899 -400.484964) (xy 398.964841 -400.477207) (xy 398.99209 -400.47672) (xy 399.85569 -400.47672)
			(xy 399.882945 -400.477126) (xy 399.936901 -400.484883) (xy 399.989204 -400.500239) (xy 400.038789 -400.522883)
			(xy 400.084647 -400.552352) (xy 400.125844 -400.588049) (xy 400.161542 -400.629245) (xy 400.191013 -400.675102)
			(xy 400.213658 -400.724686) (xy 400.229015 -400.776989) (xy 400.236773 -400.830945) (xy 400.236773 -400.885452)
			(xy 401.674283 -400.885452) (xy 401.674283 -400.830948) (xy 401.682041 -400.776998) (xy 401.697397 -400.724702)
			(xy 401.72004 -400.675123) (xy 401.749509 -400.629272) (xy 401.785203 -400.588082) (xy 401.826396 -400.552391)
			(xy 401.87225 -400.522926) (xy 401.92183 -400.500286) (xy 401.974128 -400.484934) (xy 402.028078 -400.477181)
			(xy 402.05533 -400.47672) (xy 402.91893 -400.47672) (xy 402.946182 -400.477152) (xy 403.00013 -400.484912)
			(xy 403.052425 -400.500271) (xy 403.102002 -400.522916) (xy 403.147852 -400.552385) (xy 403.189042 -400.588079)
			(xy 403.224733 -400.629272) (xy 403.254199 -400.675124) (xy 403.276839 -400.724703) (xy 403.292194 -400.776999)
			(xy 403.29995 -400.830948) (xy 403.29995 -400.885448) (xy 404.737606 -400.885448) (xy 404.737606 -400.830952)
			(xy 404.745361 -400.777011) (xy 404.760714 -400.724723) (xy 404.783351 -400.675151) (xy 404.812812 -400.629306)
			(xy 404.848498 -400.588119) (xy 404.889681 -400.55243) (xy 404.935525 -400.522965) (xy 404.985094 -400.500324)
			(xy 405.037382 -400.484968) (xy 405.091322 -400.477208) (xy 405.11857 -400.47672) (xy 405.98217 -400.47672)
			(xy 406.009426 -400.477125) (xy 406.063384 -400.484879) (xy 406.11569 -400.500234) (xy 406.165277 -400.522876)
			(xy 406.211138 -400.552345) (xy 406.252337 -400.588042) (xy 406.288037 -400.629238) (xy 406.31751 -400.675096)
			(xy 406.340156 -400.724682) (xy 406.355515 -400.776986) (xy 406.363273 -400.830944) (xy 406.363273 -400.885451)
			(xy 407.800783 -400.885451) (xy 407.800783 -400.830949) (xy 407.80854 -400.777001) (xy 407.823895 -400.724706)
			(xy 407.846537 -400.675129) (xy 407.876004 -400.629279) (xy 407.911696 -400.588089) (xy 407.952887 -400.552398)
			(xy 407.998738 -400.522932) (xy 408.048315 -400.500292) (xy 408.100611 -400.484938) (xy 408.154559 -400.477183)
			(xy 408.18181 -400.47672) (xy 409.04541 -400.47672) (xy 409.072663 -400.477151) (xy 409.126613 -400.484909)
			(xy 409.178911 -400.500266) (xy 409.22849 -400.522909) (xy 409.274343 -400.552378) (xy 409.315535 -400.588072)
			(xy 409.351228 -400.629265) (xy 409.380696 -400.675118) (xy 409.403338 -400.724699) (xy 409.418693 -400.776996)
			(xy 409.42645 -400.830947) (xy 409.42645 -400.885447) (xy 410.864106 -400.885447) (xy 410.864106 -400.830953)
			(xy 410.871861 -400.777014) (xy 410.887212 -400.724727) (xy 410.909848 -400.675157) (xy 410.939307 -400.629312)
			(xy 410.974991 -400.588126) (xy 411.016172 -400.552437) (xy 411.062013 -400.522972) (xy 411.11158 -400.50033)
			(xy 411.163865 -400.484971) (xy 411.217803 -400.47721) (xy 411.24505 -400.47672) (xy 412.10865 -400.47672)
			(xy 412.135907 -400.477124) (xy 412.189868 -400.484875) (xy 412.242175 -400.500228) (xy 412.291765 -400.522869)
			(xy 412.337628 -400.552338) (xy 412.37883 -400.588035) (xy 412.414532 -400.629232) (xy 412.444007 -400.675091)
			(xy 412.466654 -400.724678) (xy 412.482014 -400.776983) (xy 412.489773 -400.830943) (xy 412.489773 -400.885449)
			(xy 413.927306 -400.885449) (xy 413.927306 -400.830951) (xy 413.935062 -400.777008) (xy 413.950415 -400.724718)
			(xy 413.973054 -400.675145) (xy 414.002517 -400.629299) (xy 414.038205 -400.588112) (xy 414.079391 -400.552423)
			(xy 414.125237 -400.522959) (xy 414.174809 -400.500319) (xy 414.227099 -400.484964) (xy 414.281041 -400.477207)
			(xy 414.30829 -400.47672) (xy 415.17189 -400.47672) (xy 415.199145 -400.477126) (xy 415.253101 -400.484883)
			(xy 415.305404 -400.500239) (xy 415.354989 -400.522883) (xy 415.400847 -400.552352) (xy 415.442044 -400.588049)
			(xy 415.477742 -400.629245) (xy 415.507213 -400.675102) (xy 415.529858 -400.724686) (xy 415.545215 -400.776989)
			(xy 415.552973 -400.830945) (xy 415.552973 -400.885452) (xy 416.990483 -400.885452) (xy 416.990483 -400.830948)
			(xy 416.998241 -400.776998) (xy 417.013597 -400.724702) (xy 417.03624 -400.675123) (xy 417.065709 -400.629272)
			(xy 417.101403 -400.588082) (xy 417.142596 -400.552391) (xy 417.18845 -400.522926) (xy 417.23803 -400.500286)
			(xy 417.290328 -400.484934) (xy 417.344278 -400.477181) (xy 417.37153 -400.47672) (xy 418.23513 -400.47672)
			(xy 418.262382 -400.477152) (xy 418.31633 -400.484912) (xy 418.368625 -400.500271) (xy 418.418202 -400.522916)
			(xy 418.464052 -400.552385) (xy 418.505242 -400.588079) (xy 418.540933 -400.629272) (xy 418.570399 -400.675124)
			(xy 418.593039 -400.724703) (xy 418.608394 -400.776999) (xy 418.61615 -400.830948) (xy 418.61615 -400.885452)
			(xy 418.608394 -400.939401) (xy 418.593039 -400.991697) (xy 418.570399 -401.041276) (xy 418.540933 -401.087128)
			(xy 418.505242 -401.128321) (xy 418.464052 -401.164015) (xy 418.418202 -401.193484) (xy 418.368625 -401.216129)
			(xy 418.31633 -401.231488) (xy 418.262382 -401.239248) (xy 418.23513 -401.239736) (xy 417.37153 -401.239736)
			(xy 417.344278 -401.239219) (xy 417.290328 -401.231466) (xy 417.23803 -401.216114) (xy 417.18845 -401.193474)
			(xy 417.142596 -401.164009) (xy 417.101403 -401.128318) (xy 417.065709 -401.087128) (xy 417.03624 -401.041277)
			(xy 417.013597 -400.991698) (xy 416.998241 -400.939402) (xy 416.990483 -400.885452) (xy 415.552973 -400.885452)
			(xy 415.552973 -400.885455) (xy 415.545215 -400.939411) (xy 415.529858 -400.991714) (xy 415.507213 -401.041298)
			(xy 415.477742 -401.087155) (xy 415.442044 -401.128351) (xy 415.400847 -401.164048) (xy 415.354989 -401.193517)
			(xy 415.305404 -401.216161) (xy 415.253101 -401.231517) (xy 415.199145 -401.239274) (xy 415.17189 -401.239736)
			(xy 414.30829 -401.239736) (xy 414.281041 -401.239193) (xy 414.227099 -401.231436) (xy 414.174809 -401.216081)
			(xy 414.125237 -401.193441) (xy 414.079391 -401.163977) (xy 414.038205 -401.128288) (xy 414.002517 -401.087101)
			(xy 413.973054 -401.041255) (xy 413.950415 -400.991682) (xy 413.935062 -400.939392) (xy 413.927306 -400.885449)
			(xy 412.489773 -400.885449) (xy 412.489773 -400.885457) (xy 412.482014 -400.939416) (xy 412.466654 -400.991722)
			(xy 412.444007 -401.041309) (xy 412.414532 -401.087168) (xy 412.37883 -401.128365) (xy 412.337628 -401.164062)
			(xy 412.291765 -401.193531) (xy 412.242175 -401.216172) (xy 412.189868 -401.231525) (xy 412.135907 -401.239276)
			(xy 412.10865 -401.239736) (xy 411.24505 -401.239736) (xy 411.217803 -401.23919) (xy 411.163865 -401.231429)
			(xy 411.11158 -401.21607) (xy 411.062013 -401.193428) (xy 411.016172 -401.163963) (xy 410.974991 -401.128274)
			(xy 410.939307 -401.087088) (xy 410.909848 -401.041243) (xy 410.887212 -400.991673) (xy 410.871861 -400.939386)
			(xy 410.864106 -400.885447) (xy 409.42645 -400.885447) (xy 409.42645 -400.885453) (xy 409.418693 -400.939404)
			(xy 409.403338 -400.991701) (xy 409.380696 -401.041282) (xy 409.351228 -401.087135) (xy 409.315535 -401.128328)
			(xy 409.274343 -401.164022) (xy 409.22849 -401.193491) (xy 409.178911 -401.216134) (xy 409.126613 -401.231491)
			(xy 409.072663 -401.239249) (xy 409.04541 -401.239736) (xy 408.18181 -401.239736) (xy 408.154559 -401.239217)
			(xy 408.100611 -401.231462) (xy 408.048315 -401.216108) (xy 407.998738 -401.193468) (xy 407.952887 -401.164002)
			(xy 407.911696 -401.128311) (xy 407.876004 -401.087121) (xy 407.846537 -401.041271) (xy 407.823895 -400.991694)
			(xy 407.80854 -400.939399) (xy 407.800783 -400.885451) (xy 406.363273 -400.885451) (xy 406.363273 -400.885456)
			(xy 406.355515 -400.939414) (xy 406.340156 -400.991718) (xy 406.31751 -401.041304) (xy 406.288037 -401.087162)
			(xy 406.252337 -401.128358) (xy 406.211138 -401.164055) (xy 406.165277 -401.193524) (xy 406.11569 -401.216166)
			(xy 406.063384 -401.231521) (xy 406.009426 -401.239275) (xy 405.98217 -401.239736) (xy 405.11857 -401.239736)
			(xy 405.091322 -401.239192) (xy 405.037382 -401.231432) (xy 404.985094 -401.216076) (xy 404.935525 -401.193435)
			(xy 404.889682 -401.16397) (xy 404.848498 -401.128281) (xy 404.812812 -401.087094) (xy 404.783351 -401.041249)
			(xy 404.760714 -400.991677) (xy 404.745361 -400.939389) (xy 404.737606 -400.885448) (xy 403.29995 -400.885448)
			(xy 403.29995 -400.885452) (xy 403.292194 -400.939401) (xy 403.276839 -400.991697) (xy 403.254199 -401.041276)
			(xy 403.224733 -401.087128) (xy 403.189042 -401.128321) (xy 403.147852 -401.164015) (xy 403.102002 -401.193484)
			(xy 403.052425 -401.216129) (xy 403.00013 -401.231488) (xy 402.946182 -401.239248) (xy 402.91893 -401.239736)
			(xy 402.05533 -401.239736) (xy 402.028078 -401.239219) (xy 401.974128 -401.231466) (xy 401.92183 -401.216114)
			(xy 401.87225 -401.193474) (xy 401.826396 -401.164009) (xy 401.785203 -401.128318) (xy 401.749509 -401.087128)
			(xy 401.72004 -401.041277) (xy 401.697397 -400.991698) (xy 401.682041 -400.939402) (xy 401.674283 -400.885452)
			(xy 400.236773 -400.885452) (xy 400.236773 -400.885455) (xy 400.229015 -400.939411) (xy 400.213658 -400.991714)
			(xy 400.191013 -401.041298) (xy 400.161542 -401.087155) (xy 400.125844 -401.128351) (xy 400.084647 -401.164048)
			(xy 400.038789 -401.193517) (xy 399.989204 -401.216161) (xy 399.936901 -401.231517) (xy 399.882945 -401.239274)
			(xy 399.85569 -401.239736) (xy 398.99209 -401.239736) (xy 398.964841 -401.239193) (xy 398.910899 -401.231436)
			(xy 398.858609 -401.216081) (xy 398.809037 -401.193441) (xy 398.763191 -401.163977) (xy 398.722005 -401.128288)
			(xy 398.686317 -401.087101) (xy 398.656854 -401.041255) (xy 398.634215 -400.991682) (xy 398.618862 -400.939392)
			(xy 398.611106 -400.885449) (xy 397.173573 -400.885449) (xy 397.173573 -400.885457) (xy 397.165814 -400.939416)
			(xy 397.150454 -400.991722) (xy 397.127807 -401.041309) (xy 397.098332 -401.087168) (xy 397.06263 -401.128365)
			(xy 397.021428 -401.164062) (xy 396.975565 -401.193531) (xy 396.925975 -401.216172) (xy 396.873668 -401.231525)
			(xy 396.819707 -401.239276) (xy 396.79245 -401.239736) (xy 395.92885 -401.239736) (xy 395.901603 -401.23919)
			(xy 395.847665 -401.231429) (xy 395.79538 -401.21607) (xy 395.745813 -401.193428) (xy 395.699972 -401.163963)
			(xy 395.658791 -401.128274) (xy 395.623107 -401.087088) (xy 395.593648 -401.041243) (xy 395.571012 -400.991673)
			(xy 395.555661 -400.939386) (xy 395.547906 -400.885447) (xy 394.11025 -400.885447) (xy 394.11025 -400.885453)
			(xy 394.102493 -400.939404) (xy 394.087138 -400.991701) (xy 394.064496 -401.041282) (xy 394.035028 -401.087135)
			(xy 393.999335 -401.128328) (xy 393.958143 -401.164022) (xy 393.91229 -401.193491) (xy 393.862711 -401.216134)
			(xy 393.810413 -401.231491) (xy 393.756463 -401.239249) (xy 393.72921 -401.239736) (xy 392.86561 -401.239736)
			(xy 392.838359 -401.239217) (xy 392.784411 -401.231462) (xy 392.732115 -401.216108) (xy 392.682538 -401.193468)
			(xy 392.636687 -401.164002) (xy 392.595496 -401.128311) (xy 392.559804 -401.087121) (xy 392.530337 -401.041271)
			(xy 392.507695 -400.991694) (xy 392.49234 -400.939399) (xy 392.484583 -400.885451) (xy 391.047073 -400.885451)
			(xy 391.047073 -400.885456) (xy 391.039315 -400.939414) (xy 391.023956 -400.991718) (xy 391.00131 -401.041304)
			(xy 390.971837 -401.087162) (xy 390.936137 -401.128358) (xy 390.894938 -401.164055) (xy 390.849077 -401.193524)
			(xy 390.79949 -401.216166) (xy 390.747184 -401.231521) (xy 390.693226 -401.239275) (xy 390.66597 -401.239736)
			(xy 389.80237 -401.239736) (xy 389.775122 -401.239192) (xy 389.721182 -401.231432) (xy 389.668894 -401.216076)
			(xy 389.619325 -401.193435) (xy 389.573482 -401.16397) (xy 389.532298 -401.128281) (xy 389.496612 -401.087094)
			(xy 389.467151 -401.041249) (xy 389.444514 -400.991677) (xy 389.429161 -400.939389) (xy 389.421406 -400.885448)
			(xy 387.98375 -400.885448) (xy 387.98375 -400.885452) (xy 387.975994 -400.939401) (xy 387.960639 -400.991697)
			(xy 387.937999 -401.041276) (xy 387.908533 -401.087128) (xy 387.872842 -401.128321) (xy 387.831652 -401.164015)
			(xy 387.785802 -401.193484) (xy 387.736225 -401.216129) (xy 387.68393 -401.231488) (xy 387.629982 -401.239248)
			(xy 387.60273 -401.239736) (xy 386.73913 -401.239736) (xy 386.711878 -401.239219) (xy 386.657928 -401.231466)
			(xy 386.60563 -401.216114) (xy 386.55605 -401.193474) (xy 386.510196 -401.164009) (xy 386.469003 -401.128318)
			(xy 386.433309 -401.087128) (xy 386.40384 -401.041277) (xy 386.381197 -400.991698) (xy 386.365841 -400.939402)
			(xy 386.358083 -400.885452) (xy 384.920573 -400.885452) (xy 384.920573 -400.885455) (xy 384.912815 -400.939411)
			(xy 384.897458 -400.991714) (xy 384.874813 -401.041298) (xy 384.845342 -401.087155) (xy 384.809644 -401.128351)
			(xy 384.768447 -401.164048) (xy 384.722589 -401.193517) (xy 384.673004 -401.216161) (xy 384.620701 -401.231517)
			(xy 384.566745 -401.239274) (xy 384.53949 -401.239736) (xy 383.67589 -401.239736) (xy 383.648641 -401.239193)
			(xy 383.594699 -401.231436) (xy 383.542409 -401.216081) (xy 383.492837 -401.193441) (xy 383.446991 -401.163977)
			(xy 383.405805 -401.128288) (xy 383.370117 -401.087101) (xy 383.340654 -401.041255) (xy 383.318015 -400.991682)
			(xy 383.302662 -400.939392) (xy 383.294906 -400.885449) (xy 381.857373 -400.885449) (xy 381.857373 -400.885457)
			(xy 381.849614 -400.939416) (xy 381.834254 -400.991722) (xy 381.811607 -401.041309) (xy 381.782132 -401.087168)
			(xy 381.74643 -401.128365) (xy 381.705228 -401.164062) (xy 381.659365 -401.193531) (xy 381.609775 -401.216172)
			(xy 381.557468 -401.231525) (xy 381.503507 -401.239276) (xy 381.47625 -401.239736) (xy 380.61265 -401.239736)
			(xy 380.585403 -401.23919) (xy 380.531465 -401.231429) (xy 380.47918 -401.21607) (xy 380.429613 -401.193428)
			(xy 380.383772 -401.163963) (xy 380.342591 -401.128274) (xy 380.306907 -401.087088) (xy 380.277448 -401.041243)
			(xy 380.254812 -400.991673) (xy 380.239461 -400.939386) (xy 380.231706 -400.885447) (xy 378.79405 -400.885447)
			(xy 378.79405 -400.885453) (xy 378.786293 -400.939404) (xy 378.770938 -400.991701) (xy 378.748296 -401.041282)
			(xy 378.718828 -401.087135) (xy 378.683135 -401.128328) (xy 378.641943 -401.164022) (xy 378.59609 -401.193491)
			(xy 378.546511 -401.216134) (xy 378.494213 -401.231491) (xy 378.440263 -401.239249) (xy 378.41301 -401.239736)
			(xy 377.54941 -401.239736) (xy 377.522159 -401.239217) (xy 377.468211 -401.231462) (xy 377.415915 -401.216108)
			(xy 377.366338 -401.193468) (xy 377.320487 -401.164002) (xy 377.279296 -401.128311) (xy 377.243604 -401.087121)
			(xy 377.214137 -401.041271) (xy 377.191495 -400.991694) (xy 377.17614 -400.939399) (xy 377.168383 -400.885451)
			(xy 375.730873 -400.885451) (xy 375.730873 -400.885456) (xy 375.723115 -400.939414) (xy 375.707756 -400.991718)
			(xy 375.68511 -401.041304) (xy 375.655637 -401.087162) (xy 375.619937 -401.128358) (xy 375.578738 -401.164055)
			(xy 375.532877 -401.193524) (xy 375.48329 -401.216166) (xy 375.430984 -401.231521) (xy 375.377026 -401.239275)
			(xy 375.34977 -401.239736) (xy 374.48617 -401.239736) (xy 374.458922 -401.239192) (xy 374.404982 -401.231432)
			(xy 374.352694 -401.216076) (xy 374.303125 -401.193435) (xy 374.257282 -401.16397) (xy 374.216098 -401.128281)
			(xy 374.180412 -401.087094) (xy 374.150951 -401.041249) (xy 374.128314 -400.991677) (xy 374.112961 -400.939389)
			(xy 374.105206 -400.885448) (xy 372.66755 -400.885448) (xy 372.66755 -400.885452) (xy 372.659794 -400.939401)
			(xy 372.644439 -400.991697) (xy 372.621799 -401.041276) (xy 372.592333 -401.087128) (xy 372.556642 -401.128321)
			(xy 372.515452 -401.164015) (xy 372.469602 -401.193484) (xy 372.420025 -401.216129) (xy 372.36773 -401.231488)
			(xy 372.313782 -401.239248) (xy 372.28653 -401.239736) (xy 371.42293 -401.239736) (xy 371.395678 -401.239219)
			(xy 371.341728 -401.231466) (xy 371.28943 -401.216114) (xy 371.23985 -401.193474) (xy 371.193996 -401.164009)
			(xy 371.152803 -401.128318) (xy 371.117109 -401.087128) (xy 371.08764 -401.041277) (xy 371.064997 -400.991698)
			(xy 371.049641 -400.939402) (xy 371.041883 -400.885452) (xy 351.173373 -400.885452) (xy 351.173373 -400.885455)
			(xy 351.165615 -400.939411) (xy 351.150257 -400.991714) (xy 351.127612 -401.041299) (xy 351.098141 -401.087156)
			(xy 351.062443 -401.128352) (xy 351.021246 -401.164048) (xy 350.975388 -401.193518) (xy 350.925803 -401.216162)
			(xy 350.8735 -401.231518) (xy 350.819543 -401.239274) (xy 350.792288 -401.239736) (xy 349.928688 -401.239736)
			(xy 349.901439 -401.239193) (xy 349.847497 -401.231436) (xy 349.795208 -401.216081) (xy 349.745636 -401.19344)
			(xy 349.69979 -401.163976) (xy 349.658604 -401.128287) (xy 349.622917 -401.0871) (xy 349.593454 -401.041254)
			(xy 349.570815 -400.991681) (xy 349.555462 -400.939391) (xy 349.547706 -400.885449) (xy 348.11005 -400.885449)
			(xy 348.11005 -400.885451) (xy 348.102294 -400.939399) (xy 348.086941 -400.991693) (xy 348.064301 -401.041271)
			(xy 348.034837 -401.087122) (xy 347.999148 -401.128314) (xy 347.957961 -401.164009) (xy 347.912113 -401.193478)
			(xy 347.862538 -401.216124) (xy 347.810245 -401.231484) (xy 347.756299 -401.239247) (xy 347.729048 -401.239736)
			(xy 346.865448 -401.239736) (xy 346.838195 -401.23922) (xy 346.784243 -401.231469) (xy 346.731943 -401.216118)
			(xy 346.68236 -401.19348) (xy 346.636505 -401.164016) (xy 346.595309 -401.128325) (xy 346.559613 -401.087134)
			(xy 346.530143 -401.041282) (xy 346.507498 -400.991702) (xy 346.492141 -400.939404) (xy 346.484383 -400.885453)
			(xy 345.04685 -400.885453) (xy 345.039093 -400.939404) (xy 345.023737 -400.991702) (xy 345.001095 -401.041282)
			(xy 344.971628 -401.087136) (xy 344.935934 -401.128329) (xy 344.894742 -401.164023) (xy 344.848889 -401.193491)
			(xy 344.799309 -401.216135) (xy 344.747012 -401.231492) (xy 344.693061 -401.23925) (xy 344.665808 -401.239736)
			(xy 343.802208 -401.239736) (xy 343.774957 -401.239217) (xy 343.721009 -401.231462) (xy 343.668714 -401.216108)
			(xy 343.619136 -401.193467) (xy 343.573286 -401.164002) (xy 343.532095 -401.128311) (xy 343.496403 -401.087121)
			(xy 343.466937 -401.041271) (xy 343.444295 -400.991694) (xy 343.42894 -400.939399) (xy 343.421183 -400.885451)
			(xy 341.983673 -400.885451) (xy 341.983673 -400.885456) (xy 341.975915 -400.939414) (xy 341.960556 -400.991718)
			(xy 341.937909 -401.041304) (xy 341.908436 -401.087162) (xy 341.872736 -401.128359) (xy 341.831537 -401.164055)
			(xy 341.785676 -401.193525) (xy 341.736088 -401.216167) (xy 341.683783 -401.231521) (xy 341.629824 -401.239275)
			(xy 341.602568 -401.239736) (xy 340.738968 -401.239736) (xy 340.71172 -401.239192) (xy 340.65778 -401.231432)
			(xy 340.605493 -401.216075) (xy 340.555924 -401.193434) (xy 340.510081 -401.163969) (xy 340.468897 -401.12828)
			(xy 340.433212 -401.087094) (xy 340.403751 -401.041248) (xy 340.381114 -400.991677) (xy 340.365761 -400.939389)
			(xy 340.358006 -400.885448) (xy 338.92035 -400.885448) (xy 338.92035 -400.885452) (xy 338.912594 -400.939401)
			(xy 338.897239 -400.991698) (xy 338.874598 -401.041277) (xy 338.845132 -401.087129) (xy 338.809441 -401.128321)
			(xy 338.768251 -401.164016) (xy 338.722401 -401.193485) (xy 338.672824 -401.216129) (xy 338.620529 -401.231488)
			(xy 338.56658 -401.239248) (xy 338.539328 -401.239736) (xy 337.675728 -401.239736) (xy 337.648476 -401.239219)
			(xy 337.594526 -401.231465) (xy 337.542228 -401.216113) (xy 337.492648 -401.193474) (xy 337.446795 -401.164009)
			(xy 337.405602 -401.128318) (xy 337.369908 -401.087127) (xy 337.34044 -401.041276) (xy 337.317797 -400.991698)
			(xy 337.30244 -400.939402) (xy 337.294683 -400.885452) (xy 335.857173 -400.885452) (xy 335.857173 -400.885455)
			(xy 335.849415 -400.939411) (xy 335.834057 -400.991714) (xy 335.811412 -401.041299) (xy 335.781941 -401.087156)
			(xy 335.746243 -401.128352) (xy 335.705046 -401.164048) (xy 335.659188 -401.193518) (xy 335.609603 -401.216162)
			(xy 335.5573 -401.231518) (xy 335.503343 -401.239274) (xy 335.476088 -401.239736) (xy 334.612488 -401.239736)
			(xy 334.585239 -401.239193) (xy 334.531297 -401.231436) (xy 334.479008 -401.216081) (xy 334.429436 -401.19344)
			(xy 334.38359 -401.163976) (xy 334.342404 -401.128287) (xy 334.306717 -401.0871) (xy 334.277254 -401.041254)
			(xy 334.254615 -400.991681) (xy 334.239262 -400.939391) (xy 334.231506 -400.885449) (xy 332.79385 -400.885449)
			(xy 332.79385 -400.885451) (xy 332.786094 -400.939399) (xy 332.770741 -400.991693) (xy 332.748101 -401.041271)
			(xy 332.718637 -401.087122) (xy 332.682948 -401.128314) (xy 332.641761 -401.164009) (xy 332.595913 -401.193478)
			(xy 332.546338 -401.216124) (xy 332.494045 -401.231484) (xy 332.440099 -401.239247) (xy 332.412848 -401.239736)
			(xy 331.549248 -401.239736) (xy 331.521995 -401.23922) (xy 331.468043 -401.231469) (xy 331.415743 -401.216118)
			(xy 331.36616 -401.19348) (xy 331.320305 -401.164016) (xy 331.279109 -401.128325) (xy 331.243413 -401.087134)
			(xy 331.213943 -401.041282) (xy 331.191298 -400.991702) (xy 331.175941 -400.939404) (xy 331.168183 -400.885453)
			(xy 329.73065 -400.885453) (xy 329.722893 -400.939404) (xy 329.707537 -400.991702) (xy 329.684895 -401.041282)
			(xy 329.655428 -401.087136) (xy 329.619734 -401.128329) (xy 329.578542 -401.164023) (xy 329.532689 -401.193491)
			(xy 329.483109 -401.216135) (xy 329.430812 -401.231492) (xy 329.376861 -401.23925) (xy 329.349608 -401.239736)
			(xy 328.486008 -401.239736) (xy 328.458757 -401.239217) (xy 328.404809 -401.231462) (xy 328.352514 -401.216108)
			(xy 328.302936 -401.193467) (xy 328.257086 -401.164002) (xy 328.215895 -401.128311) (xy 328.180203 -401.087121)
			(xy 328.150737 -401.041271) (xy 328.128095 -400.991694) (xy 328.11274 -400.939399) (xy 328.104983 -400.885451)
			(xy 326.667473 -400.885451) (xy 326.667473 -400.885456) (xy 326.659715 -400.939414) (xy 326.644356 -400.991718)
			(xy 326.621709 -401.041304) (xy 326.592236 -401.087162) (xy 326.556536 -401.128359) (xy 326.515337 -401.164055)
			(xy 326.469476 -401.193525) (xy 326.419888 -401.216167) (xy 326.367583 -401.231521) (xy 326.313624 -401.239275)
			(xy 326.286368 -401.239736) (xy 325.422768 -401.239736) (xy 325.39552 -401.239192) (xy 325.34158 -401.231432)
			(xy 325.289293 -401.216075) (xy 325.239724 -401.193434) (xy 325.193881 -401.163969) (xy 325.152697 -401.12828)
			(xy 325.117012 -401.087094) (xy 325.087551 -401.041248) (xy 325.064914 -400.991677) (xy 325.049561 -400.939389)
			(xy 325.041806 -400.885448) (xy 323.60415 -400.885448) (xy 323.60415 -400.885452) (xy 323.596394 -400.939401)
			(xy 323.581039 -400.991698) (xy 323.558398 -401.041277) (xy 323.528932 -401.087129) (xy 323.493241 -401.128321)
			(xy 323.452051 -401.164016) (xy 323.406201 -401.193485) (xy 323.356624 -401.216129) (xy 323.304329 -401.231488)
			(xy 323.25038 -401.239248) (xy 323.223128 -401.239736) (xy 322.359528 -401.239736) (xy 322.332276 -401.239219)
			(xy 322.278326 -401.231465) (xy 322.226028 -401.216113) (xy 322.176448 -401.193474) (xy 322.130595 -401.164009)
			(xy 322.089402 -401.128318) (xy 322.053708 -401.087127) (xy 322.02424 -401.041276) (xy 322.001597 -400.991698)
			(xy 321.98624 -400.939402) (xy 321.978483 -400.885452) (xy 320.540973 -400.885452) (xy 320.540973 -400.885455)
			(xy 320.533215 -400.939411) (xy 320.517857 -400.991714) (xy 320.495212 -401.041299) (xy 320.465741 -401.087156)
			(xy 320.430043 -401.128352) (xy 320.388846 -401.164048) (xy 320.342988 -401.193518) (xy 320.293403 -401.216162)
			(xy 320.2411 -401.231518) (xy 320.187143 -401.239274) (xy 320.159888 -401.239736) (xy 319.296288 -401.239736)
			(xy 319.269039 -401.239193) (xy 319.215097 -401.231436) (xy 319.162808 -401.216081) (xy 319.113236 -401.19344)
			(xy 319.06739 -401.163976) (xy 319.026204 -401.128287) (xy 318.990517 -401.0871) (xy 318.961054 -401.041254)
			(xy 318.938415 -400.991681) (xy 318.923062 -400.939391) (xy 318.915306 -400.885449) (xy 317.47765 -400.885449)
			(xy 317.47765 -400.885451) (xy 317.469894 -400.939399) (xy 317.454541 -400.991693) (xy 317.431901 -401.041271)
			(xy 317.402437 -401.087122) (xy 317.366748 -401.128314) (xy 317.325561 -401.164009) (xy 317.279713 -401.193478)
			(xy 317.230138 -401.216124) (xy 317.177845 -401.231484) (xy 317.123899 -401.239247) (xy 317.096648 -401.239736)
			(xy 316.233048 -401.239736) (xy 316.205795 -401.23922) (xy 316.151843 -401.231469) (xy 316.099543 -401.216118)
			(xy 316.04996 -401.19348) (xy 316.004105 -401.164016) (xy 315.962909 -401.128325) (xy 315.927213 -401.087134)
			(xy 315.897743 -401.041282) (xy 315.875098 -400.991702) (xy 315.859741 -400.939404) (xy 315.851983 -400.885453)
			(xy 314.41445 -400.885453) (xy 314.406693 -400.939404) (xy 314.391337 -400.991702) (xy 314.368695 -401.041282)
			(xy 314.339228 -401.087136) (xy 314.303534 -401.128329) (xy 314.262342 -401.164023) (xy 314.216489 -401.193491)
			(xy 314.166909 -401.216135) (xy 314.114612 -401.231492) (xy 314.060661 -401.23925) (xy 314.033408 -401.239736)
			(xy 313.169808 -401.239736) (xy 313.142557 -401.239217) (xy 313.088609 -401.231462) (xy 313.036314 -401.216108)
			(xy 312.986736 -401.193467) (xy 312.940886 -401.164002) (xy 312.899695 -401.128311) (xy 312.864003 -401.087121)
			(xy 312.834537 -401.041271) (xy 312.811895 -400.991694) (xy 312.79654 -400.939399) (xy 312.788783 -400.885451)
			(xy 311.351273 -400.885451) (xy 311.351273 -400.885456) (xy 311.343515 -400.939414) (xy 311.328156 -400.991718)
			(xy 311.305509 -401.041304) (xy 311.276036 -401.087162) (xy 311.240336 -401.128359) (xy 311.199137 -401.164055)
			(xy 311.153276 -401.193525) (xy 311.103688 -401.216167) (xy 311.051383 -401.231521) (xy 310.997424 -401.239275)
			(xy 310.970168 -401.239736) (xy 310.106568 -401.239736) (xy 310.07932 -401.239192) (xy 310.02538 -401.231432)
			(xy 309.973093 -401.216075) (xy 309.923524 -401.193434) (xy 309.877681 -401.163969) (xy 309.836497 -401.12828)
			(xy 309.800812 -401.087094) (xy 309.771351 -401.041248) (xy 309.748714 -400.991677) (xy 309.733361 -400.939389)
			(xy 309.725606 -400.885448) (xy 308.28795 -400.885448) (xy 308.28795 -400.885452) (xy 308.280194 -400.939401)
			(xy 308.264839 -400.991698) (xy 308.242198 -401.041277) (xy 308.212732 -401.087129) (xy 308.177041 -401.128321)
			(xy 308.135851 -401.164016) (xy 308.090001 -401.193485) (xy 308.040424 -401.216129) (xy 307.988129 -401.231488)
			(xy 307.93418 -401.239248) (xy 307.906928 -401.239736) (xy 307.043328 -401.239736) (xy 307.016076 -401.239219)
			(xy 306.962126 -401.231465) (xy 306.909828 -401.216113) (xy 306.860248 -401.193474) (xy 306.814395 -401.164009)
			(xy 306.773202 -401.128318) (xy 306.737508 -401.087127) (xy 306.70804 -401.041276) (xy 306.685397 -400.991698)
			(xy 306.67004 -400.939402) (xy 306.662283 -400.885452) (xy 305.224773 -400.885452) (xy 305.224773 -400.885455)
			(xy 305.217015 -400.939411) (xy 305.201657 -400.991714) (xy 305.179012 -401.041299) (xy 305.149541 -401.087156)
			(xy 305.113843 -401.128352) (xy 305.072646 -401.164048) (xy 305.026788 -401.193518) (xy 304.977203 -401.216162)
			(xy 304.9249 -401.231518) (xy 304.870943 -401.239274) (xy 304.843688 -401.239736) (xy 303.980088 -401.239736)
			(xy 303.952839 -401.239193) (xy 303.898897 -401.231436) (xy 303.846608 -401.216081) (xy 303.797036 -401.19344)
			(xy 303.75119 -401.163976) (xy 303.710004 -401.128287) (xy 303.674317 -401.0871) (xy 303.644854 -401.041254)
			(xy 303.622215 -400.991681) (xy 303.606862 -400.939391) (xy 303.599106 -400.885449) (xy 280.76398 -400.885449)
			(xy 280.76398 -402.0155) (xy 287.066441 -402.0155) (xy 287.070455 -401.951698) (xy 287.082434 -401.888902)
			(xy 287.102189 -401.828103) (xy 287.129408 -401.77026) (xy 287.163662 -401.716283) (xy 287.204411 -401.667026)
			(xy 287.251013 -401.623264) (xy 287.302731 -401.585688) (xy 287.358752 -401.55489) (xy 287.418191 -401.531357)
			(xy 287.48011 -401.515458) (xy 287.543534 -401.507446) (xy 287.575498 -401.506944) (xy 287.575752 -401.506944)
			(xy 287.607498 -401.507464) (xy 287.670494 -401.515393) (xy 287.732014 -401.531096) (xy 287.791102 -401.55433)
			(xy 287.846842 -401.584733) (xy 287.898367 -401.621834) (xy 287.921954 -401.643088) (xy 287.929217 -401.649272)
			(xy 287.946967 -401.656223) (xy 287.966029 -401.656223) (xy 287.983779 -401.649272) (xy 287.991042 -401.643088)
			(xy 288.014631 -401.621832) (xy 288.06614 -401.5847) (xy 288.121874 -401.554276) (xy 288.180965 -401.531035)
			(xy 288.242492 -401.515338) (xy 288.305495 -401.507431) (xy 288.337244 -401.506944) (xy 288.337498 -401.506944)
			(xy 288.369457 -401.507521) (xy 288.432872 -401.515532) (xy 288.494783 -401.531427) (xy 288.554213 -401.554957)
			(xy 288.610226 -401.58575) (xy 288.661937 -401.623321) (xy 288.708532 -401.667076) (xy 288.749276 -401.716326)
			(xy 288.783525 -401.770295) (xy 288.810741 -401.82813) (xy 288.830493 -401.888921) (xy 288.84247 -401.951707)
			(xy 288.846484 -402.0155) (xy 289.606441 -402.0155) (xy 289.610455 -401.951698) (xy 289.622434 -401.888902)
			(xy 289.642189 -401.828103) (xy 289.669408 -401.77026) (xy 289.703662 -401.716283) (xy 289.744411 -401.667026)
			(xy 289.791013 -401.623264) (xy 289.842731 -401.585688) (xy 289.898752 -401.55489) (xy 289.958191 -401.531357)
			(xy 290.02011 -401.515458) (xy 290.083534 -401.507446) (xy 290.115498 -401.506944) (xy 290.115752 -401.506944)
			(xy 290.147498 -401.507464) (xy 290.210494 -401.515393) (xy 290.272014 -401.531096) (xy 290.331102 -401.55433)
			(xy 290.386842 -401.584733) (xy 290.438367 -401.621834) (xy 290.461954 -401.643088) (xy 290.469217 -401.649272)
			(xy 290.486967 -401.656223) (xy 290.506029 -401.656223) (xy 290.523779 -401.649272) (xy 290.531042 -401.643088)
			(xy 290.554631 -401.621832) (xy 290.60614 -401.5847) (xy 290.661874 -401.554276) (xy 290.720965 -401.531035)
			(xy 290.782492 -401.515338) (xy 290.845495 -401.507431) (xy 290.877244 -401.506944) (xy 290.877498 -401.506944)
			(xy 290.909457 -401.507521) (xy 290.972872 -401.515532) (xy 291.034783 -401.531427) (xy 291.094213 -401.554957)
			(xy 291.150226 -401.58575) (xy 291.201937 -401.623321) (xy 291.248532 -401.667076) (xy 291.289276 -401.716326)
			(xy 291.323525 -401.770295) (xy 291.350741 -401.82813) (xy 291.370493 -401.888921) (xy 291.38247 -401.951707)
			(xy 291.386484 -402.0155) (xy 292.146441 -402.0155) (xy 292.150455 -401.951698) (xy 292.162434 -401.888902)
			(xy 292.182189 -401.828103) (xy 292.209408 -401.77026) (xy 292.243662 -401.716283) (xy 292.284411 -401.667026)
			(xy 292.331013 -401.623264) (xy 292.382731 -401.585688) (xy 292.438752 -401.55489) (xy 292.498191 -401.531357)
			(xy 292.56011 -401.515458) (xy 292.623534 -401.507446) (xy 292.655498 -401.506944) (xy 292.655752 -401.506944)
			(xy 292.687498 -401.507464) (xy 292.750494 -401.515393) (xy 292.812014 -401.531096) (xy 292.871102 -401.55433)
			(xy 292.926842 -401.584733) (xy 292.978367 -401.621834) (xy 293.001954 -401.643088) (xy 293.009217 -401.649272)
			(xy 293.026967 -401.656223) (xy 293.046029 -401.656223) (xy 293.063779 -401.649272) (xy 293.071042 -401.643088)
			(xy 293.094631 -401.621832) (xy 293.14614 -401.5847) (xy 293.201874 -401.554276) (xy 293.260965 -401.531035)
			(xy 293.322492 -401.515338) (xy 293.385495 -401.507431) (xy 293.417244 -401.506944) (xy 293.417498 -401.506944)
			(xy 293.449457 -401.507521) (xy 293.512872 -401.515532) (xy 293.574783 -401.531427) (xy 293.634213 -401.554957)
			(xy 293.690226 -401.58575) (xy 293.741937 -401.623321) (xy 293.788532 -401.667076) (xy 293.829276 -401.716326)
			(xy 293.863525 -401.770295) (xy 293.890741 -401.82813) (xy 293.910493 -401.888921) (xy 293.92247 -401.951707)
			(xy 293.926484 -402.0155) (xy 294.53602 -402.0155) (xy 294.540035 -401.951693) (xy 294.552015 -401.888892)
			(xy 294.571773 -401.828089) (xy 294.598995 -401.770241) (xy 294.633253 -401.716261) (xy 294.674007 -401.667001)
			(xy 294.720613 -401.623237) (xy 294.772338 -401.58566) (xy 294.828364 -401.554862) (xy 294.887809 -401.531329)
			(xy 294.949734 -401.515433) (xy 295.013163 -401.507423) (xy 295.04513 -401.506944) (xy 295.045384 -401.506944)
			(xy 295.077131 -401.507444) (xy 295.140127 -401.515377) (xy 295.201647 -401.531084) (xy 295.260736 -401.554322)
			(xy 295.316476 -401.584728) (xy 295.368 -401.621832) (xy 295.391586 -401.643088) (xy 295.398849 -401.649272)
			(xy 295.416599 -401.656223) (xy 295.435661 -401.656223) (xy 295.453411 -401.649272) (xy 295.460674 -401.643088)
			(xy 295.48425 -401.621817) (xy 295.535761 -401.584686) (xy 295.591498 -401.554265) (xy 295.650592 -401.531026)
			(xy 295.712121 -401.515332) (xy 295.775126 -401.507429) (xy 295.806876 -401.506944) (xy 295.80713 -401.506944)
			(xy 295.839087 -401.507544) (xy 295.902496 -401.515558) (xy 295.964401 -401.531455) (xy 296.023825 -401.554986)
			(xy 296.079832 -401.585779) (xy 296.131538 -401.623348) (xy 296.178128 -401.667102) (xy 296.218866 -401.716349)
			(xy 296.253112 -401.770314) (xy 296.280324 -401.828145) (xy 296.300074 -401.888931) (xy 296.312049 -401.951712)
			(xy 296.316063 -402.0155) (xy 297.07602 -402.0155) (xy 297.080035 -401.951693) (xy 297.092015 -401.888892)
			(xy 297.111773 -401.828089) (xy 297.138995 -401.770241) (xy 297.173253 -401.716261) (xy 297.214007 -401.667001)
			(xy 297.260613 -401.623237) (xy 297.312338 -401.58566) (xy 297.368364 -401.554862) (xy 297.427809 -401.531329)
			(xy 297.489734 -401.515433) (xy 297.553163 -401.507423) (xy 297.58513 -401.506944) (xy 297.585384 -401.506944)
			(xy 297.617131 -401.507444) (xy 297.680127 -401.515377) (xy 297.741647 -401.531084) (xy 297.800736 -401.554322)
			(xy 297.856476 -401.584728) (xy 297.908 -401.621832) (xy 297.931586 -401.643088) (xy 297.938849 -401.649272)
			(xy 297.956599 -401.656223) (xy 297.975661 -401.656223) (xy 297.993411 -401.649272) (xy 298.000674 -401.643088)
			(xy 298.02425 -401.621817) (xy 298.075761 -401.584686) (xy 298.131498 -401.554265) (xy 298.190592 -401.531026)
			(xy 298.252121 -401.515332) (xy 298.315126 -401.507429) (xy 298.346876 -401.506944) (xy 298.34713 -401.506944)
			(xy 298.379087 -401.507544) (xy 298.442496 -401.515558) (xy 298.504401 -401.531455) (xy 298.563825 -401.554986)
			(xy 298.619832 -401.585779) (xy 298.671538 -401.623348) (xy 298.718128 -401.667102) (xy 298.758866 -401.716349)
			(xy 298.793112 -401.770314) (xy 298.820324 -401.828145) (xy 298.840074 -401.888931) (xy 298.852049 -401.951712)
			(xy 298.856063 -402.0155) (xy 298.852049 -402.079288) (xy 298.840074 -402.142069) (xy 298.820324 -402.202855)
			(xy 298.793112 -402.260686) (xy 298.758866 -402.314651) (xy 298.718128 -402.363898) (xy 298.671538 -402.407652)
			(xy 298.619832 -402.445221) (xy 298.563825 -402.476014) (xy 298.504401 -402.499545) (xy 298.442496 -402.515442)
			(xy 298.379087 -402.523456) (xy 298.34713 -402.52396) (xy 298.346876 -402.52396) (xy 298.315131 -402.523422)
			(xy 298.252136 -402.515497) (xy 298.190616 -402.499797) (xy 298.131527 -402.476566) (xy 298.075787 -402.446166)
			(xy 298.024261 -402.409069) (xy 298.000674 -402.387816) (xy 297.993411 -402.381632) (xy 297.975661 -402.374681)
			(xy 297.956599 -402.374681) (xy 297.938849 -402.381632) (xy 297.931586 -402.387816) (xy 297.908028 -402.409107)
			(xy 297.856512 -402.446235) (xy 297.800771 -402.476654) (xy 297.741674 -402.499889) (xy 297.680142 -402.515579)
			(xy 297.617135 -402.523478) (xy 297.585384 -402.52396) (xy 297.58513 -402.52396) (xy 297.553163 -402.523577)
			(xy 297.489734 -402.515567) (xy 297.427809 -402.499671) (xy 297.368364 -402.476138) (xy 297.312338 -402.44534)
			(xy 297.260613 -402.407763) (xy 297.214007 -402.363999) (xy 297.173253 -402.314739) (xy 297.138995 -402.260759)
			(xy 297.111773 -402.202911) (xy 297.092015 -402.142108) (xy 297.080035 -402.079307) (xy 297.07602 -402.0155)
			(xy 296.316063 -402.0155) (xy 296.312049 -402.079288) (xy 296.300074 -402.142069) (xy 296.280324 -402.202855)
			(xy 296.253112 -402.260686) (xy 296.218866 -402.314651) (xy 296.178128 -402.363898) (xy 296.131538 -402.407652)
			(xy 296.079832 -402.445221) (xy 296.023825 -402.476014) (xy 295.964401 -402.499545) (xy 295.902496 -402.515442)
			(xy 295.839087 -402.523456) (xy 295.80713 -402.52396) (xy 295.806876 -402.52396) (xy 295.775131 -402.523422)
			(xy 295.712136 -402.515497) (xy 295.650616 -402.499797) (xy 295.591527 -402.476566) (xy 295.535787 -402.446166)
			(xy 295.484261 -402.409069) (xy 295.460674 -402.387816) (xy 295.453411 -402.381632) (xy 295.435661 -402.374681)
			(xy 295.416599 -402.374681) (xy 295.398849 -402.381632) (xy 295.391586 -402.387816) (xy 295.368028 -402.409107)
			(xy 295.316512 -402.446235) (xy 295.260771 -402.476654) (xy 295.201674 -402.499889) (xy 295.140142 -402.515579)
			(xy 295.077135 -402.523478) (xy 295.045384 -402.52396) (xy 295.04513 -402.52396) (xy 295.013163 -402.523577)
			(xy 294.949734 -402.515567) (xy 294.887809 -402.499671) (xy 294.828364 -402.476138) (xy 294.772338 -402.44534)
			(xy 294.720613 -402.407763) (xy 294.674007 -402.363999) (xy 294.633253 -402.314739) (xy 294.598995 -402.260759)
			(xy 294.571773 -402.202911) (xy 294.552015 -402.142108) (xy 294.540035 -402.079307) (xy 294.53602 -402.0155)
			(xy 293.926484 -402.0155) (xy 293.92247 -402.079293) (xy 293.910493 -402.142079) (xy 293.890741 -402.20287)
			(xy 293.863525 -402.260705) (xy 293.829276 -402.314674) (xy 293.788532 -402.363924) (xy 293.741937 -402.407679)
			(xy 293.690226 -402.44525) (xy 293.634213 -402.476043) (xy 293.574783 -402.499573) (xy 293.512872 -402.515468)
			(xy 293.449457 -402.523479) (xy 293.417498 -402.52396) (xy 293.417244 -402.52396) (xy 293.385498 -402.523442)
			(xy 293.322502 -402.515512) (xy 293.260982 -402.499809) (xy 293.201894 -402.476575) (xy 293.146154 -402.446171)
			(xy 293.094629 -402.40907) (xy 293.071042 -402.387816) (xy 293.063779 -402.381632) (xy 293.046029 -402.374681)
			(xy 293.026967 -402.374681) (xy 293.009217 -402.381632) (xy 293.001954 -402.387816) (xy 292.978367 -402.409074)
			(xy 292.926858 -402.446206) (xy 292.871123 -402.47663) (xy 292.812032 -402.499871) (xy 292.750504 -402.515567)
			(xy 292.687501 -402.523474) (xy 292.655752 -402.52396) (xy 292.655498 -402.52396) (xy 292.623534 -402.523554)
			(xy 292.56011 -402.515542) (xy 292.498191 -402.499643) (xy 292.438752 -402.47611) (xy 292.382731 -402.445312)
			(xy 292.331013 -402.407736) (xy 292.284411 -402.363974) (xy 292.243662 -402.314717) (xy 292.209408 -402.26074)
			(xy 292.182189 -402.202897) (xy 292.162434 -402.142098) (xy 292.150455 -402.079302) (xy 292.146441 -402.0155)
			(xy 291.386484 -402.0155) (xy 291.38247 -402.079293) (xy 291.370493 -402.142079) (xy 291.350741 -402.20287)
			(xy 291.323525 -402.260705) (xy 291.289276 -402.314674) (xy 291.248532 -402.363924) (xy 291.201937 -402.407679)
			(xy 291.150226 -402.44525) (xy 291.094213 -402.476043) (xy 291.034783 -402.499573) (xy 290.972872 -402.515468)
			(xy 290.909457 -402.523479) (xy 290.877498 -402.52396) (xy 290.877244 -402.52396) (xy 290.845498 -402.523442)
			(xy 290.782502 -402.515512) (xy 290.720982 -402.499809) (xy 290.661894 -402.476575) (xy 290.606154 -402.446171)
			(xy 290.554629 -402.40907) (xy 290.531042 -402.387816) (xy 290.523779 -402.381632) (xy 290.506029 -402.374681)
			(xy 290.486967 -402.374681) (xy 290.469217 -402.381632) (xy 290.461954 -402.387816) (xy 290.438367 -402.409074)
			(xy 290.386858 -402.446206) (xy 290.331123 -402.47663) (xy 290.272032 -402.499871) (xy 290.210504 -402.515567)
			(xy 290.147501 -402.523474) (xy 290.115752 -402.52396) (xy 290.115498 -402.52396) (xy 290.083534 -402.523554)
			(xy 290.02011 -402.515542) (xy 289.958191 -402.499643) (xy 289.898752 -402.47611) (xy 289.842731 -402.445312)
			(xy 289.791013 -402.407736) (xy 289.744411 -402.363974) (xy 289.703662 -402.314717) (xy 289.669408 -402.26074)
			(xy 289.642189 -402.202897) (xy 289.622434 -402.142098) (xy 289.610455 -402.079302) (xy 289.606441 -402.0155)
			(xy 288.846484 -402.0155) (xy 288.84247 -402.079293) (xy 288.830493 -402.142079) (xy 288.810741 -402.20287)
			(xy 288.783525 -402.260705) (xy 288.749276 -402.314674) (xy 288.708532 -402.363924) (xy 288.661937 -402.407679)
			(xy 288.610226 -402.44525) (xy 288.554213 -402.476043) (xy 288.494783 -402.499573) (xy 288.432872 -402.515468)
			(xy 288.369457 -402.523479) (xy 288.337498 -402.52396) (xy 288.337244 -402.52396) (xy 288.305498 -402.523442)
			(xy 288.242502 -402.515512) (xy 288.180982 -402.499809) (xy 288.121894 -402.476575) (xy 288.066154 -402.446171)
			(xy 288.014629 -402.40907) (xy 287.991042 -402.387816) (xy 287.983779 -402.381632) (xy 287.966029 -402.374681)
			(xy 287.946967 -402.374681) (xy 287.929217 -402.381632) (xy 287.921954 -402.387816) (xy 287.898367 -402.409074)
			(xy 287.846858 -402.446206) (xy 287.791123 -402.47663) (xy 287.732032 -402.499871) (xy 287.670504 -402.515567)
			(xy 287.607501 -402.523474) (xy 287.575752 -402.52396) (xy 287.575498 -402.52396) (xy 287.543534 -402.523554)
			(xy 287.48011 -402.515542) (xy 287.418191 -402.499643) (xy 287.358752 -402.47611) (xy 287.302731 -402.445312)
			(xy 287.251013 -402.407736) (xy 287.204411 -402.363974) (xy 287.163662 -402.314717) (xy 287.129408 -402.26074)
			(xy 287.102189 -402.202897) (xy 287.082434 -402.142098) (xy 287.070455 -402.079302) (xy 287.066441 -402.0155)
			(xy 280.76398 -402.0155) (xy 280.76398 -402.1074) (xy 280.76343 -402.132362) (xy 280.753694 -402.181326)
			(xy 280.734578 -402.227444) (xy 280.706818 -402.268937) (xy 280.689558 -402.286978) (xy 280.501598 -402.474938)
			(xy 280.483557 -402.492195) (xy 280.442055 -402.519934) (xy 280.395938 -402.539043) (xy 280.346979 -402.548787)
			(xy 280.32202 -402.54936) (xy 239.86236 -402.54936) (xy 239.8374 -402.548779) (xy 239.788437 -402.539054)
			(xy 239.742319 -402.519947) (xy 239.700824 -402.492195) (xy 239.682782 -402.474938) (xy 239.497362 -402.289518)
			(xy 239.480115 -402.271468) (xy 239.452373 -402.229969) (xy 239.433262 -402.183855) (xy 239.423515 -402.134899)
			(xy 239.42294 -402.10994) (xy 2.509012 -402.10994) (xy 2.509012 -402.656674) (xy 98.152872 -402.656674)
			(xy 98.152872 -402.602126) (xy 98.160635 -402.548133) (xy 98.176003 -402.495795) (xy 98.198664 -402.446176)
			(xy 98.228156 -402.400288) (xy 98.263878 -402.359064) (xy 98.305104 -402.323344) (xy 98.350994 -402.293855)
			(xy 98.400613 -402.271196) (xy 98.452953 -402.255831) (xy 98.506946 -402.24807) (xy 98.53422 -402.247608)
			(xy 99.39782 -402.247608) (xy 99.425086 -402.248156) (xy 99.479063 -402.255919) (xy 99.531387 -402.271285)
			(xy 99.58099 -402.293941) (xy 99.626865 -402.323425) (xy 99.668077 -402.359137) (xy 99.703787 -402.400351)
			(xy 99.733269 -402.446227) (xy 99.755922 -402.495832) (xy 99.771285 -402.548156) (xy 99.779046 -402.602134)
			(xy 99.779046 -402.656666) (xy 99.771285 -402.710644) (xy 99.755922 -402.762968) (xy 99.733269 -402.812573)
			(xy 99.703787 -402.858449) (xy 99.668077 -402.899663) (xy 99.626865 -402.935375) (xy 99.58099 -402.964859)
			(xy 99.531387 -402.987515) (xy 99.479063 -403.002881) (xy 99.425086 -403.010644) (xy 99.39782 -403.011132)
			(xy 98.53422 -403.011132) (xy 98.506946 -403.01073) (xy 98.452953 -403.002969) (xy 98.400613 -402.987604)
			(xy 98.350994 -402.964945) (xy 98.305104 -402.935456) (xy 98.263878 -402.899736) (xy 98.228156 -402.858512)
			(xy 98.198664 -402.812624) (xy 98.176003 -402.763005) (xy 98.160635 -402.710667) (xy 98.152872 -402.656674)
			(xy 2.509012 -402.656674) (xy 2.509012 -403.371812) (xy 2.5095 -403.425034) (xy 2.517117 -403.531207)
			(xy 2.532283 -403.636566) (xy 2.554922 -403.740575) (xy 2.584919 -403.842706) (xy 2.610452 -403.911156)
			(xy 47.598731 -403.911156) (xy 47.598731 -403.856644) (xy 47.606489 -403.802686) (xy 47.621848 -403.750382)
			(xy 47.644495 -403.700796) (xy 47.673969 -403.654938) (xy 47.709669 -403.613742) (xy 47.750868 -403.578046)
			(xy 47.796729 -403.548577) (xy 47.846317 -403.525935) (xy 47.898623 -403.510581) (xy 47.952582 -403.502828)
			(xy 47.979838 -403.502368) (xy 48.843438 -403.502368) (xy 48.870686 -403.502905) (xy 48.924626 -403.510665)
			(xy 48.976913 -403.526023) (xy 49.026482 -403.548665) (xy 49.072325 -403.57813) (xy 49.113508 -403.613819)
			(xy 49.149193 -403.655006) (xy 49.178654 -403.700851) (xy 49.201291 -403.750423) (xy 49.216643 -403.802711)
			(xy 49.224398 -403.856652) (xy 49.224398 -403.911148) (xy 49.224397 -403.911152) (xy 50.662054 -403.911152)
			(xy 50.662054 -403.856648) (xy 50.66981 -403.802699) (xy 50.685165 -403.750403) (xy 50.707806 -403.700824)
			(xy 50.737272 -403.654971) (xy 50.772964 -403.613779) (xy 50.814154 -403.578085) (xy 50.860004 -403.548617)
			(xy 50.909582 -403.525973) (xy 50.961877 -403.510615) (xy 51.015826 -403.502855) (xy 51.043078 -403.502368)
			(xy 51.906678 -403.502368) (xy 51.93393 -403.502878) (xy 51.98788 -403.510632) (xy 52.040177 -403.525985)
			(xy 52.089757 -403.548625) (xy 52.13561 -403.57809) (xy 52.176803 -403.613782) (xy 52.212497 -403.654972)
			(xy 52.241965 -403.700824) (xy 52.264607 -403.750402) (xy 52.279964 -403.802698) (xy 52.287721 -403.856648)
			(xy 52.287721 -403.911152) (xy 52.287721 -403.911155) (xy 53.725231 -403.911155) (xy 53.725231 -403.856645)
			(xy 53.732989 -403.802689) (xy 53.748347 -403.750386) (xy 53.770992 -403.700801) (xy 53.800464 -403.654945)
			(xy 53.836162 -403.613749) (xy 53.877359 -403.578053) (xy 53.923217 -403.548583) (xy 53.972803 -403.525941)
			(xy 54.025106 -403.510585) (xy 54.079063 -403.50283) (xy 54.106318 -403.502368) (xy 54.969918 -403.502368)
			(xy 54.997167 -403.502903) (xy 55.051109 -403.510662) (xy 55.103398 -403.526017) (xy 55.15297 -403.548658)
			(xy 55.198815 -403.578123) (xy 55.240001 -403.613812) (xy 55.275688 -403.654999) (xy 55.305151 -403.700846)
			(xy 55.327789 -403.750419) (xy 55.343142 -403.802709) (xy 55.350898 -403.856651) (xy 55.350898 -403.911149)
			(xy 55.350898 -403.911151) (xy 56.788554 -403.911151) (xy 56.788554 -403.856649) (xy 56.79631 -403.802702)
			(xy 56.811664 -403.750407) (xy 56.834303 -403.700829) (xy 56.863767 -403.654978) (xy 56.899457 -403.613786)
			(xy 56.940644 -403.578093) (xy 56.986492 -403.548623) (xy 57.036067 -403.525978) (xy 57.08836 -403.510619)
			(xy 57.142307 -403.502857) (xy 57.169558 -403.502368) (xy 58.033158 -403.502368) (xy 58.060411 -403.502876)
			(xy 58.114363 -403.510628) (xy 58.166663 -403.525979) (xy 58.216245 -403.548618) (xy 58.262101 -403.578083)
			(xy 58.303296 -403.613775) (xy 58.338992 -403.654966) (xy 58.368462 -403.700818) (xy 58.391106 -403.750398)
			(xy 58.406463 -403.802696) (xy 58.414221 -403.856647) (xy 58.414221 -403.911153) (xy 59.851754 -403.911153)
			(xy 59.851754 -403.856647) (xy 59.859511 -403.802696) (xy 59.874867 -403.750398) (xy 59.897509 -403.700818)
			(xy 59.926977 -403.654965) (xy 59.962671 -403.613772) (xy 60.003863 -403.578078) (xy 60.049716 -403.54861)
			(xy 60.099296 -403.525967) (xy 60.151594 -403.510611) (xy 60.205545 -403.502854) (xy 60.232798 -403.502368)
			(xy 61.096398 -403.502368) (xy 61.123649 -403.502879) (xy 61.177597 -403.510635) (xy 61.229892 -403.52599)
			(xy 61.279469 -403.548631) (xy 61.32532 -403.578097) (xy 61.36651 -403.613789) (xy 61.402201 -403.654979)
			(xy 61.431668 -403.700829) (xy 61.454309 -403.750406) (xy 61.469664 -403.802701) (xy 61.477421 -403.856649)
			(xy 61.477421 -403.911151) (xy 61.47742 -403.911156) (xy 62.914931 -403.911156) (xy 62.914931 -403.856644)
			(xy 62.922689 -403.802686) (xy 62.938048 -403.750382) (xy 62.960695 -403.700796) (xy 62.990169 -403.654938)
			(xy 63.025869 -403.613742) (xy 63.067068 -403.578046) (xy 63.112929 -403.548577) (xy 63.162517 -403.525935)
			(xy 63.214823 -403.510581) (xy 63.268782 -403.502828) (xy 63.296038 -403.502368) (xy 64.159638 -403.502368)
			(xy 64.186886 -403.502905) (xy 64.240826 -403.510665) (xy 64.293113 -403.526023) (xy 64.342682 -403.548665)
			(xy 64.388525 -403.57813) (xy 64.429708 -403.613819) (xy 64.465393 -403.655006) (xy 64.494854 -403.700851)
			(xy 64.517491 -403.750423) (xy 64.532843 -403.802711) (xy 64.540598 -403.856652) (xy 64.540598 -403.911148)
			(xy 64.540597 -403.911152) (xy 65.978254 -403.911152) (xy 65.978254 -403.856648) (xy 65.98601 -403.802699)
			(xy 66.001365 -403.750403) (xy 66.024006 -403.700824) (xy 66.053472 -403.654971) (xy 66.089164 -403.613779)
			(xy 66.130354 -403.578085) (xy 66.176204 -403.548617) (xy 66.225782 -403.525973) (xy 66.278077 -403.510615)
			(xy 66.332026 -403.502855) (xy 66.359278 -403.502368) (xy 67.222878 -403.502368) (xy 67.25013 -403.502878)
			(xy 67.30408 -403.510632) (xy 67.356377 -403.525985) (xy 67.405957 -403.548625) (xy 67.45181 -403.57809)
			(xy 67.493003 -403.613782) (xy 67.528697 -403.654972) (xy 67.558165 -403.700824) (xy 67.580807 -403.750402)
			(xy 67.596164 -403.802698) (xy 67.603921 -403.856648) (xy 67.603921 -403.911152) (xy 67.603921 -403.911155)
			(xy 69.041431 -403.911155) (xy 69.041431 -403.856645) (xy 69.049189 -403.802689) (xy 69.064547 -403.750386)
			(xy 69.087192 -403.700801) (xy 69.116664 -403.654945) (xy 69.152362 -403.613749) (xy 69.193559 -403.578053)
			(xy 69.239417 -403.548583) (xy 69.289003 -403.525941) (xy 69.341306 -403.510585) (xy 69.395263 -403.50283)
			(xy 69.422518 -403.502368) (xy 70.286118 -403.502368) (xy 70.313367 -403.502903) (xy 70.367309 -403.510662)
			(xy 70.419598 -403.526017) (xy 70.46917 -403.548658) (xy 70.515015 -403.578123) (xy 70.556201 -403.613812)
			(xy 70.591888 -403.654999) (xy 70.621351 -403.700846) (xy 70.643989 -403.750419) (xy 70.659342 -403.802709)
			(xy 70.667098 -403.856651) (xy 70.667098 -403.911149) (xy 70.667098 -403.911151) (xy 72.104754 -403.911151)
			(xy 72.104754 -403.856649) (xy 72.11251 -403.802702) (xy 72.127864 -403.750407) (xy 72.150503 -403.700829)
			(xy 72.179967 -403.654978) (xy 72.215657 -403.613786) (xy 72.256844 -403.578093) (xy 72.302692 -403.548623)
			(xy 72.352267 -403.525978) (xy 72.40456 -403.510619) (xy 72.458507 -403.502857) (xy 72.485758 -403.502368)
			(xy 73.349358 -403.502368) (xy 73.376611 -403.502876) (xy 73.430563 -403.510628) (xy 73.482863 -403.525979)
			(xy 73.532445 -403.548618) (xy 73.578301 -403.578083) (xy 73.619496 -403.613775) (xy 73.655192 -403.654966)
			(xy 73.684662 -403.700818) (xy 73.707306 -403.750398) (xy 73.722663 -403.802696) (xy 73.730421 -403.856647)
			(xy 73.730421 -403.911153) (xy 75.167954 -403.911153) (xy 75.167954 -403.856647) (xy 75.175711 -403.802696)
			(xy 75.191067 -403.750398) (xy 75.213709 -403.700818) (xy 75.243177 -403.654965) (xy 75.278871 -403.613772)
			(xy 75.320063 -403.578078) (xy 75.365916 -403.54861) (xy 75.415496 -403.525967) (xy 75.467794 -403.510611)
			(xy 75.521745 -403.502854) (xy 75.548998 -403.502368) (xy 76.412598 -403.502368) (xy 76.439849 -403.502879)
			(xy 76.493797 -403.510635) (xy 76.546092 -403.52599) (xy 76.595669 -403.548631) (xy 76.64152 -403.578097)
			(xy 76.68271 -403.613789) (xy 76.718401 -403.654979) (xy 76.747868 -403.700829) (xy 76.770509 -403.750406)
			(xy 76.785864 -403.802701) (xy 76.793621 -403.856649) (xy 76.793621 -403.911151) (xy 76.79362 -403.911156)
			(xy 78.231131 -403.911156) (xy 78.231131 -403.856644) (xy 78.238889 -403.802686) (xy 78.254248 -403.750382)
			(xy 78.276895 -403.700796) (xy 78.306369 -403.654938) (xy 78.342069 -403.613742) (xy 78.383268 -403.578046)
			(xy 78.429129 -403.548577) (xy 78.478717 -403.525935) (xy 78.531023 -403.510581) (xy 78.584982 -403.502828)
			(xy 78.612238 -403.502368) (xy 79.475838 -403.502368) (xy 79.503086 -403.502905) (xy 79.557026 -403.510665)
			(xy 79.609313 -403.526023) (xy 79.658882 -403.548665) (xy 79.704725 -403.57813) (xy 79.745908 -403.613819)
			(xy 79.781593 -403.655006) (xy 79.811054 -403.700851) (xy 79.833691 -403.750423) (xy 79.849043 -403.802711)
			(xy 79.856798 -403.856652) (xy 79.856798 -403.911148) (xy 79.856797 -403.911152) (xy 81.294454 -403.911152)
			(xy 81.294454 -403.856648) (xy 81.30221 -403.802699) (xy 81.317565 -403.750403) (xy 81.340206 -403.700824)
			(xy 81.369672 -403.654971) (xy 81.405364 -403.613779) (xy 81.446554 -403.578085) (xy 81.492404 -403.548617)
			(xy 81.541982 -403.525973) (xy 81.594277 -403.510615) (xy 81.648226 -403.502855) (xy 81.675478 -403.502368)
			(xy 82.539078 -403.502368) (xy 82.56633 -403.502878) (xy 82.62028 -403.510632) (xy 82.672577 -403.525985)
			(xy 82.722157 -403.548625) (xy 82.76801 -403.57809) (xy 82.809203 -403.613782) (xy 82.844897 -403.654972)
			(xy 82.874365 -403.700824) (xy 82.897007 -403.750402) (xy 82.912364 -403.802698) (xy 82.920121 -403.856648)
			(xy 82.920121 -403.911152) (xy 82.920121 -403.911155) (xy 84.357631 -403.911155) (xy 84.357631 -403.856645)
			(xy 84.365389 -403.802689) (xy 84.380747 -403.750386) (xy 84.403392 -403.700801) (xy 84.432864 -403.654945)
			(xy 84.468562 -403.613749) (xy 84.509759 -403.578053) (xy 84.555617 -403.548583) (xy 84.605203 -403.525941)
			(xy 84.657506 -403.510585) (xy 84.711463 -403.50283) (xy 84.738718 -403.502368) (xy 85.602318 -403.502368)
			(xy 85.629567 -403.502903) (xy 85.683509 -403.510662) (xy 85.735798 -403.526017) (xy 85.78537 -403.548658)
			(xy 85.831215 -403.578123) (xy 85.872401 -403.613812) (xy 85.908088 -403.654999) (xy 85.937551 -403.700846)
			(xy 85.960189 -403.750419) (xy 85.975542 -403.802709) (xy 85.983298 -403.856651) (xy 85.983298 -403.911149)
			(xy 85.983298 -403.911151) (xy 87.420954 -403.911151) (xy 87.420954 -403.856649) (xy 87.42871 -403.802702)
			(xy 87.444064 -403.750407) (xy 87.466703 -403.700829) (xy 87.496167 -403.654978) (xy 87.531857 -403.613786)
			(xy 87.573044 -403.578093) (xy 87.618892 -403.548623) (xy 87.668467 -403.525978) (xy 87.72076 -403.510619)
			(xy 87.774707 -403.502857) (xy 87.801958 -403.502368) (xy 88.665558 -403.502368) (xy 88.692811 -403.502876)
			(xy 88.746763 -403.510628) (xy 88.799063 -403.525979) (xy 88.848645 -403.548618) (xy 88.894501 -403.578083)
			(xy 88.935696 -403.613775) (xy 88.971392 -403.654966) (xy 89.000862 -403.700818) (xy 89.023506 -403.750398)
			(xy 89.038863 -403.802696) (xy 89.046621 -403.856647) (xy 89.046621 -403.911153) (xy 90.484154 -403.911153)
			(xy 90.484154 -403.856647) (xy 90.491911 -403.802696) (xy 90.507267 -403.750398) (xy 90.529909 -403.700818)
			(xy 90.559377 -403.654965) (xy 90.595071 -403.613772) (xy 90.636263 -403.578078) (xy 90.682116 -403.54861)
			(xy 90.731696 -403.525967) (xy 90.783994 -403.510611) (xy 90.837945 -403.502854) (xy 90.865198 -403.502368)
			(xy 91.728798 -403.502368) (xy 91.756049 -403.502879) (xy 91.809997 -403.510635) (xy 91.862292 -403.52599)
			(xy 91.911869 -403.548631) (xy 91.95772 -403.578097) (xy 91.99891 -403.613789) (xy 92.034601 -403.654979)
			(xy 92.064068 -403.700829) (xy 92.086709 -403.750406) (xy 92.102064 -403.802701) (xy 92.109821 -403.856649)
			(xy 92.109821 -403.911151) (xy 92.10982 -403.911156) (xy 93.547331 -403.911156) (xy 93.547331 -403.856644)
			(xy 93.555089 -403.802686) (xy 93.570448 -403.750382) (xy 93.593095 -403.700796) (xy 93.622569 -403.654938)
			(xy 93.658269 -403.613742) (xy 93.699468 -403.578046) (xy 93.745329 -403.548577) (xy 93.794917 -403.525935)
			(xy 93.847223 -403.510581) (xy 93.901182 -403.502828) (xy 93.928438 -403.502368) (xy 94.792038 -403.502368)
			(xy 94.819286 -403.502905) (xy 94.873226 -403.510665) (xy 94.925513 -403.526023) (xy 94.975082 -403.548665)
			(xy 95.020925 -403.57813) (xy 95.062108 -403.613819) (xy 95.097793 -403.655006) (xy 95.127254 -403.700851)
			(xy 95.149891 -403.750423) (xy 95.165243 -403.802711) (xy 95.172998 -403.856652) (xy 95.172998 -403.911148)
			(xy 95.172998 -403.911151) (xy 119.773954 -403.911151) (xy 119.773954 -403.856649) (xy 119.78171 -403.802702)
			(xy 119.797063 -403.750408) (xy 119.819702 -403.70083) (xy 119.849166 -403.654979) (xy 119.884855 -403.613788)
			(xy 119.926042 -403.578094) (xy 119.97189 -403.548625) (xy 120.021465 -403.525979) (xy 120.073757 -403.510619)
			(xy 120.127703 -403.502857) (xy 120.154954 -403.502368) (xy 121.018554 -403.502368) (xy 121.045807 -403.502876)
			(xy 121.09976 -403.510627) (xy 121.15206 -403.525978) (xy 121.201643 -403.548617) (xy 121.247499 -403.578082)
			(xy 121.288694 -403.613773) (xy 121.324391 -403.654964) (xy 121.353861 -403.700817) (xy 121.376506 -403.750397)
			(xy 121.391863 -403.802695) (xy 121.399621 -403.856647) (xy 121.399621 -403.911153) (xy 122.837154 -403.911153)
			(xy 122.837154 -403.856647) (xy 122.844911 -403.802697) (xy 122.860266 -403.750399) (xy 122.882909 -403.700819)
			(xy 122.912376 -403.654966) (xy 122.948069 -403.613774) (xy 122.989261 -403.57808) (xy 123.035114 -403.548611)
			(xy 123.084694 -403.525969) (xy 123.136991 -403.510612) (xy 123.190941 -403.502854) (xy 123.218194 -403.502368)
			(xy 124.081794 -403.502368) (xy 124.109045 -403.502879) (xy 124.162994 -403.510635) (xy 124.215289 -403.525989)
			(xy 124.264867 -403.54863) (xy 124.310718 -403.578096) (xy 124.351908 -403.613787) (xy 124.3876 -403.654978)
			(xy 124.417067 -403.700828) (xy 124.439709 -403.750406) (xy 124.455064 -403.802701) (xy 124.462821 -403.856649)
			(xy 124.462821 -403.911151) (xy 124.46282 -403.911156) (xy 125.900331 -403.911156) (xy 125.900331 -403.856644)
			(xy 125.908089 -403.802686) (xy 125.923448 -403.750383) (xy 125.946095 -403.700797) (xy 125.975568 -403.654939)
			(xy 126.011267 -403.613743) (xy 126.052467 -403.578047) (xy 126.098327 -403.548578) (xy 126.147914 -403.525936)
			(xy 126.20022 -403.510582) (xy 126.254178 -403.502829) (xy 126.281434 -403.502368) (xy 127.145034 -403.502368)
			(xy 127.172282 -403.502905) (xy 127.226223 -403.510664) (xy 127.27851 -403.526022) (xy 127.32808 -403.548663)
			(xy 127.373923 -403.578129) (xy 127.415106 -403.613818) (xy 127.450792 -403.655004) (xy 127.480253 -403.70085)
			(xy 127.50289 -403.750422) (xy 127.518243 -403.802711) (xy 127.525998 -403.856652) (xy 127.525998 -403.911148)
			(xy 127.525997 -403.911152) (xy 128.963654 -403.911152) (xy 128.963654 -403.856648) (xy 128.97141 -403.802699)
			(xy 128.986765 -403.750403) (xy 129.009406 -403.700825) (xy 129.038871 -403.654973) (xy 129.074562 -403.613781)
			(xy 129.115752 -403.578087) (xy 129.161602 -403.548618) (xy 129.211179 -403.525974) (xy 129.263474 -403.510616)
			(xy 129.317422 -403.502856) (xy 129.344674 -403.502368) (xy 130.208274 -403.502368) (xy 130.235526 -403.502878)
			(xy 130.289477 -403.510631) (xy 130.341774 -403.525984) (xy 130.391355 -403.548623) (xy 130.437208 -403.578089)
			(xy 130.478401 -403.61378) (xy 130.514096 -403.654971) (xy 130.543564 -403.700822) (xy 130.566207 -403.750401)
			(xy 130.581563 -403.802698) (xy 130.589321 -403.856648) (xy 130.589321 -403.911152) (xy 130.589321 -403.911155)
			(xy 132.026831 -403.911155) (xy 132.026831 -403.856645) (xy 132.034589 -403.802689) (xy 132.049946 -403.750387)
			(xy 132.072591 -403.700803) (xy 132.102063 -403.654946) (xy 132.13776 -403.61375) (xy 132.178957 -403.578054)
			(xy 132.224815 -403.548585) (xy 132.2744 -403.525942) (xy 132.326703 -403.510586) (xy 132.380659 -403.50283)
			(xy 132.407914 -403.502368) (xy 133.271514 -403.502368) (xy 133.298763 -403.502903) (xy 133.352706 -403.510661)
			(xy 133.404995 -403.526016) (xy 133.454568 -403.548657) (xy 133.500413 -403.578121) (xy 133.541599 -403.613811)
			(xy 133.577287 -403.654998) (xy 133.60675 -403.700845) (xy 133.629389 -403.750418) (xy 133.644742 -403.802708)
			(xy 133.652498 -403.856651) (xy 133.652498 -403.911149) (xy 133.652498 -403.911151) (xy 135.090154 -403.911151)
			(xy 135.090154 -403.856649) (xy 135.09791 -403.802702) (xy 135.113263 -403.750408) (xy 135.135902 -403.70083)
			(xy 135.165366 -403.654979) (xy 135.201055 -403.613788) (xy 135.242242 -403.578094) (xy 135.28809 -403.548625)
			(xy 135.337665 -403.525979) (xy 135.389957 -403.510619) (xy 135.443903 -403.502857) (xy 135.471154 -403.502368)
			(xy 136.334754 -403.502368) (xy 136.362007 -403.502876) (xy 136.41596 -403.510627) (xy 136.46826 -403.525978)
			(xy 136.517843 -403.548617) (xy 136.563699 -403.578082) (xy 136.604894 -403.613773) (xy 136.640591 -403.654964)
			(xy 136.670061 -403.700817) (xy 136.692706 -403.750397) (xy 136.708063 -403.802695) (xy 136.715821 -403.856647)
			(xy 136.715821 -403.911153) (xy 138.153354 -403.911153) (xy 138.153354 -403.856647) (xy 138.161111 -403.802697)
			(xy 138.176466 -403.750399) (xy 138.199109 -403.700819) (xy 138.228576 -403.654966) (xy 138.264269 -403.613774)
			(xy 138.305461 -403.57808) (xy 138.351314 -403.548611) (xy 138.400894 -403.525969) (xy 138.453191 -403.510612)
			(xy 138.507141 -403.502854) (xy 138.534394 -403.502368) (xy 139.397994 -403.502368) (xy 139.425245 -403.502879)
			(xy 139.479194 -403.510635) (xy 139.531489 -403.525989) (xy 139.581067 -403.54863) (xy 139.626918 -403.578096)
			(xy 139.668108 -403.613787) (xy 139.7038 -403.654978) (xy 139.733267 -403.700828) (xy 139.755909 -403.750406)
			(xy 139.771264 -403.802701) (xy 139.779021 -403.856649) (xy 139.779021 -403.911151) (xy 139.77902 -403.911156)
			(xy 141.216531 -403.911156) (xy 141.216531 -403.856644) (xy 141.224289 -403.802686) (xy 141.239648 -403.750383)
			(xy 141.262295 -403.700797) (xy 141.291768 -403.654939) (xy 141.327467 -403.613743) (xy 141.368667 -403.578047)
			(xy 141.414527 -403.548578) (xy 141.464114 -403.525936) (xy 141.51642 -403.510582) (xy 141.570378 -403.502829)
			(xy 141.597634 -403.502368) (xy 142.461234 -403.502368) (xy 142.488482 -403.502905) (xy 142.542423 -403.510664)
			(xy 142.59471 -403.526022) (xy 142.64428 -403.548663) (xy 142.690123 -403.578129) (xy 142.731306 -403.613818)
			(xy 142.766992 -403.655004) (xy 142.796453 -403.70085) (xy 142.81909 -403.750422) (xy 142.834443 -403.802711)
			(xy 142.842198 -403.856652) (xy 142.842198 -403.911148) (xy 142.842197 -403.911152) (xy 144.279854 -403.911152)
			(xy 144.279854 -403.856648) (xy 144.28761 -403.802699) (xy 144.302965 -403.750403) (xy 144.325606 -403.700825)
			(xy 144.355071 -403.654973) (xy 144.390762 -403.613781) (xy 144.431952 -403.578087) (xy 144.477802 -403.548618)
			(xy 144.527379 -403.525974) (xy 144.579674 -403.510616) (xy 144.633622 -403.502856) (xy 144.660874 -403.502368)
			(xy 145.524474 -403.502368) (xy 145.551726 -403.502878) (xy 145.605677 -403.510631) (xy 145.657974 -403.525984)
			(xy 145.707555 -403.548623) (xy 145.753408 -403.578089) (xy 145.794601 -403.61378) (xy 145.830296 -403.654971)
			(xy 145.859764 -403.700822) (xy 145.882407 -403.750401) (xy 145.897763 -403.802698) (xy 145.905521 -403.856648)
			(xy 145.905521 -403.911152) (xy 145.905521 -403.911155) (xy 147.343031 -403.911155) (xy 147.343031 -403.856645)
			(xy 147.350789 -403.802689) (xy 147.366146 -403.750387) (xy 147.388791 -403.700803) (xy 147.418263 -403.654946)
			(xy 147.45396 -403.61375) (xy 147.495157 -403.578054) (xy 147.541015 -403.548585) (xy 147.5906 -403.525942)
			(xy 147.642903 -403.510586) (xy 147.696859 -403.50283) (xy 147.724114 -403.502368) (xy 148.587714 -403.502368)
			(xy 148.614963 -403.502903) (xy 148.668906 -403.510661) (xy 148.721195 -403.526016) (xy 148.770768 -403.548657)
			(xy 148.816613 -403.578121) (xy 148.857799 -403.613811) (xy 148.893487 -403.654998) (xy 148.92295 -403.700845)
			(xy 148.945589 -403.750418) (xy 148.960942 -403.802708) (xy 148.968698 -403.856651) (xy 148.968698 -403.911149)
			(xy 148.968698 -403.911151) (xy 150.406354 -403.911151) (xy 150.406354 -403.856649) (xy 150.41411 -403.802702)
			(xy 150.429463 -403.750408) (xy 150.452102 -403.70083) (xy 150.481566 -403.654979) (xy 150.517255 -403.613788)
			(xy 150.558442 -403.578094) (xy 150.60429 -403.548625) (xy 150.653865 -403.525979) (xy 150.706157 -403.510619)
			(xy 150.760103 -403.502857) (xy 150.787354 -403.502368) (xy 151.650954 -403.502368) (xy 151.678207 -403.502876)
			(xy 151.73216 -403.510627) (xy 151.78446 -403.525978) (xy 151.834043 -403.548617) (xy 151.879899 -403.578082)
			(xy 151.921094 -403.613773) (xy 151.956791 -403.654964) (xy 151.986261 -403.700817) (xy 152.008906 -403.750397)
			(xy 152.024263 -403.802695) (xy 152.032021 -403.856647) (xy 152.032021 -403.911153) (xy 153.469554 -403.911153)
			(xy 153.469554 -403.856647) (xy 153.477311 -403.802697) (xy 153.492666 -403.750399) (xy 153.515309 -403.700819)
			(xy 153.544776 -403.654966) (xy 153.580469 -403.613774) (xy 153.621661 -403.57808) (xy 153.667514 -403.548611)
			(xy 153.717094 -403.525969) (xy 153.769391 -403.510612) (xy 153.823341 -403.502854) (xy 153.850594 -403.502368)
			(xy 154.714194 -403.502368) (xy 154.741445 -403.502879) (xy 154.795394 -403.510635) (xy 154.847689 -403.525989)
			(xy 154.897267 -403.54863) (xy 154.943118 -403.578096) (xy 154.984308 -403.613787) (xy 155.02 -403.654978)
			(xy 155.049467 -403.700828) (xy 155.072109 -403.750406) (xy 155.087464 -403.802701) (xy 155.095221 -403.856649)
			(xy 155.095221 -403.911151) (xy 155.09522 -403.911156) (xy 156.532731 -403.911156) (xy 156.532731 -403.856644)
			(xy 156.540489 -403.802686) (xy 156.555848 -403.750383) (xy 156.578495 -403.700797) (xy 156.607968 -403.654939)
			(xy 156.643667 -403.613743) (xy 156.684867 -403.578047) (xy 156.730727 -403.548578) (xy 156.780314 -403.525936)
			(xy 156.83262 -403.510582) (xy 156.886578 -403.502829) (xy 156.913834 -403.502368) (xy 157.777434 -403.502368)
			(xy 157.804682 -403.502905) (xy 157.858623 -403.510664) (xy 157.91091 -403.526022) (xy 157.96048 -403.548663)
			(xy 158.006323 -403.578129) (xy 158.047506 -403.613818) (xy 158.083192 -403.655004) (xy 158.112653 -403.70085)
			(xy 158.13529 -403.750422) (xy 158.150643 -403.802711) (xy 158.158398 -403.856652) (xy 158.158398 -403.911148)
			(xy 158.158397 -403.911152) (xy 159.596054 -403.911152) (xy 159.596054 -403.856648) (xy 159.60381 -403.802699)
			(xy 159.619165 -403.750403) (xy 159.641806 -403.700825) (xy 159.671271 -403.654973) (xy 159.706962 -403.613781)
			(xy 159.748152 -403.578087) (xy 159.794002 -403.548618) (xy 159.843579 -403.525974) (xy 159.895874 -403.510616)
			(xy 159.949822 -403.502856) (xy 159.977074 -403.502368) (xy 160.840674 -403.502368) (xy 160.867926 -403.502878)
			(xy 160.921877 -403.510631) (xy 160.974174 -403.525984) (xy 161.023755 -403.548623) (xy 161.069608 -403.578089)
			(xy 161.110801 -403.61378) (xy 161.146496 -403.654971) (xy 161.175964 -403.700822) (xy 161.198607 -403.750401)
			(xy 161.213963 -403.802698) (xy 161.221721 -403.856648) (xy 161.221721 -403.911152) (xy 161.221721 -403.911155)
			(xy 162.659231 -403.911155) (xy 162.659231 -403.856645) (xy 162.666989 -403.802689) (xy 162.682346 -403.750387)
			(xy 162.704991 -403.700803) (xy 162.734463 -403.654946) (xy 162.77016 -403.61375) (xy 162.811357 -403.578054)
			(xy 162.857215 -403.548585) (xy 162.9068 -403.525942) (xy 162.959103 -403.510586) (xy 163.013059 -403.50283)
			(xy 163.040314 -403.502368) (xy 163.903914 -403.502368) (xy 163.931163 -403.502903) (xy 163.985106 -403.510661)
			(xy 164.037395 -403.526016) (xy 164.086968 -403.548657) (xy 164.132813 -403.578121) (xy 164.173999 -403.613811)
			(xy 164.209687 -403.654998) (xy 164.23915 -403.700845) (xy 164.261789 -403.750418) (xy 164.277142 -403.802708)
			(xy 164.284898 -403.856651) (xy 164.284898 -403.911149) (xy 164.284898 -403.911151) (xy 165.722554 -403.911151)
			(xy 165.722554 -403.856649) (xy 165.73031 -403.802702) (xy 165.745663 -403.750408) (xy 165.768302 -403.70083)
			(xy 165.797766 -403.654979) (xy 165.833455 -403.613788) (xy 165.874642 -403.578094) (xy 165.92049 -403.548625)
			(xy 165.970065 -403.525979) (xy 166.022357 -403.510619) (xy 166.076303 -403.502857) (xy 166.103554 -403.502368)
			(xy 166.967154 -403.502368) (xy 166.994407 -403.502876) (xy 167.04836 -403.510627) (xy 167.10066 -403.525978)
			(xy 167.150243 -403.548617) (xy 167.196099 -403.578082) (xy 167.237294 -403.613773) (xy 167.272991 -403.654964)
			(xy 167.302461 -403.700817) (xy 167.325106 -403.750397) (xy 167.340463 -403.802695) (xy 167.348221 -403.856647)
			(xy 167.348221 -403.911153) (xy 167.340463 -403.965105) (xy 167.325106 -404.017403) (xy 167.31136 -404.0475)
			(xy 287.066441 -404.0475) (xy 287.070455 -403.983698) (xy 287.082434 -403.920902) (xy 287.102189 -403.860103)
			(xy 287.129408 -403.80226) (xy 287.163662 -403.748283) (xy 287.204411 -403.699026) (xy 287.251013 -403.655264)
			(xy 287.302731 -403.617688) (xy 287.358752 -403.58689) (xy 287.418191 -403.563357) (xy 287.48011 -403.547458)
			(xy 287.543534 -403.539446) (xy 287.575498 -403.538944) (xy 287.575752 -403.538944) (xy 287.607498 -403.539464)
			(xy 287.670494 -403.547393) (xy 287.732014 -403.563096) (xy 287.791102 -403.58633) (xy 287.846842 -403.616733)
			(xy 287.898367 -403.653834) (xy 287.921954 -403.675088) (xy 287.929217 -403.681272) (xy 287.946967 -403.688223)
			(xy 287.966029 -403.688223) (xy 287.983779 -403.681272) (xy 287.991042 -403.675088) (xy 288.014631 -403.653832)
			(xy 288.06614 -403.6167) (xy 288.121874 -403.586276) (xy 288.180965 -403.563035) (xy 288.242492 -403.547338)
			(xy 288.305495 -403.539431) (xy 288.337244 -403.538944) (xy 288.337498 -403.538944) (xy 288.369457 -403.539521)
			(xy 288.432872 -403.547532) (xy 288.494783 -403.563427) (xy 288.554213 -403.586957) (xy 288.610226 -403.61775)
			(xy 288.661937 -403.655321) (xy 288.708532 -403.699076) (xy 288.749276 -403.748326) (xy 288.783525 -403.802295)
			(xy 288.810741 -403.86013) (xy 288.830493 -403.920921) (xy 288.84247 -403.983707) (xy 288.846484 -404.0475)
			(xy 289.606441 -404.0475) (xy 289.610455 -403.983698) (xy 289.622434 -403.920902) (xy 289.642189 -403.860103)
			(xy 289.669408 -403.80226) (xy 289.703662 -403.748283) (xy 289.744411 -403.699026) (xy 289.791013 -403.655264)
			(xy 289.842731 -403.617688) (xy 289.898752 -403.58689) (xy 289.958191 -403.563357) (xy 290.02011 -403.547458)
			(xy 290.083534 -403.539446) (xy 290.115498 -403.538944) (xy 290.115752 -403.538944) (xy 290.147498 -403.539464)
			(xy 290.210494 -403.547393) (xy 290.272014 -403.563096) (xy 290.331102 -403.58633) (xy 290.386842 -403.616733)
			(xy 290.438367 -403.653834) (xy 290.461954 -403.675088) (xy 290.469217 -403.681272) (xy 290.486967 -403.688223)
			(xy 290.506029 -403.688223) (xy 290.523779 -403.681272) (xy 290.531042 -403.675088) (xy 290.554631 -403.653832)
			(xy 290.60614 -403.6167) (xy 290.661874 -403.586276) (xy 290.720965 -403.563035) (xy 290.782492 -403.547338)
			(xy 290.845495 -403.539431) (xy 290.877244 -403.538944) (xy 290.877498 -403.538944) (xy 290.909457 -403.539521)
			(xy 290.972872 -403.547532) (xy 291.034783 -403.563427) (xy 291.094213 -403.586957) (xy 291.150226 -403.61775)
			(xy 291.201937 -403.655321) (xy 291.248532 -403.699076) (xy 291.289276 -403.748326) (xy 291.323525 -403.802295)
			(xy 291.350741 -403.86013) (xy 291.370493 -403.920921) (xy 291.38247 -403.983707) (xy 291.386484 -404.0475)
			(xy 292.146441 -404.0475) (xy 292.150455 -403.983698) (xy 292.162434 -403.920902) (xy 292.182189 -403.860103)
			(xy 292.209408 -403.80226) (xy 292.243662 -403.748283) (xy 292.284411 -403.699026) (xy 292.331013 -403.655264)
			(xy 292.382731 -403.617688) (xy 292.438752 -403.58689) (xy 292.498191 -403.563357) (xy 292.56011 -403.547458)
			(xy 292.623534 -403.539446) (xy 292.655498 -403.538944) (xy 292.655752 -403.538944) (xy 292.687498 -403.539464)
			(xy 292.750494 -403.547393) (xy 292.812014 -403.563096) (xy 292.871102 -403.58633) (xy 292.926842 -403.616733)
			(xy 292.978367 -403.653834) (xy 293.001954 -403.675088) (xy 293.009217 -403.681272) (xy 293.026967 -403.688223)
			(xy 293.046029 -403.688223) (xy 293.063779 -403.681272) (xy 293.071042 -403.675088) (xy 293.094631 -403.653832)
			(xy 293.14614 -403.6167) (xy 293.201874 -403.586276) (xy 293.260965 -403.563035) (xy 293.322492 -403.547338)
			(xy 293.385495 -403.539431) (xy 293.417244 -403.538944) (xy 293.417498 -403.538944) (xy 293.449457 -403.539521)
			(xy 293.512872 -403.547532) (xy 293.574783 -403.563427) (xy 293.634213 -403.586957) (xy 293.690226 -403.61775)
			(xy 293.741937 -403.655321) (xy 293.788532 -403.699076) (xy 293.829276 -403.748326) (xy 293.863525 -403.802295)
			(xy 293.890741 -403.86013) (xy 293.910493 -403.920921) (xy 293.92247 -403.983707) (xy 293.926484 -404.0475)
			(xy 294.53602 -404.0475) (xy 294.540035 -403.983693) (xy 294.552015 -403.920892) (xy 294.571773 -403.860089)
			(xy 294.598995 -403.802241) (xy 294.633253 -403.748261) (xy 294.674007 -403.699001) (xy 294.720613 -403.655237)
			(xy 294.772338 -403.61766) (xy 294.828364 -403.586862) (xy 294.887809 -403.563329) (xy 294.949734 -403.547433)
			(xy 295.013163 -403.539423) (xy 295.04513 -403.538944) (xy 295.045384 -403.538944) (xy 295.077131 -403.539444)
			(xy 295.140127 -403.547377) (xy 295.201647 -403.563084) (xy 295.260736 -403.586322) (xy 295.316476 -403.616728)
			(xy 295.368 -403.653832) (xy 295.391586 -403.675088) (xy 295.398849 -403.681272) (xy 295.416599 -403.688223)
			(xy 295.435661 -403.688223) (xy 295.453411 -403.681272) (xy 295.460674 -403.675088) (xy 295.48425 -403.653817)
			(xy 295.535761 -403.616686) (xy 295.591498 -403.586265) (xy 295.650592 -403.563026) (xy 295.712121 -403.547332)
			(xy 295.775126 -403.539429) (xy 295.806876 -403.538944) (xy 295.80713 -403.538944) (xy 295.839087 -403.539544)
			(xy 295.902496 -403.547558) (xy 295.964401 -403.563455) (xy 296.023825 -403.586986) (xy 296.079832 -403.617779)
			(xy 296.131538 -403.655348) (xy 296.178128 -403.699102) (xy 296.218866 -403.748349) (xy 296.253112 -403.802314)
			(xy 296.280324 -403.860145) (xy 296.300074 -403.920931) (xy 296.312049 -403.983712) (xy 296.316063 -404.0475)
			(xy 297.07602 -404.0475) (xy 297.080035 -403.983693) (xy 297.092015 -403.920892) (xy 297.111773 -403.860089)
			(xy 297.138995 -403.802241) (xy 297.173253 -403.748261) (xy 297.214007 -403.699001) (xy 297.260613 -403.655237)
			(xy 297.312338 -403.61766) (xy 297.368364 -403.586862) (xy 297.427809 -403.563329) (xy 297.489734 -403.547433)
			(xy 297.553163 -403.539423) (xy 297.58513 -403.538944) (xy 297.585384 -403.538944) (xy 297.617131 -403.539444)
			(xy 297.680127 -403.547377) (xy 297.741647 -403.563084) (xy 297.800736 -403.586322) (xy 297.856476 -403.616728)
			(xy 297.908 -403.653832) (xy 297.931586 -403.675088) (xy 297.938849 -403.681272) (xy 297.956599 -403.688223)
			(xy 297.975661 -403.688223) (xy 297.993411 -403.681272) (xy 298.000674 -403.675088) (xy 298.02425 -403.653817)
			(xy 298.075761 -403.616686) (xy 298.131498 -403.586265) (xy 298.190592 -403.563026) (xy 298.252121 -403.547332)
			(xy 298.315126 -403.539429) (xy 298.346876 -403.538944) (xy 298.34713 -403.538944) (xy 298.379087 -403.539544)
			(xy 298.442496 -403.547558) (xy 298.504401 -403.563455) (xy 298.563825 -403.586986) (xy 298.619832 -403.617779)
			(xy 298.671538 -403.655348) (xy 298.718128 -403.699102) (xy 298.758866 -403.748349) (xy 298.793112 -403.802314)
			(xy 298.820324 -403.860145) (xy 298.836897 -403.911152) (xy 303.599054 -403.911152) (xy 303.599054 -403.856648)
			(xy 303.60681 -403.802698) (xy 303.622166 -403.7504) (xy 303.644808 -403.700821) (xy 303.674275 -403.654968)
			(xy 303.709967 -403.613776) (xy 303.751159 -403.578082) (xy 303.79701 -403.548613) (xy 303.846589 -403.52597)
			(xy 303.898886 -403.510613) (xy 303.952836 -403.502855) (xy 303.980088 -403.502368) (xy 304.843688 -403.502368)
			(xy 304.87094 -403.502878) (xy 304.924889 -403.510634) (xy 304.977185 -403.525988) (xy 305.026763 -403.548628)
			(xy 305.072615 -403.578094) (xy 305.113806 -403.613785) (xy 305.149499 -403.654976) (xy 305.178966 -403.700826)
			(xy 305.201608 -403.750404) (xy 305.216964 -403.8027) (xy 305.224721 -403.856648) (xy 305.224721 -403.911152)
			(xy 305.22472 -403.911156) (xy 306.662231 -403.911156) (xy 306.662231 -403.856644) (xy 306.669989 -403.802687)
			(xy 306.685348 -403.750384) (xy 306.707994 -403.700799) (xy 306.737466 -403.654941) (xy 306.773165 -403.613745)
			(xy 306.814364 -403.578049) (xy 306.860223 -403.54858) (xy 306.90981 -403.525938) (xy 306.962115 -403.510583)
			(xy 307.016072 -403.502829) (xy 307.043328 -403.502368) (xy 307.906928 -403.502368) (xy 307.934176 -403.502904)
			(xy 307.988117 -403.510663) (xy 308.040405 -403.52602) (xy 308.089976 -403.548661) (xy 308.13582 -403.578126)
			(xy 308.177004 -403.613816) (xy 308.21269 -403.655002) (xy 308.242152 -403.700849) (xy 308.26479 -403.750421)
			(xy 308.280143 -403.80271) (xy 308.287898 -403.856652) (xy 308.287898 -403.911148) (xy 308.287897 -403.911152)
			(xy 309.725554 -403.911152) (xy 309.725554 -403.856648) (xy 309.73331 -403.8027) (xy 309.748664 -403.750405)
			(xy 309.771305 -403.700826) (xy 309.80077 -403.654975) (xy 309.83646 -403.613783) (xy 309.877649 -403.578089)
			(xy 309.923498 -403.54862) (xy 309.973075 -403.525976) (xy 310.025369 -403.510617) (xy 310.079317 -403.502856)
			(xy 310.106568 -403.502368) (xy 310.970168 -403.502368) (xy 310.997421 -403.502877) (xy 311.051372 -403.51063)
			(xy 311.10367 -403.525982) (xy 311.153251 -403.548621) (xy 311.199105 -403.578087) (xy 311.240299 -403.613778)
			(xy 311.275994 -403.654969) (xy 311.305463 -403.700821) (xy 311.328107 -403.7504) (xy 311.343463 -403.802697)
			(xy 311.351221 -403.856647) (xy 311.351221 -403.911153) (xy 311.351221 -403.911155) (xy 312.788731 -403.911155)
			(xy 312.788731 -403.856645) (xy 312.796489 -403.80269) (xy 312.811846 -403.750388) (xy 312.834491 -403.700804)
			(xy 312.863961 -403.654948) (xy 312.899658 -403.613752) (xy 312.940854 -403.578056) (xy 312.986711 -403.548587)
			(xy 313.036296 -403.525943) (xy 313.088598 -403.510587) (xy 313.142553 -403.50283) (xy 313.169808 -403.502368)
			(xy 314.033408 -403.502368) (xy 314.060657 -403.502903) (xy 314.114601 -403.51066) (xy 314.166891 -403.526015)
			(xy 314.216464 -403.548655) (xy 314.26231 -403.578119) (xy 314.303497 -403.613809) (xy 314.339186 -403.654996)
			(xy 314.368649 -403.700843) (xy 314.391288 -403.750417) (xy 314.406642 -403.802707) (xy 314.414398 -403.856651)
			(xy 314.414398 -403.911149) (xy 314.414397 -403.911157) (xy 315.851931 -403.911157) (xy 315.851931 -403.856643)
			(xy 315.85969 -403.802685) (xy 315.875049 -403.75038) (xy 315.897697 -403.700793) (xy 315.927171 -403.654935)
			(xy 315.962872 -403.613738) (xy 316.004073 -403.578042) (xy 316.049935 -403.548574) (xy 316.099525 -403.525932)
			(xy 316.151832 -403.51058) (xy 316.205791 -403.502828) (xy 316.233048 -403.502368) (xy 317.096648 -403.502368)
			(xy 317.123895 -403.502905) (xy 317.177834 -403.510667) (xy 317.23012 -403.526025) (xy 317.279688 -403.548668)
			(xy 317.325529 -403.578133) (xy 317.366711 -403.613823) (xy 317.402395 -403.655009) (xy 317.431855 -403.700854)
			(xy 317.454491 -403.750425) (xy 317.469843 -403.802713) (xy 317.477598 -403.856653) (xy 317.477598 -403.911147)
			(xy 317.477597 -403.911152) (xy 318.915254 -403.911152) (xy 318.915254 -403.856648) (xy 318.92301 -403.802698)
			(xy 318.938366 -403.7504) (xy 318.961008 -403.700821) (xy 318.990475 -403.654968) (xy 319.026167 -403.613776)
			(xy 319.067359 -403.578082) (xy 319.11321 -403.548613) (xy 319.162789 -403.52597) (xy 319.215086 -403.510613)
			(xy 319.269036 -403.502855) (xy 319.296288 -403.502368) (xy 320.159888 -403.502368) (xy 320.18714 -403.502878)
			(xy 320.241089 -403.510634) (xy 320.293385 -403.525988) (xy 320.342963 -403.548628) (xy 320.388815 -403.578094)
			(xy 320.430006 -403.613785) (xy 320.465699 -403.654976) (xy 320.495166 -403.700826) (xy 320.517808 -403.750404)
			(xy 320.533164 -403.8027) (xy 320.540921 -403.856648) (xy 320.540921 -403.911152) (xy 320.54092 -403.911156)
			(xy 321.978431 -403.911156) (xy 321.978431 -403.856644) (xy 321.986189 -403.802687) (xy 322.001548 -403.750384)
			(xy 322.024194 -403.700799) (xy 322.053666 -403.654941) (xy 322.089365 -403.613745) (xy 322.130564 -403.578049)
			(xy 322.176423 -403.54858) (xy 322.22601 -403.525938) (xy 322.278315 -403.510583) (xy 322.332272 -403.502829)
			(xy 322.359528 -403.502368) (xy 323.223128 -403.502368) (xy 323.250376 -403.502904) (xy 323.304317 -403.510663)
			(xy 323.356605 -403.52602) (xy 323.406176 -403.548661) (xy 323.45202 -403.578126) (xy 323.493204 -403.613816)
			(xy 323.52889 -403.655002) (xy 323.558352 -403.700849) (xy 323.58099 -403.750421) (xy 323.596343 -403.80271)
			(xy 323.604098 -403.856652) (xy 323.604098 -403.911148) (xy 323.604097 -403.911152) (xy 325.041754 -403.911152)
			(xy 325.041754 -403.856648) (xy 325.04951 -403.8027) (xy 325.064864 -403.750405) (xy 325.087505 -403.700826)
			(xy 325.11697 -403.654975) (xy 325.15266 -403.613783) (xy 325.193849 -403.578089) (xy 325.239698 -403.54862)
			(xy 325.289275 -403.525976) (xy 325.341569 -403.510617) (xy 325.395517 -403.502856) (xy 325.422768 -403.502368)
			(xy 326.286368 -403.502368) (xy 326.313621 -403.502877) (xy 326.367572 -403.51063) (xy 326.41987 -403.525982)
			(xy 326.469451 -403.548621) (xy 326.515305 -403.578087) (xy 326.556499 -403.613778) (xy 326.592194 -403.654969)
			(xy 326.621663 -403.700821) (xy 326.644307 -403.7504) (xy 326.659663 -403.802697) (xy 326.667421 -403.856647)
			(xy 326.667421 -403.911153) (xy 326.667421 -403.911155) (xy 328.104931 -403.911155) (xy 328.104931 -403.856645)
			(xy 328.112689 -403.80269) (xy 328.128046 -403.750388) (xy 328.150691 -403.700804) (xy 328.180161 -403.654948)
			(xy 328.215858 -403.613752) (xy 328.257054 -403.578056) (xy 328.302911 -403.548587) (xy 328.352496 -403.525943)
			(xy 328.404798 -403.510587) (xy 328.458753 -403.50283) (xy 328.486008 -403.502368) (xy 329.349608 -403.502368)
			(xy 329.376857 -403.502903) (xy 329.430801 -403.51066) (xy 329.483091 -403.526015) (xy 329.532664 -403.548655)
			(xy 329.57851 -403.578119) (xy 329.619697 -403.613809) (xy 329.655386 -403.654996) (xy 329.684849 -403.700843)
			(xy 329.707488 -403.750417) (xy 329.722842 -403.802707) (xy 329.730598 -403.856651) (xy 329.730598 -403.911149)
			(xy 329.730597 -403.911157) (xy 331.168131 -403.911157) (xy 331.168131 -403.856643) (xy 331.17589 -403.802685)
			(xy 331.191249 -403.75038) (xy 331.213897 -403.700793) (xy 331.243371 -403.654935) (xy 331.279072 -403.613738)
			(xy 331.320273 -403.578042) (xy 331.366135 -403.548574) (xy 331.415725 -403.525932) (xy 331.468032 -403.51058)
			(xy 331.521991 -403.502828) (xy 331.549248 -403.502368) (xy 332.412848 -403.502368) (xy 332.440095 -403.502905)
			(xy 332.494034 -403.510667) (xy 332.54632 -403.526025) (xy 332.595888 -403.548668) (xy 332.641729 -403.578133)
			(xy 332.682911 -403.613823) (xy 332.718595 -403.655009) (xy 332.748055 -403.700854) (xy 332.770691 -403.750425)
			(xy 332.786043 -403.802713) (xy 332.793798 -403.856653) (xy 332.793798 -403.911147) (xy 332.793797 -403.911152)
			(xy 334.231454 -403.911152) (xy 334.231454 -403.856648) (xy 334.23921 -403.802698) (xy 334.254566 -403.7504)
			(xy 334.277208 -403.700821) (xy 334.306675 -403.654968) (xy 334.342367 -403.613776) (xy 334.383559 -403.578082)
			(xy 334.42941 -403.548613) (xy 334.478989 -403.52597) (xy 334.531286 -403.510613) (xy 334.585236 -403.502855)
			(xy 334.612488 -403.502368) (xy 335.476088 -403.502368) (xy 335.50334 -403.502878) (xy 335.557289 -403.510634)
			(xy 335.609585 -403.525988) (xy 335.659163 -403.548628) (xy 335.705015 -403.578094) (xy 335.746206 -403.613785)
			(xy 335.781899 -403.654976) (xy 335.811366 -403.700826) (xy 335.834008 -403.750404) (xy 335.849364 -403.8027)
			(xy 335.857121 -403.856648) (xy 335.857121 -403.911152) (xy 335.85712 -403.911156) (xy 337.294631 -403.911156)
			(xy 337.294631 -403.856644) (xy 337.302389 -403.802687) (xy 337.317748 -403.750384) (xy 337.340394 -403.700799)
			(xy 337.369866 -403.654941) (xy 337.405565 -403.613745) (xy 337.446764 -403.578049) (xy 337.492623 -403.54858)
			(xy 337.54221 -403.525938) (xy 337.594515 -403.510583) (xy 337.648472 -403.502829) (xy 337.675728 -403.502368)
			(xy 338.539328 -403.502368) (xy 338.566576 -403.502904) (xy 338.620517 -403.510663) (xy 338.672805 -403.52602)
			(xy 338.722376 -403.548661) (xy 338.76822 -403.578126) (xy 338.809404 -403.613816) (xy 338.84509 -403.655002)
			(xy 338.874552 -403.700849) (xy 338.89719 -403.750421) (xy 338.912543 -403.80271) (xy 338.920298 -403.856652)
			(xy 338.920298 -403.911148) (xy 338.920297 -403.911152) (xy 340.357954 -403.911152) (xy 340.357954 -403.856648)
			(xy 340.36571 -403.8027) (xy 340.381064 -403.750405) (xy 340.403705 -403.700826) (xy 340.43317 -403.654975)
			(xy 340.46886 -403.613783) (xy 340.510049 -403.578089) (xy 340.555898 -403.54862) (xy 340.605475 -403.525976)
			(xy 340.657769 -403.510617) (xy 340.711717 -403.502856) (xy 340.738968 -403.502368) (xy 341.602568 -403.502368)
			(xy 341.629821 -403.502877) (xy 341.683772 -403.51063) (xy 341.73607 -403.525982) (xy 341.785651 -403.548621)
			(xy 341.831505 -403.578087) (xy 341.872699 -403.613778) (xy 341.908394 -403.654969) (xy 341.937863 -403.700821)
			(xy 341.960507 -403.7504) (xy 341.975863 -403.802697) (xy 341.983621 -403.856647) (xy 341.983621 -403.911153)
			(xy 341.983621 -403.911155) (xy 343.421131 -403.911155) (xy 343.421131 -403.856645) (xy 343.428889 -403.80269)
			(xy 343.444246 -403.750388) (xy 343.466891 -403.700804) (xy 343.496361 -403.654948) (xy 343.532058 -403.613752)
			(xy 343.573254 -403.578056) (xy 343.619111 -403.548587) (xy 343.668696 -403.525943) (xy 343.720998 -403.510587)
			(xy 343.774953 -403.50283) (xy 343.802208 -403.502368) (xy 344.665808 -403.502368) (xy 344.693057 -403.502903)
			(xy 344.747001 -403.51066) (xy 344.799291 -403.526015) (xy 344.848864 -403.548655) (xy 344.89471 -403.578119)
			(xy 344.935897 -403.613809) (xy 344.971586 -403.654996) (xy 345.001049 -403.700843) (xy 345.023688 -403.750417)
			(xy 345.039042 -403.802707) (xy 345.046798 -403.856651) (xy 345.046798 -403.911149) (xy 345.046797 -403.911157)
			(xy 346.484331 -403.911157) (xy 346.484331 -403.856643) (xy 346.49209 -403.802685) (xy 346.507449 -403.75038)
			(xy 346.530097 -403.700793) (xy 346.559571 -403.654935) (xy 346.595272 -403.613738) (xy 346.636473 -403.578042)
			(xy 346.682335 -403.548574) (xy 346.731925 -403.525932) (xy 346.784232 -403.51058) (xy 346.838191 -403.502828)
			(xy 346.865448 -403.502368) (xy 347.729048 -403.502368) (xy 347.756295 -403.502905) (xy 347.810234 -403.510667)
			(xy 347.86252 -403.526025) (xy 347.912088 -403.548668) (xy 347.957929 -403.578133) (xy 347.999111 -403.613823)
			(xy 348.034795 -403.655009) (xy 348.064255 -403.700854) (xy 348.086891 -403.750425) (xy 348.102243 -403.802713)
			(xy 348.109998 -403.856653) (xy 348.109998 -403.911147) (xy 348.109997 -403.911152) (xy 349.547654 -403.911152)
			(xy 349.547654 -403.856648) (xy 349.55541 -403.802698) (xy 349.570766 -403.7504) (xy 349.593408 -403.700821)
			(xy 349.622875 -403.654968) (xy 349.658567 -403.613776) (xy 349.699759 -403.578082) (xy 349.74561 -403.548613)
			(xy 349.795189 -403.52597) (xy 349.847486 -403.510613) (xy 349.901436 -403.502855) (xy 349.928688 -403.502368)
			(xy 350.792288 -403.502368) (xy 350.81954 -403.502878) (xy 350.873489 -403.510634) (xy 350.925785 -403.525988)
			(xy 350.975363 -403.548628) (xy 351.021215 -403.578094) (xy 351.062406 -403.613785) (xy 351.098099 -403.654976)
			(xy 351.127566 -403.700826) (xy 351.150208 -403.750404) (xy 351.165564 -403.8027) (xy 351.173321 -403.856648)
			(xy 351.173321 -403.911152) (xy 351.17332 -403.911156) (xy 371.041831 -403.911156) (xy 371.041831 -403.856644)
			(xy 371.049589 -403.802687) (xy 371.064948 -403.750383) (xy 371.087594 -403.700798) (xy 371.117067 -403.654941)
			(xy 371.152766 -403.613745) (xy 371.193965 -403.578049) (xy 371.239824 -403.54858) (xy 371.289412 -403.525937)
			(xy 371.341716 -403.510583) (xy 371.395674 -403.502829) (xy 371.42293 -403.502368) (xy 372.28653 -403.502368)
			(xy 372.313778 -403.502904) (xy 372.367719 -403.510664) (xy 372.420007 -403.52602) (xy 372.469577 -403.548662)
			(xy 372.515421 -403.578127) (xy 372.556605 -403.613816) (xy 372.592291 -403.655003) (xy 372.621753 -403.700849)
			(xy 372.64439 -403.750421) (xy 372.659743 -403.80271) (xy 372.667498 -403.856652) (xy 372.667498 -403.911148)
			(xy 372.667497 -403.911152) (xy 374.105154 -403.911152) (xy 374.105154 -403.856648) (xy 374.11291 -403.8027)
			(xy 374.128265 -403.750404) (xy 374.150905 -403.700826) (xy 374.18037 -403.654974) (xy 374.216061 -403.613782)
			(xy 374.25725 -403.578088) (xy 374.3031 -403.548619) (xy 374.352676 -403.525975) (xy 374.404971 -403.510616)
			(xy 374.458918 -403.502856) (xy 374.48617 -403.502368) (xy 375.34977 -403.502368) (xy 375.377023 -403.502877)
			(xy 375.430973 -403.51063) (xy 375.483271 -403.525983) (xy 375.532852 -403.548622) (xy 375.578706 -403.578087)
			(xy 375.6199 -403.613779) (xy 375.655595 -403.65497) (xy 375.685064 -403.700821) (xy 375.707707 -403.7504)
			(xy 375.723063 -403.802697) (xy 375.730821 -403.856647) (xy 375.730821 -403.911153) (xy 375.730821 -403.911155)
			(xy 377.168331 -403.911155) (xy 377.168331 -403.856645) (xy 377.176089 -403.80269) (xy 377.191446 -403.750388)
			(xy 377.214091 -403.700804) (xy 377.243562 -403.654947) (xy 377.279259 -403.613752) (xy 377.320455 -403.578056)
			(xy 377.366313 -403.548586) (xy 377.415897 -403.525943) (xy 377.468199 -403.510587) (xy 377.522155 -403.50283)
			(xy 377.54941 -403.502368) (xy 378.41301 -403.502368) (xy 378.440259 -403.502903) (xy 378.494202 -403.51066)
			(xy 378.546492 -403.526015) (xy 378.596065 -403.548655) (xy 378.641911 -403.57812) (xy 378.683098 -403.613809)
			(xy 378.718786 -403.654997) (xy 378.748249 -403.700844) (xy 378.770888 -403.750417) (xy 378.786242 -403.802708)
			(xy 378.793998 -403.856651) (xy 378.793998 -403.911149) (xy 378.793998 -403.911151) (xy 380.231654 -403.911151)
			(xy 380.231654 -403.856649) (xy 380.239409 -403.802703) (xy 380.254763 -403.750409) (xy 380.277402 -403.700832)
			(xy 380.306865 -403.654981) (xy 380.342554 -403.613789) (xy 380.383741 -403.578095) (xy 380.429588 -403.548626)
			(xy 380.479162 -403.52598) (xy 380.531454 -403.51062) (xy 380.585399 -403.502857) (xy 380.61265 -403.502368)
			(xy 381.47625 -403.502368) (xy 381.503503 -403.502876) (xy 381.557456 -403.510627) (xy 381.609757 -403.525977)
			(xy 381.65934 -403.548616) (xy 381.705197 -403.57808) (xy 381.746393 -403.613772) (xy 381.78209 -403.654963)
			(xy 381.81156 -403.700816) (xy 381.834205 -403.750396) (xy 381.849563 -403.802695) (xy 381.857321 -403.856647)
			(xy 381.857321 -403.911153) (xy 383.294854 -403.911153) (xy 383.294854 -403.856647) (xy 383.302611 -403.802697)
			(xy 383.317966 -403.7504) (xy 383.340608 -403.70082) (xy 383.370075 -403.654968) (xy 383.405768 -403.613775)
			(xy 383.44696 -403.578081) (xy 383.492812 -403.548613) (xy 383.542391 -403.52597) (xy 383.594687 -403.510613)
			(xy 383.648638 -403.502855) (xy 383.67589 -403.502368) (xy 384.53949 -403.502368) (xy 384.566742 -403.502879)
			(xy 384.62069 -403.510634) (xy 384.672986 -403.525988) (xy 384.722564 -403.548629) (xy 384.768416 -403.578095)
			(xy 384.809607 -403.613786) (xy 384.845299 -403.654976) (xy 384.874767 -403.700827) (xy 384.897408 -403.750405)
			(xy 384.912764 -403.8027) (xy 384.920521 -403.856648) (xy 384.920521 -403.911152) (xy 384.92052 -403.911156)
			(xy 386.358031 -403.911156) (xy 386.358031 -403.856644) (xy 386.365789 -403.802687) (xy 386.381148 -403.750383)
			(xy 386.403794 -403.700798) (xy 386.433267 -403.654941) (xy 386.468966 -403.613745) (xy 386.510165 -403.578049)
			(xy 386.556024 -403.54858) (xy 386.605612 -403.525937) (xy 386.657916 -403.510583) (xy 386.711874 -403.502829)
			(xy 386.73913 -403.502368) (xy 387.60273 -403.502368) (xy 387.629978 -403.502904) (xy 387.683919 -403.510664)
			(xy 387.736207 -403.52602) (xy 387.785777 -403.548662) (xy 387.831621 -403.578127) (xy 387.872805 -403.613816)
			(xy 387.908491 -403.655003) (xy 387.937953 -403.700849) (xy 387.96059 -403.750421) (xy 387.975943 -403.80271)
			(xy 387.983698 -403.856652) (xy 387.983698 -403.911148) (xy 387.983697 -403.911152) (xy 389.421354 -403.911152)
			(xy 389.421354 -403.856648) (xy 389.42911 -403.8027) (xy 389.444465 -403.750404) (xy 389.467105 -403.700826)
			(xy 389.49657 -403.654974) (xy 389.532261 -403.613782) (xy 389.57345 -403.578088) (xy 389.6193 -403.548619)
			(xy 389.668876 -403.525975) (xy 389.721171 -403.510616) (xy 389.775118 -403.502856) (xy 389.80237 -403.502368)
			(xy 390.66597 -403.502368) (xy 390.693223 -403.502877) (xy 390.747173 -403.51063) (xy 390.799471 -403.525983)
			(xy 390.849052 -403.548622) (xy 390.894906 -403.578087) (xy 390.9361 -403.613779) (xy 390.971795 -403.65497)
			(xy 391.001264 -403.700821) (xy 391.023907 -403.7504) (xy 391.039263 -403.802697) (xy 391.047021 -403.856647)
			(xy 391.047021 -403.911153) (xy 391.047021 -403.911155) (xy 392.484531 -403.911155) (xy 392.484531 -403.856645)
			(xy 392.492289 -403.80269) (xy 392.507646 -403.750388) (xy 392.530291 -403.700804) (xy 392.559762 -403.654947)
			(xy 392.595459 -403.613752) (xy 392.636655 -403.578056) (xy 392.682513 -403.548586) (xy 392.732097 -403.525943)
			(xy 392.784399 -403.510587) (xy 392.838355 -403.50283) (xy 392.86561 -403.502368) (xy 393.72921 -403.502368)
			(xy 393.756459 -403.502903) (xy 393.810402 -403.51066) (xy 393.862692 -403.526015) (xy 393.912265 -403.548655)
			(xy 393.958111 -403.57812) (xy 393.999298 -403.613809) (xy 394.034986 -403.654997) (xy 394.064449 -403.700844)
			(xy 394.087088 -403.750417) (xy 394.102442 -403.802708) (xy 394.110198 -403.856651) (xy 394.110198 -403.911149)
			(xy 394.110198 -403.911151) (xy 395.547854 -403.911151) (xy 395.547854 -403.856649) (xy 395.555609 -403.802703)
			(xy 395.570963 -403.750409) (xy 395.593602 -403.700832) (xy 395.623065 -403.654981) (xy 395.658754 -403.613789)
			(xy 395.699941 -403.578095) (xy 395.745788 -403.548626) (xy 395.795362 -403.52598) (xy 395.847654 -403.51062)
			(xy 395.901599 -403.502857) (xy 395.92885 -403.502368) (xy 396.79245 -403.502368) (xy 396.819703 -403.502876)
			(xy 396.873656 -403.510627) (xy 396.925957 -403.525977) (xy 396.97554 -403.548616) (xy 397.021397 -403.57808)
			(xy 397.062593 -403.613772) (xy 397.09829 -403.654963) (xy 397.12776 -403.700816) (xy 397.150405 -403.750396)
			(xy 397.165763 -403.802695) (xy 397.173521 -403.856647) (xy 397.173521 -403.911153) (xy 398.611054 -403.911153)
			(xy 398.611054 -403.856647) (xy 398.618811 -403.802697) (xy 398.634166 -403.7504) (xy 398.656808 -403.70082)
			(xy 398.686275 -403.654968) (xy 398.721968 -403.613775) (xy 398.76316 -403.578081) (xy 398.809012 -403.548613)
			(xy 398.858591 -403.52597) (xy 398.910887 -403.510613) (xy 398.964838 -403.502855) (xy 398.99209 -403.502368)
			(xy 399.85569 -403.502368) (xy 399.882942 -403.502879) (xy 399.93689 -403.510634) (xy 399.989186 -403.525988)
			(xy 400.038764 -403.548629) (xy 400.084616 -403.578095) (xy 400.125807 -403.613786) (xy 400.161499 -403.654976)
			(xy 400.190967 -403.700827) (xy 400.213608 -403.750405) (xy 400.228964 -403.8027) (xy 400.236721 -403.856648)
			(xy 400.236721 -403.911152) (xy 400.23672 -403.911156) (xy 401.674231 -403.911156) (xy 401.674231 -403.856644)
			(xy 401.681989 -403.802687) (xy 401.697348 -403.750383) (xy 401.719994 -403.700798) (xy 401.749467 -403.654941)
			(xy 401.785166 -403.613745) (xy 401.826365 -403.578049) (xy 401.872224 -403.54858) (xy 401.921812 -403.525937)
			(xy 401.974116 -403.510583) (xy 402.028074 -403.502829) (xy 402.05533 -403.502368) (xy 402.91893 -403.502368)
			(xy 402.946178 -403.502904) (xy 403.000119 -403.510664) (xy 403.052407 -403.52602) (xy 403.101977 -403.548662)
			(xy 403.147821 -403.578127) (xy 403.189005 -403.613816) (xy 403.224691 -403.655003) (xy 403.254153 -403.700849)
			(xy 403.27679 -403.750421) (xy 403.292143 -403.80271) (xy 403.299898 -403.856652) (xy 403.299898 -403.911148)
			(xy 403.299897 -403.911152) (xy 404.737554 -403.911152) (xy 404.737554 -403.856648) (xy 404.74531 -403.8027)
			(xy 404.760665 -403.750404) (xy 404.783305 -403.700826) (xy 404.81277 -403.654974) (xy 404.848461 -403.613782)
			(xy 404.88965 -403.578088) (xy 404.9355 -403.548619) (xy 404.985076 -403.525975) (xy 405.037371 -403.510616)
			(xy 405.091318 -403.502856) (xy 405.11857 -403.502368) (xy 405.98217 -403.502368) (xy 406.009423 -403.502877)
			(xy 406.063373 -403.51063) (xy 406.115671 -403.525983) (xy 406.165252 -403.548622) (xy 406.211106 -403.578087)
			(xy 406.2523 -403.613779) (xy 406.287995 -403.65497) (xy 406.317464 -403.700821) (xy 406.340107 -403.7504)
			(xy 406.355463 -403.802697) (xy 406.363221 -403.856647) (xy 406.363221 -403.911153) (xy 406.363221 -403.911155)
			(xy 407.800731 -403.911155) (xy 407.800731 -403.856645) (xy 407.808489 -403.80269) (xy 407.823846 -403.750388)
			(xy 407.846491 -403.700804) (xy 407.875962 -403.654947) (xy 407.911659 -403.613752) (xy 407.952855 -403.578056)
			(xy 407.998713 -403.548586) (xy 408.048297 -403.525943) (xy 408.100599 -403.510587) (xy 408.154555 -403.50283)
			(xy 408.18181 -403.502368) (xy 409.04541 -403.502368) (xy 409.072659 -403.502903) (xy 409.126602 -403.51066)
			(xy 409.178892 -403.526015) (xy 409.228465 -403.548655) (xy 409.274311 -403.57812) (xy 409.315498 -403.613809)
			(xy 409.351186 -403.654997) (xy 409.380649 -403.700844) (xy 409.403288 -403.750417) (xy 409.418642 -403.802708)
			(xy 409.426398 -403.856651) (xy 409.426398 -403.911149) (xy 409.426398 -403.911151) (xy 410.864054 -403.911151)
			(xy 410.864054 -403.856649) (xy 410.871809 -403.802703) (xy 410.887163 -403.750409) (xy 410.909802 -403.700832)
			(xy 410.939265 -403.654981) (xy 410.974954 -403.613789) (xy 411.016141 -403.578095) (xy 411.061988 -403.548626)
			(xy 411.111562 -403.52598) (xy 411.163854 -403.51062) (xy 411.217799 -403.502857) (xy 411.24505 -403.502368)
			(xy 412.10865 -403.502368) (xy 412.135903 -403.502876) (xy 412.189856 -403.510627) (xy 412.242157 -403.525977)
			(xy 412.29174 -403.548616) (xy 412.337597 -403.57808) (xy 412.378793 -403.613772) (xy 412.41449 -403.654963)
			(xy 412.44396 -403.700816) (xy 412.466605 -403.750396) (xy 412.481963 -403.802695) (xy 412.489721 -403.856647)
			(xy 412.489721 -403.911153) (xy 413.927254 -403.911153) (xy 413.927254 -403.856647) (xy 413.935011 -403.802697)
			(xy 413.950366 -403.7504) (xy 413.973008 -403.70082) (xy 414.002475 -403.654968) (xy 414.038168 -403.613775)
			(xy 414.07936 -403.578081) (xy 414.125212 -403.548613) (xy 414.174791 -403.52597) (xy 414.227087 -403.510613)
			(xy 414.281038 -403.502855) (xy 414.30829 -403.502368) (xy 415.17189 -403.502368) (xy 415.199142 -403.502879)
			(xy 415.25309 -403.510634) (xy 415.305386 -403.525988) (xy 415.354964 -403.548629) (xy 415.400816 -403.578095)
			(xy 415.442007 -403.613786) (xy 415.477699 -403.654976) (xy 415.507167 -403.700827) (xy 415.529808 -403.750405)
			(xy 415.545164 -403.8027) (xy 415.552921 -403.856648) (xy 415.552921 -403.911152) (xy 415.55292 -403.911156)
			(xy 416.990431 -403.911156) (xy 416.990431 -403.856644) (xy 416.998189 -403.802687) (xy 417.013548 -403.750383)
			(xy 417.036194 -403.700798) (xy 417.065667 -403.654941) (xy 417.101366 -403.613745) (xy 417.142565 -403.578049)
			(xy 417.188424 -403.54858) (xy 417.238012 -403.525937) (xy 417.290316 -403.510583) (xy 417.344274 -403.502829)
			(xy 417.37153 -403.502368) (xy 418.23513 -403.502368) (xy 418.262378 -403.502904) (xy 418.316319 -403.510664)
			(xy 418.368607 -403.52602) (xy 418.418177 -403.548662) (xy 418.464021 -403.578127) (xy 418.505205 -403.613816)
			(xy 418.540891 -403.655003) (xy 418.570353 -403.700849) (xy 418.59299 -403.750421) (xy 418.608343 -403.80271)
			(xy 418.616098 -403.856652) (xy 418.616098 -403.911148) (xy 418.608343 -403.96509) (xy 418.59299 -404.017379)
			(xy 418.570353 -404.066951) (xy 418.540891 -404.112797) (xy 418.505205 -404.153984) (xy 418.464021 -404.189673)
			(xy 418.418177 -404.219138) (xy 418.368607 -404.24178) (xy 418.316319 -404.257136) (xy 418.262378 -404.264896)
			(xy 418.23513 -404.265384) (xy 417.37153 -404.265384) (xy 417.344274 -404.264971) (xy 417.290316 -404.257217)
			(xy 417.238012 -404.241863) (xy 417.188424 -404.21922) (xy 417.142565 -404.189751) (xy 417.101366 -404.154055)
			(xy 417.065667 -404.112859) (xy 417.036194 -404.067002) (xy 417.013548 -404.017417) (xy 416.998189 -403.965113)
			(xy 416.990431 -403.911156) (xy 415.55292 -403.911156) (xy 415.545164 -403.9651) (xy 415.529808 -404.017395)
			(xy 415.507167 -404.066973) (xy 415.477699 -404.112824) (xy 415.442007 -404.154014) (xy 415.400816 -404.189705)
			(xy 415.354964 -404.219171) (xy 415.305386 -404.241812) (xy 415.25309 -404.257166) (xy 415.199142 -404.264921)
			(xy 415.17189 -404.265384) (xy 414.30829 -404.265384) (xy 414.281038 -404.264945) (xy 414.227087 -404.257187)
			(xy 414.174791 -404.24183) (xy 414.125212 -404.219187) (xy 414.07936 -404.189719) (xy 414.038168 -404.154025)
			(xy 414.002475 -404.112832) (xy 413.973008 -404.06698) (xy 413.950366 -404.0174) (xy 413.935011 -403.965103)
			(xy 413.927254 -403.911153) (xy 412.489721 -403.911153) (xy 412.481963 -403.965105) (xy 412.466605 -404.017404)
			(xy 412.44396 -404.066984) (xy 412.41449 -404.112837) (xy 412.378793 -404.154028) (xy 412.337597 -404.18972)
			(xy 412.29174 -404.219184) (xy 412.242157 -404.241823) (xy 412.189856 -404.257173) (xy 412.135903 -404.264924)
			(xy 412.10865 -404.265384) (xy 411.24505 -404.265384) (xy 411.217799 -404.264943) (xy 411.163854 -404.25718)
			(xy 411.111562 -404.24182) (xy 411.061988 -404.219174) (xy 411.016141 -404.189705) (xy 410.974954 -404.154011)
			(xy 410.939265 -404.112819) (xy 410.909802 -404.066968) (xy 410.887163 -404.017391) (xy 410.871809 -403.965097)
			(xy 410.864054 -403.911151) (xy 409.426398 -403.911151) (xy 409.418642 -403.965092) (xy 409.403288 -404.017383)
			(xy 409.380649 -404.066956) (xy 409.351186 -404.112803) (xy 409.315498 -404.153991) (xy 409.274311 -404.18968)
			(xy 409.228465 -404.219145) (xy 409.178892 -404.241785) (xy 409.126602 -404.25714) (xy 409.072659 -404.264897)
			(xy 409.04541 -404.265384) (xy 408.18181 -404.265384) (xy 408.154555 -404.26497) (xy 408.100599 -404.257213)
			(xy 408.048297 -404.241857) (xy 407.998713 -404.219214) (xy 407.952855 -404.189744) (xy 407.911659 -404.154048)
			(xy 407.875962 -404.112853) (xy 407.846491 -404.066996) (xy 407.823846 -404.017412) (xy 407.808489 -403.96511)
			(xy 407.800731 -403.911155) (xy 406.363221 -403.911155) (xy 406.355463 -403.965103) (xy 406.340107 -404.0174)
			(xy 406.317464 -404.066979) (xy 406.287995 -404.11283) (xy 406.2523 -404.154021) (xy 406.211106 -404.189713)
			(xy 406.165252 -404.219178) (xy 406.115671 -404.241817) (xy 406.063373 -404.25717) (xy 406.009423 -404.264923)
			(xy 405.98217 -404.265384) (xy 405.11857 -404.265384) (xy 405.091318 -404.264944) (xy 405.037371 -404.257184)
			(xy 404.985076 -404.241825) (xy 404.9355 -404.219181) (xy 404.88965 -404.189712) (xy 404.848461 -404.154018)
			(xy 404.81277 -404.112826) (xy 404.783305 -404.066974) (xy 404.760665 -404.017396) (xy 404.74531 -403.9651)
			(xy 404.737554 -403.911152) (xy 403.299897 -403.911152) (xy 403.292143 -403.96509) (xy 403.27679 -404.017379)
			(xy 403.254153 -404.066951) (xy 403.224691 -404.112797) (xy 403.189005 -404.153984) (xy 403.147821 -404.189673)
			(xy 403.101977 -404.219138) (xy 403.052407 -404.24178) (xy 403.000119 -404.257136) (xy 402.946178 -404.264896)
			(xy 402.91893 -404.265384) (xy 402.05533 -404.265384) (xy 402.028074 -404.264971) (xy 401.974116 -404.257217)
			(xy 401.921812 -404.241863) (xy 401.872224 -404.21922) (xy 401.826365 -404.189751) (xy 401.785166 -404.154055)
			(xy 401.749467 -404.112859) (xy 401.719994 -404.067002) (xy 401.697348 -404.017417) (xy 401.681989 -403.965113)
			(xy 401.674231 -403.911156) (xy 400.23672 -403.911156) (xy 400.228964 -403.9651) (xy 400.213608 -404.017395)
			(xy 400.190967 -404.066973) (xy 400.161499 -404.112824) (xy 400.125807 -404.154014) (xy 400.084616 -404.189705)
			(xy 400.038764 -404.219171) (xy 399.989186 -404.241812) (xy 399.93689 -404.257166) (xy 399.882942 -404.264921)
			(xy 399.85569 -404.265384) (xy 398.99209 -404.265384) (xy 398.964838 -404.264945) (xy 398.910887 -404.257187)
			(xy 398.858591 -404.24183) (xy 398.809012 -404.219187) (xy 398.76316 -404.189719) (xy 398.721968 -404.154025)
			(xy 398.686275 -404.112832) (xy 398.656808 -404.06698) (xy 398.634166 -404.0174) (xy 398.618811 -403.965103)
			(xy 398.611054 -403.911153) (xy 397.173521 -403.911153) (xy 397.165763 -403.965105) (xy 397.150405 -404.017404)
			(xy 397.12776 -404.066984) (xy 397.09829 -404.112837) (xy 397.062593 -404.154028) (xy 397.021397 -404.18972)
			(xy 396.97554 -404.219184) (xy 396.925957 -404.241823) (xy 396.873656 -404.257173) (xy 396.819703 -404.264924)
			(xy 396.79245 -404.265384) (xy 395.92885 -404.265384) (xy 395.901599 -404.264943) (xy 395.847654 -404.25718)
			(xy 395.795362 -404.24182) (xy 395.745788 -404.219174) (xy 395.699941 -404.189705) (xy 395.658754 -404.154011)
			(xy 395.623065 -404.112819) (xy 395.593602 -404.066968) (xy 395.570963 -404.017391) (xy 395.555609 -403.965097)
			(xy 395.547854 -403.911151) (xy 394.110198 -403.911151) (xy 394.102442 -403.965092) (xy 394.087088 -404.017383)
			(xy 394.064449 -404.066956) (xy 394.034986 -404.112803) (xy 393.999298 -404.153991) (xy 393.958111 -404.18968)
			(xy 393.912265 -404.219145) (xy 393.862692 -404.241785) (xy 393.810402 -404.25714) (xy 393.756459 -404.264897)
			(xy 393.72921 -404.265384) (xy 392.86561 -404.265384) (xy 392.838355 -404.26497) (xy 392.784399 -404.257213)
			(xy 392.732097 -404.241857) (xy 392.682513 -404.219214) (xy 392.636655 -404.189744) (xy 392.595459 -404.154048)
			(xy 392.559762 -404.112853) (xy 392.530291 -404.066996) (xy 392.507646 -404.017412) (xy 392.492289 -403.96511)
			(xy 392.484531 -403.911155) (xy 391.047021 -403.911155) (xy 391.039263 -403.965103) (xy 391.023907 -404.0174)
			(xy 391.001264 -404.066979) (xy 390.971795 -404.11283) (xy 390.9361 -404.154021) (xy 390.894906 -404.189713)
			(xy 390.849052 -404.219178) (xy 390.799471 -404.241817) (xy 390.747173 -404.25717) (xy 390.693223 -404.264923)
			(xy 390.66597 -404.265384) (xy 389.80237 -404.265384) (xy 389.775118 -404.264944) (xy 389.721171 -404.257184)
			(xy 389.668876 -404.241825) (xy 389.6193 -404.219181) (xy 389.57345 -404.189712) (xy 389.532261 -404.154018)
			(xy 389.49657 -404.112826) (xy 389.467105 -404.066974) (xy 389.444465 -404.017396) (xy 389.42911 -403.9651)
			(xy 389.421354 -403.911152) (xy 387.983697 -403.911152) (xy 387.975943 -403.96509) (xy 387.96059 -404.017379)
			(xy 387.937953 -404.066951) (xy 387.908491 -404.112797) (xy 387.872805 -404.153984) (xy 387.831621 -404.189673)
			(xy 387.785777 -404.219138) (xy 387.736207 -404.24178) (xy 387.683919 -404.257136) (xy 387.629978 -404.264896)
			(xy 387.60273 -404.265384) (xy 386.73913 -404.265384) (xy 386.711874 -404.264971) (xy 386.657916 -404.257217)
			(xy 386.605612 -404.241863) (xy 386.556024 -404.21922) (xy 386.510165 -404.189751) (xy 386.468966 -404.154055)
			(xy 386.433267 -404.112859) (xy 386.403794 -404.067002) (xy 386.381148 -404.017417) (xy 386.365789 -403.965113)
			(xy 386.358031 -403.911156) (xy 384.92052 -403.911156) (xy 384.912764 -403.9651) (xy 384.897408 -404.017395)
			(xy 384.874767 -404.066973) (xy 384.845299 -404.112824) (xy 384.809607 -404.154014) (xy 384.768416 -404.189705)
			(xy 384.722564 -404.219171) (xy 384.672986 -404.241812) (xy 384.62069 -404.257166) (xy 384.566742 -404.264921)
			(xy 384.53949 -404.265384) (xy 383.67589 -404.265384) (xy 383.648638 -404.264945) (xy 383.594687 -404.257187)
			(xy 383.542391 -404.24183) (xy 383.492812 -404.219187) (xy 383.44696 -404.189719) (xy 383.405768 -404.154025)
			(xy 383.370075 -404.112832) (xy 383.340608 -404.06698) (xy 383.317966 -404.0174) (xy 383.302611 -403.965103)
			(xy 383.294854 -403.911153) (xy 381.857321 -403.911153) (xy 381.849563 -403.965105) (xy 381.834205 -404.017404)
			(xy 381.81156 -404.066984) (xy 381.78209 -404.112837) (xy 381.746393 -404.154028) (xy 381.705197 -404.18972)
			(xy 381.65934 -404.219184) (xy 381.609757 -404.241823) (xy 381.557456 -404.257173) (xy 381.503503 -404.264924)
			(xy 381.47625 -404.265384) (xy 380.61265 -404.265384) (xy 380.585399 -404.264943) (xy 380.531454 -404.25718)
			(xy 380.479162 -404.24182) (xy 380.429588 -404.219174) (xy 380.383741 -404.189705) (xy 380.342554 -404.154011)
			(xy 380.306865 -404.112819) (xy 380.277402 -404.066968) (xy 380.254763 -404.017391) (xy 380.239409 -403.965097)
			(xy 380.231654 -403.911151) (xy 378.793998 -403.911151) (xy 378.786242 -403.965092) (xy 378.770888 -404.017383)
			(xy 378.748249 -404.066956) (xy 378.718786 -404.112803) (xy 378.683098 -404.153991) (xy 378.641911 -404.18968)
			(xy 378.596065 -404.219145) (xy 378.546492 -404.241785) (xy 378.494202 -404.25714) (xy 378.440259 -404.264897)
			(xy 378.41301 -404.265384) (xy 377.54941 -404.265384) (xy 377.522155 -404.26497) (xy 377.468199 -404.257213)
			(xy 377.415897 -404.241857) (xy 377.366313 -404.219214) (xy 377.320455 -404.189744) (xy 377.279259 -404.154048)
			(xy 377.243562 -404.112853) (xy 377.214091 -404.066996) (xy 377.191446 -404.017412) (xy 377.176089 -403.96511)
			(xy 377.168331 -403.911155) (xy 375.730821 -403.911155) (xy 375.723063 -403.965103) (xy 375.707707 -404.0174)
			(xy 375.685064 -404.066979) (xy 375.655595 -404.11283) (xy 375.6199 -404.154021) (xy 375.578706 -404.189713)
			(xy 375.532852 -404.219178) (xy 375.483271 -404.241817) (xy 375.430973 -404.25717) (xy 375.377023 -404.264923)
			(xy 375.34977 -404.265384) (xy 374.48617 -404.265384) (xy 374.458918 -404.264944) (xy 374.404971 -404.257184)
			(xy 374.352676 -404.241825) (xy 374.3031 -404.219181) (xy 374.25725 -404.189712) (xy 374.216061 -404.154018)
			(xy 374.18037 -404.112826) (xy 374.150905 -404.066974) (xy 374.128265 -404.017396) (xy 374.11291 -403.9651)
			(xy 374.105154 -403.911152) (xy 372.667497 -403.911152) (xy 372.659743 -403.96509) (xy 372.64439 -404.017379)
			(xy 372.621753 -404.066951) (xy 372.592291 -404.112797) (xy 372.556605 -404.153984) (xy 372.515421 -404.189673)
			(xy 372.469577 -404.219138) (xy 372.420007 -404.24178) (xy 372.367719 -404.257136) (xy 372.313778 -404.264896)
			(xy 372.28653 -404.265384) (xy 371.42293 -404.265384) (xy 371.395674 -404.264971) (xy 371.341716 -404.257217)
			(xy 371.289412 -404.241863) (xy 371.239824 -404.21922) (xy 371.193965 -404.189751) (xy 371.152766 -404.154055)
			(xy 371.117067 -404.112859) (xy 371.087594 -404.067002) (xy 371.064948 -404.017417) (xy 371.049589 -403.965113)
			(xy 371.041831 -403.911156) (xy 351.17332 -403.911156) (xy 351.165564 -403.9651) (xy 351.150208 -404.017396)
			(xy 351.127566 -404.066974) (xy 351.098099 -404.112824) (xy 351.062406 -404.154015) (xy 351.021215 -404.189706)
			(xy 350.975363 -404.219172) (xy 350.925785 -404.241812) (xy 350.873489 -404.257166) (xy 350.81954 -404.264922)
			(xy 350.792288 -404.265384) (xy 349.928688 -404.265384) (xy 349.901436 -404.264945) (xy 349.847486 -404.257187)
			(xy 349.795189 -404.24183) (xy 349.74561 -404.219187) (xy 349.699759 -404.189718) (xy 349.658567 -404.154024)
			(xy 349.622875 -404.112832) (xy 349.593408 -404.066979) (xy 349.570766 -404.0174) (xy 349.55541 -403.965102)
			(xy 349.547654 -403.911152) (xy 348.109997 -403.911152) (xy 348.102243 -403.965087) (xy 348.086891 -404.017375)
			(xy 348.064255 -404.066946) (xy 348.034795 -404.112791) (xy 347.999111 -404.153977) (xy 347.957929 -404.189667)
			(xy 347.912088 -404.219132) (xy 347.86252 -404.241775) (xy 347.810234 -404.257133) (xy 347.756295 -404.264895)
			(xy 347.729048 -404.265384) (xy 346.865448 -404.265384) (xy 346.838191 -404.264972) (xy 346.784232 -404.25722)
			(xy 346.731925 -404.241868) (xy 346.682335 -404.219226) (xy 346.636473 -404.189758) (xy 346.595272 -404.154062)
			(xy 346.559571 -404.112865) (xy 346.530097 -404.067007) (xy 346.507449 -404.01742) (xy 346.49209 -403.965115)
			(xy 346.484331 -403.911157) (xy 345.046797 -403.911157) (xy 345.039042 -403.965093) (xy 345.023688 -404.017383)
			(xy 345.001049 -404.066957) (xy 344.971586 -404.112804) (xy 344.935897 -404.153991) (xy 344.89471 -404.189681)
			(xy 344.848864 -404.219145) (xy 344.799291 -404.241785) (xy 344.747001 -404.25714) (xy 344.693057 -404.264897)
			(xy 344.665808 -404.265384) (xy 343.802208 -404.265384) (xy 343.774953 -404.26497) (xy 343.720998 -404.257213)
			(xy 343.668696 -404.241857) (xy 343.619111 -404.219213) (xy 343.573254 -404.189744) (xy 343.532058 -404.154048)
			(xy 343.496361 -404.112852) (xy 343.466891 -404.066996) (xy 343.444246 -404.017412) (xy 343.428889 -403.96511)
			(xy 343.421131 -403.911155) (xy 341.983621 -403.911155) (xy 341.975863 -403.965103) (xy 341.960507 -404.0174)
			(xy 341.937863 -404.066979) (xy 341.908394 -404.112831) (xy 341.872699 -404.154022) (xy 341.831505 -404.189713)
			(xy 341.785651 -404.219179) (xy 341.73607 -404.241818) (xy 341.683772 -404.25717) (xy 341.629821 -404.264923)
			(xy 341.602568 -404.265384) (xy 340.738968 -404.265384) (xy 340.711717 -404.264944) (xy 340.657769 -404.257183)
			(xy 340.605475 -404.241824) (xy 340.555898 -404.21918) (xy 340.510049 -404.189711) (xy 340.46886 -404.154017)
			(xy 340.43317 -404.112825) (xy 340.403705 -404.066974) (xy 340.381064 -404.017395) (xy 340.36571 -403.9651)
			(xy 340.357954 -403.911152) (xy 338.920297 -403.911152) (xy 338.912543 -403.96509) (xy 338.89719 -404.017379)
			(xy 338.874552 -404.066951) (xy 338.84509 -404.112798) (xy 338.809404 -404.153984) (xy 338.76822 -404.189674)
			(xy 338.722376 -404.219139) (xy 338.672805 -404.24178) (xy 338.620517 -404.257137) (xy 338.566576 -404.264896)
			(xy 338.539328 -404.265384) (xy 337.675728 -404.265384) (xy 337.648472 -404.264971) (xy 337.594515 -404.257217)
			(xy 337.54221 -404.241862) (xy 337.492623 -404.21922) (xy 337.446764 -404.189751) (xy 337.405565 -404.154055)
			(xy 337.369866 -404.112859) (xy 337.340394 -404.067001) (xy 337.317748 -404.017416) (xy 337.302389 -403.965113)
			(xy 337.294631 -403.911156) (xy 335.85712 -403.911156) (xy 335.849364 -403.9651) (xy 335.834008 -404.017396)
			(xy 335.811366 -404.066974) (xy 335.781899 -404.112824) (xy 335.746206 -404.154015) (xy 335.705015 -404.189706)
			(xy 335.659163 -404.219172) (xy 335.609585 -404.241812) (xy 335.557289 -404.257166) (xy 335.50334 -404.264922)
			(xy 335.476088 -404.265384) (xy 334.612488 -404.265384) (xy 334.585236 -404.264945) (xy 334.531286 -404.257187)
			(xy 334.478989 -404.24183) (xy 334.42941 -404.219187) (xy 334.383559 -404.189718) (xy 334.342367 -404.154024)
			(xy 334.306675 -404.112832) (xy 334.277208 -404.066979) (xy 334.254566 -404.0174) (xy 334.23921 -403.965102)
			(xy 334.231454 -403.911152) (xy 332.793797 -403.911152) (xy 332.786043 -403.965087) (xy 332.770691 -404.017375)
			(xy 332.748055 -404.066946) (xy 332.718595 -404.112791) (xy 332.682911 -404.153977) (xy 332.641729 -404.189667)
			(xy 332.595888 -404.219132) (xy 332.54632 -404.241775) (xy 332.494034 -404.257133) (xy 332.440095 -404.264895)
			(xy 332.412848 -404.265384) (xy 331.549248 -404.265384) (xy 331.521991 -404.264972) (xy 331.468032 -404.25722)
			(xy 331.415725 -404.241868) (xy 331.366135 -404.219226) (xy 331.320273 -404.189758) (xy 331.279072 -404.154062)
			(xy 331.243371 -404.112865) (xy 331.213897 -404.067007) (xy 331.191249 -404.01742) (xy 331.17589 -403.965115)
			(xy 331.168131 -403.911157) (xy 329.730597 -403.911157) (xy 329.722842 -403.965093) (xy 329.707488 -404.017383)
			(xy 329.684849 -404.066957) (xy 329.655386 -404.112804) (xy 329.619697 -404.153991) (xy 329.57851 -404.189681)
			(xy 329.532664 -404.219145) (xy 329.483091 -404.241785) (xy 329.430801 -404.25714) (xy 329.376857 -404.264897)
			(xy 329.349608 -404.265384) (xy 328.486008 -404.265384) (xy 328.458753 -404.26497) (xy 328.404798 -404.257213)
			(xy 328.352496 -404.241857) (xy 328.302911 -404.219213) (xy 328.257054 -404.189744) (xy 328.215858 -404.154048)
			(xy 328.180161 -404.112852) (xy 328.150691 -404.066996) (xy 328.128046 -404.017412) (xy 328.112689 -403.96511)
			(xy 328.104931 -403.911155) (xy 326.667421 -403.911155) (xy 326.659663 -403.965103) (xy 326.644307 -404.0174)
			(xy 326.621663 -404.066979) (xy 326.592194 -404.112831) (xy 326.556499 -404.154022) (xy 326.515305 -404.189713)
			(xy 326.469451 -404.219179) (xy 326.41987 -404.241818) (xy 326.367572 -404.25717) (xy 326.313621 -404.264923)
			(xy 326.286368 -404.265384) (xy 325.422768 -404.265384) (xy 325.395517 -404.264944) (xy 325.341569 -404.257183)
			(xy 325.289275 -404.241824) (xy 325.239698 -404.21918) (xy 325.193849 -404.189711) (xy 325.15266 -404.154017)
			(xy 325.11697 -404.112825) (xy 325.087505 -404.066974) (xy 325.064864 -404.017395) (xy 325.04951 -403.9651)
			(xy 325.041754 -403.911152) (xy 323.604097 -403.911152) (xy 323.596343 -403.96509) (xy 323.58099 -404.017379)
			(xy 323.558352 -404.066951) (xy 323.52889 -404.112798) (xy 323.493204 -404.153984) (xy 323.45202 -404.189674)
			(xy 323.406176 -404.219139) (xy 323.356605 -404.24178) (xy 323.304317 -404.257137) (xy 323.250376 -404.264896)
			(xy 323.223128 -404.265384) (xy 322.359528 -404.265384) (xy 322.332272 -404.264971) (xy 322.278315 -404.257217)
			(xy 322.22601 -404.241862) (xy 322.176423 -404.21922) (xy 322.130564 -404.189751) (xy 322.089365 -404.154055)
			(xy 322.053666 -404.112859) (xy 322.024194 -404.067001) (xy 322.001548 -404.017416) (xy 321.986189 -403.965113)
			(xy 321.978431 -403.911156) (xy 320.54092 -403.911156) (xy 320.533164 -403.9651) (xy 320.517808 -404.017396)
			(xy 320.495166 -404.066974) (xy 320.465699 -404.112824) (xy 320.430006 -404.154015) (xy 320.388815 -404.189706)
			(xy 320.342963 -404.219172) (xy 320.293385 -404.241812) (xy 320.241089 -404.257166) (xy 320.18714 -404.264922)
			(xy 320.159888 -404.265384) (xy 319.296288 -404.265384) (xy 319.269036 -404.264945) (xy 319.215086 -404.257187)
			(xy 319.162789 -404.24183) (xy 319.11321 -404.219187) (xy 319.067359 -404.189718) (xy 319.026167 -404.154024)
			(xy 318.990475 -404.112832) (xy 318.961008 -404.066979) (xy 318.938366 -404.0174) (xy 318.92301 -403.965102)
			(xy 318.915254 -403.911152) (xy 317.477597 -403.911152) (xy 317.469843 -403.965087) (xy 317.454491 -404.017375)
			(xy 317.431855 -404.066946) (xy 317.402395 -404.112791) (xy 317.366711 -404.153977) (xy 317.325529 -404.189667)
			(xy 317.279688 -404.219132) (xy 317.23012 -404.241775) (xy 317.177834 -404.257133) (xy 317.123895 -404.264895)
			(xy 317.096648 -404.265384) (xy 316.233048 -404.265384) (xy 316.205791 -404.264972) (xy 316.151832 -404.25722)
			(xy 316.099525 -404.241868) (xy 316.049935 -404.219226) (xy 316.004073 -404.189758) (xy 315.962872 -404.154062)
			(xy 315.927171 -404.112865) (xy 315.897697 -404.067007) (xy 315.875049 -404.01742) (xy 315.85969 -403.965115)
			(xy 315.851931 -403.911157) (xy 314.414397 -403.911157) (xy 314.406642 -403.965093) (xy 314.391288 -404.017383)
			(xy 314.368649 -404.066957) (xy 314.339186 -404.112804) (xy 314.303497 -404.153991) (xy 314.26231 -404.189681)
			(xy 314.216464 -404.219145) (xy 314.166891 -404.241785) (xy 314.114601 -404.25714) (xy 314.060657 -404.264897)
			(xy 314.033408 -404.265384) (xy 313.169808 -404.265384) (xy 313.142553 -404.26497) (xy 313.088598 -404.257213)
			(xy 313.036296 -404.241857) (xy 312.986711 -404.219213) (xy 312.940854 -404.189744) (xy 312.899658 -404.154048)
			(xy 312.863961 -404.112852) (xy 312.834491 -404.066996) (xy 312.811846 -404.017412) (xy 312.796489 -403.96511)
			(xy 312.788731 -403.911155) (xy 311.351221 -403.911155) (xy 311.343463 -403.965103) (xy 311.328107 -404.0174)
			(xy 311.305463 -404.066979) (xy 311.275994 -404.112831) (xy 311.240299 -404.154022) (xy 311.199105 -404.189713)
			(xy 311.153251 -404.219179) (xy 311.10367 -404.241818) (xy 311.051372 -404.25717) (xy 310.997421 -404.264923)
			(xy 310.970168 -404.265384) (xy 310.106568 -404.265384) (xy 310.079317 -404.264944) (xy 310.025369 -404.257183)
			(xy 309.973075 -404.241824) (xy 309.923498 -404.21918) (xy 309.877649 -404.189711) (xy 309.83646 -404.154017)
			(xy 309.80077 -404.112825) (xy 309.771305 -404.066974) (xy 309.748664 -404.017395) (xy 309.73331 -403.9651)
			(xy 309.725554 -403.911152) (xy 308.287897 -403.911152) (xy 308.280143 -403.96509) (xy 308.26479 -404.017379)
			(xy 308.242152 -404.066951) (xy 308.21269 -404.112798) (xy 308.177004 -404.153984) (xy 308.13582 -404.189674)
			(xy 308.089976 -404.219139) (xy 308.040405 -404.24178) (xy 307.988117 -404.257137) (xy 307.934176 -404.264896)
			(xy 307.906928 -404.265384) (xy 307.043328 -404.265384) (xy 307.016072 -404.264971) (xy 306.962115 -404.257217)
			(xy 306.90981 -404.241862) (xy 306.860223 -404.21922) (xy 306.814364 -404.189751) (xy 306.773165 -404.154055)
			(xy 306.737466 -404.112859) (xy 306.707994 -404.067001) (xy 306.685348 -404.017416) (xy 306.669989 -403.965113)
			(xy 306.662231 -403.911156) (xy 305.22472 -403.911156) (xy 305.216964 -403.9651) (xy 305.201608 -404.017396)
			(xy 305.178966 -404.066974) (xy 305.149499 -404.112824) (xy 305.113806 -404.154015) (xy 305.072615 -404.189706)
			(xy 305.026763 -404.219172) (xy 304.977185 -404.241812) (xy 304.924889 -404.257166) (xy 304.87094 -404.264922)
			(xy 304.843688 -404.265384) (xy 303.980088 -404.265384) (xy 303.952836 -404.264945) (xy 303.898886 -404.257187)
			(xy 303.846589 -404.24183) (xy 303.79701 -404.219187) (xy 303.751159 -404.189718) (xy 303.709967 -404.154024)
			(xy 303.674275 -404.112832) (xy 303.644808 -404.066979) (xy 303.622166 -404.0174) (xy 303.60681 -403.965102)
			(xy 303.599054 -403.911152) (xy 298.836897 -403.911152) (xy 298.840074 -403.920931) (xy 298.852049 -403.983712)
			(xy 298.856063 -404.0475) (xy 298.852049 -404.111288) (xy 298.840074 -404.174069) (xy 298.820324 -404.234855)
			(xy 298.793112 -404.292686) (xy 298.758866 -404.346651) (xy 298.718128 -404.395898) (xy 298.671538 -404.439652)
			(xy 298.619832 -404.477221) (xy 298.563825 -404.508014) (xy 298.504401 -404.531545) (xy 298.442496 -404.547442)
			(xy 298.379087 -404.555456) (xy 298.34713 -404.55596) (xy 298.346876 -404.55596) (xy 298.315131 -404.555422)
			(xy 298.252136 -404.547497) (xy 298.190616 -404.531797) (xy 298.131527 -404.508566) (xy 298.075787 -404.478166)
			(xy 298.024261 -404.441069) (xy 298.000674 -404.419816) (xy 297.993411 -404.413632) (xy 297.975661 -404.406681)
			(xy 297.956599 -404.406681) (xy 297.938849 -404.413632) (xy 297.931586 -404.419816) (xy 297.908028 -404.441107)
			(xy 297.856512 -404.478235) (xy 297.800771 -404.508654) (xy 297.741674 -404.531889) (xy 297.680142 -404.547579)
			(xy 297.617135 -404.555478) (xy 297.585384 -404.55596) (xy 297.58513 -404.55596) (xy 297.553163 -404.555577)
			(xy 297.489734 -404.547567) (xy 297.427809 -404.531671) (xy 297.368364 -404.508138) (xy 297.312338 -404.47734)
			(xy 297.260613 -404.439763) (xy 297.214007 -404.395999) (xy 297.173253 -404.346739) (xy 297.138995 -404.292759)
			(xy 297.111773 -404.234911) (xy 297.092015 -404.174108) (xy 297.080035 -404.111307) (xy 297.07602 -404.0475)
			(xy 296.316063 -404.0475) (xy 296.312049 -404.111288) (xy 296.300074 -404.174069) (xy 296.280324 -404.234855)
			(xy 296.253112 -404.292686) (xy 296.218866 -404.346651) (xy 296.178128 -404.395898) (xy 296.131538 -404.439652)
			(xy 296.079832 -404.477221) (xy 296.023825 -404.508014) (xy 295.964401 -404.531545) (xy 295.902496 -404.547442)
			(xy 295.839087 -404.555456) (xy 295.80713 -404.55596) (xy 295.806876 -404.55596) (xy 295.775131 -404.555422)
			(xy 295.712136 -404.547497) (xy 295.650616 -404.531797) (xy 295.591527 -404.508566) (xy 295.535787 -404.478166)
			(xy 295.484261 -404.441069) (xy 295.460674 -404.419816) (xy 295.453411 -404.413632) (xy 295.435661 -404.406681)
			(xy 295.416599 -404.406681) (xy 295.398849 -404.413632) (xy 295.391586 -404.419816) (xy 295.368028 -404.441107)
			(xy 295.316512 -404.478235) (xy 295.260771 -404.508654) (xy 295.201674 -404.531889) (xy 295.140142 -404.547579)
			(xy 295.077135 -404.555478) (xy 295.045384 -404.55596) (xy 295.04513 -404.55596) (xy 295.013163 -404.555577)
			(xy 294.949734 -404.547567) (xy 294.887809 -404.531671) (xy 294.828364 -404.508138) (xy 294.772338 -404.47734)
			(xy 294.720613 -404.439763) (xy 294.674007 -404.395999) (xy 294.633253 -404.346739) (xy 294.598995 -404.292759)
			(xy 294.571773 -404.234911) (xy 294.552015 -404.174108) (xy 294.540035 -404.111307) (xy 294.53602 -404.0475)
			(xy 293.926484 -404.0475) (xy 293.92247 -404.111293) (xy 293.910493 -404.174079) (xy 293.890741 -404.23487)
			(xy 293.863525 -404.292705) (xy 293.829276 -404.346674) (xy 293.788532 -404.395924) (xy 293.741937 -404.439679)
			(xy 293.690226 -404.47725) (xy 293.634213 -404.508043) (xy 293.574783 -404.531573) (xy 293.512872 -404.547468)
			(xy 293.449457 -404.555479) (xy 293.417498 -404.55596) (xy 293.417244 -404.55596) (xy 293.385498 -404.555442)
			(xy 293.322502 -404.547512) (xy 293.260982 -404.531809) (xy 293.201894 -404.508575) (xy 293.146154 -404.478171)
			(xy 293.094629 -404.44107) (xy 293.071042 -404.419816) (xy 293.063779 -404.413632) (xy 293.046029 -404.406681)
			(xy 293.026967 -404.406681) (xy 293.009217 -404.413632) (xy 293.001954 -404.419816) (xy 292.978367 -404.441074)
			(xy 292.926858 -404.478206) (xy 292.871123 -404.50863) (xy 292.812032 -404.531871) (xy 292.750504 -404.547567)
			(xy 292.687501 -404.555474) (xy 292.655752 -404.55596) (xy 292.655498 -404.55596) (xy 292.623534 -404.555554)
			(xy 292.56011 -404.547542) (xy 292.498191 -404.531643) (xy 292.438752 -404.50811) (xy 292.382731 -404.477312)
			(xy 292.331013 -404.439736) (xy 292.284411 -404.395974) (xy 292.243662 -404.346717) (xy 292.209408 -404.29274)
			(xy 292.182189 -404.234897) (xy 292.162434 -404.174098) (xy 292.150455 -404.111302) (xy 292.146441 -404.0475)
			(xy 291.386484 -404.0475) (xy 291.38247 -404.111293) (xy 291.370493 -404.174079) (xy 291.350741 -404.23487)
			(xy 291.323525 -404.292705) (xy 291.289276 -404.346674) (xy 291.248532 -404.395924) (xy 291.201937 -404.439679)
			(xy 291.150226 -404.47725) (xy 291.094213 -404.508043) (xy 291.034783 -404.531573) (xy 290.972872 -404.547468)
			(xy 290.909457 -404.555479) (xy 290.877498 -404.55596) (xy 290.877244 -404.55596) (xy 290.845498 -404.555442)
			(xy 290.782502 -404.547512) (xy 290.720982 -404.531809) (xy 290.661894 -404.508575) (xy 290.606154 -404.478171)
			(xy 290.554629 -404.44107) (xy 290.531042 -404.419816) (xy 290.523779 -404.413632) (xy 290.506029 -404.406681)
			(xy 290.486967 -404.406681) (xy 290.469217 -404.413632) (xy 290.461954 -404.419816) (xy 290.438367 -404.441074)
			(xy 290.386858 -404.478206) (xy 290.331123 -404.50863) (xy 290.272032 -404.531871) (xy 290.210504 -404.547567)
			(xy 290.147501 -404.555474) (xy 290.115752 -404.55596) (xy 290.115498 -404.55596) (xy 290.083534 -404.555554)
			(xy 290.02011 -404.547542) (xy 289.958191 -404.531643) (xy 289.898752 -404.50811) (xy 289.842731 -404.477312)
			(xy 289.791013 -404.439736) (xy 289.744411 -404.395974) (xy 289.703662 -404.346717) (xy 289.669408 -404.29274)
			(xy 289.642189 -404.234897) (xy 289.622434 -404.174098) (xy 289.610455 -404.111302) (xy 289.606441 -404.0475)
			(xy 288.846484 -404.0475) (xy 288.84247 -404.111293) (xy 288.830493 -404.174079) (xy 288.810741 -404.23487)
			(xy 288.783525 -404.292705) (xy 288.749276 -404.346674) (xy 288.708532 -404.395924) (xy 288.661937 -404.439679)
			(xy 288.610226 -404.47725) (xy 288.554213 -404.508043) (xy 288.494783 -404.531573) (xy 288.432872 -404.547468)
			(xy 288.369457 -404.555479) (xy 288.337498 -404.55596) (xy 288.337244 -404.55596) (xy 288.305498 -404.555442)
			(xy 288.242502 -404.547512) (xy 288.180982 -404.531809) (xy 288.121894 -404.508575) (xy 288.066154 -404.478171)
			(xy 288.014629 -404.44107) (xy 287.991042 -404.419816) (xy 287.983779 -404.413632) (xy 287.966029 -404.406681)
			(xy 287.946967 -404.406681) (xy 287.929217 -404.413632) (xy 287.921954 -404.419816) (xy 287.898367 -404.441074)
			(xy 287.846858 -404.478206) (xy 287.791123 -404.50863) (xy 287.732032 -404.531871) (xy 287.670504 -404.547567)
			(xy 287.607501 -404.555474) (xy 287.575752 -404.55596) (xy 287.575498 -404.55596) (xy 287.543534 -404.555554)
			(xy 287.48011 -404.547542) (xy 287.418191 -404.531643) (xy 287.358752 -404.50811) (xy 287.302731 -404.477312)
			(xy 287.251013 -404.439736) (xy 287.204411 -404.395974) (xy 287.163662 -404.346717) (xy 287.129408 -404.29274)
			(xy 287.102189 -404.234897) (xy 287.082434 -404.174098) (xy 287.070455 -404.111302) (xy 287.066441 -404.0475)
			(xy 167.31136 -404.0475) (xy 167.302461 -404.066983) (xy 167.272991 -404.112836) (xy 167.237294 -404.154027)
			(xy 167.196099 -404.189718) (xy 167.150243 -404.219183) (xy 167.10066 -404.241822) (xy 167.04836 -404.257173)
			(xy 166.994407 -404.264924) (xy 166.967154 -404.265384) (xy 166.103554 -404.265384) (xy 166.076303 -404.264943)
			(xy 166.022357 -404.257181) (xy 165.970065 -404.241821) (xy 165.92049 -404.219175) (xy 165.874642 -404.189706)
			(xy 165.833455 -404.154012) (xy 165.797766 -404.112821) (xy 165.768302 -404.06697) (xy 165.745663 -404.017392)
			(xy 165.73031 -403.965098) (xy 165.722554 -403.911151) (xy 164.284898 -403.911151) (xy 164.277142 -403.965092)
			(xy 164.261789 -404.017382) (xy 164.23915 -404.066955) (xy 164.209687 -404.112802) (xy 164.173999 -404.153989)
			(xy 164.132813 -404.189679) (xy 164.086968 -404.219143) (xy 164.037395 -404.241784) (xy 163.985106 -404.257139)
			(xy 163.931163 -404.264897) (xy 163.903914 -404.265384) (xy 163.040314 -404.265384) (xy 163.013059 -404.26497)
			(xy 162.959103 -404.257214) (xy 162.9068 -404.241858) (xy 162.857215 -404.219215) (xy 162.811357 -404.189746)
			(xy 162.77016 -404.15405) (xy 162.734463 -404.112854) (xy 162.704991 -404.066997) (xy 162.682346 -404.017413)
			(xy 162.666989 -403.965111) (xy 162.659231 -403.911155) (xy 161.221721 -403.911155) (xy 161.213963 -403.965102)
			(xy 161.198607 -404.017399) (xy 161.175964 -404.066978) (xy 161.146496 -404.112829) (xy 161.110801 -404.15402)
			(xy 161.069608 -404.189711) (xy 161.023755 -404.219177) (xy 160.974174 -404.241816) (xy 160.921877 -404.257169)
			(xy 160.867926 -404.264922) (xy 160.840674 -404.265384) (xy 159.977074 -404.265384) (xy 159.949822 -404.264944)
			(xy 159.895874 -404.257184) (xy 159.843579 -404.241826) (xy 159.794002 -404.219182) (xy 159.748152 -404.189713)
			(xy 159.706962 -404.154019) (xy 159.671271 -404.112827) (xy 159.641806 -404.066975) (xy 159.619165 -404.017397)
			(xy 159.60381 -403.965101) (xy 159.596054 -403.911152) (xy 158.158397 -403.911152) (xy 158.150643 -403.965089)
			(xy 158.13529 -404.017378) (xy 158.112653 -404.06695) (xy 158.083192 -404.112796) (xy 158.047506 -404.153982)
			(xy 158.006323 -404.189671) (xy 157.96048 -404.219137) (xy 157.91091 -404.241778) (xy 157.858623 -404.257136)
			(xy 157.804682 -404.264895) (xy 157.777434 -404.265384) (xy 156.913834 -404.265384) (xy 156.886578 -404.264971)
			(xy 156.83262 -404.257218) (xy 156.780314 -404.241864) (xy 156.730727 -404.219222) (xy 156.684867 -404.189753)
			(xy 156.643667 -404.154057) (xy 156.607968 -404.112861) (xy 156.578495 -404.067003) (xy 156.555848 -404.017417)
			(xy 156.540489 -403.965114) (xy 156.532731 -403.911156) (xy 155.09522 -403.911156) (xy 155.087464 -403.965099)
			(xy 155.072109 -404.017394) (xy 155.049467 -404.066972) (xy 155.02 -404.112822) (xy 154.984308 -404.154013)
			(xy 154.943118 -404.189704) (xy 154.897267 -404.21917) (xy 154.847689 -404.241811) (xy 154.795394 -404.257165)
			(xy 154.741445 -404.264921) (xy 154.714194 -404.265384) (xy 153.850594 -404.265384) (xy 153.823341 -404.264946)
			(xy 153.769391 -404.257188) (xy 153.717094 -404.241831) (xy 153.667514 -404.219189) (xy 153.621661 -404.18972)
			(xy 153.580469 -404.154026) (xy 153.544776 -404.112834) (xy 153.515309 -404.066981) (xy 153.492666 -404.017401)
			(xy 153.477311 -403.965103) (xy 153.469554 -403.911153) (xy 152.032021 -403.911153) (xy 152.024263 -403.965105)
			(xy 152.008906 -404.017403) (xy 151.986261 -404.066983) (xy 151.956791 -404.112836) (xy 151.921094 -404.154027)
			(xy 151.879899 -404.189718) (xy 151.834043 -404.219183) (xy 151.78446 -404.241822) (xy 151.73216 -404.257173)
			(xy 151.678207 -404.264924) (xy 151.650954 -404.265384) (xy 150.787354 -404.265384) (xy 150.760103 -404.264943)
			(xy 150.706157 -404.257181) (xy 150.653865 -404.241821) (xy 150.60429 -404.219175) (xy 150.558442 -404.189706)
			(xy 150.517255 -404.154012) (xy 150.481566 -404.112821) (xy 150.452102 -404.06697) (xy 150.429463 -404.017392)
			(xy 150.41411 -403.965098) (xy 150.406354 -403.911151) (xy 148.968698 -403.911151) (xy 148.960942 -403.965092)
			(xy 148.945589 -404.017382) (xy 148.92295 -404.066955) (xy 148.893487 -404.112802) (xy 148.857799 -404.153989)
			(xy 148.816613 -404.189679) (xy 148.770768 -404.219143) (xy 148.721195 -404.241784) (xy 148.668906 -404.257139)
			(xy 148.614963 -404.264897) (xy 148.587714 -404.265384) (xy 147.724114 -404.265384) (xy 147.696859 -404.26497)
			(xy 147.642903 -404.257214) (xy 147.5906 -404.241858) (xy 147.541015 -404.219215) (xy 147.495157 -404.189746)
			(xy 147.45396 -404.15405) (xy 147.418263 -404.112854) (xy 147.388791 -404.066997) (xy 147.366146 -404.017413)
			(xy 147.350789 -403.965111) (xy 147.343031 -403.911155) (xy 145.905521 -403.911155) (xy 145.897763 -403.965102)
			(xy 145.882407 -404.017399) (xy 145.859764 -404.066978) (xy 145.830296 -404.112829) (xy 145.794601 -404.15402)
			(xy 145.753408 -404.189711) (xy 145.707555 -404.219177) (xy 145.657974 -404.241816) (xy 145.605677 -404.257169)
			(xy 145.551726 -404.264922) (xy 145.524474 -404.265384) (xy 144.660874 -404.265384) (xy 144.633622 -404.264944)
			(xy 144.579674 -404.257184) (xy 144.527379 -404.241826) (xy 144.477802 -404.219182) (xy 144.431952 -404.189713)
			(xy 144.390762 -404.154019) (xy 144.355071 -404.112827) (xy 144.325606 -404.066975) (xy 144.302965 -404.017397)
			(xy 144.28761 -403.965101) (xy 144.279854 -403.911152) (xy 142.842197 -403.911152) (xy 142.834443 -403.965089)
			(xy 142.81909 -404.017378) (xy 142.796453 -404.06695) (xy 142.766992 -404.112796) (xy 142.731306 -404.153982)
			(xy 142.690123 -404.189671) (xy 142.64428 -404.219137) (xy 142.59471 -404.241778) (xy 142.542423 -404.257136)
			(xy 142.488482 -404.264895) (xy 142.461234 -404.265384) (xy 141.597634 -404.265384) (xy 141.570378 -404.264971)
			(xy 141.51642 -404.257218) (xy 141.464114 -404.241864) (xy 141.414527 -404.219222) (xy 141.368667 -404.189753)
			(xy 141.327467 -404.154057) (xy 141.291768 -404.112861) (xy 141.262295 -404.067003) (xy 141.239648 -404.017417)
			(xy 141.224289 -403.965114) (xy 141.216531 -403.911156) (xy 139.77902 -403.911156) (xy 139.771264 -403.965099)
			(xy 139.755909 -404.017394) (xy 139.733267 -404.066972) (xy 139.7038 -404.112822) (xy 139.668108 -404.154013)
			(xy 139.626918 -404.189704) (xy 139.581067 -404.21917) (xy 139.531489 -404.241811) (xy 139.479194 -404.257165)
			(xy 139.425245 -404.264921) (xy 139.397994 -404.265384) (xy 138.534394 -404.265384) (xy 138.507141 -404.264946)
			(xy 138.453191 -404.257188) (xy 138.400894 -404.241831) (xy 138.351314 -404.219189) (xy 138.305461 -404.18972)
			(xy 138.264269 -404.154026) (xy 138.228576 -404.112834) (xy 138.199109 -404.066981) (xy 138.176466 -404.017401)
			(xy 138.161111 -403.965103) (xy 138.153354 -403.911153) (xy 136.715821 -403.911153) (xy 136.708063 -403.965105)
			(xy 136.692706 -404.017403) (xy 136.670061 -404.066983) (xy 136.640591 -404.112836) (xy 136.604894 -404.154027)
			(xy 136.563699 -404.189718) (xy 136.517843 -404.219183) (xy 136.46826 -404.241822) (xy 136.41596 -404.257173)
			(xy 136.362007 -404.264924) (xy 136.334754 -404.265384) (xy 135.471154 -404.265384) (xy 135.443903 -404.264943)
			(xy 135.389957 -404.257181) (xy 135.337665 -404.241821) (xy 135.28809 -404.219175) (xy 135.242242 -404.189706)
			(xy 135.201055 -404.154012) (xy 135.165366 -404.112821) (xy 135.135902 -404.06697) (xy 135.113263 -404.017392)
			(xy 135.09791 -403.965098) (xy 135.090154 -403.911151) (xy 133.652498 -403.911151) (xy 133.644742 -403.965092)
			(xy 133.629389 -404.017382) (xy 133.60675 -404.066955) (xy 133.577287 -404.112802) (xy 133.541599 -404.153989)
			(xy 133.500413 -404.189679) (xy 133.454568 -404.219143) (xy 133.404995 -404.241784) (xy 133.352706 -404.257139)
			(xy 133.298763 -404.264897) (xy 133.271514 -404.265384) (xy 132.407914 -404.265384) (xy 132.380659 -404.26497)
			(xy 132.326703 -404.257214) (xy 132.2744 -404.241858) (xy 132.224815 -404.219215) (xy 132.178957 -404.189746)
			(xy 132.13776 -404.15405) (xy 132.102063 -404.112854) (xy 132.072591 -404.066997) (xy 132.049946 -404.017413)
			(xy 132.034589 -403.965111) (xy 132.026831 -403.911155) (xy 130.589321 -403.911155) (xy 130.581563 -403.965102)
			(xy 130.566207 -404.017399) (xy 130.543564 -404.066978) (xy 130.514096 -404.112829) (xy 130.478401 -404.15402)
			(xy 130.437208 -404.189711) (xy 130.391355 -404.219177) (xy 130.341774 -404.241816) (xy 130.289477 -404.257169)
			(xy 130.235526 -404.264922) (xy 130.208274 -404.265384) (xy 129.344674 -404.265384) (xy 129.317422 -404.264944)
			(xy 129.263474 -404.257184) (xy 129.211179 -404.241826) (xy 129.161602 -404.219182) (xy 129.115752 -404.189713)
			(xy 129.074562 -404.154019) (xy 129.038871 -404.112827) (xy 129.009406 -404.066975) (xy 128.986765 -404.017397)
			(xy 128.97141 -403.965101) (xy 128.963654 -403.911152) (xy 127.525997 -403.911152) (xy 127.518243 -403.965089)
			(xy 127.50289 -404.017378) (xy 127.480253 -404.06695) (xy 127.450792 -404.112796) (xy 127.415106 -404.153982)
			(xy 127.373923 -404.189671) (xy 127.32808 -404.219137) (xy 127.27851 -404.241778) (xy 127.226223 -404.257136)
			(xy 127.172282 -404.264895) (xy 127.145034 -404.265384) (xy 126.281434 -404.265384) (xy 126.254178 -404.264971)
			(xy 126.20022 -404.257218) (xy 126.147914 -404.241864) (xy 126.098327 -404.219222) (xy 126.052467 -404.189753)
			(xy 126.011267 -404.154057) (xy 125.975568 -404.112861) (xy 125.946095 -404.067003) (xy 125.923448 -404.017417)
			(xy 125.908089 -403.965114) (xy 125.900331 -403.911156) (xy 124.46282 -403.911156) (xy 124.455064 -403.965099)
			(xy 124.439709 -404.017394) (xy 124.417067 -404.066972) (xy 124.3876 -404.112822) (xy 124.351908 -404.154013)
			(xy 124.310718 -404.189704) (xy 124.264867 -404.21917) (xy 124.215289 -404.241811) (xy 124.162994 -404.257165)
			(xy 124.109045 -404.264921) (xy 124.081794 -404.265384) (xy 123.218194 -404.265384) (xy 123.190941 -404.264946)
			(xy 123.136991 -404.257188) (xy 123.084694 -404.241831) (xy 123.035114 -404.219189) (xy 122.989261 -404.18972)
			(xy 122.948069 -404.154026) (xy 122.912376 -404.112834) (xy 122.882909 -404.066981) (xy 122.860266 -404.017401)
			(xy 122.844911 -403.965103) (xy 122.837154 -403.911153) (xy 121.399621 -403.911153) (xy 121.391863 -403.965105)
			(xy 121.376506 -404.017403) (xy 121.353861 -404.066983) (xy 121.324391 -404.112836) (xy 121.288694 -404.154027)
			(xy 121.247499 -404.189718) (xy 121.201643 -404.219183) (xy 121.15206 -404.241822) (xy 121.09976 -404.257173)
			(xy 121.045807 -404.264924) (xy 121.018554 -404.265384) (xy 120.154954 -404.265384) (xy 120.127703 -404.264943)
			(xy 120.073757 -404.257181) (xy 120.021465 -404.241821) (xy 119.97189 -404.219175) (xy 119.926042 -404.189706)
			(xy 119.884855 -404.154012) (xy 119.849166 -404.112821) (xy 119.819702 -404.06697) (xy 119.797063 -404.017392)
			(xy 119.78171 -403.965098) (xy 119.773954 -403.911151) (xy 95.172998 -403.911151) (xy 95.165243 -403.965089)
			(xy 95.149891 -404.017377) (xy 95.127254 -404.066949) (xy 95.097793 -404.112794) (xy 95.062108 -404.153981)
			(xy 95.020925 -404.18967) (xy 94.975082 -404.219135) (xy 94.925513 -404.241777) (xy 94.873226 -404.257135)
			(xy 94.819286 -404.264895) (xy 94.792038 -404.265384) (xy 93.928438 -404.265384) (xy 93.901182 -404.264972)
			(xy 93.847223 -404.257219) (xy 93.794917 -404.241865) (xy 93.745329 -404.219223) (xy 93.699468 -404.189754)
			(xy 93.658269 -404.154058) (xy 93.622569 -404.112862) (xy 93.593095 -404.067004) (xy 93.570448 -404.017418)
			(xy 93.555089 -403.965114) (xy 93.547331 -403.911156) (xy 92.10982 -403.911156) (xy 92.102064 -403.965099)
			(xy 92.086709 -404.017394) (xy 92.064068 -404.066971) (xy 92.034601 -404.112821) (xy 91.99891 -404.154011)
			(xy 91.95772 -404.189703) (xy 91.911869 -404.219169) (xy 91.862292 -404.24181) (xy 91.809997 -404.257165)
			(xy 91.756049 -404.264921) (xy 91.728798 -404.265384) (xy 90.865198 -404.265384) (xy 90.837945 -404.264946)
			(xy 90.783994 -404.257189) (xy 90.731696 -404.241833) (xy 90.682116 -404.21919) (xy 90.636263 -404.189722)
			(xy 90.595071 -404.154028) (xy 90.559377 -404.112835) (xy 90.529909 -404.066982) (xy 90.507267 -404.017402)
			(xy 90.491911 -403.965104) (xy 90.484154 -403.911153) (xy 89.046621 -403.911153) (xy 89.038863 -403.965104)
			(xy 89.023506 -404.017402) (xy 89.000862 -404.066982) (xy 88.971392 -404.112834) (xy 88.935696 -404.154025)
			(xy 88.894501 -404.189717) (xy 88.848645 -404.219182) (xy 88.799063 -404.241821) (xy 88.746763 -404.257172)
			(xy 88.692811 -404.264924) (xy 88.665558 -404.265384) (xy 87.801958 -404.265384) (xy 87.774707 -404.264943)
			(xy 87.72076 -404.257181) (xy 87.668467 -404.241822) (xy 87.618892 -404.219177) (xy 87.573044 -404.189707)
			(xy 87.531857 -404.154014) (xy 87.496167 -404.112822) (xy 87.466703 -404.066971) (xy 87.444064 -404.017393)
			(xy 87.42871 -403.965098) (xy 87.420954 -403.911151) (xy 85.983298 -403.911151) (xy 85.975542 -403.965091)
			(xy 85.960189 -404.017381) (xy 85.937551 -404.066954) (xy 85.908088 -404.112801) (xy 85.872401 -404.153988)
			(xy 85.831215 -404.189677) (xy 85.78537 -404.219142) (xy 85.735798 -404.241783) (xy 85.683509 -404.257138)
			(xy 85.629567 -404.264897) (xy 85.602318 -404.265384) (xy 84.738718 -404.265384) (xy 84.711463 -404.26497)
			(xy 84.657506 -404.257215) (xy 84.605203 -404.241859) (xy 84.555617 -404.219217) (xy 84.509759 -404.189747)
			(xy 84.468562 -404.154051) (xy 84.432864 -404.112855) (xy 84.403392 -404.066999) (xy 84.380747 -404.017414)
			(xy 84.365389 -403.965111) (xy 84.357631 -403.911155) (xy 82.920121 -403.911155) (xy 82.912364 -403.965102)
			(xy 82.897007 -404.017398) (xy 82.874365 -404.066976) (xy 82.844897 -404.112828) (xy 82.809203 -404.154018)
			(xy 82.76801 -404.18971) (xy 82.722157 -404.219175) (xy 82.672577 -404.241815) (xy 82.62028 -404.257168)
			(xy 82.56633 -404.264922) (xy 82.539078 -404.265384) (xy 81.675478 -404.265384) (xy 81.648226 -404.264945)
			(xy 81.594277 -404.257185) (xy 81.541982 -404.241827) (xy 81.492404 -404.219183) (xy 81.446554 -404.189715)
			(xy 81.405364 -404.154021) (xy 81.369672 -404.112829) (xy 81.340206 -404.066976) (xy 81.317565 -404.017397)
			(xy 81.30221 -403.965101) (xy 81.294454 -403.911152) (xy 79.856797 -403.911152) (xy 79.849043 -403.965089)
			(xy 79.833691 -404.017377) (xy 79.811054 -404.066949) (xy 79.781593 -404.112794) (xy 79.745908 -404.153981)
			(xy 79.704725 -404.18967) (xy 79.658882 -404.219135) (xy 79.609313 -404.241777) (xy 79.557026 -404.257135)
			(xy 79.503086 -404.264895) (xy 79.475838 -404.265384) (xy 78.612238 -404.265384) (xy 78.584982 -404.264972)
			(xy 78.531023 -404.257219) (xy 78.478717 -404.241865) (xy 78.429129 -404.219223) (xy 78.383268 -404.189754)
			(xy 78.342069 -404.154058) (xy 78.306369 -404.112862) (xy 78.276895 -404.067004) (xy 78.254248 -404.017418)
			(xy 78.238889 -403.965114) (xy 78.231131 -403.911156) (xy 76.79362 -403.911156) (xy 76.785864 -403.965099)
			(xy 76.770509 -404.017394) (xy 76.747868 -404.066971) (xy 76.718401 -404.112821) (xy 76.68271 -404.154011)
			(xy 76.64152 -404.189703) (xy 76.595669 -404.219169) (xy 76.546092 -404.24181) (xy 76.493797 -404.257165)
			(xy 76.439849 -404.264921) (xy 76.412598 -404.265384) (xy 75.548998 -404.265384) (xy 75.521745 -404.264946)
			(xy 75.467794 -404.257189) (xy 75.415496 -404.241833) (xy 75.365916 -404.21919) (xy 75.320063 -404.189722)
			(xy 75.278871 -404.154028) (xy 75.243177 -404.112835) (xy 75.213709 -404.066982) (xy 75.191067 -404.017402)
			(xy 75.175711 -403.965104) (xy 75.167954 -403.911153) (xy 73.730421 -403.911153) (xy 73.722663 -403.965104)
			(xy 73.707306 -404.017402) (xy 73.684662 -404.066982) (xy 73.655192 -404.112834) (xy 73.619496 -404.154025)
			(xy 73.578301 -404.189717) (xy 73.532445 -404.219182) (xy 73.482863 -404.241821) (xy 73.430563 -404.257172)
			(xy 73.376611 -404.264924) (xy 73.349358 -404.265384) (xy 72.485758 -404.265384) (xy 72.458507 -404.264943)
			(xy 72.40456 -404.257181) (xy 72.352267 -404.241822) (xy 72.302692 -404.219177) (xy 72.256844 -404.189707)
			(xy 72.215657 -404.154014) (xy 72.179967 -404.112822) (xy 72.150503 -404.066971) (xy 72.127864 -404.017393)
			(xy 72.11251 -403.965098) (xy 72.104754 -403.911151) (xy 70.667098 -403.911151) (xy 70.659342 -403.965091)
			(xy 70.643989 -404.017381) (xy 70.621351 -404.066954) (xy 70.591888 -404.112801) (xy 70.556201 -404.153988)
			(xy 70.515015 -404.189677) (xy 70.46917 -404.219142) (xy 70.419598 -404.241783) (xy 70.367309 -404.257138)
			(xy 70.313367 -404.264897) (xy 70.286118 -404.265384) (xy 69.422518 -404.265384) (xy 69.395263 -404.26497)
			(xy 69.341306 -404.257215) (xy 69.289003 -404.241859) (xy 69.239417 -404.219217) (xy 69.193559 -404.189747)
			(xy 69.152362 -404.154051) (xy 69.116664 -404.112855) (xy 69.087192 -404.066999) (xy 69.064547 -404.017414)
			(xy 69.049189 -403.965111) (xy 69.041431 -403.911155) (xy 67.603921 -403.911155) (xy 67.596164 -403.965102)
			(xy 67.580807 -404.017398) (xy 67.558165 -404.066976) (xy 67.528697 -404.112828) (xy 67.493003 -404.154018)
			(xy 67.45181 -404.18971) (xy 67.405957 -404.219175) (xy 67.356377 -404.241815) (xy 67.30408 -404.257168)
			(xy 67.25013 -404.264922) (xy 67.222878 -404.265384) (xy 66.359278 -404.265384) (xy 66.332026 -404.264945)
			(xy 66.278077 -404.257185) (xy 66.225782 -404.241827) (xy 66.176204 -404.219183) (xy 66.130354 -404.189715)
			(xy 66.089164 -404.154021) (xy 66.053472 -404.112829) (xy 66.024006 -404.066976) (xy 66.001365 -404.017397)
			(xy 65.98601 -403.965101) (xy 65.978254 -403.911152) (xy 64.540597 -403.911152) (xy 64.532843 -403.965089)
			(xy 64.517491 -404.017377) (xy 64.494854 -404.066949) (xy 64.465393 -404.112794) (xy 64.429708 -404.153981)
			(xy 64.388525 -404.18967) (xy 64.342682 -404.219135) (xy 64.293113 -404.241777) (xy 64.240826 -404.257135)
			(xy 64.186886 -404.264895) (xy 64.159638 -404.265384) (xy 63.296038 -404.265384) (xy 63.268782 -404.264972)
			(xy 63.214823 -404.257219) (xy 63.162517 -404.241865) (xy 63.112929 -404.219223) (xy 63.067068 -404.189754)
			(xy 63.025869 -404.154058) (xy 62.990169 -404.112862) (xy 62.960695 -404.067004) (xy 62.938048 -404.017418)
			(xy 62.922689 -403.965114) (xy 62.914931 -403.911156) (xy 61.47742 -403.911156) (xy 61.469664 -403.965099)
			(xy 61.454309 -404.017394) (xy 61.431668 -404.066971) (xy 61.402201 -404.112821) (xy 61.36651 -404.154011)
			(xy 61.32532 -404.189703) (xy 61.279469 -404.219169) (xy 61.229892 -404.24181) (xy 61.177597 -404.257165)
			(xy 61.123649 -404.264921) (xy 61.096398 -404.265384) (xy 60.232798 -404.265384) (xy 60.205545 -404.264946)
			(xy 60.151594 -404.257189) (xy 60.099296 -404.241833) (xy 60.049716 -404.21919) (xy 60.003863 -404.189722)
			(xy 59.962671 -404.154028) (xy 59.926977 -404.112835) (xy 59.897509 -404.066982) (xy 59.874867 -404.017402)
			(xy 59.859511 -403.965104) (xy 59.851754 -403.911153) (xy 58.414221 -403.911153) (xy 58.406463 -403.965104)
			(xy 58.391106 -404.017402) (xy 58.368462 -404.066982) (xy 58.338992 -404.112834) (xy 58.303296 -404.154025)
			(xy 58.262101 -404.189717) (xy 58.216245 -404.219182) (xy 58.166663 -404.241821) (xy 58.114363 -404.257172)
			(xy 58.060411 -404.264924) (xy 58.033158 -404.265384) (xy 57.169558 -404.265384) (xy 57.142307 -404.264943)
			(xy 57.08836 -404.257181) (xy 57.036067 -404.241822) (xy 56.986492 -404.219177) (xy 56.940644 -404.189707)
			(xy 56.899457 -404.154014) (xy 56.863767 -404.112822) (xy 56.834303 -404.066971) (xy 56.811664 -404.017393)
			(xy 56.79631 -403.965098) (xy 56.788554 -403.911151) (xy 55.350898 -403.911151) (xy 55.343142 -403.965091)
			(xy 55.327789 -404.017381) (xy 55.305151 -404.066954) (xy 55.275688 -404.112801) (xy 55.240001 -404.153988)
			(xy 55.198815 -404.189677) (xy 55.15297 -404.219142) (xy 55.103398 -404.241783) (xy 55.051109 -404.257138)
			(xy 54.997167 -404.264897) (xy 54.969918 -404.265384) (xy 54.106318 -404.265384) (xy 54.079063 -404.26497)
			(xy 54.025106 -404.257215) (xy 53.972803 -404.241859) (xy 53.923217 -404.219217) (xy 53.877359 -404.189747)
			(xy 53.836162 -404.154051) (xy 53.800464 -404.112855) (xy 53.770992 -404.066999) (xy 53.748347 -404.017414)
			(xy 53.732989 -403.965111) (xy 53.725231 -403.911155) (xy 52.287721 -403.911155) (xy 52.279964 -403.965102)
			(xy 52.264607 -404.017398) (xy 52.241965 -404.066976) (xy 52.212497 -404.112828) (xy 52.176803 -404.154018)
			(xy 52.13561 -404.18971) (xy 52.089757 -404.219175) (xy 52.040177 -404.241815) (xy 51.98788 -404.257168)
			(xy 51.93393 -404.264922) (xy 51.906678 -404.265384) (xy 51.043078 -404.265384) (xy 51.015826 -404.264945)
			(xy 50.961877 -404.257185) (xy 50.909582 -404.241827) (xy 50.860004 -404.219183) (xy 50.814154 -404.189715)
			(xy 50.772964 -404.154021) (xy 50.737272 -404.112829) (xy 50.707806 -404.066976) (xy 50.685165 -404.017397)
			(xy 50.66981 -403.965101) (xy 50.662054 -403.911152) (xy 49.224397 -403.911152) (xy 49.216643 -403.965089)
			(xy 49.201291 -404.017377) (xy 49.178654 -404.066949) (xy 49.149193 -404.112794) (xy 49.113508 -404.153981)
			(xy 49.072325 -404.18967) (xy 49.026482 -404.219135) (xy 48.976913 -404.241777) (xy 48.924626 -404.257135)
			(xy 48.870686 -404.264895) (xy 48.843438 -404.265384) (xy 47.979838 -404.265384) (xy 47.952582 -404.264972)
			(xy 47.898623 -404.257219) (xy 47.846317 -404.241865) (xy 47.796729 -404.219223) (xy 47.750868 -404.189754)
			(xy 47.709669 -404.154058) (xy 47.673969 -404.112862) (xy 47.644495 -404.067004) (xy 47.621848 -404.017418)
			(xy 47.606489 -403.965114) (xy 47.598731 -403.911156) (xy 2.610452 -403.911156) (xy 2.622121 -403.942439)
			(xy 2.666338 -404.039266) (xy 2.717346 -404.132693) (xy 2.774884 -404.222247) (xy 2.838661 -404.307471)
			(xy 2.908351 -404.387931) (xy 2.945638 -404.425912) (xy 3.748786 -405.22906) (xy 102.242112 -405.22906)
			(xy 102.242112 -404.36546) (xy 102.242598 -404.338209) (xy 102.250354 -404.284261) (xy 102.265709 -404.231966)
			(xy 102.288351 -404.182389) (xy 102.317817 -404.136539) (xy 102.353508 -404.095348) (xy 102.394699 -404.059657)
			(xy 102.440549 -404.030191) (xy 102.490126 -404.007549) (xy 102.542421 -403.992194) (xy 102.596369 -403.984438)
			(xy 102.650871 -403.984438) (xy 102.704819 -403.992194) (xy 102.757114 -404.007549) (xy 102.806691 -404.030191)
			(xy 102.852541 -404.059657) (xy 102.893732 -404.095348) (xy 102.929423 -404.136539) (xy 102.958889 -404.182389)
			(xy 102.981531 -404.231966) (xy 102.996886 -404.284261) (xy 103.004642 -404.338209) (xy 103.005128 -404.36546)
			(xy 103.005128 -405.22906) (xy 103.004642 -405.256311) (xy 102.996886 -405.310259) (xy 102.981531 -405.362554)
			(xy 102.958889 -405.412131) (xy 102.929423 -405.457981) (xy 102.893732 -405.499172) (xy 102.852541 -405.534863)
			(xy 102.806691 -405.564329) (xy 102.757114 -405.586971) (xy 102.704819 -405.602326) (xy 102.650871 -405.610082)
			(xy 102.596369 -405.610082) (xy 102.542421 -405.602326) (xy 102.490126 -405.586971) (xy 102.440549 -405.564329)
			(xy 102.394699 -405.534863) (xy 102.353508 -405.499172) (xy 102.317817 -405.457981) (xy 102.288351 -405.412131)
			(xy 102.265709 -405.362554) (xy 102.250354 -405.310259) (xy 102.242598 -405.256311) (xy 102.242112 -405.22906)
			(xy 3.748786 -405.22906) (xy 5.555234 -407.035508) (xy 15.978632 -407.035508) (xy 15.978632 -406.171908)
			(xy 15.979118 -406.144657) (xy 15.986874 -406.090709) (xy 16.002229 -406.038414) (xy 16.024871 -405.988837)
			(xy 16.054337 -405.942987) (xy 16.090028 -405.901796) (xy 16.131219 -405.866105) (xy 16.177069 -405.836639)
			(xy 16.226646 -405.813997) (xy 16.278941 -405.798642) (xy 16.332889 -405.790886) (xy 16.387391 -405.790886)
			(xy 16.441339 -405.798642) (xy 16.493634 -405.813997) (xy 16.543211 -405.836639) (xy 16.589061 -405.866105)
			(xy 16.630252 -405.901796) (xy 16.665943 -405.942987) (xy 16.695409 -405.988837) (xy 16.718051 -406.038414)
			(xy 16.733406 -406.090709) (xy 16.741162 -406.144657) (xy 16.741648 -406.171908) (xy 16.741648 -407.031753)
			(xy 48.944975 -407.031753) (xy 48.944975 -406.977247) (xy 48.952733 -406.923295) (xy 48.96809 -406.870997)
			(xy 48.990734 -406.821417) (xy 49.020204 -406.775565) (xy 49.0559 -406.734373) (xy 49.097095 -406.698681)
			(xy 49.142951 -406.669216) (xy 49.192533 -406.646577) (xy 49.244833 -406.631225) (xy 49.298785 -406.623473)
			(xy 49.326038 -406.623012) (xy 50.189638 -406.623012) (xy 50.216889 -406.62346) (xy 50.270835 -406.631222)
			(xy 50.323128 -406.646581) (xy 50.372703 -406.669225) (xy 50.418551 -406.698694) (xy 50.459739 -406.734388)
			(xy 50.495428 -406.775579) (xy 50.524893 -406.82143) (xy 50.547532 -406.871007) (xy 50.562886 -406.923302)
			(xy 50.570642 -406.977249) (xy 50.570642 -407.031749) (xy 52.008298 -407.031749) (xy 52.008298 -406.977251)
			(xy 52.016054 -406.923308) (xy 52.031407 -406.871018) (xy 52.054045 -406.821445) (xy 52.083508 -406.775598)
			(xy 52.119195 -406.734411) (xy 52.16038 -406.698721) (xy 52.206226 -406.669256) (xy 52.255797 -406.646615)
			(xy 52.308087 -406.631258) (xy 52.362029 -406.6235) (xy 52.389278 -406.623012) (xy 53.252878 -406.623012)
			(xy 53.280133 -406.623433) (xy 53.33409 -406.631188) (xy 53.386393 -406.646543) (xy 53.435978 -406.669186)
			(xy 53.481837 -406.698655) (xy 53.523034 -406.73435) (xy 53.558732 -406.775546) (xy 53.588204 -406.821402)
			(xy 53.610849 -406.870987) (xy 53.626207 -406.923289) (xy 53.633965 -406.977245) (xy 53.633965 -407.031752)
			(xy 55.071475 -407.031752) (xy 55.071475 -406.977248) (xy 55.079232 -406.923298) (xy 55.094589 -406.871002)
			(xy 55.117231 -406.821423) (xy 55.146699 -406.775571) (xy 55.182393 -406.73438) (xy 55.223586 -406.698688)
			(xy 55.269439 -406.669222) (xy 55.319018 -406.646582) (xy 55.371316 -406.631229) (xy 55.425266 -406.623474)
			(xy 55.452518 -406.623012) (xy 56.316118 -406.623012) (xy 56.34337 -406.623459) (xy 56.397318 -406.631218)
			(xy 56.449614 -406.646576) (xy 56.499191 -406.669219) (xy 56.545042 -406.698687) (xy 56.586232 -406.734381)
			(xy 56.621924 -406.775573) (xy 56.65139 -406.821424) (xy 56.674031 -406.871003) (xy 56.689386 -406.923299)
			(xy 56.697142 -406.977248) (xy 56.697142 -407.031748) (xy 58.134798 -407.031748) (xy 58.134798 -406.977252)
			(xy 58.142553 -406.923311) (xy 58.157905 -406.871022) (xy 58.180542 -406.821451) (xy 58.210003 -406.775605)
			(xy 58.245688 -406.734418) (xy 58.286871 -406.698728) (xy 58.332714 -406.669262) (xy 58.382283 -406.64662)
			(xy 58.43457 -406.631262) (xy 58.48851 -406.623501) (xy 58.515758 -406.623012) (xy 59.379358 -406.623012)
			(xy 59.406614 -406.623432) (xy 59.460573 -406.631185) (xy 59.512878 -406.646538) (xy 59.562466 -406.669179)
			(xy 59.608327 -406.698648) (xy 59.649527 -406.734343) (xy 59.685227 -406.775539) (xy 59.714701 -406.821397)
			(xy 59.737348 -406.870982) (xy 59.752707 -406.923286) (xy 59.760465 -406.977244) (xy 59.760465 -407.03175)
			(xy 61.197998 -407.03175) (xy 61.197998 -406.97725) (xy 61.205754 -406.923306) (xy 61.221108 -406.871014)
			(xy 61.243748 -406.821439) (xy 61.273213 -406.775592) (xy 61.308902 -406.734404) (xy 61.35009 -406.698714)
			(xy 61.395938 -406.669249) (xy 61.445512 -406.646609) (xy 61.497804 -406.631255) (xy 61.551748 -406.623498)
			(xy 61.578998 -406.623012) (xy 62.442598 -406.623012) (xy 62.469852 -406.623435) (xy 62.523806 -406.631192)
			(xy 62.576107 -406.646549) (xy 62.62569 -406.669192) (xy 62.671546 -406.698662) (xy 62.712741 -406.734357)
			(xy 62.748437 -406.775552) (xy 62.777907 -406.821408) (xy 62.800551 -406.870991) (xy 62.815908 -406.923292)
			(xy 62.823665 -406.977246) (xy 62.823665 -407.031753) (xy 64.261175 -407.031753) (xy 64.261175 -406.977247)
			(xy 64.268933 -406.923295) (xy 64.28429 -406.870997) (xy 64.306934 -406.821417) (xy 64.336404 -406.775565)
			(xy 64.3721 -406.734373) (xy 64.413295 -406.698681) (xy 64.459151 -406.669216) (xy 64.508733 -406.646577)
			(xy 64.561033 -406.631225) (xy 64.614985 -406.623473) (xy 64.642238 -406.623012) (xy 65.505838 -406.623012)
			(xy 65.533089 -406.62346) (xy 65.587035 -406.631222) (xy 65.639328 -406.646581) (xy 65.688903 -406.669225)
			(xy 65.734751 -406.698694) (xy 65.775939 -406.734388) (xy 65.811628 -406.775579) (xy 65.841093 -406.82143)
			(xy 65.863732 -406.871007) (xy 65.879086 -406.923302) (xy 65.886842 -406.977249) (xy 65.886842 -407.031749)
			(xy 67.324498 -407.031749) (xy 67.324498 -406.977251) (xy 67.332254 -406.923308) (xy 67.347607 -406.871018)
			(xy 67.370245 -406.821445) (xy 67.399708 -406.775598) (xy 67.435395 -406.734411) (xy 67.47658 -406.698721)
			(xy 67.522426 -406.669256) (xy 67.571997 -406.646615) (xy 67.624287 -406.631258) (xy 67.678229 -406.6235)
			(xy 67.705478 -406.623012) (xy 68.569078 -406.623012) (xy 68.596333 -406.623433) (xy 68.65029 -406.631188)
			(xy 68.702593 -406.646543) (xy 68.752178 -406.669186) (xy 68.798037 -406.698655) (xy 68.839234 -406.73435)
			(xy 68.874932 -406.775546) (xy 68.904404 -406.821402) (xy 68.927049 -406.870987) (xy 68.942407 -406.923289)
			(xy 68.950165 -406.977245) (xy 68.950165 -407.031752) (xy 70.387675 -407.031752) (xy 70.387675 -406.977248)
			(xy 70.395432 -406.923298) (xy 70.410789 -406.871002) (xy 70.433431 -406.821423) (xy 70.462899 -406.775571)
			(xy 70.498593 -406.73438) (xy 70.539786 -406.698688) (xy 70.585639 -406.669222) (xy 70.635218 -406.646582)
			(xy 70.687516 -406.631229) (xy 70.741466 -406.623474) (xy 70.768718 -406.623012) (xy 71.632318 -406.623012)
			(xy 71.65957 -406.623459) (xy 71.713518 -406.631218) (xy 71.765814 -406.646576) (xy 71.815391 -406.669219)
			(xy 71.861242 -406.698687) (xy 71.902432 -406.734381) (xy 71.938124 -406.775573) (xy 71.96759 -406.821424)
			(xy 71.990231 -406.871003) (xy 72.005586 -406.923299) (xy 72.013342 -406.977248) (xy 72.013342 -407.031748)
			(xy 73.450998 -407.031748) (xy 73.450998 -406.977252) (xy 73.458753 -406.923311) (xy 73.474105 -406.871022)
			(xy 73.496742 -406.821451) (xy 73.526203 -406.775605) (xy 73.561888 -406.734418) (xy 73.603071 -406.698728)
			(xy 73.648914 -406.669262) (xy 73.698483 -406.64662) (xy 73.75077 -406.631262) (xy 73.80471 -406.623501)
			(xy 73.831958 -406.623012) (xy 74.695558 -406.623012) (xy 74.722814 -406.623432) (xy 74.776773 -406.631185)
			(xy 74.829078 -406.646538) (xy 74.878666 -406.669179) (xy 74.924527 -406.698648) (xy 74.965727 -406.734343)
			(xy 75.001427 -406.775539) (xy 75.030901 -406.821397) (xy 75.053548 -406.870982) (xy 75.068907 -406.923286)
			(xy 75.076665 -406.977244) (xy 75.076665 -407.03175) (xy 76.514198 -407.03175) (xy 76.514198 -406.97725)
			(xy 76.521954 -406.923306) (xy 76.537308 -406.871014) (xy 76.559948 -406.821439) (xy 76.589413 -406.775592)
			(xy 76.625102 -406.734404) (xy 76.66629 -406.698714) (xy 76.712138 -406.669249) (xy 76.761712 -406.646609)
			(xy 76.814004 -406.631255) (xy 76.867948 -406.623498) (xy 76.895198 -406.623012) (xy 77.758798 -406.623012)
			(xy 77.786052 -406.623435) (xy 77.840006 -406.631192) (xy 77.892307 -406.646549) (xy 77.94189 -406.669192)
			(xy 77.987746 -406.698662) (xy 78.028941 -406.734357) (xy 78.064637 -406.775552) (xy 78.094107 -406.821408)
			(xy 78.116751 -406.870991) (xy 78.132108 -406.923292) (xy 78.139865 -406.977246) (xy 78.139865 -407.031753)
			(xy 79.577375 -407.031753) (xy 79.577375 -406.977247) (xy 79.585133 -406.923295) (xy 79.60049 -406.870997)
			(xy 79.623134 -406.821417) (xy 79.652604 -406.775565) (xy 79.6883 -406.734373) (xy 79.729495 -406.698681)
			(xy 79.775351 -406.669216) (xy 79.824933 -406.646577) (xy 79.877233 -406.631225) (xy 79.931185 -406.623473)
			(xy 79.958438 -406.623012) (xy 80.822038 -406.623012) (xy 80.849289 -406.62346) (xy 80.903235 -406.631222)
			(xy 80.955528 -406.646581) (xy 81.005103 -406.669225) (xy 81.050951 -406.698694) (xy 81.092139 -406.734388)
			(xy 81.127828 -406.775579) (xy 81.157293 -406.82143) (xy 81.179932 -406.871007) (xy 81.195286 -406.923302)
			(xy 81.203042 -406.977249) (xy 81.203042 -407.031749) (xy 82.640698 -407.031749) (xy 82.640698 -406.977251)
			(xy 82.648454 -406.923308) (xy 82.663807 -406.871018) (xy 82.686445 -406.821445) (xy 82.715908 -406.775598)
			(xy 82.751595 -406.734411) (xy 82.79278 -406.698721) (xy 82.838626 -406.669256) (xy 82.888197 -406.646615)
			(xy 82.940487 -406.631258) (xy 82.994429 -406.6235) (xy 83.021678 -406.623012) (xy 83.885278 -406.623012)
			(xy 83.912533 -406.623433) (xy 83.96649 -406.631188) (xy 84.018793 -406.646543) (xy 84.068378 -406.669186)
			(xy 84.114237 -406.698655) (xy 84.155434 -406.73435) (xy 84.191132 -406.775546) (xy 84.220604 -406.821402)
			(xy 84.243249 -406.870987) (xy 84.258607 -406.923289) (xy 84.266365 -406.977245) (xy 84.266365 -407.031752)
			(xy 85.703875 -407.031752) (xy 85.703875 -406.977248) (xy 85.711632 -406.923298) (xy 85.726989 -406.871002)
			(xy 85.749631 -406.821423) (xy 85.779099 -406.775571) (xy 85.814793 -406.73438) (xy 85.855986 -406.698688)
			(xy 85.901839 -406.669222) (xy 85.951418 -406.646582) (xy 86.003716 -406.631229) (xy 86.057666 -406.623474)
			(xy 86.084918 -406.623012) (xy 86.948518 -406.623012) (xy 86.97577 -406.623459) (xy 87.029718 -406.631218)
			(xy 87.082014 -406.646576) (xy 87.131591 -406.669219) (xy 87.177442 -406.698687) (xy 87.218632 -406.734381)
			(xy 87.254324 -406.775573) (xy 87.28379 -406.821424) (xy 87.306431 -406.871003) (xy 87.321786 -406.923299)
			(xy 87.329542 -406.977248) (xy 87.329542 -407.031748) (xy 88.767198 -407.031748) (xy 88.767198 -406.977252)
			(xy 88.774953 -406.923311) (xy 88.790305 -406.871022) (xy 88.812942 -406.821451) (xy 88.842403 -406.775605)
			(xy 88.878088 -406.734418) (xy 88.919271 -406.698728) (xy 88.965114 -406.669262) (xy 89.014683 -406.64662)
			(xy 89.06697 -406.631262) (xy 89.12091 -406.623501) (xy 89.148158 -406.623012) (xy 90.011758 -406.623012)
			(xy 90.039014 -406.623432) (xy 90.092973 -406.631185) (xy 90.145278 -406.646538) (xy 90.194866 -406.669179)
			(xy 90.240727 -406.698648) (xy 90.281927 -406.734343) (xy 90.317627 -406.775539) (xy 90.347101 -406.821397)
			(xy 90.369748 -406.870982) (xy 90.385107 -406.923286) (xy 90.392865 -406.977244) (xy 90.392865 -407.03175)
			(xy 91.830398 -407.03175) (xy 91.830398 -406.97725) (xy 91.838154 -406.923306) (xy 91.853508 -406.871014)
			(xy 91.876148 -406.821439) (xy 91.905613 -406.775592) (xy 91.941302 -406.734404) (xy 91.98249 -406.698714)
			(xy 92.028338 -406.669249) (xy 92.077912 -406.646609) (xy 92.130204 -406.631255) (xy 92.184148 -406.623498)
			(xy 92.211398 -406.623012) (xy 93.074998 -406.623012) (xy 93.102252 -406.623435) (xy 93.156206 -406.631192)
			(xy 93.208507 -406.646549) (xy 93.25809 -406.669192) (xy 93.303946 -406.698662) (xy 93.345141 -406.734357)
			(xy 93.380837 -406.775552) (xy 93.410307 -406.821408) (xy 93.432951 -406.870991) (xy 93.448308 -406.923292)
			(xy 93.456065 -406.977246) (xy 93.456065 -407.031753) (xy 94.893575 -407.031753) (xy 94.893575 -406.977247)
			(xy 94.901333 -406.923295) (xy 94.91669 -406.870997) (xy 94.939334 -406.821417) (xy 94.968804 -406.775565)
			(xy 95.0045 -406.734373) (xy 95.045695 -406.698681) (xy 95.091551 -406.669216) (xy 95.141133 -406.646577)
			(xy 95.193433 -406.631225) (xy 95.247385 -406.623473) (xy 95.274638 -406.623012) (xy 96.138238 -406.623012)
			(xy 96.165489 -406.62346) (xy 96.219435 -406.631222) (xy 96.271728 -406.646581) (xy 96.321303 -406.669225)
			(xy 96.367151 -406.698694) (xy 96.408339 -406.734388) (xy 96.444028 -406.775579) (xy 96.473493 -406.82143)
			(xy 96.496132 -406.871007) (xy 96.511486 -406.923302) (xy 96.519242 -406.977249) (xy 96.519242 -407.031751)
			(xy 96.511486 -407.085698) (xy 96.496132 -407.137993) (xy 96.495694 -407.138953) (xy 106.243063 -407.138953)
			(xy 106.243063 -407.084447) (xy 106.250821 -407.030495) (xy 106.266177 -406.978197) (xy 106.288821 -406.928617)
			(xy 106.31829 -406.882763) (xy 106.353985 -406.841571) (xy 106.395179 -406.805878) (xy 106.441034 -406.776411)
			(xy 106.490616 -406.75377) (xy 106.542915 -406.738416) (xy 106.596867 -406.730662) (xy 106.62412 -406.7302)
			(xy 107.48772 -406.7302) (xy 107.514971 -406.730671) (xy 107.568918 -406.73843) (xy 107.621211 -406.753787)
			(xy 107.670787 -406.77643) (xy 107.716636 -406.805898) (xy 107.757824 -406.84159) (xy 107.793514 -406.88278)
			(xy 107.82298 -406.928631) (xy 107.84562 -406.978208) (xy 107.860974 -407.030502) (xy 107.861153 -407.031748)
			(xy 121.120198 -407.031748) (xy 121.120198 -406.977252) (xy 121.127953 -406.923312) (xy 121.143305 -406.871023)
			(xy 121.165942 -406.821452) (xy 121.195402 -406.775606) (xy 121.231087 -406.734419) (xy 121.272269 -406.69873)
			(xy 121.318111 -406.669264) (xy 121.36768 -406.646621) (xy 121.419967 -406.631263) (xy 121.473906 -406.623501)
			(xy 121.501154 -406.623012) (xy 122.364754 -406.623012) (xy 122.39201 -406.623432) (xy 122.445969 -406.631184)
			(xy 122.498275 -406.646537) (xy 122.547864 -406.669178) (xy 122.593725 -406.698646) (xy 122.634926 -406.734342)
			(xy 122.670626 -406.775538) (xy 122.7001 -406.821396) (xy 122.722747 -406.870981) (xy 122.738106 -406.923286)
			(xy 122.745865 -406.977244) (xy 122.745865 -407.03175) (xy 124.183398 -407.03175) (xy 124.183398 -406.97725)
			(xy 124.191154 -406.923306) (xy 124.206508 -406.871015) (xy 124.229148 -406.821441) (xy 124.258612 -406.775593)
			(xy 124.294301 -406.734405) (xy 124.335488 -406.698715) (xy 124.381335 -406.669251) (xy 124.430909 -406.64661)
			(xy 124.4832 -406.631255) (xy 124.537144 -406.623499) (xy 124.564394 -406.623012) (xy 125.427994 -406.623012)
			(xy 125.455249 -406.623434) (xy 125.509203 -406.631191) (xy 125.561504 -406.646548) (xy 125.611088 -406.669191)
			(xy 125.656944 -406.69866) (xy 125.69814 -406.734356) (xy 125.733836 -406.775551) (xy 125.763306 -406.821407)
			(xy 125.78595 -406.87099) (xy 125.801308 -406.923291) (xy 125.809065 -406.977245) (xy 125.809065 -407.031753)
			(xy 127.246575 -407.031753) (xy 127.246575 -406.977247) (xy 127.254333 -406.923296) (xy 127.26969 -406.870998)
			(xy 127.292334 -406.821418) (xy 127.321803 -406.775566) (xy 127.357499 -406.734375) (xy 127.398693 -406.698683)
			(xy 127.444548 -406.669217) (xy 127.49413 -406.646578) (xy 127.546429 -406.631226) (xy 127.600381 -406.623473)
			(xy 127.627634 -406.623012) (xy 128.491234 -406.623012) (xy 128.518485 -406.62346) (xy 128.572432 -406.631221)
			(xy 128.624725 -406.64658) (xy 128.674301 -406.669224) (xy 128.720149 -406.698693) (xy 128.761338 -406.734386)
			(xy 128.797028 -406.775578) (xy 128.826492 -406.821429) (xy 128.849132 -406.871007) (xy 128.864486 -406.923301)
			(xy 128.872242 -406.977249) (xy 128.872242 -407.031749) (xy 130.309898 -407.031749) (xy 130.309898 -406.977251)
			(xy 130.317654 -406.923309) (xy 130.333007 -406.871019) (xy 130.355645 -406.821446) (xy 130.385107 -406.775599)
			(xy 130.420794 -406.734412) (xy 130.461979 -406.698722) (xy 130.507823 -406.669257) (xy 130.557395 -406.646616)
			(xy 130.609683 -406.631259) (xy 130.663625 -406.6235) (xy 130.690874 -406.623012) (xy 131.554474 -406.623012)
			(xy 131.58173 -406.623433) (xy 131.635686 -406.631187) (xy 131.68799 -406.646542) (xy 131.737576 -406.669184)
			(xy 131.783435 -406.698653) (xy 131.824633 -406.734349) (xy 131.860331 -406.775544) (xy 131.889803 -406.821401)
			(xy 131.912449 -406.870986) (xy 131.927807 -406.923288) (xy 131.935565 -406.977245) (xy 131.935565 -407.031752)
			(xy 133.373075 -407.031752) (xy 133.373075 -406.977248) (xy 133.380832 -406.923299) (xy 133.396188 -406.871002)
			(xy 133.418831 -406.821424) (xy 133.448298 -406.775573) (xy 133.483992 -406.734382) (xy 133.525184 -406.69869)
			(xy 133.571036 -406.669224) (xy 133.620616 -406.646583) (xy 133.672912 -406.631229) (xy 133.726862 -406.623474)
			(xy 133.754114 -406.623012) (xy 134.617714 -406.623012) (xy 134.644966 -406.623459) (xy 134.698915 -406.631217)
			(xy 134.751211 -406.646574) (xy 134.800789 -406.669218) (xy 134.84664 -406.698686) (xy 134.887831 -406.734379)
			(xy 134.923523 -406.775571) (xy 134.952989 -406.821423) (xy 134.97563 -406.871002) (xy 134.990986 -406.923299)
			(xy 134.998742 -406.977248) (xy 134.998742 -407.031748) (xy 136.436398 -407.031748) (xy 136.436398 -406.977252)
			(xy 136.444153 -406.923312) (xy 136.459505 -406.871023) (xy 136.482142 -406.821452) (xy 136.511602 -406.775606)
			(xy 136.547287 -406.734419) (xy 136.588469 -406.69873) (xy 136.634311 -406.669264) (xy 136.68388 -406.646621)
			(xy 136.736167 -406.631263) (xy 136.790106 -406.623501) (xy 136.817354 -406.623012) (xy 137.680954 -406.623012)
			(xy 137.70821 -406.623432) (xy 137.762169 -406.631184) (xy 137.814475 -406.646537) (xy 137.864064 -406.669178)
			(xy 137.909925 -406.698646) (xy 137.951126 -406.734342) (xy 137.986826 -406.775538) (xy 138.0163 -406.821396)
			(xy 138.038947 -406.870981) (xy 138.054306 -406.923286) (xy 138.062065 -406.977244) (xy 138.062065 -407.03175)
			(xy 139.499598 -407.03175) (xy 139.499598 -406.97725) (xy 139.507354 -406.923306) (xy 139.522708 -406.871015)
			(xy 139.545348 -406.821441) (xy 139.574812 -406.775593) (xy 139.610501 -406.734405) (xy 139.651688 -406.698715)
			(xy 139.697535 -406.669251) (xy 139.747109 -406.64661) (xy 139.7994 -406.631255) (xy 139.853344 -406.623499)
			(xy 139.880594 -406.623012) (xy 140.744194 -406.623012) (xy 140.771449 -406.623434) (xy 140.825403 -406.631191)
			(xy 140.877704 -406.646548) (xy 140.927288 -406.669191) (xy 140.973144 -406.69866) (xy 141.01434 -406.734356)
			(xy 141.050036 -406.775551) (xy 141.079506 -406.821407) (xy 141.10215 -406.87099) (xy 141.117508 -406.923291)
			(xy 141.125265 -406.977245) (xy 141.125265 -407.031753) (xy 142.562775 -407.031753) (xy 142.562775 -406.977247)
			(xy 142.570533 -406.923296) (xy 142.58589 -406.870998) (xy 142.608534 -406.821418) (xy 142.638003 -406.775566)
			(xy 142.673699 -406.734375) (xy 142.714893 -406.698683) (xy 142.760748 -406.669217) (xy 142.81033 -406.646578)
			(xy 142.862629 -406.631226) (xy 142.916581 -406.623473) (xy 142.943834 -406.623012) (xy 143.807434 -406.623012)
			(xy 143.834685 -406.62346) (xy 143.888632 -406.631221) (xy 143.940925 -406.64658) (xy 143.990501 -406.669224)
			(xy 144.036349 -406.698693) (xy 144.077538 -406.734386) (xy 144.113228 -406.775578) (xy 144.142692 -406.821429)
			(xy 144.165332 -406.871007) (xy 144.180686 -406.923301) (xy 144.188442 -406.977249) (xy 144.188442 -407.031749)
			(xy 145.626098 -407.031749) (xy 145.626098 -406.977251) (xy 145.633854 -406.923309) (xy 145.649207 -406.871019)
			(xy 145.671845 -406.821446) (xy 145.701307 -406.775599) (xy 145.736994 -406.734412) (xy 145.778179 -406.698722)
			(xy 145.824023 -406.669257) (xy 145.873595 -406.646616) (xy 145.925883 -406.631259) (xy 145.979825 -406.6235)
			(xy 146.007074 -406.623012) (xy 146.870674 -406.623012) (xy 146.89793 -406.623433) (xy 146.951886 -406.631187)
			(xy 147.00419 -406.646542) (xy 147.053776 -406.669184) (xy 147.099635 -406.698653) (xy 147.140833 -406.734349)
			(xy 147.176531 -406.775544) (xy 147.206003 -406.821401) (xy 147.228649 -406.870986) (xy 147.244007 -406.923288)
			(xy 147.251765 -406.977245) (xy 147.251765 -407.031752) (xy 148.689275 -407.031752) (xy 148.689275 -406.977248)
			(xy 148.697032 -406.923299) (xy 148.712388 -406.871002) (xy 148.735031 -406.821424) (xy 148.764498 -406.775573)
			(xy 148.800192 -406.734382) (xy 148.841384 -406.69869) (xy 148.887236 -406.669224) (xy 148.936816 -406.646583)
			(xy 148.989112 -406.631229) (xy 149.043062 -406.623474) (xy 149.070314 -406.623012) (xy 149.933914 -406.623012)
			(xy 149.961166 -406.623459) (xy 150.015115 -406.631217) (xy 150.067411 -406.646574) (xy 150.116989 -406.669218)
			(xy 150.16284 -406.698686) (xy 150.204031 -406.734379) (xy 150.239723 -406.775571) (xy 150.269189 -406.821423)
			(xy 150.29183 -406.871002) (xy 150.307186 -406.923299) (xy 150.314942 -406.977248) (xy 150.314942 -407.031748)
			(xy 151.752598 -407.031748) (xy 151.752598 -406.977252) (xy 151.760353 -406.923312) (xy 151.775705 -406.871023)
			(xy 151.798342 -406.821452) (xy 151.827802 -406.775606) (xy 151.863487 -406.734419) (xy 151.904669 -406.69873)
			(xy 151.950511 -406.669264) (xy 152.00008 -406.646621) (xy 152.052367 -406.631263) (xy 152.106306 -406.623501)
			(xy 152.133554 -406.623012) (xy 152.997154 -406.623012) (xy 153.02441 -406.623432) (xy 153.078369 -406.631184)
			(xy 153.130675 -406.646537) (xy 153.180264 -406.669178) (xy 153.226125 -406.698646) (xy 153.267326 -406.734342)
			(xy 153.303026 -406.775538) (xy 153.3325 -406.821396) (xy 153.355147 -406.870981) (xy 153.370506 -406.923286)
			(xy 153.378265 -406.977244) (xy 153.378265 -407.03175) (xy 154.815798 -407.03175) (xy 154.815798 -406.97725)
			(xy 154.823554 -406.923306) (xy 154.838908 -406.871015) (xy 154.861548 -406.821441) (xy 154.891012 -406.775593)
			(xy 154.926701 -406.734405) (xy 154.967888 -406.698715) (xy 155.013735 -406.669251) (xy 155.063309 -406.64661)
			(xy 155.1156 -406.631255) (xy 155.169544 -406.623499) (xy 155.196794 -406.623012) (xy 156.060394 -406.623012)
			(xy 156.087649 -406.623434) (xy 156.141603 -406.631191) (xy 156.193904 -406.646548) (xy 156.243488 -406.669191)
			(xy 156.289344 -406.69866) (xy 156.33054 -406.734356) (xy 156.366236 -406.775551) (xy 156.395706 -406.821407)
			(xy 156.41835 -406.87099) (xy 156.433708 -406.923291) (xy 156.441465 -406.977245) (xy 156.441465 -407.031753)
			(xy 157.878975 -407.031753) (xy 157.878975 -406.977247) (xy 157.886733 -406.923296) (xy 157.90209 -406.870998)
			(xy 157.924734 -406.821418) (xy 157.954203 -406.775566) (xy 157.989899 -406.734375) (xy 158.031093 -406.698683)
			(xy 158.076948 -406.669217) (xy 158.12653 -406.646578) (xy 158.178829 -406.631226) (xy 158.232781 -406.623473)
			(xy 158.260034 -406.623012) (xy 159.123634 -406.623012) (xy 159.150885 -406.62346) (xy 159.204832 -406.631221)
			(xy 159.257125 -406.64658) (xy 159.306701 -406.669224) (xy 159.352549 -406.698693) (xy 159.393738 -406.734386)
			(xy 159.429428 -406.775578) (xy 159.458892 -406.821429) (xy 159.481532 -406.871007) (xy 159.496886 -406.923301)
			(xy 159.504642 -406.977249) (xy 159.504642 -407.031749) (xy 160.942298 -407.031749) (xy 160.942298 -406.977251)
			(xy 160.950054 -406.923309) (xy 160.965407 -406.871019) (xy 160.988045 -406.821446) (xy 161.017507 -406.775599)
			(xy 161.053194 -406.734412) (xy 161.094379 -406.698722) (xy 161.140223 -406.669257) (xy 161.189795 -406.646616)
			(xy 161.242083 -406.631259) (xy 161.296025 -406.6235) (xy 161.323274 -406.623012) (xy 162.186874 -406.623012)
			(xy 162.21413 -406.623433) (xy 162.268086 -406.631187) (xy 162.32039 -406.646542) (xy 162.369976 -406.669184)
			(xy 162.415835 -406.698653) (xy 162.457033 -406.734349) (xy 162.492731 -406.775544) (xy 162.522203 -406.821401)
			(xy 162.544849 -406.870986) (xy 162.560207 -406.923288) (xy 162.567965 -406.977245) (xy 162.567965 -407.031752)
			(xy 164.005475 -407.031752) (xy 164.005475 -406.977248) (xy 164.013232 -406.923299) (xy 164.028588 -406.871002)
			(xy 164.051231 -406.821424) (xy 164.080698 -406.775573) (xy 164.116392 -406.734382) (xy 164.157584 -406.69869)
			(xy 164.203436 -406.669224) (xy 164.253016 -406.646583) (xy 164.305312 -406.631229) (xy 164.359262 -406.623474)
			(xy 164.386514 -406.623012) (xy 165.250114 -406.623012) (xy 165.277366 -406.623459) (xy 165.331315 -406.631217)
			(xy 165.383611 -406.646574) (xy 165.433189 -406.669218) (xy 165.47904 -406.698686) (xy 165.520231 -406.734379)
			(xy 165.555923 -406.775571) (xy 165.585389 -406.821423) (xy 165.60803 -406.871002) (xy 165.623386 -406.923299)
			(xy 165.631142 -406.977248) (xy 165.631142 -407.031748) (xy 167.068798 -407.031748) (xy 167.068798 -406.977252)
			(xy 167.076553 -406.923312) (xy 167.091905 -406.871023) (xy 167.114542 -406.821452) (xy 167.144002 -406.775606)
			(xy 167.179687 -406.734419) (xy 167.220869 -406.69873) (xy 167.266711 -406.669264) (xy 167.31628 -406.646621)
			(xy 167.368567 -406.631263) (xy 167.422506 -406.623501) (xy 167.449754 -406.623012) (xy 168.313354 -406.623012)
			(xy 168.34061 -406.623432) (xy 168.394569 -406.631184) (xy 168.446875 -406.646537) (xy 168.496464 -406.669178)
			(xy 168.542325 -406.698646) (xy 168.583526 -406.734342) (xy 168.619226 -406.775538) (xy 168.6487 -406.821396)
			(xy 168.671347 -406.870981) (xy 168.686706 -406.923286) (xy 168.694465 -406.977244) (xy 168.694465 -407.031749)
			(xy 304.945298 -407.031749) (xy 304.945298 -406.977251) (xy 304.953054 -406.923307) (xy 304.968408 -406.871016)
			(xy 304.991047 -406.821442) (xy 305.02051 -406.775595) (xy 305.056199 -406.734407) (xy 305.097385 -406.698718)
			(xy 305.143232 -406.669252) (xy 305.192805 -406.646612) (xy 305.245095 -406.631257) (xy 305.299039 -406.623499)
			(xy 305.326288 -406.623012) (xy 306.189888 -406.623012) (xy 306.217143 -406.623434) (xy 306.271098 -406.63119)
			(xy 306.3234 -406.646546) (xy 306.372984 -406.669189) (xy 306.418841 -406.698658) (xy 306.460038 -406.734354)
			(xy 306.495735 -406.775549) (xy 306.525205 -406.821405) (xy 306.54785 -406.870989) (xy 306.563207 -406.92329)
			(xy 306.570965 -406.977245) (xy 306.570965 -407.031753) (xy 308.008475 -407.031753) (xy 308.008475 -406.977247)
			(xy 308.016233 -406.923297) (xy 308.031589 -406.870999) (xy 308.054233 -406.82142) (xy 308.083702 -406.775568)
			(xy 308.119397 -406.734377) (xy 308.16059 -406.698685) (xy 308.206445 -406.669219) (xy 308.256026 -406.64658)
			(xy 308.308324 -406.631227) (xy 308.362275 -406.623473) (xy 308.389528 -406.623012) (xy 309.253128 -406.623012)
			(xy 309.280379 -406.62346) (xy 309.334327 -406.63122) (xy 309.386621 -406.646578) (xy 309.436197 -406.669222)
			(xy 309.482047 -406.698691) (xy 309.523236 -406.734384) (xy 309.558926 -406.775576) (xy 309.588391 -406.821427)
			(xy 309.611032 -406.871005) (xy 309.626386 -406.923301) (xy 309.634142 -406.977249) (xy 309.634142 -407.031748)
			(xy 311.071798 -407.031748) (xy 311.071798 -406.977252) (xy 311.079553 -406.92331) (xy 311.094906 -406.87102)
			(xy 311.117544 -406.821448) (xy 311.147005 -406.775601) (xy 311.182692 -406.734414) (xy 311.223876 -406.698725)
			(xy 311.26972 -406.669259) (xy 311.31929 -406.646617) (xy 311.371578 -406.63126) (xy 311.42552 -406.6235)
			(xy 311.452768 -406.623012) (xy 312.316368 -406.623012) (xy 312.343624 -406.623433) (xy 312.397581 -406.631186)
			(xy 312.449886 -406.64654) (xy 312.499472 -406.669182) (xy 312.545332 -406.698651) (xy 312.586531 -406.734347)
			(xy 312.62223 -406.775542) (xy 312.651702 -406.821399) (xy 312.674348 -406.870984) (xy 312.689707 -406.923288)
			(xy 312.697465 -406.977244) (xy 312.697465 -407.031752) (xy 314.134975 -407.031752) (xy 314.134975 -406.977248)
			(xy 314.142732 -406.923299) (xy 314.158088 -406.871004) (xy 314.18073 -406.821426) (xy 314.210197 -406.775575)
			(xy 314.245889 -406.734384) (xy 314.287081 -406.698692) (xy 314.332933 -406.669226) (xy 314.382511 -406.646585)
			(xy 314.434807 -406.63123) (xy 314.488756 -406.623475) (xy 314.516008 -406.623012) (xy 315.379608 -406.623012)
			(xy 315.40686 -406.623458) (xy 315.46081 -406.631216) (xy 315.513107 -406.646573) (xy 315.562685 -406.669216)
			(xy 315.608537 -406.698684) (xy 315.649729 -406.734377) (xy 315.685421 -406.775569) (xy 315.714888 -406.821422)
			(xy 315.73753 -406.871001) (xy 315.752885 -406.923298) (xy 315.760642 -406.977248) (xy 315.760642 -407.031752)
			(xy 315.760642 -407.031754) (xy 317.198175 -407.031754) (xy 317.198175 -406.977246) (xy 317.205933 -406.923294)
			(xy 317.221291 -406.870995) (xy 317.243936 -406.821414) (xy 317.273407 -406.775561) (xy 317.309104 -406.73437)
			(xy 317.3503 -406.698678) (xy 317.396157 -406.669213) (xy 317.44574 -406.646574) (xy 317.498041 -406.631223)
			(xy 317.551994 -406.623472) (xy 317.579248 -406.623012) (xy 318.442848 -406.623012) (xy 318.470098 -406.623461)
			(xy 318.524044 -406.631224) (xy 318.576336 -406.646584) (xy 318.625909 -406.669229) (xy 318.671756 -406.698698)
			(xy 318.712943 -406.734391) (xy 318.748631 -406.775582) (xy 318.778094 -406.821433) (xy 318.800733 -406.87101)
			(xy 318.816087 -406.923303) (xy 318.823842 -406.97725) (xy 318.823842 -407.031749) (xy 320.261498 -407.031749)
			(xy 320.261498 -406.977251) (xy 320.269254 -406.923307) (xy 320.284608 -406.871016) (xy 320.307247 -406.821442)
			(xy 320.33671 -406.775595) (xy 320.372399 -406.734407) (xy 320.413585 -406.698718) (xy 320.459432 -406.669252)
			(xy 320.509005 -406.646612) (xy 320.561295 -406.631257) (xy 320.615239 -406.623499) (xy 320.642488 -406.623012)
			(xy 321.506088 -406.623012) (xy 321.533343 -406.623434) (xy 321.587298 -406.63119) (xy 321.6396 -406.646546)
			(xy 321.689184 -406.669189) (xy 321.735041 -406.698658) (xy 321.776238 -406.734354) (xy 321.811935 -406.775549)
			(xy 321.841405 -406.821405) (xy 321.86405 -406.870989) (xy 321.879407 -406.92329) (xy 321.887165 -406.977245)
			(xy 321.887165 -407.031753) (xy 323.324675 -407.031753) (xy 323.324675 -406.977247) (xy 323.332433 -406.923297)
			(xy 323.347789 -406.870999) (xy 323.370433 -406.82142) (xy 323.399902 -406.775568) (xy 323.435597 -406.734377)
			(xy 323.47679 -406.698685) (xy 323.522645 -406.669219) (xy 323.572226 -406.64658) (xy 323.624524 -406.631227)
			(xy 323.678475 -406.623473) (xy 323.705728 -406.623012) (xy 324.569328 -406.623012) (xy 324.596579 -406.62346)
			(xy 324.650527 -406.63122) (xy 324.702821 -406.646578) (xy 324.752397 -406.669222) (xy 324.798247 -406.698691)
			(xy 324.839436 -406.734384) (xy 324.875126 -406.775576) (xy 324.904591 -406.821427) (xy 324.927232 -406.871005)
			(xy 324.942586 -406.923301) (xy 324.950342 -406.977249) (xy 324.950342 -407.031748) (xy 326.387998 -407.031748)
			(xy 326.387998 -406.977252) (xy 326.395753 -406.92331) (xy 326.411106 -406.87102) (xy 326.433744 -406.821448)
			(xy 326.463205 -406.775601) (xy 326.498892 -406.734414) (xy 326.540076 -406.698725) (xy 326.58592 -406.669259)
			(xy 326.63549 -406.646617) (xy 326.687778 -406.63126) (xy 326.74172 -406.6235) (xy 326.768968 -406.623012)
			(xy 327.632568 -406.623012) (xy 327.659824 -406.623433) (xy 327.713781 -406.631186) (xy 327.766086 -406.64654)
			(xy 327.815672 -406.669182) (xy 327.861532 -406.698651) (xy 327.902731 -406.734347) (xy 327.93843 -406.775542)
			(xy 327.967902 -406.821399) (xy 327.990548 -406.870984) (xy 328.005907 -406.923288) (xy 328.013665 -406.977244)
			(xy 328.013665 -407.031752) (xy 329.451175 -407.031752) (xy 329.451175 -406.977248) (xy 329.458932 -406.923299)
			(xy 329.474288 -406.871004) (xy 329.49693 -406.821426) (xy 329.526397 -406.775575) (xy 329.562089 -406.734384)
			(xy 329.603281 -406.698692) (xy 329.649133 -406.669226) (xy 329.698711 -406.646585) (xy 329.751007 -406.63123)
			(xy 329.804956 -406.623475) (xy 329.832208 -406.623012) (xy 330.695808 -406.623012) (xy 330.72306 -406.623458)
			(xy 330.77701 -406.631216) (xy 330.829307 -406.646573) (xy 330.878885 -406.669216) (xy 330.924737 -406.698684)
			(xy 330.965929 -406.734377) (xy 331.001621 -406.775569) (xy 331.031088 -406.821422) (xy 331.05373 -406.871001)
			(xy 331.069085 -406.923298) (xy 331.076842 -406.977248) (xy 331.076842 -407.031752) (xy 331.076842 -407.031754)
			(xy 332.514375 -407.031754) (xy 332.514375 -406.977246) (xy 332.522133 -406.923294) (xy 332.537491 -406.870995)
			(xy 332.560136 -406.821414) (xy 332.589607 -406.775561) (xy 332.625304 -406.73437) (xy 332.6665 -406.698678)
			(xy 332.712357 -406.669213) (xy 332.76194 -406.646574) (xy 332.814241 -406.631223) (xy 332.868194 -406.623472)
			(xy 332.895448 -406.623012) (xy 333.759048 -406.623012) (xy 333.786298 -406.623461) (xy 333.840244 -406.631224)
			(xy 333.892536 -406.646584) (xy 333.942109 -406.669229) (xy 333.987956 -406.698698) (xy 334.029143 -406.734391)
			(xy 334.064831 -406.775582) (xy 334.094294 -406.821433) (xy 334.116933 -406.87101) (xy 334.132287 -406.923303)
			(xy 334.140042 -406.97725) (xy 334.140042 -407.031749) (xy 335.577698 -407.031749) (xy 335.577698 -406.977251)
			(xy 335.585454 -406.923307) (xy 335.600808 -406.871016) (xy 335.623447 -406.821442) (xy 335.65291 -406.775595)
			(xy 335.688599 -406.734407) (xy 335.729785 -406.698718) (xy 335.775632 -406.669252) (xy 335.825205 -406.646612)
			(xy 335.877495 -406.631257) (xy 335.931439 -406.623499) (xy 335.958688 -406.623012) (xy 336.822288 -406.623012)
			(xy 336.849543 -406.623434) (xy 336.903498 -406.63119) (xy 336.9558 -406.646546) (xy 337.005384 -406.669189)
			(xy 337.051241 -406.698658) (xy 337.092438 -406.734354) (xy 337.128135 -406.775549) (xy 337.157605 -406.821405)
			(xy 337.18025 -406.870989) (xy 337.195607 -406.92329) (xy 337.203365 -406.977245) (xy 337.203365 -407.031753)
			(xy 338.640875 -407.031753) (xy 338.640875 -406.977247) (xy 338.648633 -406.923297) (xy 338.663989 -406.870999)
			(xy 338.686633 -406.82142) (xy 338.716102 -406.775568) (xy 338.751797 -406.734377) (xy 338.79299 -406.698685)
			(xy 338.838845 -406.669219) (xy 338.888426 -406.64658) (xy 338.940724 -406.631227) (xy 338.994675 -406.623473)
			(xy 339.021928 -406.623012) (xy 339.885528 -406.623012) (xy 339.912779 -406.62346) (xy 339.966727 -406.63122)
			(xy 340.019021 -406.646578) (xy 340.068597 -406.669222) (xy 340.114447 -406.698691) (xy 340.155636 -406.734384)
			(xy 340.191326 -406.775576) (xy 340.220791 -406.821427) (xy 340.243432 -406.871005) (xy 340.258786 -406.923301)
			(xy 340.266542 -406.977249) (xy 340.266542 -407.031748) (xy 341.704198 -407.031748) (xy 341.704198 -406.977252)
			(xy 341.711953 -406.92331) (xy 341.727306 -406.87102) (xy 341.749944 -406.821448) (xy 341.779405 -406.775601)
			(xy 341.815092 -406.734414) (xy 341.856276 -406.698725) (xy 341.90212 -406.669259) (xy 341.95169 -406.646617)
			(xy 342.003978 -406.63126) (xy 342.05792 -406.6235) (xy 342.085168 -406.623012) (xy 342.948768 -406.623012)
			(xy 342.976024 -406.623433) (xy 343.029981 -406.631186) (xy 343.082286 -406.64654) (xy 343.131872 -406.669182)
			(xy 343.177732 -406.698651) (xy 343.218931 -406.734347) (xy 343.25463 -406.775542) (xy 343.284102 -406.821399)
			(xy 343.306748 -406.870984) (xy 343.322107 -406.923288) (xy 343.329865 -406.977244) (xy 343.329865 -407.031752)
			(xy 344.767375 -407.031752) (xy 344.767375 -406.977248) (xy 344.775132 -406.923299) (xy 344.790488 -406.871004)
			(xy 344.81313 -406.821426) (xy 344.842597 -406.775575) (xy 344.878289 -406.734384) (xy 344.919481 -406.698692)
			(xy 344.965333 -406.669226) (xy 345.014911 -406.646585) (xy 345.067207 -406.63123) (xy 345.121156 -406.623475)
			(xy 345.148408 -406.623012) (xy 346.012008 -406.623012) (xy 346.03926 -406.623458) (xy 346.09321 -406.631216)
			(xy 346.145507 -406.646573) (xy 346.195085 -406.669216) (xy 346.240937 -406.698684) (xy 346.282129 -406.734377)
			(xy 346.317821 -406.775569) (xy 346.347288 -406.821422) (xy 346.36993 -406.871001) (xy 346.385285 -406.923298)
			(xy 346.393042 -406.977248) (xy 346.393042 -407.031752) (xy 346.393042 -407.031754) (xy 347.830575 -407.031754)
			(xy 347.830575 -406.977246) (xy 347.838333 -406.923294) (xy 347.853691 -406.870995) (xy 347.876336 -406.821414)
			(xy 347.905807 -406.775561) (xy 347.941504 -406.73437) (xy 347.9827 -406.698678) (xy 348.028557 -406.669213)
			(xy 348.07814 -406.646574) (xy 348.130441 -406.631223) (xy 348.184394 -406.623472) (xy 348.211648 -406.623012)
			(xy 349.075248 -406.623012) (xy 349.102498 -406.623461) (xy 349.156444 -406.631224) (xy 349.208736 -406.646584)
			(xy 349.258309 -406.669229) (xy 349.304156 -406.698698) (xy 349.345343 -406.734391) (xy 349.381031 -406.775582)
			(xy 349.410494 -406.821433) (xy 349.433133 -406.87101) (xy 349.448487 -406.923303) (xy 349.456242 -406.97725)
			(xy 349.456242 -407.031749) (xy 350.893898 -407.031749) (xy 350.893898 -406.977251) (xy 350.901654 -406.923307)
			(xy 350.917008 -406.871016) (xy 350.939647 -406.821442) (xy 350.96911 -406.775595) (xy 351.004799 -406.734407)
			(xy 351.045985 -406.698718) (xy 351.091832 -406.669252) (xy 351.141405 -406.646612) (xy 351.193695 -406.631257)
			(xy 351.247639 -406.623499) (xy 351.274888 -406.623012) (xy 352.138488 -406.623012) (xy 352.165743 -406.623434)
			(xy 352.219698 -406.63119) (xy 352.272 -406.646546) (xy 352.321584 -406.669189) (xy 352.367441 -406.698658)
			(xy 352.408638 -406.734354) (xy 352.444335 -406.775549) (xy 352.473805 -406.821405) (xy 352.49645 -406.870989)
			(xy 352.511807 -406.92329) (xy 352.519565 -406.977245) (xy 352.519565 -407.031753) (xy 372.388075 -407.031753)
			(xy 372.388075 -406.977247) (xy 372.395833 -406.923296) (xy 372.411189 -406.870999) (xy 372.433833 -406.821419)
			(xy 372.463302 -406.775567) (xy 372.498997 -406.734376) (xy 372.540191 -406.698684) (xy 372.586046 -406.669219)
			(xy 372.635627 -406.646579) (xy 372.687926 -406.631226) (xy 372.741877 -406.623473) (xy 372.76913 -406.623012)
			(xy 373.63273 -406.623012) (xy 373.659981 -406.62346) (xy 373.713929 -406.63122) (xy 373.766222 -406.646579)
			(xy 373.815799 -406.669223) (xy 373.861648 -406.698691) (xy 373.902836 -406.734385) (xy 373.938527 -406.775576)
			(xy 373.967992 -406.821428) (xy 373.990632 -406.871006) (xy 374.005986 -406.923301) (xy 374.013742 -406.977249)
			(xy 374.013742 -407.031748) (xy 375.451398 -407.031748) (xy 375.451398 -406.977252) (xy 375.459153 -406.923309)
			(xy 375.474506 -406.87102) (xy 375.497144 -406.821447) (xy 375.526606 -406.775601) (xy 375.562292 -406.734414)
			(xy 375.603477 -406.698724) (xy 375.649321 -406.669258) (xy 375.698892 -406.646617) (xy 375.75118 -406.63126)
			(xy 375.805122 -406.6235) (xy 375.83237 -406.623012) (xy 376.69597 -406.623012) (xy 376.723226 -406.623433)
			(xy 376.777183 -406.631187) (xy 376.829487 -406.646541) (xy 376.879074 -406.669183) (xy 376.924933 -406.698652)
			(xy 376.966131 -406.734347) (xy 377.00183 -406.775543) (xy 377.031303 -406.8214) (xy 377.053948 -406.870985)
			(xy 377.069307 -406.923288) (xy 377.077065 -406.977244) (xy 377.077065 -407.031752) (xy 378.514575 -407.031752)
			(xy 378.514575 -406.977248) (xy 378.522332 -406.923299) (xy 378.537688 -406.871003) (xy 378.56033 -406.821425)
			(xy 378.589797 -406.775574) (xy 378.62549 -406.734383) (xy 378.666682 -406.698691) (xy 378.712534 -406.669225)
			(xy 378.762113 -406.646584) (xy 378.814409 -406.63123) (xy 378.868358 -406.623475) (xy 378.89561 -406.623012)
			(xy 379.75921 -406.623012) (xy 379.786462 -406.623459) (xy 379.840412 -406.631217) (xy 379.892708 -406.646573)
			(xy 379.942287 -406.669216) (xy 379.988138 -406.698684) (xy 380.029329 -406.734378) (xy 380.065022 -406.77557)
			(xy 380.094489 -406.821422) (xy 380.11713 -406.871001) (xy 380.132486 -406.923298) (xy 380.140242 -406.977248)
			(xy 380.140242 -407.031748) (xy 381.577898 -407.031748) (xy 381.577898 -406.977252) (xy 381.585653 -406.923312)
			(xy 381.601005 -406.871024) (xy 381.623641 -406.821453) (xy 381.653101 -406.775607) (xy 381.688785 -406.734421)
			(xy 381.729967 -406.698731) (xy 381.775809 -406.669265) (xy 381.825377 -406.646622) (xy 381.877663 -406.631264)
			(xy 381.931603 -406.623502) (xy 381.95885 -406.623012) (xy 382.82245 -406.623012) (xy 382.849707 -406.623431)
			(xy 382.903666 -406.631183) (xy 382.955973 -406.646536) (xy 383.005562 -406.669176) (xy 383.051423 -406.698645)
			(xy 383.092624 -406.73434) (xy 383.128325 -406.775536) (xy 383.1578 -406.821394) (xy 383.180447 -406.870981)
			(xy 383.195806 -406.923285) (xy 383.203565 -406.977243) (xy 383.203565 -407.031749) (xy 384.641098 -407.031749)
			(xy 384.641098 -406.977251) (xy 384.648854 -406.923307) (xy 384.664208 -406.871016) (xy 384.686847 -406.821442)
			(xy 384.716311 -406.775594) (xy 384.751999 -406.734406) (xy 384.793186 -406.698717) (xy 384.839033 -406.669252)
			(xy 384.888606 -406.646611) (xy 384.940897 -406.631256) (xy 384.994841 -406.623499) (xy 385.02209 -406.623012)
			(xy 385.88569 -406.623012) (xy 385.912945 -406.623434) (xy 385.9669 -406.63119) (xy 386.019202 -406.646546)
			(xy 386.068786 -406.66919) (xy 386.114642 -406.698659) (xy 386.155838 -406.734354) (xy 386.191535 -406.77555)
			(xy 386.221006 -406.821406) (xy 386.24365 -406.870989) (xy 386.259007 -406.923291) (xy 386.266765 -406.977245)
			(xy 386.266765 -407.031753) (xy 387.704275 -407.031753) (xy 387.704275 -406.977247) (xy 387.712033 -406.923296)
			(xy 387.727389 -406.870999) (xy 387.750033 -406.821419) (xy 387.779502 -406.775567) (xy 387.815197 -406.734376)
			(xy 387.856391 -406.698684) (xy 387.902246 -406.669219) (xy 387.951827 -406.646579) (xy 388.004126 -406.631226)
			(xy 388.058077 -406.623473) (xy 388.08533 -406.623012) (xy 388.94893 -406.623012) (xy 388.976181 -406.62346)
			(xy 389.030129 -406.63122) (xy 389.082422 -406.646579) (xy 389.131999 -406.669223) (xy 389.177848 -406.698691)
			(xy 389.219036 -406.734385) (xy 389.254727 -406.775576) (xy 389.284192 -406.821428) (xy 389.306832 -406.871006)
			(xy 389.322186 -406.923301) (xy 389.329942 -406.977249) (xy 389.329942 -407.031748) (xy 390.767598 -407.031748)
			(xy 390.767598 -406.977252) (xy 390.775353 -406.923309) (xy 390.790706 -406.87102) (xy 390.813344 -406.821447)
			(xy 390.842806 -406.775601) (xy 390.878492 -406.734414) (xy 390.919677 -406.698724) (xy 390.965521 -406.669258)
			(xy 391.015092 -406.646617) (xy 391.06738 -406.63126) (xy 391.121322 -406.6235) (xy 391.14857 -406.623012)
			(xy 392.01217 -406.623012) (xy 392.039426 -406.623433) (xy 392.093383 -406.631187) (xy 392.145687 -406.646541)
			(xy 392.195274 -406.669183) (xy 392.241133 -406.698652) (xy 392.282331 -406.734347) (xy 392.31803 -406.775543)
			(xy 392.347503 -406.8214) (xy 392.370148 -406.870985) (xy 392.385507 -406.923288) (xy 392.393265 -406.977244)
			(xy 392.393265 -407.031752) (xy 393.830775 -407.031752) (xy 393.830775 -406.977248) (xy 393.838532 -406.923299)
			(xy 393.853888 -406.871003) (xy 393.87653 -406.821425) (xy 393.905997 -406.775574) (xy 393.94169 -406.734383)
			(xy 393.982882 -406.698691) (xy 394.028734 -406.669225) (xy 394.078313 -406.646584) (xy 394.130609 -406.63123)
			(xy 394.184558 -406.623475) (xy 394.21181 -406.623012) (xy 395.07541 -406.623012) (xy 395.102662 -406.623459)
			(xy 395.156612 -406.631217) (xy 395.208908 -406.646573) (xy 395.258487 -406.669216) (xy 395.304338 -406.698684)
			(xy 395.345529 -406.734378) (xy 395.381222 -406.77557) (xy 395.410689 -406.821422) (xy 395.43333 -406.871001)
			(xy 395.448686 -406.923298) (xy 395.456442 -406.977248) (xy 395.456442 -407.031748) (xy 396.894098 -407.031748)
			(xy 396.894098 -406.977252) (xy 396.901853 -406.923312) (xy 396.917205 -406.871024) (xy 396.939841 -406.821453)
			(xy 396.969301 -406.775607) (xy 397.004985 -406.734421) (xy 397.046167 -406.698731) (xy 397.092009 -406.669265)
			(xy 397.141577 -406.646622) (xy 397.193863 -406.631264) (xy 397.247803 -406.623502) (xy 397.27505 -406.623012)
			(xy 398.13865 -406.623012) (xy 398.165907 -406.623431) (xy 398.219866 -406.631183) (xy 398.272173 -406.646536)
			(xy 398.321762 -406.669176) (xy 398.367623 -406.698645) (xy 398.408824 -406.73434) (xy 398.444525 -406.775536)
			(xy 398.474 -406.821394) (xy 398.496647 -406.870981) (xy 398.512006 -406.923285) (xy 398.519765 -406.977243)
			(xy 398.519765 -407.031749) (xy 399.957298 -407.031749) (xy 399.957298 -406.977251) (xy 399.965054 -406.923307)
			(xy 399.980408 -406.871016) (xy 400.003047 -406.821442) (xy 400.032511 -406.775594) (xy 400.068199 -406.734406)
			(xy 400.109386 -406.698717) (xy 400.155233 -406.669252) (xy 400.204806 -406.646611) (xy 400.257097 -406.631256)
			(xy 400.311041 -406.623499) (xy 400.33829 -406.623012) (xy 401.20189 -406.623012) (xy 401.229145 -406.623434)
			(xy 401.2831 -406.63119) (xy 401.335402 -406.646546) (xy 401.384986 -406.66919) (xy 401.430842 -406.698659)
			(xy 401.472038 -406.734354) (xy 401.507735 -406.77555) (xy 401.537206 -406.821406) (xy 401.55985 -406.870989)
			(xy 401.575207 -406.923291) (xy 401.582965 -406.977245) (xy 401.582965 -407.031753) (xy 403.020475 -407.031753)
			(xy 403.020475 -406.977247) (xy 403.028233 -406.923296) (xy 403.043589 -406.870999) (xy 403.066233 -406.821419)
			(xy 403.095702 -406.775567) (xy 403.131397 -406.734376) (xy 403.172591 -406.698684) (xy 403.218446 -406.669219)
			(xy 403.268027 -406.646579) (xy 403.320326 -406.631226) (xy 403.374277 -406.623473) (xy 403.40153 -406.623012)
			(xy 404.26513 -406.623012) (xy 404.292381 -406.62346) (xy 404.346329 -406.63122) (xy 404.398622 -406.646579)
			(xy 404.448199 -406.669223) (xy 404.494048 -406.698691) (xy 404.535236 -406.734385) (xy 404.570927 -406.775576)
			(xy 404.600392 -406.821428) (xy 404.623032 -406.871006) (xy 404.638386 -406.923301) (xy 404.646142 -406.977249)
			(xy 404.646142 -407.031748) (xy 406.083798 -407.031748) (xy 406.083798 -406.977252) (xy 406.091553 -406.923309)
			(xy 406.106906 -406.87102) (xy 406.129544 -406.821447) (xy 406.159006 -406.775601) (xy 406.194692 -406.734414)
			(xy 406.235877 -406.698724) (xy 406.281721 -406.669258) (xy 406.331292 -406.646617) (xy 406.38358 -406.63126)
			(xy 406.437522 -406.6235) (xy 406.46477 -406.623012) (xy 407.32837 -406.623012) (xy 407.355626 -406.623433)
			(xy 407.409583 -406.631187) (xy 407.461887 -406.646541) (xy 407.511474 -406.669183) (xy 407.557333 -406.698652)
			(xy 407.598531 -406.734347) (xy 407.63423 -406.775543) (xy 407.663703 -406.8214) (xy 407.686348 -406.870985)
			(xy 407.701707 -406.923288) (xy 407.709465 -406.977244) (xy 407.709465 -407.031752) (xy 409.146975 -407.031752)
			(xy 409.146975 -406.977248) (xy 409.154732 -406.923299) (xy 409.170088 -406.871003) (xy 409.19273 -406.821425)
			(xy 409.222197 -406.775574) (xy 409.25789 -406.734383) (xy 409.299082 -406.698691) (xy 409.344934 -406.669225)
			(xy 409.394513 -406.646584) (xy 409.446809 -406.63123) (xy 409.500758 -406.623475) (xy 409.52801 -406.623012)
			(xy 410.39161 -406.623012) (xy 410.418862 -406.623459) (xy 410.472812 -406.631217) (xy 410.525108 -406.646573)
			(xy 410.574687 -406.669216) (xy 410.620538 -406.698684) (xy 410.661729 -406.734378) (xy 410.697422 -406.77557)
			(xy 410.726889 -406.821422) (xy 410.74953 -406.871001) (xy 410.764886 -406.923298) (xy 410.772642 -406.977248)
			(xy 410.772642 -407.031748) (xy 412.210298 -407.031748) (xy 412.210298 -406.977252) (xy 412.218053 -406.923312)
			(xy 412.233405 -406.871024) (xy 412.256041 -406.821453) (xy 412.285501 -406.775607) (xy 412.321185 -406.734421)
			(xy 412.362367 -406.698731) (xy 412.408209 -406.669265) (xy 412.457777 -406.646622) (xy 412.510063 -406.631264)
			(xy 412.564003 -406.623502) (xy 412.59125 -406.623012) (xy 413.45485 -406.623012) (xy 413.482107 -406.623431)
			(xy 413.536066 -406.631183) (xy 413.588373 -406.646536) (xy 413.637962 -406.669176) (xy 413.683823 -406.698645)
			(xy 413.725024 -406.73434) (xy 413.760725 -406.775536) (xy 413.7902 -406.821394) (xy 413.812847 -406.870981)
			(xy 413.828206 -406.923285) (xy 413.835965 -406.977243) (xy 413.835965 -407.031749) (xy 415.273498 -407.031749)
			(xy 415.273498 -406.977251) (xy 415.281254 -406.923307) (xy 415.296608 -406.871016) (xy 415.319247 -406.821442)
			(xy 415.348711 -406.775594) (xy 415.384399 -406.734406) (xy 415.425586 -406.698717) (xy 415.471433 -406.669252)
			(xy 415.521006 -406.646611) (xy 415.573297 -406.631256) (xy 415.627241 -406.623499) (xy 415.65449 -406.623012)
			(xy 416.51809 -406.623012) (xy 416.545345 -406.623434) (xy 416.5993 -406.63119) (xy 416.651602 -406.646546)
			(xy 416.701186 -406.66919) (xy 416.747042 -406.698659) (xy 416.788238 -406.734354) (xy 416.823935 -406.77555)
			(xy 416.853406 -406.821406) (xy 416.87605 -406.870989) (xy 416.891407 -406.923291) (xy 416.899165 -406.977245)
			(xy 416.899165 -407.031753) (xy 418.336675 -407.031753) (xy 418.336675 -406.977247) (xy 418.344433 -406.923296)
			(xy 418.359789 -406.870999) (xy 418.382433 -406.821419) (xy 418.411902 -406.775567) (xy 418.447597 -406.734376)
			(xy 418.488791 -406.698684) (xy 418.534646 -406.669219) (xy 418.584227 -406.646579) (xy 418.636526 -406.631226)
			(xy 418.690477 -406.623473) (xy 418.71773 -406.623012) (xy 419.58133 -406.623012) (xy 419.608581 -406.62346)
			(xy 419.662529 -406.63122) (xy 419.714822 -406.646579) (xy 419.764399 -406.669223) (xy 419.810248 -406.698691)
			(xy 419.851436 -406.734385) (xy 419.887127 -406.775576) (xy 419.916592 -406.821428) (xy 419.939232 -406.871006)
			(xy 419.954586 -406.923301) (xy 419.962342 -406.977249) (xy 419.962342 -407.031751) (xy 419.954586 -407.085699)
			(xy 419.939232 -407.137994) (xy 419.916592 -407.187572) (xy 419.887127 -407.233424) (xy 419.851436 -407.274615)
			(xy 419.810248 -407.310309) (xy 419.764399 -407.339777) (xy 419.714822 -407.362421) (xy 419.662529 -407.37778)
			(xy 419.608581 -407.38554) (xy 419.58133 -407.386028) (xy 418.71773 -407.386028) (xy 418.690477 -407.385527)
			(xy 418.636526 -407.377774) (xy 418.584227 -407.362421) (xy 418.534646 -407.339781) (xy 418.488791 -407.310316)
			(xy 418.447597 -407.274624) (xy 418.411902 -407.233433) (xy 418.382433 -407.187581) (xy 418.359789 -407.138001)
			(xy 418.344433 -407.085704) (xy 418.336675 -407.031753) (xy 416.899165 -407.031753) (xy 416.899165 -407.031755)
			(xy 416.891407 -407.085709) (xy 416.87605 -407.138011) (xy 416.853406 -407.187594) (xy 416.823935 -407.23345)
			(xy 416.788238 -407.274646) (xy 416.747042 -407.310341) (xy 416.701186 -407.33981) (xy 416.651602 -407.362454)
			(xy 416.5993 -407.37781) (xy 416.545345 -407.385566) (xy 416.51809 -407.386028) (xy 415.65449 -407.386028)
			(xy 415.627241 -407.385501) (xy 415.573297 -407.377744) (xy 415.521006 -407.362389) (xy 415.471433 -407.339748)
			(xy 415.425586 -407.310283) (xy 415.384399 -407.274594) (xy 415.348711 -407.233406) (xy 415.319247 -407.187558)
			(xy 415.296608 -407.137984) (xy 415.281254 -407.085693) (xy 415.273498 -407.031749) (xy 413.835965 -407.031749)
			(xy 413.835965 -407.031757) (xy 413.828206 -407.085715) (xy 413.812847 -407.138019) (xy 413.7902 -407.187606)
			(xy 413.760725 -407.233464) (xy 413.725024 -407.27466) (xy 413.683823 -407.310355) (xy 413.637962 -407.339824)
			(xy 413.588373 -407.362464) (xy 413.536066 -407.377817) (xy 413.482107 -407.385569) (xy 413.45485 -407.386028)
			(xy 412.59125 -407.386028) (xy 412.564003 -407.385498) (xy 412.510063 -407.377736) (xy 412.457777 -407.362378)
			(xy 412.408209 -407.339735) (xy 412.362367 -407.310269) (xy 412.321185 -407.274579) (xy 412.285501 -407.233393)
			(xy 412.256041 -407.187547) (xy 412.233405 -407.137976) (xy 412.218053 -407.085688) (xy 412.210298 -407.031748)
			(xy 410.772642 -407.031748) (xy 410.772642 -407.031752) (xy 410.764886 -407.085702) (xy 410.74953 -407.137999)
			(xy 410.726889 -407.187578) (xy 410.697422 -407.23343) (xy 410.661729 -407.274622) (xy 410.620538 -407.310316)
			(xy 410.574687 -407.339784) (xy 410.525108 -407.362427) (xy 410.472812 -407.377783) (xy 410.418862 -407.385541)
			(xy 410.39161 -407.386028) (xy 409.52801 -407.386028) (xy 409.500758 -407.385525) (xy 409.446809 -407.37777)
			(xy 409.394513 -407.362416) (xy 409.344934 -407.339775) (xy 409.299082 -407.310309) (xy 409.25789 -407.274617)
			(xy 409.222197 -407.233426) (xy 409.19273 -407.187575) (xy 409.170088 -407.137997) (xy 409.154732 -407.085701)
			(xy 409.146975 -407.031752) (xy 407.709465 -407.031752) (xy 407.709465 -407.031756) (xy 407.701707 -407.085712)
			(xy 407.686348 -407.138015) (xy 407.663703 -407.1876) (xy 407.63423 -407.233457) (xy 407.598531 -407.274653)
			(xy 407.557333 -407.310348) (xy 407.511474 -407.339817) (xy 407.461887 -407.362459) (xy 407.409583 -407.377813)
			(xy 407.355626 -407.385567) (xy 407.32837 -407.386028) (xy 406.46477 -407.386028) (xy 406.437522 -407.3855)
			(xy 406.38358 -407.37774) (xy 406.331292 -407.362383) (xy 406.281721 -407.339742) (xy 406.235877 -407.310276)
			(xy 406.194692 -407.274586) (xy 406.159006 -407.233399) (xy 406.129544 -407.187553) (xy 406.106906 -407.13798)
			(xy 406.091553 -407.085691) (xy 406.083798 -407.031748) (xy 404.646142 -407.031748) (xy 404.646142 -407.031751)
			(xy 404.638386 -407.085699) (xy 404.623032 -407.137994) (xy 404.600392 -407.187572) (xy 404.570927 -407.233424)
			(xy 404.535236 -407.274615) (xy 404.494048 -407.310309) (xy 404.448199 -407.339777) (xy 404.398622 -407.362421)
			(xy 404.346329 -407.37778) (xy 404.292381 -407.38554) (xy 404.26513 -407.386028) (xy 403.40153 -407.386028)
			(xy 403.374277 -407.385527) (xy 403.320326 -407.377774) (xy 403.268027 -407.362421) (xy 403.218446 -407.339781)
			(xy 403.172591 -407.310316) (xy 403.131397 -407.274624) (xy 403.095702 -407.233433) (xy 403.066233 -407.187581)
			(xy 403.043589 -407.138001) (xy 403.028233 -407.085704) (xy 403.020475 -407.031753) (xy 401.582965 -407.031753)
			(xy 401.582965 -407.031755) (xy 401.575207 -407.085709) (xy 401.55985 -407.138011) (xy 401.537206 -407.187594)
			(xy 401.507735 -407.23345) (xy 401.472038 -407.274646) (xy 401.430842 -407.310341) (xy 401.384986 -407.33981)
			(xy 401.335402 -407.362454) (xy 401.2831 -407.37781) (xy 401.229145 -407.385566) (xy 401.20189 -407.386028)
			(xy 400.33829 -407.386028) (xy 400.311041 -407.385501) (xy 400.257097 -407.377744) (xy 400.204806 -407.362389)
			(xy 400.155233 -407.339748) (xy 400.109386 -407.310283) (xy 400.068199 -407.274594) (xy 400.032511 -407.233406)
			(xy 400.003047 -407.187558) (xy 399.980408 -407.137984) (xy 399.965054 -407.085693) (xy 399.957298 -407.031749)
			(xy 398.519765 -407.031749) (xy 398.519765 -407.031757) (xy 398.512006 -407.085715) (xy 398.496647 -407.138019)
			(xy 398.474 -407.187606) (xy 398.444525 -407.233464) (xy 398.408824 -407.27466) (xy 398.367623 -407.310355)
			(xy 398.321762 -407.339824) (xy 398.272173 -407.362464) (xy 398.219866 -407.377817) (xy 398.165907 -407.385569)
			(xy 398.13865 -407.386028) (xy 397.27505 -407.386028) (xy 397.247803 -407.385498) (xy 397.193863 -407.377736)
			(xy 397.141577 -407.362378) (xy 397.092009 -407.339735) (xy 397.046167 -407.310269) (xy 397.004985 -407.274579)
			(xy 396.969301 -407.233393) (xy 396.939841 -407.187547) (xy 396.917205 -407.137976) (xy 396.901853 -407.085688)
			(xy 396.894098 -407.031748) (xy 395.456442 -407.031748) (xy 395.456442 -407.031752) (xy 395.448686 -407.085702)
			(xy 395.43333 -407.137999) (xy 395.410689 -407.187578) (xy 395.381222 -407.23343) (xy 395.345529 -407.274622)
			(xy 395.304338 -407.310316) (xy 395.258487 -407.339784) (xy 395.208908 -407.362427) (xy 395.156612 -407.377783)
			(xy 395.102662 -407.385541) (xy 395.07541 -407.386028) (xy 394.21181 -407.386028) (xy 394.184558 -407.385525)
			(xy 394.130609 -407.37777) (xy 394.078313 -407.362416) (xy 394.028734 -407.339775) (xy 393.982882 -407.310309)
			(xy 393.94169 -407.274617) (xy 393.905997 -407.233426) (xy 393.87653 -407.187575) (xy 393.853888 -407.137997)
			(xy 393.838532 -407.085701) (xy 393.830775 -407.031752) (xy 392.393265 -407.031752) (xy 392.393265 -407.031756)
			(xy 392.385507 -407.085712) (xy 392.370148 -407.138015) (xy 392.347503 -407.1876) (xy 392.31803 -407.233457)
			(xy 392.282331 -407.274653) (xy 392.241133 -407.310348) (xy 392.195274 -407.339817) (xy 392.145687 -407.362459)
			(xy 392.093383 -407.377813) (xy 392.039426 -407.385567) (xy 392.01217 -407.386028) (xy 391.14857 -407.386028)
			(xy 391.121322 -407.3855) (xy 391.06738 -407.37774) (xy 391.015092 -407.362383) (xy 390.965521 -407.339742)
			(xy 390.919677 -407.310276) (xy 390.878492 -407.274586) (xy 390.842806 -407.233399) (xy 390.813344 -407.187553)
			(xy 390.790706 -407.13798) (xy 390.775353 -407.085691) (xy 390.767598 -407.031748) (xy 389.329942 -407.031748)
			(xy 389.329942 -407.031751) (xy 389.322186 -407.085699) (xy 389.306832 -407.137994) (xy 389.284192 -407.187572)
			(xy 389.254727 -407.233424) (xy 389.219036 -407.274615) (xy 389.177848 -407.310309) (xy 389.131999 -407.339777)
			(xy 389.082422 -407.362421) (xy 389.030129 -407.37778) (xy 388.976181 -407.38554) (xy 388.94893 -407.386028)
			(xy 388.08533 -407.386028) (xy 388.058077 -407.385527) (xy 388.004126 -407.377774) (xy 387.951827 -407.362421)
			(xy 387.902246 -407.339781) (xy 387.856391 -407.310316) (xy 387.815197 -407.274624) (xy 387.779502 -407.233433)
			(xy 387.750033 -407.187581) (xy 387.727389 -407.138001) (xy 387.712033 -407.085704) (xy 387.704275 -407.031753)
			(xy 386.266765 -407.031753) (xy 386.266765 -407.031755) (xy 386.259007 -407.085709) (xy 386.24365 -407.138011)
			(xy 386.221006 -407.187594) (xy 386.191535 -407.23345) (xy 386.155838 -407.274646) (xy 386.114642 -407.310341)
			(xy 386.068786 -407.33981) (xy 386.019202 -407.362454) (xy 385.9669 -407.37781) (xy 385.912945 -407.385566)
			(xy 385.88569 -407.386028) (xy 385.02209 -407.386028) (xy 384.994841 -407.385501) (xy 384.940897 -407.377744)
			(xy 384.888606 -407.362389) (xy 384.839033 -407.339748) (xy 384.793186 -407.310283) (xy 384.751999 -407.274594)
			(xy 384.716311 -407.233406) (xy 384.686847 -407.187558) (xy 384.664208 -407.137984) (xy 384.648854 -407.085693)
			(xy 384.641098 -407.031749) (xy 383.203565 -407.031749) (xy 383.203565 -407.031757) (xy 383.195806 -407.085715)
			(xy 383.180447 -407.138019) (xy 383.1578 -407.187606) (xy 383.128325 -407.233464) (xy 383.092624 -407.27466)
			(xy 383.051423 -407.310355) (xy 383.005562 -407.339824) (xy 382.955973 -407.362464) (xy 382.903666 -407.377817)
			(xy 382.849707 -407.385569) (xy 382.82245 -407.386028) (xy 381.95885 -407.386028) (xy 381.931603 -407.385498)
			(xy 381.877663 -407.377736) (xy 381.825377 -407.362378) (xy 381.775809 -407.339735) (xy 381.729967 -407.310269)
			(xy 381.688785 -407.274579) (xy 381.653101 -407.233393) (xy 381.623641 -407.187547) (xy 381.601005 -407.137976)
			(xy 381.585653 -407.085688) (xy 381.577898 -407.031748) (xy 380.140242 -407.031748) (xy 380.140242 -407.031752)
			(xy 380.132486 -407.085702) (xy 380.11713 -407.137999) (xy 380.094489 -407.187578) (xy 380.065022 -407.23343)
			(xy 380.029329 -407.274622) (xy 379.988138 -407.310316) (xy 379.942287 -407.339784) (xy 379.892708 -407.362427)
			(xy 379.840412 -407.377783) (xy 379.786462 -407.385541) (xy 379.75921 -407.386028) (xy 378.89561 -407.386028)
			(xy 378.868358 -407.385525) (xy 378.814409 -407.37777) (xy 378.762113 -407.362416) (xy 378.712534 -407.339775)
			(xy 378.666682 -407.310309) (xy 378.62549 -407.274617) (xy 378.589797 -407.233426) (xy 378.56033 -407.187575)
			(xy 378.537688 -407.137997) (xy 378.522332 -407.085701) (xy 378.514575 -407.031752) (xy 377.077065 -407.031752)
			(xy 377.077065 -407.031756) (xy 377.069307 -407.085712) (xy 377.053948 -407.138015) (xy 377.031303 -407.1876)
			(xy 377.00183 -407.233457) (xy 376.966131 -407.274653) (xy 376.924933 -407.310348) (xy 376.879074 -407.339817)
			(xy 376.829487 -407.362459) (xy 376.777183 -407.377813) (xy 376.723226 -407.385567) (xy 376.69597 -407.386028)
			(xy 375.83237 -407.386028) (xy 375.805122 -407.3855) (xy 375.75118 -407.37774) (xy 375.698892 -407.362383)
			(xy 375.649321 -407.339742) (xy 375.603477 -407.310276) (xy 375.562292 -407.274586) (xy 375.526606 -407.233399)
			(xy 375.497144 -407.187553) (xy 375.474506 -407.13798) (xy 375.459153 -407.085691) (xy 375.451398 -407.031748)
			(xy 374.013742 -407.031748) (xy 374.013742 -407.031751) (xy 374.005986 -407.085699) (xy 373.990632 -407.137994)
			(xy 373.967992 -407.187572) (xy 373.938527 -407.233424) (xy 373.902836 -407.274615) (xy 373.861648 -407.310309)
			(xy 373.815799 -407.339777) (xy 373.766222 -407.362421) (xy 373.713929 -407.37778) (xy 373.659981 -407.38554)
			(xy 373.63273 -407.386028) (xy 372.76913 -407.386028) (xy 372.741877 -407.385527) (xy 372.687926 -407.377774)
			(xy 372.635627 -407.362421) (xy 372.586046 -407.339781) (xy 372.540191 -407.310316) (xy 372.498997 -407.274624)
			(xy 372.463302 -407.233433) (xy 372.433833 -407.187581) (xy 372.411189 -407.138001) (xy 372.395833 -407.085704)
			(xy 372.388075 -407.031753) (xy 352.519565 -407.031753) (xy 352.519565 -407.031755) (xy 352.511807 -407.08571)
			(xy 352.49645 -407.138011) (xy 352.473805 -407.187595) (xy 352.444335 -407.233451) (xy 352.408638 -407.274646)
			(xy 352.367441 -407.310342) (xy 352.321584 -407.339811) (xy 352.272 -407.362454) (xy 352.219698 -407.37781)
			(xy 352.165743 -407.385566) (xy 352.138488 -407.386028) (xy 351.274888 -407.386028) (xy 351.247639 -407.385501)
			(xy 351.193695 -407.377743) (xy 351.141405 -407.362388) (xy 351.091832 -407.339748) (xy 351.045985 -407.310282)
			(xy 351.004799 -407.274593) (xy 350.96911 -407.233405) (xy 350.939647 -407.187558) (xy 350.917008 -407.137984)
			(xy 350.901654 -407.085693) (xy 350.893898 -407.031749) (xy 349.456242 -407.031749) (xy 349.456242 -407.03175)
			(xy 349.448487 -407.085697) (xy 349.433133 -407.137991) (xy 349.410494 -407.187567) (xy 349.381031 -407.233418)
			(xy 349.345343 -407.274609) (xy 349.304156 -407.310302) (xy 349.258309 -407.339771) (xy 349.208736 -407.362416)
			(xy 349.156444 -407.377776) (xy 349.102498 -407.385539) (xy 349.075248 -407.386028) (xy 348.211648 -407.386028)
			(xy 348.184394 -407.385528) (xy 348.130441 -407.377777) (xy 348.07814 -407.362426) (xy 348.028557 -407.339787)
			(xy 347.9827 -407.310322) (xy 347.941504 -407.27463) (xy 347.905807 -407.233439) (xy 347.876336 -407.187586)
			(xy 347.853691 -407.138005) (xy 347.838333 -407.085706) (xy 347.830575 -407.031754) (xy 346.393042 -407.031754)
			(xy 346.385285 -407.085702) (xy 346.36993 -407.137999) (xy 346.347288 -407.187578) (xy 346.317821 -407.233431)
			(xy 346.282129 -407.274623) (xy 346.240937 -407.310316) (xy 346.195085 -407.339784) (xy 346.145507 -407.362427)
			(xy 346.09321 -407.377784) (xy 346.03926 -407.385542) (xy 346.012008 -407.386028) (xy 345.148408 -407.386028)
			(xy 345.121156 -407.385525) (xy 345.067207 -407.37777) (xy 345.014911 -407.362415) (xy 344.965333 -407.339774)
			(xy 344.919481 -407.310308) (xy 344.878289 -407.274616) (xy 344.842597 -407.233425) (xy 344.81313 -407.187574)
			(xy 344.790488 -407.137996) (xy 344.775132 -407.085701) (xy 344.767375 -407.031752) (xy 343.329865 -407.031752)
			(xy 343.329865 -407.031756) (xy 343.322107 -407.085712) (xy 343.306748 -407.138016) (xy 343.284102 -407.187601)
			(xy 343.25463 -407.233458) (xy 343.218931 -407.274653) (xy 343.177732 -407.310349) (xy 343.131872 -407.339818)
			(xy 343.082286 -407.36246) (xy 343.029981 -407.377814) (xy 342.976024 -407.385567) (xy 342.948768 -407.386028)
			(xy 342.085168 -407.386028) (xy 342.05792 -407.3855) (xy 342.003978 -407.37774) (xy 341.95169 -407.362383)
			(xy 341.90212 -407.339741) (xy 341.856276 -407.310275) (xy 341.815092 -407.274586) (xy 341.779405 -407.233399)
			(xy 341.749944 -407.187552) (xy 341.727306 -407.13798) (xy 341.711953 -407.08569) (xy 341.704198 -407.031748)
			(xy 340.266542 -407.031748) (xy 340.266542 -407.031751) (xy 340.258786 -407.0857) (xy 340.243432 -407.137995)
			(xy 340.220791 -407.187573) (xy 340.191326 -407.233424) (xy 340.155636 -407.274616) (xy 340.114447 -407.310309)
			(xy 340.068597 -407.339778) (xy 340.019021 -407.362422) (xy 339.966727 -407.37778) (xy 339.912779 -407.38554)
			(xy 339.885528 -407.386028) (xy 339.021928 -407.386028) (xy 338.994675 -407.385527) (xy 338.940724 -407.377773)
			(xy 338.888426 -407.36242) (xy 338.838845 -407.339781) (xy 338.79299 -407.310315) (xy 338.751797 -407.274623)
			(xy 338.716102 -407.233432) (xy 338.686633 -407.18758) (xy 338.663989 -407.138001) (xy 338.648633 -407.085703)
			(xy 338.640875 -407.031753) (xy 337.203365 -407.031753) (xy 337.203365 -407.031755) (xy 337.195607 -407.08571)
			(xy 337.18025 -407.138011) (xy 337.157605 -407.187595) (xy 337.128135 -407.233451) (xy 337.092438 -407.274646)
			(xy 337.051241 -407.310342) (xy 337.005384 -407.339811) (xy 336.9558 -407.362454) (xy 336.903498 -407.37781)
			(xy 336.849543 -407.385566) (xy 336.822288 -407.386028) (xy 335.958688 -407.386028) (xy 335.931439 -407.385501)
			(xy 335.877495 -407.377743) (xy 335.825205 -407.362388) (xy 335.775632 -407.339748) (xy 335.729785 -407.310282)
			(xy 335.688599 -407.274593) (xy 335.65291 -407.233405) (xy 335.623447 -407.187558) (xy 335.600808 -407.137984)
			(xy 335.585454 -407.085693) (xy 335.577698 -407.031749) (xy 334.140042 -407.031749) (xy 334.140042 -407.03175)
			(xy 334.132287 -407.085697) (xy 334.116933 -407.137991) (xy 334.094294 -407.187567) (xy 334.064831 -407.233418)
			(xy 334.029143 -407.274609) (xy 333.987956 -407.310302) (xy 333.942109 -407.339771) (xy 333.892536 -407.362416)
			(xy 333.840244 -407.377776) (xy 333.786298 -407.385539) (xy 333.759048 -407.386028) (xy 332.895448 -407.386028)
			(xy 332.868194 -407.385528) (xy 332.814241 -407.377777) (xy 332.76194 -407.362426) (xy 332.712357 -407.339787)
			(xy 332.6665 -407.310322) (xy 332.625304 -407.27463) (xy 332.589607 -407.233439) (xy 332.560136 -407.187586)
			(xy 332.537491 -407.138005) (xy 332.522133 -407.085706) (xy 332.514375 -407.031754) (xy 331.076842 -407.031754)
			(xy 331.069085 -407.085702) (xy 331.05373 -407.137999) (xy 331.031088 -407.187578) (xy 331.001621 -407.233431)
			(xy 330.965929 -407.274623) (xy 330.924737 -407.310316) (xy 330.878885 -407.339784) (xy 330.829307 -407.362427)
			(xy 330.77701 -407.377784) (xy 330.72306 -407.385542) (xy 330.695808 -407.386028) (xy 329.832208 -407.386028)
			(xy 329.804956 -407.385525) (xy 329.751007 -407.37777) (xy 329.698711 -407.362415) (xy 329.649133 -407.339774)
			(xy 329.603281 -407.310308) (xy 329.562089 -407.274616) (xy 329.526397 -407.233425) (xy 329.49693 -407.187574)
			(xy 329.474288 -407.137996) (xy 329.458932 -407.085701) (xy 329.451175 -407.031752) (xy 328.013665 -407.031752)
			(xy 328.013665 -407.031756) (xy 328.005907 -407.085712) (xy 327.990548 -407.138016) (xy 327.967902 -407.187601)
			(xy 327.93843 -407.233458) (xy 327.902731 -407.274653) (xy 327.861532 -407.310349) (xy 327.815672 -407.339818)
			(xy 327.766086 -407.36246) (xy 327.713781 -407.377814) (xy 327.659824 -407.385567) (xy 327.632568 -407.386028)
			(xy 326.768968 -407.386028) (xy 326.74172 -407.3855) (xy 326.687778 -407.37774) (xy 326.63549 -407.362383)
			(xy 326.58592 -407.339741) (xy 326.540076 -407.310275) (xy 326.498892 -407.274586) (xy 326.463205 -407.233399)
			(xy 326.433744 -407.187552) (xy 326.411106 -407.13798) (xy 326.395753 -407.08569) (xy 326.387998 -407.031748)
			(xy 324.950342 -407.031748) (xy 324.950342 -407.031751) (xy 324.942586 -407.0857) (xy 324.927232 -407.137995)
			(xy 324.904591 -407.187573) (xy 324.875126 -407.233424) (xy 324.839436 -407.274616) (xy 324.798247 -407.310309)
			(xy 324.752397 -407.339778) (xy 324.702821 -407.362422) (xy 324.650527 -407.37778) (xy 324.596579 -407.38554)
			(xy 324.569328 -407.386028) (xy 323.705728 -407.386028) (xy 323.678475 -407.385527) (xy 323.624524 -407.377773)
			(xy 323.572226 -407.36242) (xy 323.522645 -407.339781) (xy 323.47679 -407.310315) (xy 323.435597 -407.274623)
			(xy 323.399902 -407.233432) (xy 323.370433 -407.18758) (xy 323.347789 -407.138001) (xy 323.332433 -407.085703)
			(xy 323.324675 -407.031753) (xy 321.887165 -407.031753) (xy 321.887165 -407.031755) (xy 321.879407 -407.08571)
			(xy 321.86405 -407.138011) (xy 321.841405 -407.187595) (xy 321.811935 -407.233451) (xy 321.776238 -407.274646)
			(xy 321.735041 -407.310342) (xy 321.689184 -407.339811) (xy 321.6396 -407.362454) (xy 321.587298 -407.37781)
			(xy 321.533343 -407.385566) (xy 321.506088 -407.386028) (xy 320.642488 -407.386028) (xy 320.615239 -407.385501)
			(xy 320.561295 -407.377743) (xy 320.509005 -407.362388) (xy 320.459432 -407.339748) (xy 320.413585 -407.310282)
			(xy 320.372399 -407.274593) (xy 320.33671 -407.233405) (xy 320.307247 -407.187558) (xy 320.284608 -407.137984)
			(xy 320.269254 -407.085693) (xy 320.261498 -407.031749) (xy 318.823842 -407.031749) (xy 318.823842 -407.03175)
			(xy 318.816087 -407.085697) (xy 318.800733 -407.137991) (xy 318.778094 -407.187567) (xy 318.748631 -407.233418)
			(xy 318.712943 -407.274609) (xy 318.671756 -407.310302) (xy 318.625909 -407.339771) (xy 318.576336 -407.362416)
			(xy 318.524044 -407.377776) (xy 318.470098 -407.385539) (xy 318.442848 -407.386028) (xy 317.579248 -407.386028)
			(xy 317.551994 -407.385528) (xy 317.498041 -407.377777) (xy 317.44574 -407.362426) (xy 317.396157 -407.339787)
			(xy 317.3503 -407.310322) (xy 317.309104 -407.27463) (xy 317.273407 -407.233439) (xy 317.243936 -407.187586)
			(xy 317.221291 -407.138005) (xy 317.205933 -407.085706) (xy 317.198175 -407.031754) (xy 315.760642 -407.031754)
			(xy 315.752885 -407.085702) (xy 315.73753 -407.137999) (xy 315.714888 -407.187578) (xy 315.685421 -407.233431)
			(xy 315.649729 -407.274623) (xy 315.608537 -407.310316) (xy 315.562685 -407.339784) (xy 315.513107 -407.362427)
			(xy 315.46081 -407.377784) (xy 315.40686 -407.385542) (xy 315.379608 -407.386028) (xy 314.516008 -407.386028)
			(xy 314.488756 -407.385525) (xy 314.434807 -407.37777) (xy 314.382511 -407.362415) (xy 314.332933 -407.339774)
			(xy 314.287081 -407.310308) (xy 314.245889 -407.274616) (xy 314.210197 -407.233425) (xy 314.18073 -407.187574)
			(xy 314.158088 -407.137996) (xy 314.142732 -407.085701) (xy 314.134975 -407.031752) (xy 312.697465 -407.031752)
			(xy 312.697465 -407.031756) (xy 312.689707 -407.085712) (xy 312.674348 -407.138016) (xy 312.651702 -407.187601)
			(xy 312.62223 -407.233458) (xy 312.586531 -407.274653) (xy 312.545332 -407.310349) (xy 312.499472 -407.339818)
			(xy 312.449886 -407.36246) (xy 312.397581 -407.377814) (xy 312.343624 -407.385567) (xy 312.316368 -407.386028)
			(xy 311.452768 -407.386028) (xy 311.42552 -407.3855) (xy 311.371578 -407.37774) (xy 311.31929 -407.362383)
			(xy 311.26972 -407.339741) (xy 311.223876 -407.310275) (xy 311.182692 -407.274586) (xy 311.147005 -407.233399)
			(xy 311.117544 -407.187552) (xy 311.094906 -407.13798) (xy 311.079553 -407.08569) (xy 311.071798 -407.031748)
			(xy 309.634142 -407.031748) (xy 309.634142 -407.031751) (xy 309.626386 -407.0857) (xy 309.611032 -407.137995)
			(xy 309.588391 -407.187573) (xy 309.558926 -407.233424) (xy 309.523236 -407.274616) (xy 309.482047 -407.310309)
			(xy 309.436197 -407.339778) (xy 309.386621 -407.362422) (xy 309.334327 -407.37778) (xy 309.280379 -407.38554)
			(xy 309.253128 -407.386028) (xy 308.389528 -407.386028) (xy 308.362275 -407.385527) (xy 308.308324 -407.377773)
			(xy 308.256026 -407.36242) (xy 308.206445 -407.339781) (xy 308.16059 -407.310315) (xy 308.119397 -407.274623)
			(xy 308.083702 -407.233432) (xy 308.054233 -407.18758) (xy 308.031589 -407.138001) (xy 308.016233 -407.085703)
			(xy 308.008475 -407.031753) (xy 306.570965 -407.031753) (xy 306.570965 -407.031755) (xy 306.563207 -407.08571)
			(xy 306.54785 -407.138011) (xy 306.525205 -407.187595) (xy 306.495735 -407.233451) (xy 306.460038 -407.274646)
			(xy 306.418841 -407.310342) (xy 306.372984 -407.339811) (xy 306.3234 -407.362454) (xy 306.271098 -407.37781)
			(xy 306.217143 -407.385566) (xy 306.189888 -407.386028) (xy 305.326288 -407.386028) (xy 305.299039 -407.385501)
			(xy 305.245095 -407.377743) (xy 305.192805 -407.362388) (xy 305.143232 -407.339748) (xy 305.097385 -407.310282)
			(xy 305.056199 -407.274593) (xy 305.02051 -407.233405) (xy 304.991047 -407.187558) (xy 304.968408 -407.137984)
			(xy 304.953054 -407.085693) (xy 304.945298 -407.031749) (xy 168.694465 -407.031749) (xy 168.694465 -407.031756)
			(xy 168.686706 -407.085714) (xy 168.671347 -407.138019) (xy 168.6487 -407.187604) (xy 168.619226 -407.233462)
			(xy 168.583526 -407.274658) (xy 168.542325 -407.310354) (xy 168.496464 -407.339822) (xy 168.446875 -407.362463)
			(xy 168.394569 -407.377816) (xy 168.34061 -407.385568) (xy 168.313354 -407.386028) (xy 167.449754 -407.386028)
			(xy 167.422506 -407.385499) (xy 167.368567 -407.377737) (xy 167.31628 -407.362379) (xy 167.266711 -407.339736)
			(xy 167.220869 -407.31027) (xy 167.179687 -407.274581) (xy 167.144002 -407.233394) (xy 167.114542 -407.187548)
			(xy 167.091905 -407.137977) (xy 167.076553 -407.085688) (xy 167.068798 -407.031748) (xy 165.631142 -407.031748)
			(xy 165.631142 -407.031752) (xy 165.623386 -407.085701) (xy 165.60803 -407.137998) (xy 165.585389 -407.187577)
			(xy 165.555923 -407.233429) (xy 165.520231 -407.274621) (xy 165.47904 -407.310314) (xy 165.433189 -407.339782)
			(xy 165.383611 -407.362426) (xy 165.331315 -407.377783) (xy 165.277366 -407.385541) (xy 165.250114 -407.386028)
			(xy 164.386514 -407.386028) (xy 164.359262 -407.385526) (xy 164.305312 -407.377771) (xy 164.253016 -407.362417)
			(xy 164.203436 -407.339776) (xy 164.157584 -407.31031) (xy 164.116392 -407.274618) (xy 164.080698 -407.233427)
			(xy 164.051231 -407.187576) (xy 164.028588 -407.137998) (xy 164.013232 -407.085701) (xy 164.005475 -407.031752)
			(xy 162.567965 -407.031752) (xy 162.567965 -407.031755) (xy 162.560207 -407.085712) (xy 162.544849 -407.138014)
			(xy 162.522203 -407.187599) (xy 162.492731 -407.233456) (xy 162.457033 -407.274651) (xy 162.415835 -407.310347)
			(xy 162.369976 -407.339816) (xy 162.32039 -407.362458) (xy 162.268086 -407.377813) (xy 162.21413 -407.385567)
			(xy 162.186874 -407.386028) (xy 161.323274 -407.386028) (xy 161.296025 -407.3855) (xy 161.242083 -407.377741)
			(xy 161.189795 -407.362384) (xy 161.140223 -407.339743) (xy 161.094379 -407.310278) (xy 161.053194 -407.274588)
			(xy 161.017507 -407.233401) (xy 160.988045 -407.187554) (xy 160.965407 -407.137981) (xy 160.950054 -407.085691)
			(xy 160.942298 -407.031749) (xy 159.504642 -407.031749) (xy 159.504642 -407.031751) (xy 159.496886 -407.085699)
			(xy 159.481532 -407.137993) (xy 159.458892 -407.187571) (xy 159.429428 -407.233422) (xy 159.393738 -407.274614)
			(xy 159.352549 -407.310307) (xy 159.306701 -407.339776) (xy 159.257125 -407.36242) (xy 159.204832 -407.377779)
			(xy 159.150885 -407.38554) (xy 159.123634 -407.386028) (xy 158.260034 -407.386028) (xy 158.232781 -407.385527)
			(xy 158.178829 -407.377774) (xy 158.12653 -407.362422) (xy 158.076948 -407.339783) (xy 158.031093 -407.310317)
			(xy 157.989899 -407.274625) (xy 157.954203 -407.233434) (xy 157.924734 -407.187582) (xy 157.90209 -407.138002)
			(xy 157.886733 -407.085704) (xy 157.878975 -407.031753) (xy 156.441465 -407.031753) (xy 156.441465 -407.031755)
			(xy 156.433708 -407.085709) (xy 156.41835 -407.13801) (xy 156.395706 -407.187593) (xy 156.366236 -407.233449)
			(xy 156.33054 -407.274644) (xy 156.289344 -407.31034) (xy 156.243488 -407.339809) (xy 156.193904 -407.362452)
			(xy 156.141603 -407.377809) (xy 156.087649 -407.385566) (xy 156.060394 -407.386028) (xy 155.196794 -407.386028)
			(xy 155.169544 -407.385501) (xy 155.1156 -407.377745) (xy 155.063309 -407.36239) (xy 155.013735 -407.339749)
			(xy 154.967888 -407.310285) (xy 154.926701 -407.274595) (xy 154.891012 -407.233407) (xy 154.861548 -407.187559)
			(xy 154.838908 -407.137985) (xy 154.823554 -407.085694) (xy 154.815798 -407.03175) (xy 153.378265 -407.03175)
			(xy 153.378265 -407.031756) (xy 153.370506 -407.085714) (xy 153.355147 -407.138019) (xy 153.3325 -407.187604)
			(xy 153.303026 -407.233462) (xy 153.267326 -407.274658) (xy 153.226125 -407.310354) (xy 153.180264 -407.339822)
			(xy 153.130675 -407.362463) (xy 153.078369 -407.377816) (xy 153.02441 -407.385568) (xy 152.997154 -407.386028)
			(xy 152.133554 -407.386028) (xy 152.106306 -407.385499) (xy 152.052367 -407.377737) (xy 152.00008 -407.362379)
			(xy 151.950511 -407.339736) (xy 151.904669 -407.31027) (xy 151.863487 -407.274581) (xy 151.827802 -407.233394)
			(xy 151.798342 -407.187548) (xy 151.775705 -407.137977) (xy 151.760353 -407.085688) (xy 151.752598 -407.031748)
			(xy 150.314942 -407.031748) (xy 150.314942 -407.031752) (xy 150.307186 -407.085701) (xy 150.29183 -407.137998)
			(xy 150.269189 -407.187577) (xy 150.239723 -407.233429) (xy 150.204031 -407.274621) (xy 150.16284 -407.310314)
			(xy 150.116989 -407.339782) (xy 150.067411 -407.362426) (xy 150.015115 -407.377783) (xy 149.961166 -407.385541)
			(xy 149.933914 -407.386028) (xy 149.070314 -407.386028) (xy 149.043062 -407.385526) (xy 148.989112 -407.377771)
			(xy 148.936816 -407.362417) (xy 148.887236 -407.339776) (xy 148.841384 -407.31031) (xy 148.800192 -407.274618)
			(xy 148.764498 -407.233427) (xy 148.735031 -407.187576) (xy 148.712388 -407.137998) (xy 148.697032 -407.085701)
			(xy 148.689275 -407.031752) (xy 147.251765 -407.031752) (xy 147.251765 -407.031755) (xy 147.244007 -407.085712)
			(xy 147.228649 -407.138014) (xy 147.206003 -407.187599) (xy 147.176531 -407.233456) (xy 147.140833 -407.274651)
			(xy 147.099635 -407.310347) (xy 147.053776 -407.339816) (xy 147.00419 -407.362458) (xy 146.951886 -407.377813)
			(xy 146.89793 -407.385567) (xy 146.870674 -407.386028) (xy 146.007074 -407.386028) (xy 145.979825 -407.3855)
			(xy 145.925883 -407.377741) (xy 145.873595 -407.362384) (xy 145.824023 -407.339743) (xy 145.778179 -407.310278)
			(xy 145.736994 -407.274588) (xy 145.701307 -407.233401) (xy 145.671845 -407.187554) (xy 145.649207 -407.137981)
			(xy 145.633854 -407.085691) (xy 145.626098 -407.031749) (xy 144.188442 -407.031749) (xy 144.188442 -407.031751)
			(xy 144.180686 -407.085699) (xy 144.165332 -407.137993) (xy 144.142692 -407.187571) (xy 144.113228 -407.233422)
			(xy 144.077538 -407.274614) (xy 144.036349 -407.310307) (xy 143.990501 -407.339776) (xy 143.940925 -407.36242)
			(xy 143.888632 -407.377779) (xy 143.834685 -407.38554) (xy 143.807434 -407.386028) (xy 142.943834 -407.386028)
			(xy 142.916581 -407.385527) (xy 142.862629 -407.377774) (xy 142.81033 -407.362422) (xy 142.760748 -407.339783)
			(xy 142.714893 -407.310317) (xy 142.673699 -407.274625) (xy 142.638003 -407.233434) (xy 142.608534 -407.187582)
			(xy 142.58589 -407.138002) (xy 142.570533 -407.085704) (xy 142.562775 -407.031753) (xy 141.125265 -407.031753)
			(xy 141.125265 -407.031755) (xy 141.117508 -407.085709) (xy 141.10215 -407.13801) (xy 141.079506 -407.187593)
			(xy 141.050036 -407.233449) (xy 141.01434 -407.274644) (xy 140.973144 -407.31034) (xy 140.927288 -407.339809)
			(xy 140.877704 -407.362452) (xy 140.825403 -407.377809) (xy 140.771449 -407.385566) (xy 140.744194 -407.386028)
			(xy 139.880594 -407.386028) (xy 139.853344 -407.385501) (xy 139.7994 -407.377745) (xy 139.747109 -407.36239)
			(xy 139.697535 -407.339749) (xy 139.651688 -407.310285) (xy 139.610501 -407.274595) (xy 139.574812 -407.233407)
			(xy 139.545348 -407.187559) (xy 139.522708 -407.137985) (xy 139.507354 -407.085694) (xy 139.499598 -407.03175)
			(xy 138.062065 -407.03175) (xy 138.062065 -407.031756) (xy 138.054306 -407.085714) (xy 138.038947 -407.138019)
			(xy 138.0163 -407.187604) (xy 137.986826 -407.233462) (xy 137.951126 -407.274658) (xy 137.909925 -407.310354)
			(xy 137.864064 -407.339822) (xy 137.814475 -407.362463) (xy 137.762169 -407.377816) (xy 137.70821 -407.385568)
			(xy 137.680954 -407.386028) (xy 136.817354 -407.386028) (xy 136.790106 -407.385499) (xy 136.736167 -407.377737)
			(xy 136.68388 -407.362379) (xy 136.634311 -407.339736) (xy 136.588469 -407.31027) (xy 136.547287 -407.274581)
			(xy 136.511602 -407.233394) (xy 136.482142 -407.187548) (xy 136.459505 -407.137977) (xy 136.444153 -407.085688)
			(xy 136.436398 -407.031748) (xy 134.998742 -407.031748) (xy 134.998742 -407.031752) (xy 134.990986 -407.085701)
			(xy 134.97563 -407.137998) (xy 134.952989 -407.187577) (xy 134.923523 -407.233429) (xy 134.887831 -407.274621)
			(xy 134.84664 -407.310314) (xy 134.800789 -407.339782) (xy 134.751211 -407.362426) (xy 134.698915 -407.377783)
			(xy 134.644966 -407.385541) (xy 134.617714 -407.386028) (xy 133.754114 -407.386028) (xy 133.726862 -407.385526)
			(xy 133.672912 -407.377771) (xy 133.620616 -407.362417) (xy 133.571036 -407.339776) (xy 133.525184 -407.31031)
			(xy 133.483992 -407.274618) (xy 133.448298 -407.233427) (xy 133.418831 -407.187576) (xy 133.396188 -407.137998)
			(xy 133.380832 -407.085701) (xy 133.373075 -407.031752) (xy 131.935565 -407.031752) (xy 131.935565 -407.031755)
			(xy 131.927807 -407.085712) (xy 131.912449 -407.138014) (xy 131.889803 -407.187599) (xy 131.860331 -407.233456)
			(xy 131.824633 -407.274651) (xy 131.783435 -407.310347) (xy 131.737576 -407.339816) (xy 131.68799 -407.362458)
			(xy 131.635686 -407.377813) (xy 131.58173 -407.385567) (xy 131.554474 -407.386028) (xy 130.690874 -407.386028)
			(xy 130.663625 -407.3855) (xy 130.609683 -407.377741) (xy 130.557395 -407.362384) (xy 130.507823 -407.339743)
			(xy 130.461979 -407.310278) (xy 130.420794 -407.274588) (xy 130.385107 -407.233401) (xy 130.355645 -407.187554)
			(xy 130.333007 -407.137981) (xy 130.317654 -407.085691) (xy 130.309898 -407.031749) (xy 128.872242 -407.031749)
			(xy 128.872242 -407.031751) (xy 128.864486 -407.085699) (xy 128.849132 -407.137993) (xy 128.826492 -407.187571)
			(xy 128.797028 -407.233422) (xy 128.761338 -407.274614) (xy 128.720149 -407.310307) (xy 128.674301 -407.339776)
			(xy 128.624725 -407.36242) (xy 128.572432 -407.377779) (xy 128.518485 -407.38554) (xy 128.491234 -407.386028)
			(xy 127.627634 -407.386028) (xy 127.600381 -407.385527) (xy 127.546429 -407.377774) (xy 127.49413 -407.362422)
			(xy 127.444548 -407.339783) (xy 127.398693 -407.310317) (xy 127.357499 -407.274625) (xy 127.321803 -407.233434)
			(xy 127.292334 -407.187582) (xy 127.26969 -407.138002) (xy 127.254333 -407.085704) (xy 127.246575 -407.031753)
			(xy 125.809065 -407.031753) (xy 125.809065 -407.031755) (xy 125.801308 -407.085709) (xy 125.78595 -407.13801)
			(xy 125.763306 -407.187593) (xy 125.733836 -407.233449) (xy 125.69814 -407.274644) (xy 125.656944 -407.31034)
			(xy 125.611088 -407.339809) (xy 125.561504 -407.362452) (xy 125.509203 -407.377809) (xy 125.455249 -407.385566)
			(xy 125.427994 -407.386028) (xy 124.564394 -407.386028) (xy 124.537144 -407.385501) (xy 124.4832 -407.377745)
			(xy 124.430909 -407.36239) (xy 124.381335 -407.339749) (xy 124.335488 -407.310285) (xy 124.294301 -407.274595)
			(xy 124.258612 -407.233407) (xy 124.229148 -407.187559) (xy 124.206508 -407.137985) (xy 124.191154 -407.085694)
			(xy 124.183398 -407.03175) (xy 122.745865 -407.03175) (xy 122.745865 -407.031756) (xy 122.738106 -407.085714)
			(xy 122.722747 -407.138019) (xy 122.7001 -407.187604) (xy 122.670626 -407.233462) (xy 122.634926 -407.274658)
			(xy 122.593725 -407.310354) (xy 122.547864 -407.339822) (xy 122.498275 -407.362463) (xy 122.445969 -407.377816)
			(xy 122.39201 -407.385568) (xy 122.364754 -407.386028) (xy 121.501154 -407.386028) (xy 121.473906 -407.385499)
			(xy 121.419967 -407.377737) (xy 121.36768 -407.362379) (xy 121.318111 -407.339736) (xy 121.272269 -407.31027)
			(xy 121.231087 -407.274581) (xy 121.195402 -407.233394) (xy 121.165942 -407.187548) (xy 121.143305 -407.137977)
			(xy 121.127953 -407.085688) (xy 121.120198 -407.031748) (xy 107.861153 -407.031748) (xy 107.86873 -407.084449)
			(xy 107.86873 -407.138951) (xy 107.860974 -407.192898) (xy 107.84562 -407.245192) (xy 107.822979 -407.294769)
			(xy 107.793514 -407.34062) (xy 107.757824 -407.38181) (xy 107.716636 -407.417502) (xy 107.670787 -407.44697)
			(xy 107.621211 -407.469613) (xy 107.568918 -407.48497) (xy 107.514971 -407.492729) (xy 107.48772 -407.493216)
			(xy 106.62412 -407.493216) (xy 106.596867 -407.492738) (xy 106.542915 -407.484984) (xy 106.490616 -407.46963)
			(xy 106.441034 -407.446989) (xy 106.395179 -407.417522) (xy 106.353985 -407.381829) (xy 106.31829 -407.340637)
			(xy 106.288821 -407.294783) (xy 106.266177 -407.245203) (xy 106.250821 -407.192905) (xy 106.243063 -407.138953)
			(xy 96.495694 -407.138953) (xy 96.473493 -407.18757) (xy 96.444028 -407.233421) (xy 96.408339 -407.274612)
			(xy 96.367151 -407.310306) (xy 96.321303 -407.339775) (xy 96.271728 -407.362419) (xy 96.219435 -407.377778)
			(xy 96.165489 -407.38554) (xy 96.138238 -407.386028) (xy 95.274638 -407.386028) (xy 95.247385 -407.385527)
			(xy 95.193433 -407.377775) (xy 95.141133 -407.362423) (xy 95.091551 -407.339784) (xy 95.045695 -407.310319)
			(xy 95.0045 -407.274627) (xy 94.968804 -407.233435) (xy 94.939334 -407.187583) (xy 94.91669 -407.138003)
			(xy 94.901333 -407.085705) (xy 94.893575 -407.031753) (xy 93.456065 -407.031753) (xy 93.456065 -407.031754)
			(xy 93.448308 -407.085708) (xy 93.432951 -407.138009) (xy 93.410307 -407.187592) (xy 93.380837 -407.233448)
			(xy 93.345141 -407.274643) (xy 93.303946 -407.310338) (xy 93.25809 -407.339808) (xy 93.208507 -407.362451)
			(xy 93.156206 -407.377808) (xy 93.102252 -407.385565) (xy 93.074998 -407.386028) (xy 92.211398 -407.386028)
			(xy 92.184148 -407.385502) (xy 92.130204 -407.377745) (xy 92.077912 -407.362391) (xy 92.028338 -407.339751)
			(xy 91.98249 -407.310286) (xy 91.941302 -407.274596) (xy 91.905613 -407.233408) (xy 91.876148 -407.187561)
			(xy 91.853508 -407.137986) (xy 91.838154 -407.085694) (xy 91.830398 -407.03175) (xy 90.392865 -407.03175)
			(xy 90.392865 -407.031756) (xy 90.385107 -407.085714) (xy 90.369748 -407.138018) (xy 90.347101 -407.187603)
			(xy 90.317627 -407.233461) (xy 90.281927 -407.274657) (xy 90.240727 -407.310352) (xy 90.194866 -407.339821)
			(xy 90.145278 -407.362462) (xy 90.092973 -407.377815) (xy 90.039014 -407.385568) (xy 90.011758 -407.386028)
			(xy 89.148158 -407.386028) (xy 89.12091 -407.385499) (xy 89.06697 -407.377738) (xy 89.014683 -407.36238)
			(xy 88.965114 -407.339738) (xy 88.919271 -407.310272) (xy 88.878088 -407.274582) (xy 88.842403 -407.233395)
			(xy 88.812942 -407.187549) (xy 88.790305 -407.137978) (xy 88.774953 -407.085689) (xy 88.767198 -407.031748)
			(xy 87.329542 -407.031748) (xy 87.329542 -407.031752) (xy 87.321786 -407.085701) (xy 87.306431 -407.137997)
			(xy 87.28379 -407.187576) (xy 87.254324 -407.233427) (xy 87.218632 -407.274619) (xy 87.177442 -407.310313)
			(xy 87.131591 -407.339781) (xy 87.082014 -407.362424) (xy 87.029718 -407.377782) (xy 86.97577 -407.385541)
			(xy 86.948518 -407.386028) (xy 86.084918 -407.386028) (xy 86.057666 -407.385526) (xy 86.003716 -407.377771)
			(xy 85.951418 -407.362418) (xy 85.901839 -407.339778) (xy 85.855986 -407.310312) (xy 85.814793 -407.27462)
			(xy 85.779099 -407.233429) (xy 85.749631 -407.187577) (xy 85.726989 -407.137998) (xy 85.711632 -407.085702)
			(xy 85.703875 -407.031752) (xy 84.266365 -407.031752) (xy 84.266365 -407.031755) (xy 84.258607 -407.085711)
			(xy 84.243249 -407.138013) (xy 84.220604 -407.187598) (xy 84.191132 -407.233454) (xy 84.155434 -407.27465)
			(xy 84.114237 -407.310345) (xy 84.068378 -407.339814) (xy 84.018793 -407.362457) (xy 83.96649 -407.377812)
			(xy 83.912533 -407.385567) (xy 83.885278 -407.386028) (xy 83.021678 -407.386028) (xy 82.994429 -407.3855)
			(xy 82.940487 -407.377742) (xy 82.888197 -407.362385) (xy 82.838626 -407.339744) (xy 82.79278 -407.310279)
			(xy 82.751595 -407.274589) (xy 82.715908 -407.233402) (xy 82.686445 -407.187555) (xy 82.663807 -407.137982)
			(xy 82.648454 -407.085692) (xy 82.640698 -407.031749) (xy 81.203042 -407.031749) (xy 81.203042 -407.031751)
			(xy 81.195286 -407.085698) (xy 81.179932 -407.137993) (xy 81.157293 -407.18757) (xy 81.127828 -407.233421)
			(xy 81.092139 -407.274612) (xy 81.050951 -407.310306) (xy 81.005103 -407.339775) (xy 80.955528 -407.362419)
			(xy 80.903235 -407.377778) (xy 80.849289 -407.38554) (xy 80.822038 -407.386028) (xy 79.958438 -407.386028)
			(xy 79.931185 -407.385527) (xy 79.877233 -407.377775) (xy 79.824933 -407.362423) (xy 79.775351 -407.339784)
			(xy 79.729495 -407.310319) (xy 79.6883 -407.274627) (xy 79.652604 -407.233435) (xy 79.623134 -407.187583)
			(xy 79.60049 -407.138003) (xy 79.585133 -407.085705) (xy 79.577375 -407.031753) (xy 78.139865 -407.031753)
			(xy 78.139865 -407.031754) (xy 78.132108 -407.085708) (xy 78.116751 -407.138009) (xy 78.094107 -407.187592)
			(xy 78.064637 -407.233448) (xy 78.028941 -407.274643) (xy 77.987746 -407.310338) (xy 77.94189 -407.339808)
			(xy 77.892307 -407.362451) (xy 77.840006 -407.377808) (xy 77.786052 -407.385565) (xy 77.758798 -407.386028)
			(xy 76.895198 -407.386028) (xy 76.867948 -407.385502) (xy 76.814004 -407.377745) (xy 76.761712 -407.362391)
			(xy 76.712138 -407.339751) (xy 76.66629 -407.310286) (xy 76.625102 -407.274596) (xy 76.589413 -407.233408)
			(xy 76.559948 -407.187561) (xy 76.537308 -407.137986) (xy 76.521954 -407.085694) (xy 76.514198 -407.03175)
			(xy 75.076665 -407.03175) (xy 75.076665 -407.031756) (xy 75.068907 -407.085714) (xy 75.053548 -407.138018)
			(xy 75.030901 -407.187603) (xy 75.001427 -407.233461) (xy 74.965727 -407.274657) (xy 74.924527 -407.310352)
			(xy 74.878666 -407.339821) (xy 74.829078 -407.362462) (xy 74.776773 -407.377815) (xy 74.722814 -407.385568)
			(xy 74.695558 -407.386028) (xy 73.831958 -407.386028) (xy 73.80471 -407.385499) (xy 73.75077 -407.377738)
			(xy 73.698483 -407.36238) (xy 73.648914 -407.339738) (xy 73.603071 -407.310272) (xy 73.561888 -407.274582)
			(xy 73.526203 -407.233395) (xy 73.496742 -407.187549) (xy 73.474105 -407.137978) (xy 73.458753 -407.085689)
			(xy 73.450998 -407.031748) (xy 72.013342 -407.031748) (xy 72.013342 -407.031752) (xy 72.005586 -407.085701)
			(xy 71.990231 -407.137997) (xy 71.96759 -407.187576) (xy 71.938124 -407.233427) (xy 71.902432 -407.274619)
			(xy 71.861242 -407.310313) (xy 71.815391 -407.339781) (xy 71.765814 -407.362424) (xy 71.713518 -407.377782)
			(xy 71.65957 -407.385541) (xy 71.632318 -407.386028) (xy 70.768718 -407.386028) (xy 70.741466 -407.385526)
			(xy 70.687516 -407.377771) (xy 70.635218 -407.362418) (xy 70.585639 -407.339778) (xy 70.539786 -407.310312)
			(xy 70.498593 -407.27462) (xy 70.462899 -407.233429) (xy 70.433431 -407.187577) (xy 70.410789 -407.137998)
			(xy 70.395432 -407.085702) (xy 70.387675 -407.031752) (xy 68.950165 -407.031752) (xy 68.950165 -407.031755)
			(xy 68.942407 -407.085711) (xy 68.927049 -407.138013) (xy 68.904404 -407.187598) (xy 68.874932 -407.233454)
			(xy 68.839234 -407.27465) (xy 68.798037 -407.310345) (xy 68.752178 -407.339814) (xy 68.702593 -407.362457)
			(xy 68.65029 -407.377812) (xy 68.596333 -407.385567) (xy 68.569078 -407.386028) (xy 67.705478 -407.386028)
			(xy 67.678229 -407.3855) (xy 67.624287 -407.377742) (xy 67.571997 -407.362385) (xy 67.522426 -407.339744)
			(xy 67.47658 -407.310279) (xy 67.435395 -407.274589) (xy 67.399708 -407.233402) (xy 67.370245 -407.187555)
			(xy 67.347607 -407.137982) (xy 67.332254 -407.085692) (xy 67.324498 -407.031749) (xy 65.886842 -407.031749)
			(xy 65.886842 -407.031751) (xy 65.879086 -407.085698) (xy 65.863732 -407.137993) (xy 65.841093 -407.18757)
			(xy 65.811628 -407.233421) (xy 65.775939 -407.274612) (xy 65.734751 -407.310306) (xy 65.688903 -407.339775)
			(xy 65.639328 -407.362419) (xy 65.587035 -407.377778) (xy 65.533089 -407.38554) (xy 65.505838 -407.386028)
			(xy 64.642238 -407.386028) (xy 64.614985 -407.385527) (xy 64.561033 -407.377775) (xy 64.508733 -407.362423)
			(xy 64.459151 -407.339784) (xy 64.413295 -407.310319) (xy 64.3721 -407.274627) (xy 64.336404 -407.233435)
			(xy 64.306934 -407.187583) (xy 64.28429 -407.138003) (xy 64.268933 -407.085705) (xy 64.261175 -407.031753)
			(xy 62.823665 -407.031753) (xy 62.823665 -407.031754) (xy 62.815908 -407.085708) (xy 62.800551 -407.138009)
			(xy 62.777907 -407.187592) (xy 62.748437 -407.233448) (xy 62.712741 -407.274643) (xy 62.671546 -407.310338)
			(xy 62.62569 -407.339808) (xy 62.576107 -407.362451) (xy 62.523806 -407.377808) (xy 62.469852 -407.385565)
			(xy 62.442598 -407.386028) (xy 61.578998 -407.386028) (xy 61.551748 -407.385502) (xy 61.497804 -407.377745)
			(xy 61.445512 -407.362391) (xy 61.395938 -407.339751) (xy 61.35009 -407.310286) (xy 61.308902 -407.274596)
			(xy 61.273213 -407.233408) (xy 61.243748 -407.187561) (xy 61.221108 -407.137986) (xy 61.205754 -407.085694)
			(xy 61.197998 -407.03175) (xy 59.760465 -407.03175) (xy 59.760465 -407.031756) (xy 59.752707 -407.085714)
			(xy 59.737348 -407.138018) (xy 59.714701 -407.187603) (xy 59.685227 -407.233461) (xy 59.649527 -407.274657)
			(xy 59.608327 -407.310352) (xy 59.562466 -407.339821) (xy 59.512878 -407.362462) (xy 59.460573 -407.377815)
			(xy 59.406614 -407.385568) (xy 59.379358 -407.386028) (xy 58.515758 -407.386028) (xy 58.48851 -407.385499)
			(xy 58.43457 -407.377738) (xy 58.382283 -407.36238) (xy 58.332714 -407.339738) (xy 58.286871 -407.310272)
			(xy 58.245688 -407.274582) (xy 58.210003 -407.233395) (xy 58.180542 -407.187549) (xy 58.157905 -407.137978)
			(xy 58.142553 -407.085689) (xy 58.134798 -407.031748) (xy 56.697142 -407.031748) (xy 56.697142 -407.031752)
			(xy 56.689386 -407.085701) (xy 56.674031 -407.137997) (xy 56.65139 -407.187576) (xy 56.621924 -407.233427)
			(xy 56.586232 -407.274619) (xy 56.545042 -407.310313) (xy 56.499191 -407.339781) (xy 56.449614 -407.362424)
			(xy 56.397318 -407.377782) (xy 56.34337 -407.385541) (xy 56.316118 -407.386028) (xy 55.452518 -407.386028)
			(xy 55.425266 -407.385526) (xy 55.371316 -407.377771) (xy 55.319018 -407.362418) (xy 55.269439 -407.339778)
			(xy 55.223586 -407.310312) (xy 55.182393 -407.27462) (xy 55.146699 -407.233429) (xy 55.117231 -407.187577)
			(xy 55.094589 -407.137998) (xy 55.079232 -407.085702) (xy 55.071475 -407.031752) (xy 53.633965 -407.031752)
			(xy 53.633965 -407.031755) (xy 53.626207 -407.085711) (xy 53.610849 -407.138013) (xy 53.588204 -407.187598)
			(xy 53.558732 -407.233454) (xy 53.523034 -407.27465) (xy 53.481837 -407.310345) (xy 53.435978 -407.339814)
			(xy 53.386393 -407.362457) (xy 53.33409 -407.377812) (xy 53.280133 -407.385567) (xy 53.252878 -407.386028)
			(xy 52.389278 -407.386028) (xy 52.362029 -407.3855) (xy 52.308087 -407.377742) (xy 52.255797 -407.362385)
			(xy 52.206226 -407.339744) (xy 52.16038 -407.310279) (xy 52.119195 -407.274589) (xy 52.083508 -407.233402)
			(xy 52.054045 -407.187555) (xy 52.031407 -407.137982) (xy 52.016054 -407.085692) (xy 52.008298 -407.031749)
			(xy 50.570642 -407.031749) (xy 50.570642 -407.031751) (xy 50.562886 -407.085698) (xy 50.547532 -407.137993)
			(xy 50.524893 -407.18757) (xy 50.495428 -407.233421) (xy 50.459739 -407.274612) (xy 50.418551 -407.310306)
			(xy 50.372703 -407.339775) (xy 50.323128 -407.362419) (xy 50.270835 -407.377778) (xy 50.216889 -407.38554)
			(xy 50.189638 -407.386028) (xy 49.326038 -407.386028) (xy 49.298785 -407.385527) (xy 49.244833 -407.377775)
			(xy 49.192533 -407.362423) (xy 49.142951 -407.339784) (xy 49.097095 -407.310319) (xy 49.0559 -407.274627)
			(xy 49.020204 -407.233435) (xy 48.990734 -407.187583) (xy 48.96809 -407.138003) (xy 48.952733 -407.085705)
			(xy 48.944975 -407.031753) (xy 16.741648 -407.031753) (xy 16.741648 -407.035508) (xy 16.741162 -407.062759)
			(xy 16.733406 -407.116707) (xy 16.718051 -407.169002) (xy 16.695409 -407.218579) (xy 16.665943 -407.264429)
			(xy 16.630252 -407.30562) (xy 16.589061 -407.341311) (xy 16.543211 -407.370777) (xy 16.493634 -407.393419)
			(xy 16.441339 -407.408774) (xy 16.387391 -407.41653) (xy 16.332889 -407.41653) (xy 16.278941 -407.408774)
			(xy 16.226646 -407.393419) (xy 16.177069 -407.370777) (xy 16.131219 -407.341311) (xy 16.090028 -407.30562)
			(xy 16.054337 -407.264429) (xy 16.024871 -407.218579) (xy 16.002229 -407.169002) (xy 15.986874 -407.116707)
			(xy 15.979118 -407.062759) (xy 15.978632 -407.035508) (xy 5.555234 -407.035508) (xy 6.274054 -407.754328)
			(xy 6.323476 -407.804436) (xy 6.417282 -407.909377) (xy 6.505056 -408.019414) (xy 6.586523 -408.134198)
			(xy 6.661426 -408.25337) (xy 6.729529 -408.376554) (xy 6.790618 -408.503362) (xy 6.844501 -408.633397)
			(xy 6.891008 -408.766247) (xy 6.929993 -408.901497) (xy 6.961334 -409.03872) (xy 6.984932 -409.177484)
			(xy 7.000712 -409.317352) (xy 7.008625 -409.457886) (xy 7.00913 -409.528264) (xy 7.00913 -410.057457)
			(xy 48.944923 -410.057457) (xy 48.944923 -410.002943) (xy 48.952682 -409.948984) (xy 48.968041 -409.896679)
			(xy 48.990688 -409.847092) (xy 49.020162 -409.801233) (xy 49.055863 -409.760036) (xy 49.097064 -409.724339)
			(xy 49.142925 -409.69487) (xy 49.192515 -409.672228) (xy 49.244821 -409.656874) (xy 49.298781 -409.64912)
			(xy 49.326038 -409.64866) (xy 50.189638 -409.64866) (xy 50.216885 -409.649213) (xy 50.270824 -409.656973)
			(xy 50.32311 -409.67233) (xy 50.372678 -409.694972) (xy 50.41852 -409.724436) (xy 50.459702 -409.760125)
			(xy 50.495386 -409.801311) (xy 50.524847 -409.847155) (xy 50.547483 -409.896726) (xy 50.562835 -409.949013)
			(xy 50.57059 -410.002953) (xy 50.57059 -410.057447) (xy 50.570589 -410.057453) (xy 52.008246 -410.057453)
			(xy 52.008246 -410.002947) (xy 52.016002 -409.948997) (xy 52.031358 -409.8967) (xy 52.053999 -409.84712)
			(xy 52.083466 -409.801267) (xy 52.119158 -409.760074) (xy 52.160349 -409.724379) (xy 52.206201 -409.69491)
			(xy 52.255779 -409.672265) (xy 52.308076 -409.656907) (xy 52.362025 -409.649147) (xy 52.389278 -409.64866)
			(xy 53.252878 -409.64866) (xy 53.28013 -409.649186) (xy 53.334078 -409.65694) (xy 53.386374 -409.672292)
			(xy 53.435953 -409.694932) (xy 53.481805 -409.724397) (xy 53.522997 -409.760087) (xy 53.55869 -409.801277)
			(xy 53.588158 -409.847127) (xy 53.6108 -409.896705) (xy 53.626156 -409.949) (xy 53.633913 -410.002948)
			(xy 53.633913 -410.057452) (xy 53.633912 -410.057456) (xy 55.071423 -410.057456) (xy 55.071423 -410.002944)
			(xy 55.079181 -409.948987) (xy 55.094539 -409.896683) (xy 55.117185 -409.847098) (xy 55.146657 -409.80124)
			(xy 55.182356 -409.760043) (xy 55.223554 -409.724346) (xy 55.269413 -409.694876) (xy 55.319 -409.672233)
			(xy 55.371305 -409.656877) (xy 55.425262 -409.649122) (xy 55.452518 -409.64866) (xy 56.316118 -409.64866)
			(xy 56.343366 -409.649211) (xy 56.397307 -409.656969) (xy 56.449595 -409.672325) (xy 56.499166 -409.694965)
			(xy 56.54501 -409.724429) (xy 56.586195 -409.760118) (xy 56.621882 -409.801304) (xy 56.651344 -409.84715)
			(xy 56.673982 -409.896721) (xy 56.689334 -409.94901) (xy 56.69709 -410.002952) (xy 56.69709 -410.057448)
			(xy 56.697089 -410.057452) (xy 58.134746 -410.057452) (xy 58.134746 -410.002948) (xy 58.142502 -409.949)
			(xy 58.157856 -409.896704) (xy 58.180496 -409.847125) (xy 58.209961 -409.801273) (xy 58.245651 -409.760081)
			(xy 58.28684 -409.724386) (xy 58.332689 -409.694916) (xy 58.382265 -409.672271) (xy 58.434559 -409.656911)
			(xy 58.488506 -409.649149) (xy 58.515758 -409.64866) (xy 59.379358 -409.64866) (xy 59.406611 -409.649184)
			(xy 59.460561 -409.656936) (xy 59.51286 -409.672287) (xy 59.562441 -409.694925) (xy 59.608296 -409.72439)
			(xy 59.64949 -409.76008) (xy 59.685185 -409.801271) (xy 59.714655 -409.847122) (xy 59.737298 -409.896701)
			(xy 59.752655 -409.948997) (xy 59.760413 -410.002948) (xy 59.760413 -410.057452) (xy 59.760413 -410.057453)
			(xy 61.197946 -410.057453) (xy 61.197946 -410.002947) (xy 61.205703 -409.948994) (xy 61.221059 -409.896695)
			(xy 61.243702 -409.847114) (xy 61.273171 -409.80126) (xy 61.308865 -409.760066) (xy 61.350059 -409.724372)
			(xy 61.395913 -409.694903) (xy 61.445494 -409.67226) (xy 61.497793 -409.656903) (xy 61.551745 -409.649146)
			(xy 61.578998 -409.64866) (xy 62.442598 -409.64866) (xy 62.469849 -409.649187) (xy 62.523795 -409.656943)
			(xy 62.576089 -409.672298) (xy 62.625665 -409.694938) (xy 62.671515 -409.724404) (xy 62.712704 -409.760094)
			(xy 62.748395 -409.801284) (xy 62.777861 -409.847133) (xy 62.800502 -409.896709) (xy 62.815856 -409.949003)
			(xy 62.823613 -410.002949) (xy 62.823613 -410.057451) (xy 62.823612 -410.057457) (xy 64.261123 -410.057457)
			(xy 64.261123 -410.002943) (xy 64.268882 -409.948984) (xy 64.284241 -409.896679) (xy 64.306888 -409.847092)
			(xy 64.336362 -409.801233) (xy 64.372063 -409.760036) (xy 64.413264 -409.724339) (xy 64.459125 -409.69487)
			(xy 64.508715 -409.672228) (xy 64.561021 -409.656874) (xy 64.614981 -409.64912) (xy 64.642238 -409.64866)
			(xy 65.505838 -409.64866) (xy 65.533085 -409.649213) (xy 65.587024 -409.656973) (xy 65.63931 -409.67233)
			(xy 65.688878 -409.694972) (xy 65.73472 -409.724436) (xy 65.775902 -409.760125) (xy 65.811586 -409.801311)
			(xy 65.841047 -409.847155) (xy 65.863683 -409.896726) (xy 65.879035 -409.949013) (xy 65.88679 -410.002953)
			(xy 65.88679 -410.057447) (xy 65.886789 -410.057453) (xy 67.324446 -410.057453) (xy 67.324446 -410.002947)
			(xy 67.332202 -409.948997) (xy 67.347558 -409.8967) (xy 67.370199 -409.84712) (xy 67.399666 -409.801267)
			(xy 67.435358 -409.760074) (xy 67.476549 -409.724379) (xy 67.522401 -409.69491) (xy 67.571979 -409.672265)
			(xy 67.624276 -409.656907) (xy 67.678225 -409.649147) (xy 67.705478 -409.64866) (xy 68.569078 -409.64866)
			(xy 68.59633 -409.649186) (xy 68.650278 -409.65694) (xy 68.702574 -409.672292) (xy 68.752153 -409.694932)
			(xy 68.798005 -409.724397) (xy 68.839197 -409.760087) (xy 68.87489 -409.801277) (xy 68.904358 -409.847127)
			(xy 68.927 -409.896705) (xy 68.942356 -409.949) (xy 68.950113 -410.002948) (xy 68.950113 -410.057452)
			(xy 68.950112 -410.057456) (xy 70.387623 -410.057456) (xy 70.387623 -410.002944) (xy 70.395381 -409.948987)
			(xy 70.410739 -409.896683) (xy 70.433385 -409.847098) (xy 70.462857 -409.80124) (xy 70.498556 -409.760043)
			(xy 70.539754 -409.724346) (xy 70.585613 -409.694876) (xy 70.6352 -409.672233) (xy 70.687505 -409.656877)
			(xy 70.741462 -409.649122) (xy 70.768718 -409.64866) (xy 71.632318 -409.64866) (xy 71.659566 -409.649211)
			(xy 71.713507 -409.656969) (xy 71.765795 -409.672325) (xy 71.815366 -409.694965) (xy 71.86121 -409.724429)
			(xy 71.902395 -409.760118) (xy 71.938082 -409.801304) (xy 71.967544 -409.84715) (xy 71.990182 -409.896721)
			(xy 72.005534 -409.94901) (xy 72.01329 -410.002952) (xy 72.01329 -410.057448) (xy 72.013289 -410.057452)
			(xy 73.450946 -410.057452) (xy 73.450946 -410.002948) (xy 73.458702 -409.949) (xy 73.474056 -409.896704)
			(xy 73.496696 -409.847125) (xy 73.526161 -409.801273) (xy 73.561851 -409.760081) (xy 73.60304 -409.724386)
			(xy 73.648889 -409.694916) (xy 73.698465 -409.672271) (xy 73.750759 -409.656911) (xy 73.804706 -409.649149)
			(xy 73.831958 -409.64866) (xy 74.695558 -409.64866) (xy 74.722811 -409.649184) (xy 74.776761 -409.656936)
			(xy 74.82906 -409.672287) (xy 74.878641 -409.694925) (xy 74.924496 -409.72439) (xy 74.96569 -409.76008)
			(xy 75.001385 -409.801271) (xy 75.030855 -409.847122) (xy 75.053498 -409.896701) (xy 75.068855 -409.948997)
			(xy 75.076613 -410.002948) (xy 75.076613 -410.057452) (xy 75.076613 -410.057453) (xy 76.514146 -410.057453)
			(xy 76.514146 -410.002947) (xy 76.521903 -409.948994) (xy 76.537259 -409.896695) (xy 76.559902 -409.847114)
			(xy 76.589371 -409.80126) (xy 76.625065 -409.760066) (xy 76.666259 -409.724372) (xy 76.712113 -409.694903)
			(xy 76.761694 -409.67226) (xy 76.813993 -409.656903) (xy 76.867945 -409.649146) (xy 76.895198 -409.64866)
			(xy 77.758798 -409.64866) (xy 77.786049 -409.649187) (xy 77.839995 -409.656943) (xy 77.892289 -409.672298)
			(xy 77.941865 -409.694938) (xy 77.987715 -409.724404) (xy 78.028904 -409.760094) (xy 78.064595 -409.801284)
			(xy 78.094061 -409.847133) (xy 78.116702 -409.896709) (xy 78.132056 -409.949003) (xy 78.139813 -410.002949)
			(xy 78.139813 -410.057451) (xy 78.139812 -410.057457) (xy 79.577323 -410.057457) (xy 79.577323 -410.002943)
			(xy 79.585082 -409.948984) (xy 79.600441 -409.896679) (xy 79.623088 -409.847092) (xy 79.652562 -409.801233)
			(xy 79.688263 -409.760036) (xy 79.729464 -409.724339) (xy 79.775325 -409.69487) (xy 79.824915 -409.672228)
			(xy 79.877221 -409.656874) (xy 79.931181 -409.64912) (xy 79.958438 -409.64866) (xy 80.822038 -409.64866)
			(xy 80.849285 -409.649213) (xy 80.903224 -409.656973) (xy 80.95551 -409.67233) (xy 81.005078 -409.694972)
			(xy 81.05092 -409.724436) (xy 81.092102 -409.760125) (xy 81.127786 -409.801311) (xy 81.157247 -409.847155)
			(xy 81.179883 -409.896726) (xy 81.195235 -409.949013) (xy 81.20299 -410.002953) (xy 81.20299 -410.057447)
			(xy 81.202989 -410.057453) (xy 82.640646 -410.057453) (xy 82.640646 -410.002947) (xy 82.648402 -409.948997)
			(xy 82.663758 -409.8967) (xy 82.686399 -409.84712) (xy 82.715866 -409.801267) (xy 82.751558 -409.760074)
			(xy 82.792749 -409.724379) (xy 82.838601 -409.69491) (xy 82.888179 -409.672265) (xy 82.940476 -409.656907)
			(xy 82.994425 -409.649147) (xy 83.021678 -409.64866) (xy 83.885278 -409.64866) (xy 83.91253 -409.649186)
			(xy 83.966478 -409.65694) (xy 84.018774 -409.672292) (xy 84.068353 -409.694932) (xy 84.114205 -409.724397)
			(xy 84.155397 -409.760087) (xy 84.19109 -409.801277) (xy 84.220558 -409.847127) (xy 84.2432 -409.896705)
			(xy 84.258556 -409.949) (xy 84.266313 -410.002948) (xy 84.266313 -410.057452) (xy 84.266312 -410.057456)
			(xy 85.703823 -410.057456) (xy 85.703823 -410.002944) (xy 85.711581 -409.948987) (xy 85.726939 -409.896683)
			(xy 85.749585 -409.847098) (xy 85.779057 -409.80124) (xy 85.814756 -409.760043) (xy 85.855954 -409.724346)
			(xy 85.901813 -409.694876) (xy 85.9514 -409.672233) (xy 86.003705 -409.656877) (xy 86.057662 -409.649122)
			(xy 86.084918 -409.64866) (xy 86.948518 -409.64866) (xy 86.975766 -409.649211) (xy 87.029707 -409.656969)
			(xy 87.081995 -409.672325) (xy 87.131566 -409.694965) (xy 87.17741 -409.724429) (xy 87.218595 -409.760118)
			(xy 87.254282 -409.801304) (xy 87.283744 -409.84715) (xy 87.306382 -409.896721) (xy 87.321734 -409.94901)
			(xy 87.32949 -410.002952) (xy 87.32949 -410.057448) (xy 87.329489 -410.057452) (xy 88.767146 -410.057452)
			(xy 88.767146 -410.002948) (xy 88.774902 -409.949) (xy 88.790256 -409.896704) (xy 88.812896 -409.847125)
			(xy 88.842361 -409.801273) (xy 88.878051 -409.760081) (xy 88.91924 -409.724386) (xy 88.965089 -409.694916)
			(xy 89.014665 -409.672271) (xy 89.066959 -409.656911) (xy 89.120906 -409.649149) (xy 89.148158 -409.64866)
			(xy 90.011758 -409.64866) (xy 90.039011 -409.649184) (xy 90.092961 -409.656936) (xy 90.14526 -409.672287)
			(xy 90.194841 -409.694925) (xy 90.240696 -409.72439) (xy 90.28189 -409.76008) (xy 90.317585 -409.801271)
			(xy 90.347055 -409.847122) (xy 90.369698 -409.896701) (xy 90.385055 -409.948997) (xy 90.392813 -410.002948)
			(xy 90.392813 -410.057452) (xy 90.392813 -410.057453) (xy 91.830346 -410.057453) (xy 91.830346 -410.002947)
			(xy 91.838103 -409.948994) (xy 91.853459 -409.896695) (xy 91.876102 -409.847114) (xy 91.905571 -409.80126)
			(xy 91.941265 -409.760066) (xy 91.982459 -409.724372) (xy 92.028313 -409.694903) (xy 92.077894 -409.67226)
			(xy 92.130193 -409.656903) (xy 92.184145 -409.649146) (xy 92.211398 -409.64866) (xy 93.074998 -409.64866)
			(xy 93.102249 -409.649187) (xy 93.156195 -409.656943) (xy 93.208489 -409.672298) (xy 93.258065 -409.694938)
			(xy 93.303915 -409.724404) (xy 93.345104 -409.760094) (xy 93.380795 -409.801284) (xy 93.410261 -409.847133)
			(xy 93.432902 -409.896709) (xy 93.448256 -409.949003) (xy 93.456013 -410.002949) (xy 93.456013 -410.057451)
			(xy 93.456012 -410.057457) (xy 94.893523 -410.057457) (xy 94.893523 -410.002943) (xy 94.901282 -409.948984)
			(xy 94.916641 -409.896679) (xy 94.939288 -409.847092) (xy 94.968762 -409.801233) (xy 95.004463 -409.760036)
			(xy 95.045664 -409.724339) (xy 95.091525 -409.69487) (xy 95.141115 -409.672228) (xy 95.193421 -409.656874)
			(xy 95.247381 -409.64912) (xy 95.274638 -409.64866) (xy 96.138238 -409.64866) (xy 96.165485 -409.649213)
			(xy 96.219424 -409.656973) (xy 96.27171 -409.67233) (xy 96.321278 -409.694972) (xy 96.36712 -409.724436)
			(xy 96.408302 -409.760125) (xy 96.443986 -409.801311) (xy 96.473447 -409.847155) (xy 96.496083 -409.896726)
			(xy 96.511435 -409.949013) (xy 96.51919 -410.002953) (xy 96.51919 -410.057447) (xy 96.519189 -410.057451)
			(xy 121.120146 -410.057451) (xy 121.120146 -410.002949) (xy 121.127902 -409.949) (xy 121.143256 -409.896705)
			(xy 121.165895 -409.847127) (xy 121.19536 -409.801275) (xy 121.231049 -409.760082) (xy 121.272238 -409.724388)
			(xy 121.318086 -409.694918) (xy 121.367662 -409.672272) (xy 121.419955 -409.656911) (xy 121.473903 -409.649149)
			(xy 121.501154 -409.64866) (xy 122.364754 -409.64866) (xy 122.392007 -409.649184) (xy 122.445958 -409.656935)
			(xy 122.498257 -409.672286) (xy 122.547839 -409.694924) (xy 122.593694 -409.724388) (xy 122.634889 -409.760079)
			(xy 122.670584 -409.801269) (xy 122.700054 -409.847121) (xy 122.722698 -409.8967) (xy 122.738055 -409.948997)
			(xy 122.745813 -410.002947) (xy 122.745813 -410.057453) (xy 124.183346 -410.057453) (xy 124.183346 -410.002947)
			(xy 124.191103 -409.948995) (xy 124.206459 -409.896696) (xy 124.229102 -409.847115) (xy 124.25857 -409.801261)
			(xy 124.294264 -409.760068) (xy 124.335457 -409.724373) (xy 124.38131 -409.694904) (xy 124.430891 -409.672261)
			(xy 124.483189 -409.656904) (xy 124.537141 -409.649146) (xy 124.564394 -409.64866) (xy 125.427994 -409.64866)
			(xy 125.455245 -409.649187) (xy 125.509192 -409.656942) (xy 125.561486 -409.672297) (xy 125.611063 -409.694937)
			(xy 125.656913 -409.724402) (xy 125.698103 -409.760093) (xy 125.733794 -409.801282) (xy 125.76326 -409.847132)
			(xy 125.785901 -409.896708) (xy 125.801256 -409.949002) (xy 125.809013 -410.002949) (xy 125.809013 -410.057451)
			(xy 125.809012 -410.057457) (xy 127.246523 -410.057457) (xy 127.246523 -410.002943) (xy 127.254282 -409.948985)
			(xy 127.269641 -409.89668) (xy 127.292287 -409.847093) (xy 127.321761 -409.801235) (xy 127.357462 -409.760037)
			(xy 127.398662 -409.724341) (xy 127.444523 -409.694871) (xy 127.494112 -409.672229) (xy 127.546418 -409.656874)
			(xy 127.600377 -409.649121) (xy 127.627634 -409.64866) (xy 128.491234 -409.64866) (xy 128.518481 -409.649213)
			(xy 128.572421 -409.656972) (xy 128.624707 -409.672329) (xy 128.674276 -409.69497) (xy 128.720118 -409.724435)
			(xy 128.761301 -409.760123) (xy 128.796985 -409.801309) (xy 128.826446 -409.847154) (xy 128.849083 -409.896725)
			(xy 128.864435 -409.949012) (xy 128.87219 -410.002953) (xy 128.87219 -410.057447) (xy 128.872189 -410.057452)
			(xy 130.309846 -410.057452) (xy 130.309846 -410.002948) (xy 130.317602 -409.948998) (xy 130.332957 -409.896701)
			(xy 130.355599 -409.847121) (xy 130.385065 -409.801268) (xy 130.420757 -409.760075) (xy 130.461947 -409.72438)
			(xy 130.507798 -409.694911) (xy 130.557376 -409.672266) (xy 130.609672 -409.656908) (xy 130.663622 -409.649148)
			(xy 130.690874 -409.64866) (xy 131.554474 -409.64866) (xy 131.581726 -409.649185) (xy 131.635675 -409.656939)
			(xy 131.687972 -409.672291) (xy 131.737551 -409.69493) (xy 131.783403 -409.724395) (xy 131.824596 -409.760086)
			(xy 131.860289 -409.801276) (xy 131.889757 -409.847126) (xy 131.9124 -409.896704) (xy 131.927756 -409.949)
			(xy 131.935513 -410.002948) (xy 131.935513 -410.057452) (xy 131.935512 -410.057456) (xy 133.373023 -410.057456)
			(xy 133.373023 -410.002944) (xy 133.380781 -409.948987) (xy 133.396139 -409.896684) (xy 133.418784 -409.847099)
			(xy 133.448256 -409.801241) (xy 133.483954 -409.760045) (xy 133.525152 -409.724348) (xy 133.571011 -409.694878)
			(xy 133.620597 -409.672234) (xy 133.672901 -409.656878) (xy 133.726858 -409.649122) (xy 133.754114 -409.64866)
			(xy 134.617714 -409.64866) (xy 134.644962 -409.649211) (xy 134.698904 -409.656969) (xy 134.751193 -409.672324)
			(xy 134.800764 -409.694964) (xy 134.846609 -409.724428) (xy 134.887794 -409.760116) (xy 134.923481 -409.801303)
			(xy 134.952943 -409.847149) (xy 134.975581 -409.896721) (xy 134.990934 -409.94901) (xy 134.99869 -410.002952)
			(xy 134.99869 -410.057448) (xy 134.99869 -410.057451) (xy 136.436346 -410.057451) (xy 136.436346 -410.002949)
			(xy 136.444102 -409.949) (xy 136.459456 -409.896705) (xy 136.482095 -409.847127) (xy 136.51156 -409.801275)
			(xy 136.547249 -409.760082) (xy 136.588438 -409.724388) (xy 136.634286 -409.694918) (xy 136.683862 -409.672272)
			(xy 136.736155 -409.656911) (xy 136.790103 -409.649149) (xy 136.817354 -409.64866) (xy 137.680954 -409.64866)
			(xy 137.708207 -409.649184) (xy 137.762158 -409.656935) (xy 137.814457 -409.672286) (xy 137.864039 -409.694924)
			(xy 137.909894 -409.724388) (xy 137.951089 -409.760079) (xy 137.986784 -409.801269) (xy 138.016254 -409.847121)
			(xy 138.038898 -409.8967) (xy 138.054255 -409.948997) (xy 138.062013 -410.002947) (xy 138.062013 -410.057453)
			(xy 139.499546 -410.057453) (xy 139.499546 -410.002947) (xy 139.507303 -409.948995) (xy 139.522659 -409.896696)
			(xy 139.545302 -409.847115) (xy 139.57477 -409.801261) (xy 139.610464 -409.760068) (xy 139.651657 -409.724373)
			(xy 139.69751 -409.694904) (xy 139.747091 -409.672261) (xy 139.799389 -409.656904) (xy 139.853341 -409.649146)
			(xy 139.880594 -409.64866) (xy 140.744194 -409.64866) (xy 140.771445 -409.649187) (xy 140.825392 -409.656942)
			(xy 140.877686 -409.672297) (xy 140.927263 -409.694937) (xy 140.973113 -409.724402) (xy 141.014303 -409.760093)
			(xy 141.049994 -409.801282) (xy 141.07946 -409.847132) (xy 141.102101 -409.896708) (xy 141.117456 -409.949002)
			(xy 141.125213 -410.002949) (xy 141.125213 -410.057451) (xy 141.125212 -410.057457) (xy 142.562723 -410.057457)
			(xy 142.562723 -410.002943) (xy 142.570482 -409.948985) (xy 142.585841 -409.89668) (xy 142.608487 -409.847093)
			(xy 142.637961 -409.801235) (xy 142.673662 -409.760037) (xy 142.714862 -409.724341) (xy 142.760723 -409.694871)
			(xy 142.810312 -409.672229) (xy 142.862618 -409.656874) (xy 142.916577 -409.649121) (xy 142.943834 -409.64866)
			(xy 143.807434 -409.64866) (xy 143.834681 -409.649213) (xy 143.888621 -409.656972) (xy 143.940907 -409.672329)
			(xy 143.990476 -409.69497) (xy 144.036318 -409.724435) (xy 144.077501 -409.760123) (xy 144.113185 -409.801309)
			(xy 144.142646 -409.847154) (xy 144.165283 -409.896725) (xy 144.180635 -409.949012) (xy 144.18839 -410.002953)
			(xy 144.18839 -410.057447) (xy 144.188389 -410.057452) (xy 145.626046 -410.057452) (xy 145.626046 -410.002948)
			(xy 145.633802 -409.948998) (xy 145.649157 -409.896701) (xy 145.671799 -409.847121) (xy 145.701265 -409.801268)
			(xy 145.736957 -409.760075) (xy 145.778147 -409.72438) (xy 145.823998 -409.694911) (xy 145.873576 -409.672266)
			(xy 145.925872 -409.656908) (xy 145.979822 -409.649148) (xy 146.007074 -409.64866) (xy 146.870674 -409.64866)
			(xy 146.897926 -409.649185) (xy 146.951875 -409.656939) (xy 147.004172 -409.672291) (xy 147.053751 -409.69493)
			(xy 147.099603 -409.724395) (xy 147.140796 -409.760086) (xy 147.176489 -409.801276) (xy 147.205957 -409.847126)
			(xy 147.2286 -409.896704) (xy 147.243956 -409.949) (xy 147.251713 -410.002948) (xy 147.251713 -410.057452)
			(xy 147.251712 -410.057456) (xy 148.689223 -410.057456) (xy 148.689223 -410.002944) (xy 148.696981 -409.948987)
			(xy 148.712339 -409.896684) (xy 148.734984 -409.847099) (xy 148.764456 -409.801241) (xy 148.800154 -409.760045)
			(xy 148.841352 -409.724348) (xy 148.887211 -409.694878) (xy 148.936797 -409.672234) (xy 148.989101 -409.656878)
			(xy 149.043058 -409.649122) (xy 149.070314 -409.64866) (xy 149.933914 -409.64866) (xy 149.961162 -409.649211)
			(xy 150.015104 -409.656969) (xy 150.067393 -409.672324) (xy 150.116964 -409.694964) (xy 150.162809 -409.724428)
			(xy 150.203994 -409.760116) (xy 150.239681 -409.801303) (xy 150.269143 -409.847149) (xy 150.291781 -409.896721)
			(xy 150.307134 -409.94901) (xy 150.31489 -410.002952) (xy 150.31489 -410.057448) (xy 150.31489 -410.057451)
			(xy 151.752546 -410.057451) (xy 151.752546 -410.002949) (xy 151.760302 -409.949) (xy 151.775656 -409.896705)
			(xy 151.798295 -409.847127) (xy 151.82776 -409.801275) (xy 151.863449 -409.760082) (xy 151.904638 -409.724388)
			(xy 151.950486 -409.694918) (xy 152.000062 -409.672272) (xy 152.052355 -409.656911) (xy 152.106303 -409.649149)
			(xy 152.133554 -409.64866) (xy 152.997154 -409.64866) (xy 153.024407 -409.649184) (xy 153.078358 -409.656935)
			(xy 153.130657 -409.672286) (xy 153.180239 -409.694924) (xy 153.226094 -409.724388) (xy 153.267289 -409.760079)
			(xy 153.302984 -409.801269) (xy 153.332454 -409.847121) (xy 153.355098 -409.8967) (xy 153.370455 -409.948997)
			(xy 153.378213 -410.002947) (xy 153.378213 -410.057453) (xy 154.815746 -410.057453) (xy 154.815746 -410.002947)
			(xy 154.823503 -409.948995) (xy 154.838859 -409.896696) (xy 154.861502 -409.847115) (xy 154.89097 -409.801261)
			(xy 154.926664 -409.760068) (xy 154.967857 -409.724373) (xy 155.01371 -409.694904) (xy 155.063291 -409.672261)
			(xy 155.115589 -409.656904) (xy 155.169541 -409.649146) (xy 155.196794 -409.64866) (xy 156.060394 -409.64866)
			(xy 156.087645 -409.649187) (xy 156.141592 -409.656942) (xy 156.193886 -409.672297) (xy 156.243463 -409.694937)
			(xy 156.289313 -409.724402) (xy 156.330503 -409.760093) (xy 156.366194 -409.801282) (xy 156.39566 -409.847132)
			(xy 156.418301 -409.896708) (xy 156.433656 -409.949002) (xy 156.441413 -410.002949) (xy 156.441413 -410.057451)
			(xy 156.441412 -410.057457) (xy 157.878923 -410.057457) (xy 157.878923 -410.002943) (xy 157.886682 -409.948985)
			(xy 157.902041 -409.89668) (xy 157.924687 -409.847093) (xy 157.954161 -409.801235) (xy 157.989862 -409.760037)
			(xy 158.031062 -409.724341) (xy 158.076923 -409.694871) (xy 158.126512 -409.672229) (xy 158.178818 -409.656874)
			(xy 158.232777 -409.649121) (xy 158.260034 -409.64866) (xy 159.123634 -409.64866) (xy 159.150881 -409.649213)
			(xy 159.204821 -409.656972) (xy 159.257107 -409.672329) (xy 159.306676 -409.69497) (xy 159.352518 -409.724435)
			(xy 159.393701 -409.760123) (xy 159.429385 -409.801309) (xy 159.458846 -409.847154) (xy 159.481483 -409.896725)
			(xy 159.496835 -409.949012) (xy 159.50459 -410.002953) (xy 159.50459 -410.057447) (xy 159.504589 -410.057452)
			(xy 160.942246 -410.057452) (xy 160.942246 -410.002948) (xy 160.950002 -409.948998) (xy 160.965357 -409.896701)
			(xy 160.987999 -409.847121) (xy 161.017465 -409.801268) (xy 161.053157 -409.760075) (xy 161.094347 -409.72438)
			(xy 161.140198 -409.694911) (xy 161.189776 -409.672266) (xy 161.242072 -409.656908) (xy 161.296022 -409.649148)
			(xy 161.323274 -409.64866) (xy 162.186874 -409.64866) (xy 162.214126 -409.649185) (xy 162.268075 -409.656939)
			(xy 162.320372 -409.672291) (xy 162.369951 -409.69493) (xy 162.415803 -409.724395) (xy 162.456996 -409.760086)
			(xy 162.492689 -409.801276) (xy 162.522157 -409.847126) (xy 162.5448 -409.896704) (xy 162.560156 -409.949)
			(xy 162.567913 -410.002948) (xy 162.567913 -410.057452) (xy 162.567912 -410.057456) (xy 164.005423 -410.057456)
			(xy 164.005423 -410.002944) (xy 164.013181 -409.948987) (xy 164.028539 -409.896684) (xy 164.051184 -409.847099)
			(xy 164.080656 -409.801241) (xy 164.116354 -409.760045) (xy 164.157552 -409.724348) (xy 164.203411 -409.694878)
			(xy 164.252997 -409.672234) (xy 164.305301 -409.656878) (xy 164.359258 -409.649122) (xy 164.386514 -409.64866)
			(xy 165.250114 -409.64866) (xy 165.277362 -409.649211) (xy 165.331304 -409.656969) (xy 165.383593 -409.672324)
			(xy 165.433164 -409.694964) (xy 165.479009 -409.724428) (xy 165.520194 -409.760116) (xy 165.555881 -409.801303)
			(xy 165.585343 -409.847149) (xy 165.607981 -409.896721) (xy 165.623334 -409.94901) (xy 165.63109 -410.002952)
			(xy 165.63109 -410.057448) (xy 165.63109 -410.057451) (xy 167.068746 -410.057451) (xy 167.068746 -410.002949)
			(xy 167.076502 -409.949) (xy 167.091856 -409.896705) (xy 167.114495 -409.847127) (xy 167.14396 -409.801275)
			(xy 167.179649 -409.760082) (xy 167.220838 -409.724388) (xy 167.266686 -409.694918) (xy 167.316262 -409.672272)
			(xy 167.368555 -409.656911) (xy 167.422503 -409.649149) (xy 167.449754 -409.64866) (xy 168.313354 -409.64866)
			(xy 168.340607 -409.649184) (xy 168.394558 -409.656935) (xy 168.446857 -409.672286) (xy 168.496439 -409.694924)
			(xy 168.542294 -409.724388) (xy 168.583489 -409.760079) (xy 168.619184 -409.801269) (xy 168.648654 -409.847121)
			(xy 168.671298 -409.8967) (xy 168.686655 -409.948997) (xy 168.694413 -410.002947) (xy 168.694413 -410.057453)
			(xy 168.686655 -410.111403) (xy 168.671298 -410.1637) (xy 168.648654 -410.213279) (xy 168.619184 -410.259131)
			(xy 168.583489 -410.300321) (xy 168.542294 -410.336012) (xy 168.496439 -410.365476) (xy 168.446857 -410.388114)
			(xy 168.394558 -410.403465) (xy 168.340607 -410.411216) (xy 168.313354 -410.411676) (xy 167.449754 -410.411676)
			(xy 167.422503 -410.411251) (xy 167.368555 -410.403489) (xy 167.316262 -410.388128) (xy 167.266686 -410.365482)
			(xy 167.220838 -410.336012) (xy 167.179649 -410.300318) (xy 167.14396 -410.259125) (xy 167.114495 -410.213273)
			(xy 167.091856 -410.163695) (xy 167.076502 -410.1114) (xy 167.068746 -410.057451) (xy 165.63109 -410.057451)
			(xy 165.623334 -410.11139) (xy 165.607981 -410.163679) (xy 165.585343 -410.213251) (xy 165.555881 -410.259097)
			(xy 165.520194 -410.300284) (xy 165.479009 -410.335972) (xy 165.433164 -410.365436) (xy 165.383593 -410.388076)
			(xy 165.331304 -410.403431) (xy 165.277362 -410.411189) (xy 165.250114 -410.411676) (xy 164.386514 -410.411676)
			(xy 164.359258 -410.411278) (xy 164.305301 -410.403522) (xy 164.252997 -410.388166) (xy 164.203411 -410.365522)
			(xy 164.157552 -410.336052) (xy 164.116354 -410.300355) (xy 164.080656 -410.259159) (xy 164.051184 -410.213301)
			(xy 164.028539 -410.163716) (xy 164.013181 -410.111413) (xy 164.005423 -410.057456) (xy 162.567912 -410.057456)
			(xy 162.560156 -410.1114) (xy 162.5448 -410.163696) (xy 162.522157 -410.213274) (xy 162.492689 -410.259124)
			(xy 162.456996 -410.300314) (xy 162.415803 -410.336005) (xy 162.369951 -410.36547) (xy 162.320372 -410.388109)
			(xy 162.268075 -410.403461) (xy 162.214126 -410.411215) (xy 162.186874 -410.411676) (xy 161.323274 -410.411676)
			(xy 161.296022 -410.411252) (xy 161.242072 -410.403492) (xy 161.189776 -410.388134) (xy 161.140198 -410.365489)
			(xy 161.094347 -410.33602) (xy 161.053157 -410.300325) (xy 161.017465 -410.259132) (xy 160.987999 -410.213279)
			(xy 160.965357 -410.163699) (xy 160.950002 -410.111402) (xy 160.942246 -410.057452) (xy 159.504589 -410.057452)
			(xy 159.496835 -410.111388) (xy 159.481483 -410.163675) (xy 159.458846 -410.213246) (xy 159.429385 -410.259091)
			(xy 159.393701 -410.300277) (xy 159.352518 -410.335965) (xy 159.306676 -410.36543) (xy 159.257107 -410.388071)
			(xy 159.204821 -410.403428) (xy 159.150881 -410.411187) (xy 159.123634 -410.411676) (xy 158.260034 -410.411676)
			(xy 158.232777 -410.411279) (xy 158.178818 -410.403526) (xy 158.126512 -410.388171) (xy 158.076923 -410.365529)
			(xy 158.031062 -410.336059) (xy 157.989862 -410.300363) (xy 157.954161 -410.259165) (xy 157.924687 -410.213307)
			(xy 157.902041 -410.16372) (xy 157.886682 -410.111415) (xy 157.878923 -410.057457) (xy 156.441412 -410.057457)
			(xy 156.433656 -410.111398) (xy 156.418301 -410.163692) (xy 156.39566 -410.213268) (xy 156.366194 -410.259118)
			(xy 156.330503 -410.300307) (xy 156.289313 -410.335998) (xy 156.243463 -410.365463) (xy 156.193886 -410.388103)
			(xy 156.141592 -410.403458) (xy 156.087645 -410.411213) (xy 156.060394 -410.411676) (xy 155.196794 -410.411676)
			(xy 155.169541 -410.411254) (xy 155.115589 -410.403496) (xy 155.063291 -410.388139) (xy 155.01371 -410.365496)
			(xy 154.967857 -410.336027) (xy 154.926664 -410.300332) (xy 154.89097 -410.259139) (xy 154.861502 -410.213285)
			(xy 154.838859 -410.163704) (xy 154.823503 -410.111405) (xy 154.815746 -410.057453) (xy 153.378213 -410.057453)
			(xy 153.370455 -410.111403) (xy 153.355098 -410.1637) (xy 153.332454 -410.213279) (xy 153.302984 -410.259131)
			(xy 153.267289 -410.300321) (xy 153.226094 -410.336012) (xy 153.180239 -410.365476) (xy 153.130657 -410.388114)
			(xy 153.078358 -410.403465) (xy 153.024407 -410.411216) (xy 152.997154 -410.411676) (xy 152.133554 -410.411676)
			(xy 152.106303 -410.411251) (xy 152.052355 -410.403489) (xy 152.000062 -410.388128) (xy 151.950486 -410.365482)
			(xy 151.904638 -410.336012) (xy 151.863449 -410.300318) (xy 151.82776 -410.259125) (xy 151.798295 -410.213273)
			(xy 151.775656 -410.163695) (xy 151.760302 -410.1114) (xy 151.752546 -410.057451) (xy 150.31489 -410.057451)
			(xy 150.307134 -410.11139) (xy 150.291781 -410.163679) (xy 150.269143 -410.213251) (xy 150.239681 -410.259097)
			(xy 150.203994 -410.300284) (xy 150.162809 -410.335972) (xy 150.116964 -410.365436) (xy 150.067393 -410.388076)
			(xy 150.015104 -410.403431) (xy 149.961162 -410.411189) (xy 149.933914 -410.411676) (xy 149.070314 -410.411676)
			(xy 149.043058 -410.411278) (xy 148.989101 -410.403522) (xy 148.936797 -410.388166) (xy 148.887211 -410.365522)
			(xy 148.841352 -410.336052) (xy 148.800154 -410.300355) (xy 148.764456 -410.259159) (xy 148.734984 -410.213301)
			(xy 148.712339 -410.163716) (xy 148.696981 -410.111413) (xy 148.689223 -410.057456) (xy 147.251712 -410.057456)
			(xy 147.243956 -410.1114) (xy 147.2286 -410.163696) (xy 147.205957 -410.213274) (xy 147.176489 -410.259124)
			(xy 147.140796 -410.300314) (xy 147.099603 -410.336005) (xy 147.053751 -410.36547) (xy 147.004172 -410.388109)
			(xy 146.951875 -410.403461) (xy 146.897926 -410.411215) (xy 146.870674 -410.411676) (xy 146.007074 -410.411676)
			(xy 145.979822 -410.411252) (xy 145.925872 -410.403492) (xy 145.873576 -410.388134) (xy 145.823998 -410.365489)
			(xy 145.778147 -410.33602) (xy 145.736957 -410.300325) (xy 145.701265 -410.259132) (xy 145.671799 -410.213279)
			(xy 145.649157 -410.163699) (xy 145.633802 -410.111402) (xy 145.626046 -410.057452) (xy 144.188389 -410.057452)
			(xy 144.180635 -410.111388) (xy 144.165283 -410.163675) (xy 144.142646 -410.213246) (xy 144.113185 -410.259091)
			(xy 144.077501 -410.300277) (xy 144.036318 -410.335965) (xy 143.990476 -410.36543) (xy 143.940907 -410.388071)
			(xy 143.888621 -410.403428) (xy 143.834681 -410.411187) (xy 143.807434 -410.411676) (xy 142.943834 -410.411676)
			(xy 142.916577 -410.411279) (xy 142.862618 -410.403526) (xy 142.810312 -410.388171) (xy 142.760723 -410.365529)
			(xy 142.714862 -410.336059) (xy 142.673662 -410.300363) (xy 142.637961 -410.259165) (xy 142.608487 -410.213307)
			(xy 142.585841 -410.16372) (xy 142.570482 -410.111415) (xy 142.562723 -410.057457) (xy 141.125212 -410.057457)
			(xy 141.117456 -410.111398) (xy 141.102101 -410.163692) (xy 141.07946 -410.213268) (xy 141.049994 -410.259118)
			(xy 141.014303 -410.300307) (xy 140.973113 -410.335998) (xy 140.927263 -410.365463) (xy 140.877686 -410.388103)
			(xy 140.825392 -410.403458) (xy 140.771445 -410.411213) (xy 140.744194 -410.411676) (xy 139.880594 -410.411676)
			(xy 139.853341 -410.411254) (xy 139.799389 -410.403496) (xy 139.747091 -410.388139) (xy 139.69751 -410.365496)
			(xy 139.651657 -410.336027) (xy 139.610464 -410.300332) (xy 139.57477 -410.259139) (xy 139.545302 -410.213285)
			(xy 139.522659 -410.163704) (xy 139.507303 -410.111405) (xy 139.499546 -410.057453) (xy 138.062013 -410.057453)
			(xy 138.054255 -410.111403) (xy 138.038898 -410.1637) (xy 138.016254 -410.213279) (xy 137.986784 -410.259131)
			(xy 137.951089 -410.300321) (xy 137.909894 -410.336012) (xy 137.864039 -410.365476) (xy 137.814457 -410.388114)
			(xy 137.762158 -410.403465) (xy 137.708207 -410.411216) (xy 137.680954 -410.411676) (xy 136.817354 -410.411676)
			(xy 136.790103 -410.411251) (xy 136.736155 -410.403489) (xy 136.683862 -410.388128) (xy 136.634286 -410.365482)
			(xy 136.588438 -410.336012) (xy 136.547249 -410.300318) (xy 136.51156 -410.259125) (xy 136.482095 -410.213273)
			(xy 136.459456 -410.163695) (xy 136.444102 -410.1114) (xy 136.436346 -410.057451) (xy 134.99869 -410.057451)
			(xy 134.990934 -410.11139) (xy 134.975581 -410.163679) (xy 134.952943 -410.213251) (xy 134.923481 -410.259097)
			(xy 134.887794 -410.300284) (xy 134.846609 -410.335972) (xy 134.800764 -410.365436) (xy 134.751193 -410.388076)
			(xy 134.698904 -410.403431) (xy 134.644962 -410.411189) (xy 134.617714 -410.411676) (xy 133.754114 -410.411676)
			(xy 133.726858 -410.411278) (xy 133.672901 -410.403522) (xy 133.620597 -410.388166) (xy 133.571011 -410.365522)
			(xy 133.525152 -410.336052) (xy 133.483954 -410.300355) (xy 133.448256 -410.259159) (xy 133.418784 -410.213301)
			(xy 133.396139 -410.163716) (xy 133.380781 -410.111413) (xy 133.373023 -410.057456) (xy 131.935512 -410.057456)
			(xy 131.927756 -410.1114) (xy 131.9124 -410.163696) (xy 131.889757 -410.213274) (xy 131.860289 -410.259124)
			(xy 131.824596 -410.300314) (xy 131.783403 -410.336005) (xy 131.737551 -410.36547) (xy 131.687972 -410.388109)
			(xy 131.635675 -410.403461) (xy 131.581726 -410.411215) (xy 131.554474 -410.411676) (xy 130.690874 -410.411676)
			(xy 130.663622 -410.411252) (xy 130.609672 -410.403492) (xy 130.557376 -410.388134) (xy 130.507798 -410.365489)
			(xy 130.461947 -410.33602) (xy 130.420757 -410.300325) (xy 130.385065 -410.259132) (xy 130.355599 -410.213279)
			(xy 130.332957 -410.163699) (xy 130.317602 -410.111402) (xy 130.309846 -410.057452) (xy 128.872189 -410.057452)
			(xy 128.864435 -410.111388) (xy 128.849083 -410.163675) (xy 128.826446 -410.213246) (xy 128.796985 -410.259091)
			(xy 128.761301 -410.300277) (xy 128.720118 -410.335965) (xy 128.674276 -410.36543) (xy 128.624707 -410.388071)
			(xy 128.572421 -410.403428) (xy 128.518481 -410.411187) (xy 128.491234 -410.411676) (xy 127.627634 -410.411676)
			(xy 127.600377 -410.411279) (xy 127.546418 -410.403526) (xy 127.494112 -410.388171) (xy 127.444523 -410.365529)
			(xy 127.398662 -410.336059) (xy 127.357462 -410.300363) (xy 127.321761 -410.259165) (xy 127.292287 -410.213307)
			(xy 127.269641 -410.16372) (xy 127.254282 -410.111415) (xy 127.246523 -410.057457) (xy 125.809012 -410.057457)
			(xy 125.801256 -410.111398) (xy 125.785901 -410.163692) (xy 125.76326 -410.213268) (xy 125.733794 -410.259118)
			(xy 125.698103 -410.300307) (xy 125.656913 -410.335998) (xy 125.611063 -410.365463) (xy 125.561486 -410.388103)
			(xy 125.509192 -410.403458) (xy 125.455245 -410.411213) (xy 125.427994 -410.411676) (xy 124.564394 -410.411676)
			(xy 124.537141 -410.411254) (xy 124.483189 -410.403496) (xy 124.430891 -410.388139) (xy 124.38131 -410.365496)
			(xy 124.335457 -410.336027) (xy 124.294264 -410.300332) (xy 124.25857 -410.259139) (xy 124.229102 -410.213285)
			(xy 124.206459 -410.163704) (xy 124.191103 -410.111405) (xy 124.183346 -410.057453) (xy 122.745813 -410.057453)
			(xy 122.738055 -410.111403) (xy 122.722698 -410.1637) (xy 122.700054 -410.213279) (xy 122.670584 -410.259131)
			(xy 122.634889 -410.300321) (xy 122.593694 -410.336012) (xy 122.547839 -410.365476) (xy 122.498257 -410.388114)
			(xy 122.445958 -410.403465) (xy 122.392007 -410.411216) (xy 122.364754 -410.411676) (xy 121.501154 -410.411676)
			(xy 121.473903 -410.411251) (xy 121.419955 -410.403489) (xy 121.367662 -410.388128) (xy 121.318086 -410.365482)
			(xy 121.272238 -410.336012) (xy 121.231049 -410.300318) (xy 121.19536 -410.259125) (xy 121.165895 -410.213273)
			(xy 121.143256 -410.163695) (xy 121.127902 -410.1114) (xy 121.120146 -410.057451) (xy 96.519189 -410.057451)
			(xy 96.511435 -410.111387) (xy 96.496083 -410.163674) (xy 96.473447 -410.213245) (xy 96.443986 -410.259089)
			(xy 96.408302 -410.300275) (xy 96.36712 -410.335964) (xy 96.321278 -410.365428) (xy 96.27171 -410.38807)
			(xy 96.219424 -410.403427) (xy 96.165485 -410.411187) (xy 96.138238 -410.411676) (xy 95.274638 -410.411676)
			(xy 95.247381 -410.41128) (xy 95.193421 -410.403526) (xy 95.141115 -410.388172) (xy 95.091525 -410.36553)
			(xy 95.045664 -410.336061) (xy 95.004463 -410.300364) (xy 94.968762 -410.259167) (xy 94.939288 -410.213308)
			(xy 94.916641 -410.163721) (xy 94.901282 -410.111416) (xy 94.893523 -410.057457) (xy 93.456012 -410.057457)
			(xy 93.448256 -410.111397) (xy 93.432902 -410.163691) (xy 93.410261 -410.213267) (xy 93.380795 -410.259116)
			(xy 93.345104 -410.300306) (xy 93.303915 -410.335996) (xy 93.258065 -410.365462) (xy 93.208489 -410.388102)
			(xy 93.156195 -410.403457) (xy 93.102249 -410.411213) (xy 93.074998 -410.411676) (xy 92.211398 -410.411676)
			(xy 92.184145 -410.411254) (xy 92.130193 -410.403497) (xy 92.077894 -410.38814) (xy 92.028313 -410.365497)
			(xy 91.982459 -410.336028) (xy 91.941265 -410.300334) (xy 91.905571 -410.25914) (xy 91.876102 -410.213286)
			(xy 91.853459 -410.163705) (xy 91.838103 -410.111406) (xy 91.830346 -410.057453) (xy 90.392813 -410.057453)
			(xy 90.385055 -410.111403) (xy 90.369698 -410.163699) (xy 90.347055 -410.213278) (xy 90.317585 -410.259129)
			(xy 90.28189 -410.30032) (xy 90.240696 -410.33601) (xy 90.194841 -410.365475) (xy 90.14526 -410.388113)
			(xy 90.092961 -410.403464) (xy 90.039011 -410.411216) (xy 90.011758 -410.411676) (xy 89.148158 -410.411676)
			(xy 89.120906 -410.411251) (xy 89.066959 -410.403489) (xy 89.014665 -410.388129) (xy 88.965089 -410.365484)
			(xy 88.91924 -410.336014) (xy 88.878051 -410.300319) (xy 88.842361 -410.259127) (xy 88.812896 -410.213275)
			(xy 88.790256 -410.163696) (xy 88.774902 -410.1114) (xy 88.767146 -410.057452) (xy 87.329489 -410.057452)
			(xy 87.321734 -410.11139) (xy 87.306382 -410.163679) (xy 87.283744 -410.21325) (xy 87.254282 -410.259096)
			(xy 87.218595 -410.300282) (xy 87.17741 -410.335971) (xy 87.131566 -410.365435) (xy 87.081995 -410.388075)
			(xy 87.029707 -410.403431) (xy 86.975766 -410.411189) (xy 86.948518 -410.411676) (xy 86.084918 -410.411676)
			(xy 86.057662 -410.411278) (xy 86.003705 -410.403523) (xy 85.9514 -410.388167) (xy 85.901813 -410.365524)
			(xy 85.855954 -410.336054) (xy 85.814756 -410.300357) (xy 85.779057 -410.25916) (xy 85.749585 -410.213302)
			(xy 85.726939 -410.163717) (xy 85.711581 -410.111413) (xy 85.703823 -410.057456) (xy 84.266312 -410.057456)
			(xy 84.258556 -410.1114) (xy 84.2432 -410.163695) (xy 84.220558 -410.213273) (xy 84.19109 -410.259123)
			(xy 84.155397 -410.300313) (xy 84.114205 -410.336003) (xy 84.068353 -410.365468) (xy 84.018774 -410.388108)
			(xy 83.966478 -410.40346) (xy 83.91253 -410.411214) (xy 83.885278 -410.411676) (xy 83.021678 -410.411676)
			(xy 82.994425 -410.411253) (xy 82.940476 -410.403493) (xy 82.888179 -410.388135) (xy 82.838601 -410.36549)
			(xy 82.792749 -410.336021) (xy 82.751558 -410.300326) (xy 82.715866 -410.259133) (xy 82.686399 -410.21328)
			(xy 82.663758 -410.1637) (xy 82.648402 -410.111403) (xy 82.640646 -410.057453) (xy 81.202989 -410.057453)
			(xy 81.195235 -410.111387) (xy 81.179883 -410.163674) (xy 81.157247 -410.213245) (xy 81.127786 -410.259089)
			(xy 81.092102 -410.300275) (xy 81.05092 -410.335964) (xy 81.005078 -410.365428) (xy 80.95551 -410.38807)
			(xy 80.903224 -410.403427) (xy 80.849285 -410.411187) (xy 80.822038 -410.411676) (xy 79.958438 -410.411676)
			(xy 79.931181 -410.41128) (xy 79.877221 -410.403526) (xy 79.824915 -410.388172) (xy 79.775325 -410.36553)
			(xy 79.729464 -410.336061) (xy 79.688263 -410.300364) (xy 79.652562 -410.259167) (xy 79.623088 -410.213308)
			(xy 79.600441 -410.163721) (xy 79.585082 -410.111416) (xy 79.577323 -410.057457) (xy 78.139812 -410.057457)
			(xy 78.132056 -410.111397) (xy 78.116702 -410.163691) (xy 78.094061 -410.213267) (xy 78.064595 -410.259116)
			(xy 78.028904 -410.300306) (xy 77.987715 -410.335996) (xy 77.941865 -410.365462) (xy 77.892289 -410.388102)
			(xy 77.839995 -410.403457) (xy 77.786049 -410.411213) (xy 77.758798 -410.411676) (xy 76.895198 -410.411676)
			(xy 76.867945 -410.411254) (xy 76.813993 -410.403497) (xy 76.761694 -410.38814) (xy 76.712113 -410.365497)
			(xy 76.666259 -410.336028) (xy 76.625065 -410.300334) (xy 76.589371 -410.25914) (xy 76.559902 -410.213286)
			(xy 76.537259 -410.163705) (xy 76.521903 -410.111406) (xy 76.514146 -410.057453) (xy 75.076613 -410.057453)
			(xy 75.068855 -410.111403) (xy 75.053498 -410.163699) (xy 75.030855 -410.213278) (xy 75.001385 -410.259129)
			(xy 74.96569 -410.30032) (xy 74.924496 -410.33601) (xy 74.878641 -410.365475) (xy 74.82906 -410.388113)
			(xy 74.776761 -410.403464) (xy 74.722811 -410.411216) (xy 74.695558 -410.411676) (xy 73.831958 -410.411676)
			(xy 73.804706 -410.411251) (xy 73.750759 -410.403489) (xy 73.698465 -410.388129) (xy 73.648889 -410.365484)
			(xy 73.60304 -410.336014) (xy 73.561851 -410.300319) (xy 73.526161 -410.259127) (xy 73.496696 -410.213275)
			(xy 73.474056 -410.163696) (xy 73.458702 -410.1114) (xy 73.450946 -410.057452) (xy 72.013289 -410.057452)
			(xy 72.005534 -410.11139) (xy 71.990182 -410.163679) (xy 71.967544 -410.21325) (xy 71.938082 -410.259096)
			(xy 71.902395 -410.300282) (xy 71.86121 -410.335971) (xy 71.815366 -410.365435) (xy 71.765795 -410.388075)
			(xy 71.713507 -410.403431) (xy 71.659566 -410.411189) (xy 71.632318 -410.411676) (xy 70.768718 -410.411676)
			(xy 70.741462 -410.411278) (xy 70.687505 -410.403523) (xy 70.6352 -410.388167) (xy 70.585613 -410.365524)
			(xy 70.539754 -410.336054) (xy 70.498556 -410.300357) (xy 70.462857 -410.25916) (xy 70.433385 -410.213302)
			(xy 70.410739 -410.163717) (xy 70.395381 -410.111413) (xy 70.387623 -410.057456) (xy 68.950112 -410.057456)
			(xy 68.942356 -410.1114) (xy 68.927 -410.163695) (xy 68.904358 -410.213273) (xy 68.87489 -410.259123)
			(xy 68.839197 -410.300313) (xy 68.798005 -410.336003) (xy 68.752153 -410.365468) (xy 68.702574 -410.388108)
			(xy 68.650278 -410.40346) (xy 68.59633 -410.411214) (xy 68.569078 -410.411676) (xy 67.705478 -410.411676)
			(xy 67.678225 -410.411253) (xy 67.624276 -410.403493) (xy 67.571979 -410.388135) (xy 67.522401 -410.36549)
			(xy 67.476549 -410.336021) (xy 67.435358 -410.300326) (xy 67.399666 -410.259133) (xy 67.370199 -410.21328)
			(xy 67.347558 -410.1637) (xy 67.332202 -410.111403) (xy 67.324446 -410.057453) (xy 65.886789 -410.057453)
			(xy 65.879035 -410.111387) (xy 65.863683 -410.163674) (xy 65.841047 -410.213245) (xy 65.811586 -410.259089)
			(xy 65.775902 -410.300275) (xy 65.73472 -410.335964) (xy 65.688878 -410.365428) (xy 65.63931 -410.38807)
			(xy 65.587024 -410.403427) (xy 65.533085 -410.411187) (xy 65.505838 -410.411676) (xy 64.642238 -410.411676)
			(xy 64.614981 -410.41128) (xy 64.561021 -410.403526) (xy 64.508715 -410.388172) (xy 64.459125 -410.36553)
			(xy 64.413264 -410.336061) (xy 64.372063 -410.300364) (xy 64.336362 -410.259167) (xy 64.306888 -410.213308)
			(xy 64.284241 -410.163721) (xy 64.268882 -410.111416) (xy 64.261123 -410.057457) (xy 62.823612 -410.057457)
			(xy 62.815856 -410.111397) (xy 62.800502 -410.163691) (xy 62.777861 -410.213267) (xy 62.748395 -410.259116)
			(xy 62.712704 -410.300306) (xy 62.671515 -410.335996) (xy 62.625665 -410.365462) (xy 62.576089 -410.388102)
			(xy 62.523795 -410.403457) (xy 62.469849 -410.411213) (xy 62.442598 -410.411676) (xy 61.578998 -410.411676)
			(xy 61.551745 -410.411254) (xy 61.497793 -410.403497) (xy 61.445494 -410.38814) (xy 61.395913 -410.365497)
			(xy 61.350059 -410.336028) (xy 61.308865 -410.300334) (xy 61.273171 -410.25914) (xy 61.243702 -410.213286)
			(xy 61.221059 -410.163705) (xy 61.205703 -410.111406) (xy 61.197946 -410.057453) (xy 59.760413 -410.057453)
			(xy 59.752655 -410.111403) (xy 59.737298 -410.163699) (xy 59.714655 -410.213278) (xy 59.685185 -410.259129)
			(xy 59.64949 -410.30032) (xy 59.608296 -410.33601) (xy 59.562441 -410.365475) (xy 59.51286 -410.388113)
			(xy 59.460561 -410.403464) (xy 59.406611 -410.411216) (xy 59.379358 -410.411676) (xy 58.515758 -410.411676)
			(xy 58.488506 -410.411251) (xy 58.434559 -410.403489) (xy 58.382265 -410.388129) (xy 58.332689 -410.365484)
			(xy 58.28684 -410.336014) (xy 58.245651 -410.300319) (xy 58.209961 -410.259127) (xy 58.180496 -410.213275)
			(xy 58.157856 -410.163696) (xy 58.142502 -410.1114) (xy 58.134746 -410.057452) (xy 56.697089 -410.057452)
			(xy 56.689334 -410.11139) (xy 56.673982 -410.163679) (xy 56.651344 -410.21325) (xy 56.621882 -410.259096)
			(xy 56.586195 -410.300282) (xy 56.54501 -410.335971) (xy 56.499166 -410.365435) (xy 56.449595 -410.388075)
			(xy 56.397307 -410.403431) (xy 56.343366 -410.411189) (xy 56.316118 -410.411676) (xy 55.452518 -410.411676)
			(xy 55.425262 -410.411278) (xy 55.371305 -410.403523) (xy 55.319 -410.388167) (xy 55.269413 -410.365524)
			(xy 55.223554 -410.336054) (xy 55.182356 -410.300357) (xy 55.146657 -410.25916) (xy 55.117185 -410.213302)
			(xy 55.094539 -410.163717) (xy 55.079181 -410.111413) (xy 55.071423 -410.057456) (xy 53.633912 -410.057456)
			(xy 53.626156 -410.1114) (xy 53.6108 -410.163695) (xy 53.588158 -410.213273) (xy 53.55869 -410.259123)
			(xy 53.522997 -410.300313) (xy 53.481805 -410.336003) (xy 53.435953 -410.365468) (xy 53.386374 -410.388108)
			(xy 53.334078 -410.40346) (xy 53.28013 -410.411214) (xy 53.252878 -410.411676) (xy 52.389278 -410.411676)
			(xy 52.362025 -410.411253) (xy 52.308076 -410.403493) (xy 52.255779 -410.388135) (xy 52.206201 -410.36549)
			(xy 52.160349 -410.336021) (xy 52.119158 -410.300326) (xy 52.083466 -410.259133) (xy 52.053999 -410.21328)
			(xy 52.031358 -410.1637) (xy 52.016002 -410.111403) (xy 52.008246 -410.057453) (xy 50.570589 -410.057453)
			(xy 50.562835 -410.111387) (xy 50.547483 -410.163674) (xy 50.524847 -410.213245) (xy 50.495386 -410.259089)
			(xy 50.459702 -410.300275) (xy 50.41852 -410.335964) (xy 50.372678 -410.365428) (xy 50.32311 -410.38807)
			(xy 50.270824 -410.403427) (xy 50.216885 -410.411187) (xy 50.189638 -410.411676) (xy 49.326038 -410.411676)
			(xy 49.298781 -410.41128) (xy 49.244821 -410.403526) (xy 49.192515 -410.388172) (xy 49.142925 -410.36553)
			(xy 49.097064 -410.336061) (xy 49.055863 -410.300364) (xy 49.020162 -410.259167) (xy 48.990688 -410.213308)
			(xy 48.968041 -410.163721) (xy 48.952682 -410.111416) (xy 48.944923 -410.057457) (xy 7.00913 -410.057457)
			(xy 7.00913 -411.241049) (xy 101.876886 -411.241049) (xy 101.876886 -411.186551) (xy 101.884641 -411.132608)
			(xy 101.899994 -411.080318) (xy 101.922631 -411.030744) (xy 101.952093 -410.984897) (xy 101.98778 -410.943708)
			(xy 102.028964 -410.908017) (xy 102.074809 -410.878551) (xy 102.12438 -410.855908) (xy 102.176669 -410.840549)
			(xy 102.230611 -410.832788) (xy 102.25786 -410.8323) (xy 103.12146 -410.8323) (xy 103.148715 -410.832745)
			(xy 103.202672 -410.840497) (xy 103.254975 -410.85585) (xy 103.304562 -410.878491) (xy 103.350421 -410.907958)
			(xy 103.391619 -410.943653) (xy 103.427318 -410.984847) (xy 103.45679 -411.030703) (xy 103.479436 -411.080287)
			(xy 103.494794 -411.132589) (xy 103.502553 -411.186545) (xy 103.502553 -411.241055) (xy 103.494794 -411.295011)
			(xy 103.479436 -411.347313) (xy 103.45679 -411.396897) (xy 103.427318 -411.442753) (xy 103.391619 -411.483947)
			(xy 103.350421 -411.519642) (xy 103.304562 -411.549109) (xy 103.254975 -411.57175) (xy 103.202672 -411.587103)
			(xy 103.148715 -411.594855) (xy 103.12146 -411.595316) (xy 102.25786 -411.595316) (xy 102.230611 -411.594812)
			(xy 102.176669 -411.587051) (xy 102.12438 -411.571692) (xy 102.074809 -411.549049) (xy 102.028964 -411.519583)
			(xy 101.98778 -411.483892) (xy 101.952093 -411.442703) (xy 101.922631 -411.396856) (xy 101.899994 -411.347282)
			(xy 101.884641 -411.294992) (xy 101.876886 -411.241049) (xy 7.00913 -411.241049) (xy 7.00913 -424.470068)
			(xy 39.528496 -424.470068) (xy 39.528496 -417.770056) (xy 39.529001 -417.664532) (xy 39.537085 -417.453638)
			(xy 39.553241 -417.243209) (xy 39.577444 -417.033552) (xy 39.609661 -416.824977) (xy 39.649843 -416.617789)
			(xy 39.697931 -416.412292) (xy 39.753855 -416.208788) (xy 39.817532 -416.007575) (xy 39.88887 -415.808948)
			(xy 39.967764 -415.6132) (xy 40.054097 -415.420618) (xy 40.147744 -415.231483) (xy 40.248566 -415.046074)
			(xy 40.356416 -414.864663) (xy 40.471135 -414.687516) (xy 40.592555 -414.514894) (xy 40.720498 -414.347048)
			(xy 40.854776 -414.184226) (xy 40.995192 -414.026667) (xy 41.14154 -413.874602) (xy 41.293605 -413.728254)
			(xy 41.451164 -413.587838) (xy 41.613986 -413.45356) (xy 41.781832 -413.325617) (xy 41.954454 -413.204197)
			(xy 42.131601 -413.089478) (xy 42.313012 -412.981628) (xy 42.498421 -412.880806) (xy 42.687556 -412.787159)
			(xy 42.880138 -412.700826) (xy 43.075886 -412.621932) (xy 43.274513 -412.550594) (xy 43.475726 -412.486917)
			(xy 43.67923 -412.430993) (xy 43.884727 -412.382905) (xy 44.091915 -412.342723) (xy 44.30049 -412.310506)
			(xy 44.510147 -412.286303) (xy 44.720576 -412.270147) (xy 44.93147 -412.262063) (xy 45.142518 -412.262063)
			(xy 45.353412 -412.270147) (xy 45.563841 -412.286303) (xy 45.773498 -412.310506) (xy 45.982073 -412.342723)
			(xy 46.189261 -412.382905) (xy 46.394758 -412.430993) (xy 46.598262 -412.486917) (xy 46.799475 -412.550594)
			(xy 46.998102 -412.621932) (xy 47.19385 -412.700826) (xy 47.386432 -412.787159) (xy 47.575567 -412.880806)
			(xy 47.760976 -412.981628) (xy 47.942387 -413.089478) (xy 48.119534 -413.204197) (xy 48.292156 -413.325617)
			(xy 48.460002 -413.45356) (xy 48.622824 -413.587838) (xy 48.649451 -413.611568) (xy 104.877616 -413.611568)
			(xy 104.877616 -412.747968) (xy 104.878102 -412.720717) (xy 104.885858 -412.666769) (xy 104.901213 -412.614474)
			(xy 104.923855 -412.564897) (xy 104.953321 -412.519047) (xy 104.989012 -412.477856) (xy 105.030203 -412.442165)
			(xy 105.076053 -412.412699) (xy 105.12563 -412.390057) (xy 105.177925 -412.374702) (xy 105.231873 -412.366946)
			(xy 105.286375 -412.366946) (xy 105.340323 -412.374702) (xy 105.392618 -412.390057) (xy 105.442195 -412.412699)
			(xy 105.488045 -412.442165) (xy 105.529236 -412.477856) (xy 105.564927 -412.519047) (xy 105.594393 -412.564897)
			(xy 105.617035 -412.614474) (xy 105.63239 -412.666769) (xy 105.640146 -412.720717) (xy 105.640632 -412.747968)
			(xy 105.640632 -413.611568) (xy 105.640146 -413.638819) (xy 105.63239 -413.692767) (xy 105.617035 -413.745062)
			(xy 105.594393 -413.794639) (xy 105.584722 -413.809688) (xy 116.689632 -413.809688) (xy 116.689632 -412.946088)
			(xy 116.690118 -412.918837) (xy 116.697874 -412.864889) (xy 116.713229 -412.812594) (xy 116.735871 -412.763017)
			(xy 116.765337 -412.717167) (xy 116.801028 -412.675976) (xy 116.842219 -412.640285) (xy 116.888069 -412.610819)
			(xy 116.937646 -412.588177) (xy 116.989941 -412.572822) (xy 117.043889 -412.565066) (xy 117.098391 -412.565066)
			(xy 117.152339 -412.572822) (xy 117.204634 -412.588177) (xy 117.254211 -412.610819) (xy 117.300061 -412.640285)
			(xy 117.341252 -412.675976) (xy 117.376943 -412.717167) (xy 117.406409 -412.763017) (xy 117.429051 -412.812594)
			(xy 117.444406 -412.864889) (xy 117.452162 -412.918837) (xy 117.452648 -412.946088) (xy 117.452648 -413.809688)
			(xy 117.452162 -413.836939) (xy 117.444406 -413.890887) (xy 117.429051 -413.943182) (xy 117.406409 -413.992759)
			(xy 117.376943 -414.038609) (xy 117.341252 -414.0798) (xy 117.300061 -414.115491) (xy 117.254211 -414.144957)
			(xy 117.204634 -414.167599) (xy 117.152339 -414.182954) (xy 117.098391 -414.19071) (xy 117.043889 -414.19071)
			(xy 116.989941 -414.182954) (xy 116.937646 -414.167599) (xy 116.888069 -414.144957) (xy 116.842219 -414.115491)
			(xy 116.801028 -414.0798) (xy 116.765337 -414.038609) (xy 116.735871 -413.992759) (xy 116.713229 -413.943182)
			(xy 116.697874 -413.890887) (xy 116.690118 -413.836939) (xy 116.689632 -413.809688) (xy 105.584722 -413.809688)
			(xy 105.564927 -413.840489) (xy 105.529236 -413.88168) (xy 105.488045 -413.917371) (xy 105.442195 -413.946837)
			(xy 105.392618 -413.969479) (xy 105.340323 -413.984834) (xy 105.286375 -413.99259) (xy 105.231873 -413.99259)
			(xy 105.177925 -413.984834) (xy 105.12563 -413.969479) (xy 105.076053 -413.946837) (xy 105.030203 -413.917371)
			(xy 104.989012 -413.88168) (xy 104.953321 -413.840489) (xy 104.923855 -413.794639) (xy 104.901213 -413.745062)
			(xy 104.885858 -413.692767) (xy 104.878102 -413.638819) (xy 104.877616 -413.611568) (xy 48.649451 -413.611568)
			(xy 48.780383 -413.728254) (xy 48.932448 -413.874602) (xy 49.078796 -414.026667) (xy 49.219212 -414.184226)
			(xy 49.35349 -414.347048) (xy 49.481433 -414.514894) (xy 49.602853 -414.687516) (xy 49.717572 -414.864663)
			(xy 49.825422 -415.046074) (xy 49.926244 -415.231483) (xy 50.019891 -415.420618) (xy 50.106224 -415.6132)
			(xy 50.133819 -415.681668) (xy 100.559616 -415.681668) (xy 100.559616 -414.818068) (xy 100.560102 -414.790817)
			(xy 100.567858 -414.736869) (xy 100.583213 -414.684574) (xy 100.605855 -414.634997) (xy 100.635321 -414.589147)
			(xy 100.671012 -414.547956) (xy 100.712203 -414.512265) (xy 100.758053 -414.482799) (xy 100.80763 -414.460157)
			(xy 100.859925 -414.444802) (xy 100.913873 -414.437046) (xy 100.968375 -414.437046) (xy 101.022323 -414.444802)
			(xy 101.074618 -414.460157) (xy 101.124195 -414.482799) (xy 101.170045 -414.512265) (xy 101.211236 -414.547956)
			(xy 101.246927 -414.589147) (xy 101.276393 -414.634997) (xy 101.299035 -414.684574) (xy 101.31439 -414.736869)
			(xy 101.322146 -414.790817) (xy 101.322632 -414.818068) (xy 101.322632 -415.681668) (xy 101.322146 -415.708919)
			(xy 101.31439 -415.762867) (xy 101.299035 -415.815162) (xy 101.276393 -415.864739) (xy 101.246927 -415.910589)
			(xy 101.211236 -415.95178) (xy 101.170045 -415.987471) (xy 101.124195 -416.016937) (xy 101.074618 -416.039579)
			(xy 101.022323 -416.054934) (xy 100.968375 -416.06269) (xy 100.913873 -416.06269) (xy 100.859925 -416.054934)
			(xy 100.80763 -416.039579) (xy 100.758053 -416.016937) (xy 100.712203 -415.987471) (xy 100.671012 -415.95178)
			(xy 100.635321 -415.910589) (xy 100.605855 -415.864739) (xy 100.583213 -415.815162) (xy 100.567858 -415.762867)
			(xy 100.560102 -415.708919) (xy 100.559616 -415.681668) (xy 50.133819 -415.681668) (xy 50.185118 -415.808948)
			(xy 50.256456 -416.007575) (xy 50.320133 -416.208788) (xy 50.376057 -416.412292) (xy 50.424145 -416.617789)
			(xy 50.464327 -416.824977) (xy 50.496544 -417.033552) (xy 50.520747 -417.243209) (xy 50.536903 -417.453638)
			(xy 50.544987 -417.664532) (xy 50.545492 -417.770056) (xy 50.545492 -420.089838) (xy 58.13806 -420.089838)
			(xy 58.138171 -420.074752) (xy 58.139951 -420.044634) (xy 58.141616 -420.02964) (xy 58.141616 -418.95014)
			(xy 58.139949 -418.935146) (xy 58.138169 -418.905028) (xy 58.13806 -418.889942) (xy 58.138171 -418.874856)
			(xy 58.139951 -418.844738) (xy 58.141616 -418.829744) (xy 58.141616 -418.218874) (xy 58.142085 -418.206785)
			(xy 58.149546 -418.183788) (xy 58.163733 -418.164211) (xy 58.183264 -418.14996) (xy 58.206237 -418.142424)
			(xy 58.218324 -418.141912) (xy 59.158124 -418.141912) (xy 59.170235 -418.142296) (xy 59.193265 -418.149803)
			(xy 59.212839 -418.164073) (xy 59.227033 -418.183702) (xy 59.234451 -418.206761) (xy 59.234832 -418.218874)
			(xy 59.234832 -420.760398) (xy 59.23439 -420.77249) (xy 59.226931 -420.795495) (xy 59.212739 -420.815078)
			(xy 59.193198 -420.829327) (xy 59.170215 -420.836854) (xy 59.158124 -420.83736) (xy 58.218324 -420.83736)
			(xy 58.206212 -420.836963) (xy 58.183179 -420.829465) (xy 58.163602 -420.8152) (xy 58.149408 -420.795571)
			(xy 58.141994 -420.772511) (xy 58.141616 -420.760398) (xy 58.141616 -420.150036) (xy 58.139948 -420.135042)
			(xy 58.138169 -420.104924) (xy 58.13806 -420.089838) (xy 50.545492 -420.089838) (xy 50.545492 -421.089836)
			(xy 60.138056 -421.089836) (xy 60.138167 -421.07475) (xy 60.139947 -421.044632) (xy 60.141612 -421.029638)
			(xy 60.141612 -419.950138) (xy 60.139945 -419.935144) (xy 60.138165 -419.905026) (xy 60.138056 -419.88994)
			(xy 60.138167 -419.874854) (xy 60.139947 -419.844736) (xy 60.141612 -419.829742) (xy 60.141612 -419.218872)
			(xy 60.14204 -419.206794) (xy 60.149513 -419.183822) (xy 60.163718 -419.164284) (xy 60.183265 -419.150091)
			(xy 60.206242 -419.142633) (xy 60.21832 -419.142164) (xy 61.15812 -419.142164) (xy 61.170193 -419.142647)
			(xy 61.193156 -419.150112) (xy 61.21269 -419.164304) (xy 61.226885 -419.183837) (xy 61.234352 -419.206799)
			(xy 61.234828 -419.218872) (xy 61.234828 -421.089836) (xy 68.13804 -421.089836) (xy 68.138151 -421.07475)
			(xy 68.139931 -421.044632) (xy 68.141596 -421.029638) (xy 68.141596 -419.950138) (xy 68.139929 -419.935144)
			(xy 68.138149 -419.905026) (xy 68.13804 -419.88994) (xy 68.138151 -419.874854) (xy 68.139931 -419.844736)
			(xy 68.141596 -419.829742) (xy 68.141596 -419.218872) (xy 68.14204 -419.206796) (xy 68.149511 -419.183827)
			(xy 68.163712 -419.16429) (xy 68.183255 -419.150096) (xy 68.206227 -419.142635) (xy 68.218304 -419.142164)
			(xy 69.158104 -419.142164) (xy 69.170176 -419.14266) (xy 69.193139 -419.150121) (xy 69.212673 -419.16431)
			(xy 69.226868 -419.18384) (xy 69.234336 -419.2068) (xy 69.234812 -419.218872) (xy 69.234812 -420.089838)
			(xy 70.138036 -420.089838) (xy 70.138149 -420.074753) (xy 70.139929 -420.044634) (xy 70.141592 -420.02964)
			(xy 70.141592 -418.95014) (xy 70.139925 -418.935146) (xy 70.138145 -418.905028) (xy 70.138036 -418.889942)
			(xy 70.13815 -418.874857) (xy 70.139929 -418.844738) (xy 70.141592 -418.829744) (xy 70.141592 -418.218874)
			(xy 70.142084 -418.206788) (xy 70.149542 -418.183794) (xy 70.163724 -418.164219) (xy 70.183249 -418.149968)
			(xy 70.206216 -418.142428) (xy 70.2183 -418.141912) (xy 71.1581 -418.141912) (xy 71.17021 -418.142316)
			(xy 71.193239 -418.149817) (xy 71.212814 -418.164081) (xy 71.227008 -418.183706) (xy 71.234426 -418.206762)
			(xy 71.234808 -418.218874) (xy 71.234808 -420.760398) (xy 71.234292 -420.772483) (xy 71.226841 -420.795475)
			(xy 71.212666 -420.815051) (xy 71.193146 -420.829303) (xy 71.170183 -420.836844) (xy 71.1581 -420.83736)
			(xy 70.2183 -420.83736) (xy 70.206187 -420.836983) (xy 70.183153 -420.829479) (xy 70.163576 -420.815209)
			(xy 70.149383 -420.795576) (xy 70.14197 -420.772512) (xy 70.141592 -420.760398) (xy 70.141592 -420.150036)
			(xy 70.139924 -420.135042) (xy 70.138145 -420.104924) (xy 70.138036 -420.089838) (xy 69.234812 -420.089838)
			(xy 69.234812 -421.089836) (xy 72.138032 -421.089836) (xy 72.138145 -421.074751) (xy 72.139925 -421.044632)
			(xy 72.141588 -421.029638) (xy 72.141588 -419.950138) (xy 72.13992 -419.935144) (xy 72.138141 -419.905026)
			(xy 72.138032 -419.88994) (xy 72.138145 -419.874855) (xy 72.139925 -419.844736) (xy 72.141588 -419.829742)
			(xy 72.141588 -419.218872) (xy 72.14204 -419.206796) (xy 72.14951 -419.183829) (xy 72.16371 -419.164293)
			(xy 72.18325 -419.150099) (xy 72.20622 -419.142636) (xy 72.218296 -419.142164) (xy 73.158096 -419.142164)
			(xy 73.170168 -419.142667) (xy 73.19313 -419.150125) (xy 73.212665 -419.164313) (xy 73.22686 -419.183841)
			(xy 73.234328 -419.206801) (xy 73.234804 -419.218872) (xy 73.234804 -419.702852) (xy 110.957342 -419.702852)
			(xy 110.957342 -419.648348) (xy 110.965098 -419.594399) (xy 110.980453 -419.542102) (xy 111.003093 -419.492523)
			(xy 111.032558 -419.44667) (xy 111.068249 -419.405477) (xy 111.109438 -419.369782) (xy 111.155288 -419.340312)
			(xy 111.204865 -419.317667) (xy 111.25716 -419.302306) (xy 111.311108 -419.294545) (xy 111.33836 -419.294056)
			(xy 112.20196 -419.294056) (xy 112.229212 -419.294589) (xy 112.283162 -419.30234) (xy 112.33546 -419.317691)
			(xy 112.385041 -419.340329) (xy 112.430894 -419.369793) (xy 112.472088 -419.405484) (xy 112.507783 -419.446674)
			(xy 112.537251 -419.492524) (xy 112.559895 -419.542102) (xy 112.575251 -419.594399) (xy 112.583009 -419.648348)
			(xy 112.583009 -419.702852) (xy 112.575251 -419.756801) (xy 112.559895 -419.809098) (xy 112.537251 -419.858676)
			(xy 112.507783 -419.904526) (xy 112.472088 -419.945716) (xy 112.430894 -419.981407) (xy 112.385041 -420.010871)
			(xy 112.33546 -420.033509) (xy 112.283162 -420.04886) (xy 112.229212 -420.056611) (xy 112.20196 -420.057072)
			(xy 111.33836 -420.057072) (xy 111.311108 -420.056655) (xy 111.25716 -420.048894) (xy 111.204865 -420.033533)
			(xy 111.155288 -420.010888) (xy 111.109438 -419.981418) (xy 111.068249 -419.945723) (xy 111.032558 -419.90453)
			(xy 111.003093 -419.858677) (xy 110.980453 -419.809098) (xy 110.965098 -419.756801) (xy 110.957342 -419.702852)
			(xy 73.234804 -419.702852) (xy 73.234804 -421.760396) (xy 73.234384 -421.772479) (xy 73.226917 -421.795462)
			(xy 73.212713 -421.815013) (xy 73.193162 -421.829217) (xy 73.170179 -421.836684) (xy 73.158096 -421.837104)
			(xy 72.218296 -421.837104) (xy 72.206221 -421.836639) (xy 72.183253 -421.829175) (xy 72.163716 -421.814979)
			(xy 72.149521 -421.79544) (xy 72.14206 -421.772471) (xy 72.141588 -421.760396) (xy 72.141588 -421.150034)
			(xy 72.13992 -421.13504) (xy 72.138141 -421.104922) (xy 72.138032 -421.089836) (xy 69.234812 -421.089836)
			(xy 69.234812 -421.760396) (xy 69.234332 -421.77247) (xy 69.226871 -421.795436) (xy 69.212679 -421.814973)
			(xy 69.193143 -421.829168) (xy 69.170178 -421.836631) (xy 69.158104 -421.837104) (xy 68.218304 -421.837104)
			(xy 68.206221 -421.836684) (xy 68.183238 -421.829217) (xy 68.163687 -421.815013) (xy 68.149483 -421.795462)
			(xy 68.142016 -421.772479) (xy 68.141596 -421.760396) (xy 68.141596 -421.150034) (xy 68.139928 -421.13504)
			(xy 68.138149 -421.104922) (xy 68.13804 -421.089836) (xy 61.234828 -421.089836) (xy 61.234828 -421.760396)
			(xy 61.234333 -421.772468) (xy 61.226874 -421.795432) (xy 61.212684 -421.814967) (xy 61.193154 -421.829163)
			(xy 61.170192 -421.836629) (xy 61.15812 -421.837104) (xy 60.21832 -421.837104) (xy 60.206238 -421.83667)
			(xy 60.183255 -421.829208) (xy 60.163704 -421.815007) (xy 60.1495 -421.795459) (xy 60.142032 -421.772478)
			(xy 60.141612 -421.760396) (xy 60.141612 -421.150034) (xy 60.139944 -421.13504) (xy 60.138165 -421.104922)
			(xy 60.138056 -421.089836) (xy 50.545492 -421.089836) (xy 50.545492 -423.68978) (xy 58.13806 -423.68978)
			(xy 58.138175 -423.674695) (xy 58.139953 -423.644576) (xy 58.141616 -423.629582) (xy 58.141616 -422.550082)
			(xy 58.139952 -422.535088) (xy 58.138171 -422.50497) (xy 58.13806 -422.489884) (xy 58.138175 -422.474799)
			(xy 58.139953 -422.44468) (xy 58.141616 -422.429686) (xy 58.141616 -421.81907) (xy 58.142081 -421.806981)
			(xy 58.149543 -421.783984) (xy 58.163731 -421.764406) (xy 58.183263 -421.750156) (xy 58.206237 -421.74262)
			(xy 58.218324 -421.742108) (xy 59.158124 -421.742108) (xy 59.170235 -421.742496) (xy 59.193264 -421.750003)
			(xy 59.212838 -421.764272) (xy 59.227031 -421.783899) (xy 59.23445 -421.806958) (xy 59.234832 -421.81907)
			(xy 59.234832 -423.68978) (xy 62.138052 -423.68978) (xy 62.138167 -423.674695) (xy 62.139945 -423.644576)
			(xy 62.141608 -423.629582) (xy 62.141608 -422.550082) (xy 62.139944 -422.535088) (xy 62.138163 -422.50497)
			(xy 62.138052 -422.489884) (xy 62.138167 -422.474799) (xy 62.139945 -422.44468) (xy 62.141608 -422.429686)
			(xy 62.141608 -421.81907) (xy 62.142081 -421.806982) (xy 62.149542 -421.783986) (xy 62.163728 -421.764409)
			(xy 62.183258 -421.750158) (xy 62.20623 -421.742621) (xy 62.218316 -421.742108) (xy 63.158116 -421.742108)
			(xy 63.170227 -421.742503) (xy 63.193256 -421.750008) (xy 63.212829 -421.764274) (xy 63.227023 -421.783901)
			(xy 63.234442 -421.806958) (xy 63.234824 -421.81907) (xy 63.234824 -424.360594) (xy 63.234387 -424.372687)
			(xy 63.226927 -424.395693) (xy 63.212734 -424.415276) (xy 63.193192 -424.429526) (xy 63.170207 -424.437051)
			(xy 63.158116 -424.437556) (xy 62.218316 -424.437556) (xy 62.206214 -424.437071) (xy 62.183196 -424.429582)
			(xy 62.163628 -424.415337) (xy 62.149431 -424.395733) (xy 62.142 -424.372697) (xy 62.141608 -424.360594)
			(xy 62.141608 -423.749978) (xy 62.139944 -423.734984) (xy 62.138162 -423.704866) (xy 62.138052 -423.68978)
			(xy 59.234832 -423.68978) (xy 59.234832 -424.360594) (xy 59.234387 -424.372686) (xy 59.226928 -424.395691)
			(xy 59.212737 -424.415274) (xy 59.193197 -424.429523) (xy 59.170215 -424.43705) (xy 59.158124 -424.437556)
			(xy 58.218324 -424.437556) (xy 58.206222 -424.437064) (xy 58.183205 -424.429578) (xy 58.163637 -424.415334)
			(xy 58.149439 -424.395732) (xy 58.142008 -424.372697) (xy 58.141616 -424.360594) (xy 58.141616 -423.749978)
			(xy 58.139952 -423.734984) (xy 58.13817 -423.704866) (xy 58.13806 -423.68978) (xy 50.545492 -423.68978)
			(xy 50.545492 -424.470068) (xy 50.544987 -424.575592) (xy 50.54061 -424.689778) (xy 64.138048 -424.689778)
			(xy 64.138163 -424.674693) (xy 64.139941 -424.644574) (xy 64.141604 -424.62958) (xy 64.141604 -423.55008)
			(xy 64.13994 -423.535086) (xy 64.138158 -423.504968) (xy 64.138048 -423.489882) (xy 64.138163 -423.474797)
			(xy 64.139941 -423.444678) (xy 64.141604 -423.429684) (xy 64.141604 -422.819068) (xy 64.142037 -422.806991)
			(xy 64.14951 -422.78402) (xy 64.163714 -422.764483) (xy 64.18326 -422.75029) (xy 64.206234 -422.74283)
			(xy 64.218312 -422.74236) (xy 65.158112 -422.74236) (xy 65.170184 -422.742854) (xy 65.193146 -422.750316)
			(xy 65.21268 -422.764506) (xy 65.226875 -422.784036) (xy 65.234343 -422.806996) (xy 65.23482 -422.819068)
			(xy 65.23482 -424.689778) (xy 68.13804 -424.689778) (xy 68.138155 -424.674693) (xy 68.139933 -424.644574)
			(xy 68.141596 -424.62958) (xy 68.141596 -423.55008) (xy 68.139932 -423.535086) (xy 68.13815 -423.504968)
			(xy 68.13804 -423.489882) (xy 68.138155 -423.474797) (xy 68.139933 -423.444678) (xy 68.141596 -423.429684)
			(xy 68.141596 -422.819068) (xy 68.142037 -422.806991) (xy 68.149509 -422.784022) (xy 68.163711 -422.764485)
			(xy 68.183255 -422.750292) (xy 68.206227 -422.742831) (xy 68.218304 -422.74236) (xy 69.158104 -422.74236)
			(xy 69.170176 -422.74286) (xy 69.193137 -422.75032) (xy 69.212672 -422.764508) (xy 69.226867 -422.784037)
			(xy 69.234335 -422.806997) (xy 69.234812 -422.819068) (xy 69.234812 -423.68978) (xy 70.138036 -423.68978)
			(xy 70.138153 -423.674695) (xy 70.139931 -423.644576) (xy 70.141592 -423.629582) (xy 70.141592 -422.550082)
			(xy 70.139928 -422.535088) (xy 70.138147 -422.50497) (xy 70.138036 -422.489884) (xy 70.138153 -422.474799)
			(xy 70.139931 -422.44468) (xy 70.141592 -422.429686) (xy 70.141592 -421.81907) (xy 70.142081 -421.806984)
			(xy 70.14954 -421.78399) (xy 70.163723 -421.764415) (xy 70.183248 -421.750163) (xy 70.206215 -421.742624)
			(xy 70.2183 -421.742108) (xy 71.1581 -421.742108) (xy 71.17021 -421.742516) (xy 71.193238 -421.750017)
			(xy 71.212812 -421.76428) (xy 71.227007 -421.783904) (xy 71.234426 -421.806959) (xy 71.234808 -421.81907)
			(xy 71.234808 -424.360594) (xy 71.234288 -424.372678) (xy 71.226839 -424.395671) (xy 71.212664 -424.415247)
			(xy 71.193145 -424.429499) (xy 71.170183 -424.43704) (xy 71.1581 -424.437556) (xy 70.2183 -424.437556)
			(xy 70.206197 -424.437085) (xy 70.183179 -424.429592) (xy 70.163611 -424.415343) (xy 70.149414 -424.395736)
			(xy 70.141983 -424.372698) (xy 70.141592 -424.360594) (xy 70.141592 -423.749978) (xy 70.139928 -423.734984)
			(xy 70.138146 -423.704866) (xy 70.138036 -423.68978) (xy 69.234812 -423.68978) (xy 69.234812 -424.689778)
			(xy 72.138032 -424.689778) (xy 72.138149 -424.674693) (xy 72.139927 -424.644574) (xy 72.141588 -424.62958)
			(xy 72.141588 -423.55008) (xy 72.139924 -423.535086) (xy 72.138142 -423.504968) (xy 72.138032 -423.489882)
			(xy 72.138149 -423.474797) (xy 72.139927 -423.444678) (xy 72.141588 -423.429684) (xy 72.141588 -422.819068)
			(xy 72.142037 -422.806992) (xy 72.149508 -422.784025) (xy 72.163708 -422.764488) (xy 72.18325 -422.750295)
			(xy 72.20622 -422.742832) (xy 72.218296 -422.74236) (xy 73.158096 -422.74236) (xy 73.170167 -422.742867)
			(xy 73.193129 -422.750325) (xy 73.212663 -422.764511) (xy 73.226859 -422.784039) (xy 73.234327 -422.806997)
			(xy 73.234804 -422.819068) (xy 73.234804 -424.80464) (xy 109.929157 -424.80464) (xy 109.929157 -424.6755)
			(xy 109.937107 -424.546605) (xy 109.952977 -424.418445) (xy 109.976706 -424.291504) (xy 110.008205 -424.166265)
			(xy 110.047354 -424.043202) (xy 110.094005 -423.922783) (xy 110.14798 -423.805464) (xy 110.209075 -423.69169)
			(xy 110.277058 -423.581893) (xy 110.351672 -423.47649) (xy 110.432633 -423.37588) (xy 110.519633 -423.280445)
			(xy 110.612344 -423.190546) (xy 110.710414 -423.106525) (xy 110.813469 -423.028701) (xy 110.92112 -422.957369)
			(xy 111.032959 -422.892799) (xy 111.14856 -422.835237) (xy 111.267485 -422.7849) (xy 111.389284 -422.74198)
			(xy 111.513494 -422.706639) (xy 111.639643 -422.679012) (xy 111.767255 -422.659203) (xy 111.895844 -422.647287)
			(xy 112.024922 -422.643311) (xy 112.154 -422.647287) (xy 112.282589 -422.659203) (xy 112.410201 -422.679012)
			(xy 112.53635 -422.706639) (xy 112.66056 -422.74198) (xy 112.782359 -422.7849) (xy 112.901284 -422.835237)
			(xy 113.016885 -422.892799) (xy 113.128724 -422.957369) (xy 113.236375 -423.028701) (xy 113.33943 -423.106525)
			(xy 113.4375 -423.190546) (xy 113.530211 -423.280445) (xy 113.617211 -423.37588) (xy 113.698172 -423.47649)
			(xy 113.772786 -423.581893) (xy 113.840769 -423.69169) (xy 113.901864 -423.805464) (xy 113.955839 -423.922783)
			(xy 114.00249 -424.043202) (xy 114.041639 -424.166265) (xy 114.073138 -424.291504) (xy 114.096867 -424.418445)
			(xy 114.112737 -424.546605) (xy 114.120687 -424.6755) (xy 114.121184 -424.74007) (xy 114.120687 -424.80464)
			(xy 114.112737 -424.933535) (xy 114.096867 -425.061695) (xy 114.073138 -425.188636) (xy 114.041639 -425.313875)
			(xy 114.00249 -425.436938) (xy 113.955839 -425.557357) (xy 113.901864 -425.674676) (xy 113.840769 -425.78845)
			(xy 113.772786 -425.898247) (xy 113.698172 -426.00365) (xy 113.617211 -426.10426) (xy 113.530211 -426.199695)
			(xy 113.4375 -426.289594) (xy 113.33943 -426.373615) (xy 113.236375 -426.451439) (xy 113.128724 -426.522771)
			(xy 113.016885 -426.587341) (xy 112.901284 -426.644903) (xy 112.782359 -426.69524) (xy 112.66056 -426.73816)
			(xy 112.53635 -426.773501) (xy 112.410201 -426.801128) (xy 112.282589 -426.820937) (xy 112.154 -426.832853)
			(xy 112.024922 -426.83683) (xy 111.895844 -426.832853) (xy 111.767255 -426.820937) (xy 111.639643 -426.801128)
			(xy 111.513494 -426.773501) (xy 111.389284 -426.73816) (xy 111.267485 -426.69524) (xy 111.14856 -426.644903)
			(xy 111.032959 -426.587341) (xy 110.92112 -426.522771) (xy 110.813469 -426.451439) (xy 110.710414 -426.373615)
			(xy 110.612344 -426.289594) (xy 110.519633 -426.199695) (xy 110.432633 -426.10426) (xy 110.351672 -426.00365)
			(xy 110.277058 -425.898247) (xy 110.209075 -425.78845) (xy 110.14798 -425.674676) (xy 110.094005 -425.557357)
			(xy 110.047354 -425.436938) (xy 110.008205 -425.313875) (xy 109.976706 -425.188636) (xy 109.952977 -425.061695)
			(xy 109.937107 -424.933535) (xy 109.929157 -424.80464) (xy 73.234804 -424.80464) (xy 73.234804 -425.360592)
			(xy 73.234381 -425.372675) (xy 73.226915 -425.395658) (xy 73.212712 -425.415209) (xy 73.193162 -425.429413)
			(xy 73.170179 -425.43688) (xy 73.158096 -425.4373) (xy 72.218296 -425.4373) (xy 72.206212 -425.436891)
			(xy 72.183228 -425.429421) (xy 72.163677 -425.415214) (xy 72.149473 -425.395661) (xy 72.142007 -425.372676)
			(xy 72.141588 -425.360592) (xy 72.141588 -424.749976) (xy 72.139924 -424.734982) (xy 72.138142 -424.704864)
			(xy 72.138032 -424.689778) (xy 69.234812 -424.689778) (xy 69.234812 -425.360592) (xy 69.234381 -425.372674)
			(xy 69.226916 -425.395656) (xy 69.212714 -425.415206) (xy 69.193167 -425.429411) (xy 69.170186 -425.436879)
			(xy 69.158104 -425.4373) (xy 68.218304 -425.4373) (xy 68.206221 -425.436884) (xy 68.183237 -425.429417)
			(xy 68.163686 -425.415212) (xy 68.149482 -425.39566) (xy 68.142015 -425.372675) (xy 68.141596 -425.360592)
			(xy 68.141596 -424.749976) (xy 68.139932 -424.734982) (xy 68.13815 -424.704864) (xy 68.13804 -424.689778)
			(xy 65.23482 -424.689778) (xy 65.23482 -425.360592) (xy 65.234329 -425.372665) (xy 65.22687 -425.39563)
			(xy 65.21268 -425.415166) (xy 65.193148 -425.429361) (xy 65.170185 -425.436826) (xy 65.158112 -425.4373)
			(xy 64.218312 -425.4373) (xy 64.206229 -425.436877) (xy 64.183246 -425.429412) (xy 64.163694 -425.415208)
			(xy 64.14949 -425.395658) (xy 64.142024 -425.372675) (xy 64.141604 -425.360592) (xy 64.141604 -424.749976)
			(xy 64.13994 -424.734982) (xy 64.138158 -424.704864) (xy 64.138048 -424.689778) (xy 50.54061 -424.689778)
			(xy 50.536903 -424.786486) (xy 50.520747 -424.996915) (xy 50.496544 -425.206572) (xy 50.464327 -425.415147)
			(xy 50.424145 -425.622335) (xy 50.376057 -425.827832) (xy 50.320133 -426.031336) (xy 50.256456 -426.232549)
			(xy 50.185118 -426.431176) (xy 50.106224 -426.626924) (xy 50.019891 -426.819506) (xy 49.926244 -427.008641)
			(xy 49.825422 -427.19405) (xy 49.768393 -427.289976) (xy 58.13806 -427.289976) (xy 58.138174 -427.274891)
			(xy 58.139952 -427.244772) (xy 58.141616 -427.229778) (xy 58.141616 -426.150024) (xy 58.139947 -426.135031)
			(xy 58.138169 -426.104912) (xy 58.13806 -426.089826) (xy 58.13817 -426.07474) (xy 58.139951 -426.044622)
			(xy 58.141616 -426.029628) (xy 58.141616 -425.419012) (xy 58.142023 -425.406928) (xy 58.149491 -425.383941)
			(xy 58.163697 -425.364389) (xy 58.183252 -425.350185) (xy 58.206239 -425.342722) (xy 58.218324 -425.342304)
			(xy 59.158124 -425.342304) (xy 59.170201 -425.342744) (xy 59.193171 -425.350215) (xy 59.212709 -425.364417)
			(xy 59.226902 -425.383961) (xy 59.234361 -425.406935) (xy 59.234832 -425.419012) (xy 59.234832 -427.960536)
			(xy 59.234367 -427.97261) (xy 59.226898 -427.995574) (xy 59.2127 -428.015109) (xy 59.193164 -428.029303)
			(xy 59.170198 -428.036769) (xy 59.158124 -428.037244) (xy 58.218324 -428.037244) (xy 58.206254 -428.036716)
			(xy 58.183294 -428.029264) (xy 58.16376 -428.015083) (xy 58.149563 -427.99556) (xy 58.142093 -427.972605)
			(xy 58.141616 -427.960536) (xy 58.141616 -427.350174) (xy 58.139952 -427.33518) (xy 58.13817 -427.305062)
			(xy 58.13806 -427.289976) (xy 49.768393 -427.289976) (xy 49.717572 -427.375461) (xy 49.602853 -427.552608)
			(xy 49.481433 -427.72523) (xy 49.35349 -427.893076) (xy 49.219212 -428.055898) (xy 49.078796 -428.213457)
			(xy 49.0054 -428.28972) (xy 60.138056 -428.28972) (xy 60.138166 -428.274634) (xy 60.139947 -428.244516)
			(xy 60.141612 -428.229522) (xy 60.141612 -427.150022) (xy 60.139943 -427.135029) (xy 60.138165 -427.10491)
			(xy 60.138056 -427.089824) (xy 60.138166 -427.074738) (xy 60.139947 -427.04462) (xy 60.141612 -427.029626)
			(xy 60.141612 -426.41901) (xy 60.142115 -426.406924) (xy 60.149566 -426.383928) (xy 60.163744 -426.364351)
			(xy 60.183268 -426.350099) (xy 60.206236 -426.342562) (xy 60.21832 -426.342048) (xy 61.15812 -426.342048)
			(xy 61.170225 -426.342499) (xy 61.193244 -426.349997) (xy 61.212812 -426.364252) (xy 61.227008 -426.383863)
			(xy 61.234437 -426.406904) (xy 61.234828 -426.41901) (xy 61.234828 -427.289976) (xy 62.138052 -427.289976)
			(xy 62.138166 -427.274891) (xy 62.139944 -427.244772) (xy 62.141608 -427.229778) (xy 62.141608 -426.150024)
			(xy 62.139939 -426.135031) (xy 62.138161 -426.104912) (xy 62.138052 -426.089826) (xy 62.138162 -426.07474)
			(xy 62.139943 -426.044622) (xy 62.141608 -426.029628) (xy 62.141608 -425.419012) (xy 62.142023 -425.406928)
			(xy 62.149489 -425.383943) (xy 62.163694 -425.364392) (xy 62.183247 -425.350188) (xy 62.206232 -425.342723)
			(xy 62.218316 -425.342304) (xy 63.158116 -425.342304) (xy 63.170193 -425.342751) (xy 63.193162 -425.350219)
			(xy 63.2127 -425.36442) (xy 63.226894 -425.383963) (xy 63.234353 -425.406935) (xy 63.234824 -425.419012)
			(xy 63.234824 -427.960536) (xy 63.234367 -427.972611) (xy 63.226896 -427.995577) (xy 63.212697 -428.015112)
			(xy 63.193159 -428.029306) (xy 63.170191 -428.03677) (xy 63.158116 -428.037244) (xy 62.218316 -428.037244)
			(xy 62.206246 -428.036723) (xy 62.183285 -428.029269) (xy 62.163751 -428.015086) (xy 62.149555 -427.995561)
			(xy 62.142085 -427.972606) (xy 62.141608 -427.960536) (xy 62.141608 -427.350174) (xy 62.139944 -427.33518)
			(xy 62.138162 -427.305062) (xy 62.138052 -427.289976) (xy 61.234828 -427.289976) (xy 61.234828 -428.28972)
			(xy 64.138048 -428.28972) (xy 64.138158 -428.274634) (xy 64.139939 -428.244516) (xy 64.141604 -428.229522)
			(xy 64.141604 -427.150022) (xy 64.139935 -427.135029) (xy 64.138157 -427.10491) (xy 64.138048 -427.089824)
			(xy 64.138158 -427.074738) (xy 64.139939 -427.04462) (xy 64.141604 -427.029626) (xy 64.141604 -426.41901)
			(xy 64.142115 -426.406925) (xy 64.149565 -426.38393) (xy 64.163741 -426.364353) (xy 64.183263 -426.350101)
			(xy 64.206228 -426.342563) (xy 64.218312 -426.342048) (xy 65.158112 -426.342048) (xy 65.170216 -426.342505)
			(xy 65.193235 -426.350002) (xy 65.212804 -426.364255) (xy 65.227 -426.383864) (xy 65.234429 -426.406905)
			(xy 65.23482 -426.41901) (xy 65.23482 -427.289976) (xy 66.138044 -427.289976) (xy 66.138159 -427.274891)
			(xy 66.139936 -427.244772) (xy 66.1416 -427.229778) (xy 66.1416 -426.150024) (xy 66.139931 -426.135031)
			(xy 66.138153 -426.104912) (xy 66.138044 -426.089826) (xy 66.138154 -426.07474) (xy 66.139935 -426.044622)
			(xy 66.1416 -426.029628) (xy 66.1416 -425.419012) (xy 66.142023 -425.406929) (xy 66.149488 -425.383946)
			(xy 66.163692 -425.364394) (xy 66.183242 -425.35019) (xy 66.206225 -425.342724) (xy 66.218308 -425.342304)
			(xy 67.158108 -425.342304) (xy 67.170192 -425.342706) (xy 67.193177 -425.350177) (xy 67.212729 -425.364386)
			(xy 67.226932 -425.383941) (xy 67.234397 -425.406928) (xy 67.234816 -425.419012) (xy 67.234816 -427.960536)
			(xy 67.234367 -427.972612) (xy 67.226895 -427.995579) (xy 67.212695 -428.015115) (xy 67.193154 -428.029308)
			(xy 67.170184 -428.036771) (xy 67.158108 -428.037244) (xy 66.218308 -428.037244) (xy 66.206237 -428.03673)
			(xy 66.183277 -428.029274) (xy 66.163743 -428.015089) (xy 66.149547 -427.995563) (xy 66.142077 -427.972606)
			(xy 66.1416 -427.960536) (xy 66.1416 -427.350174) (xy 66.139936 -427.33518) (xy 66.138154 -427.305062)
			(xy 66.138044 -427.289976) (xy 65.23482 -427.289976) (xy 65.23482 -428.28972) (xy 68.13804 -428.28972)
			(xy 68.138152 -428.274634) (xy 68.139933 -428.244516) (xy 68.141596 -428.229522) (xy 68.141596 -427.150022)
			(xy 68.139927 -427.135029) (xy 68.138149 -427.10491) (xy 68.13804 -427.089824) (xy 68.13815 -427.074738)
			(xy 68.139931 -427.04462) (xy 68.141596 -427.029626) (xy 68.141596 -426.41901) (xy 68.142115 -426.406925)
			(xy 68.149564 -426.383932) (xy 68.163739 -426.364356) (xy 68.183258 -426.350104) (xy 68.206221 -426.342564)
			(xy 68.218304 -426.342048) (xy 69.158104 -426.342048) (xy 69.170208 -426.342512) (xy 69.193227 -426.350006)
			(xy 69.212795 -426.364257) (xy 69.226991 -426.383866) (xy 69.234421 -426.406905) (xy 69.234812 -426.41901)
			(xy 69.234812 -427.289976) (xy 70.138036 -427.289976) (xy 70.138153 -427.274891) (xy 70.13993 -427.244772)
			(xy 70.141592 -427.229778) (xy 70.141592 -426.150024) (xy 70.139923 -426.135031) (xy 70.138145 -426.104912)
			(xy 70.138036 -426.089826) (xy 70.138148 -426.07474) (xy 70.139929 -426.044622) (xy 70.141592 -426.029628)
			(xy 70.141592 -425.419012) (xy 70.142023 -425.40693) (xy 70.149487 -425.383948) (xy 70.163689 -425.364397)
			(xy 70.183237 -425.350193) (xy 70.206218 -425.342725) (xy 70.2183 -425.342304) (xy 71.1581 -425.342304)
			(xy 71.170184 -425.342713) (xy 71.193169 -425.350182) (xy 71.21272 -425.364388) (xy 71.226924 -425.383942)
			(xy 71.234389 -425.406928) (xy 71.234808 -425.419012) (xy 71.234808 -427.960536) (xy 71.234367 -427.972612)
			(xy 71.226894 -427.995581) (xy 71.212692 -428.015117) (xy 71.193149 -428.029311) (xy 71.170177 -428.036772)
			(xy 71.1581 -428.037244) (xy 70.2183 -428.037244) (xy 70.206229 -428.036736) (xy 70.183268 -428.029278)
			(xy 70.163734 -428.015092) (xy 70.149538 -427.995564) (xy 70.142069 -427.972607) (xy 70.141592 -427.960536)
			(xy 70.141592 -427.350174) (xy 70.139928 -427.33518) (xy 70.138146 -427.305062) (xy 70.138036 -427.289976)
			(xy 69.234812 -427.289976) (xy 69.234812 -428.28972) (xy 72.138032 -428.28972) (xy 72.138144 -428.274634)
			(xy 72.139925 -428.244516) (xy 72.141588 -428.229522) (xy 72.141588 -427.150022) (xy 72.139919 -427.135029)
			(xy 72.138141 -427.10491) (xy 72.138032 -427.089824) (xy 72.138144 -427.074738) (xy 72.139925 -427.04462)
			(xy 72.141588 -427.029626) (xy 72.141588 -426.41901) (xy 72.142017 -426.406916) (xy 72.149477 -426.383908)
			(xy 72.163671 -426.364324) (xy 72.183216 -426.350075) (xy 72.206204 -426.342551) (xy 72.218296 -426.342048)
			(xy 73.158096 -426.342048) (xy 73.170199 -426.342519) (xy 73.193218 -426.350011) (xy 73.212787 -426.36426)
			(xy 73.226983 -426.383867) (xy 73.234413 -426.406905) (xy 73.234804 -426.41901) (xy 73.234804 -427.289976)
			(xy 75.138026 -427.289976) (xy 75.138117 -427.275402) (xy 75.139771 -427.246301) (xy 75.141328 -427.23181)
			(xy 75.141328 -426.147992) (xy 75.139785 -426.1335) (xy 75.138132 -426.1044) (xy 75.138026 -426.089826)
			(xy 75.138121 -426.075252) (xy 75.139773 -426.046151) (xy 75.141328 -426.03166) (xy 75.141328 -425.419012)
			(xy 75.141727 -425.406901) (xy 75.149227 -425.383869) (xy 75.163492 -425.364294) (xy 75.183119 -425.3501)
			(xy 75.206178 -425.342684) (xy 75.21829 -425.342304) (xy 76.15809 -425.342304) (xy 76.170175 -425.342815)
			(xy 76.19317 -425.350265) (xy 76.212747 -425.364441) (xy 76.226999 -425.383963) (xy 76.234537 -425.406928)
			(xy 76.235052 -425.419012) (xy 76.235052 -427.960536) (xy 76.234615 -427.972642) (xy 76.227112 -427.995661)
			(xy 76.212854 -428.015229) (xy 76.19324 -428.029424) (xy 76.170197 -428.036854) (xy 76.15809 -428.037244)
			(xy 75.21829 -428.037244) (xy 75.206198 -428.036801) (xy 75.183195 -428.029339) (xy 75.163614 -428.015147)
			(xy 75.149364 -427.995608) (xy 75.141835 -427.972626) (xy 75.141328 -427.960536) (xy 75.141328 -427.348142)
			(xy 75.139781 -427.33365) (xy 75.138131 -427.30455) (xy 75.138026 -427.289976) (xy 73.234804 -427.289976)
			(xy 73.234804 -428.28972) (xy 77.138022 -428.28972) (xy 77.138117 -428.275146) (xy 77.139768 -428.246045)
			(xy 77.141324 -428.231554) (xy 77.141324 -427.14799) (xy 77.139781 -427.133498) (xy 77.138128 -427.104398)
			(xy 77.138022 -427.089824) (xy 77.138117 -427.07525) (xy 77.139769 -427.046149) (xy 77.141324 -427.031658)
			(xy 77.141324 -426.41901) (xy 77.14182 -426.406897) (xy 77.149303 -426.383857) (xy 77.163539 -426.364256)
			(xy 77.183135 -426.350014) (xy 77.206174 -426.342524) (xy 77.218286 -426.342048) (xy 78.158086 -426.342048)
			(xy 78.170209 -426.342472) (xy 78.193269 -426.349962) (xy 78.212885 -426.364212) (xy 78.227136 -426.383827)
			(xy 78.234627 -426.406887) (xy 78.235048 -426.41901) (xy 78.235048 -427.289976) (xy 79.138018 -427.289976)
			(xy 79.138109 -427.275402) (xy 79.139763 -427.246301) (xy 79.14132 -427.23181) (xy 79.14132 -426.147992)
			(xy 79.139777 -426.1335) (xy 79.138124 -426.1044) (xy 79.138018 -426.089826) (xy 79.138113 -426.075252)
			(xy 79.139765 -426.046151) (xy 79.14132 -426.03166) (xy 79.14132 -425.419012) (xy 79.141727 -425.406902)
			(xy 79.149226 -425.383872) (xy 79.163489 -425.364297) (xy 79.183114 -425.350102) (xy 79.20617 -425.342685)
			(xy 79.218282 -425.342304) (xy 80.158082 -425.342304) (xy 80.170167 -425.342822) (xy 80.193161 -425.35027)
			(xy 80.212738 -425.364444) (xy 80.226991 -425.383965) (xy 80.234529 -425.406929) (xy 80.235044 -425.419012)
			(xy 80.235044 -427.960536) (xy 80.234615 -427.972642) (xy 80.227111 -427.995663) (xy 80.212851 -428.015232)
			(xy 80.193235 -428.029427) (xy 80.17019 -428.036855) (xy 80.158082 -428.037244) (xy 79.218282 -428.037244)
			(xy 79.20619 -428.036808) (xy 79.183186 -428.029344) (xy 79.163605 -428.01515) (xy 79.149355 -427.995609)
			(xy 79.141827 -427.972627) (xy 79.14132 -427.960536) (xy 79.14132 -427.348142) (xy 79.139773 -427.33365)
			(xy 79.138123 -427.30455) (xy 79.138018 -427.289976) (xy 78.235048 -427.289976) (xy 78.235048 -428.28972)
			(xy 81.138014 -428.28972) (xy 81.138108 -428.275146) (xy 81.13976 -428.246045) (xy 81.141316 -428.231554)
			(xy 81.141316 -427.14799) (xy 81.139773 -427.133498) (xy 81.13812 -427.104398) (xy 81.138014 -427.089824)
			(xy 81.138108 -427.07525) (xy 81.13976 -427.046149) (xy 81.141316 -427.031658) (xy 81.141316 -426.41901)
			(xy 81.14182 -426.406898) (xy 81.149302 -426.383859) (xy 81.163536 -426.364259) (xy 81.18313 -426.350016)
			(xy 81.206166 -426.342525) (xy 81.218278 -426.342048) (xy 82.158078 -426.342048) (xy 82.170201 -426.342479)
			(xy 82.19326 -426.349966) (xy 82.212877 -426.364215) (xy 82.227128 -426.383829) (xy 82.234619 -426.406887)
			(xy 82.23504 -426.41901) (xy 82.23504 -427.289976) (xy 83.13801 -427.289976) (xy 83.1381 -427.275402)
			(xy 83.139755 -427.246301) (xy 83.141312 -427.23181) (xy 83.141312 -426.147992) (xy 83.139769 -426.1335)
			(xy 83.138116 -426.1044) (xy 83.13801 -426.089826) (xy 83.138105 -426.075252) (xy 83.139756 -426.046151)
			(xy 83.141312 -426.03166) (xy 83.141312 -425.419012) (xy 83.141727 -425.406903) (xy 83.149224 -425.383874)
			(xy 83.163486 -425.364299) (xy 83.183109 -425.350105) (xy 83.206163 -425.342686) (xy 83.218274 -425.342304)
			(xy 84.158074 -425.342304) (xy 84.170159 -425.342829) (xy 84.193152 -425.350274) (xy 84.21273 -425.364447)
			(xy 84.226982 -425.383966) (xy 84.234521 -425.406929) (xy 84.235036 -425.419012) (xy 84.235036 -427.960536)
			(xy 84.234615 -427.972643) (xy 84.22711 -427.995665) (xy 84.212848 -428.015235) (xy 84.19323 -428.029429)
			(xy 84.170183 -428.036856) (xy 84.158074 -428.037244) (xy 83.218274 -428.037244) (xy 83.206181 -428.036815)
			(xy 83.183177 -428.029349) (xy 83.163596 -428.015153) (xy 83.149347 -427.995611) (xy 83.141819 -427.972627)
			(xy 83.141312 -427.960536) (xy 83.141312 -427.348142) (xy 83.139765 -427.33365) (xy 83.138115 -427.30455)
			(xy 83.13801 -427.289976) (xy 82.23504 -427.289976) (xy 82.23504 -428.28972) (xy 85.138006 -428.28972)
			(xy 85.1381 -428.275146) (xy 85.139752 -428.246045) (xy 85.141308 -428.231554) (xy 85.141308 -427.14799)
			(xy 85.139765 -427.133498) (xy 85.138112 -427.104398) (xy 85.138006 -427.089824) (xy 85.1381 -427.07525)
			(xy 85.139752 -427.046149) (xy 85.141308 -427.031658) (xy 85.141308 -426.41901) (xy 85.14182 -426.406899)
			(xy 85.149301 -426.383861) (xy 85.163533 -426.364262) (xy 85.183125 -426.350019) (xy 85.206159 -426.342526)
			(xy 85.21827 -426.342048) (xy 86.15807 -426.342048) (xy 86.170192 -426.342486) (xy 86.193252 -426.349971)
			(xy 86.212868 -426.364218) (xy 86.22712 -426.38383) (xy 86.234611 -426.406888) (xy 86.235032 -426.41901)
			(xy 86.235032 -427.289976) (xy 87.138002 -427.289976) (xy 87.138092 -427.275402) (xy 87.139747 -427.246301)
			(xy 87.141304 -427.23181) (xy 87.141304 -426.147992) (xy 87.139761 -426.1335) (xy 87.138108 -426.1044)
			(xy 87.138002 -426.089826) (xy 87.138097 -426.075252) (xy 87.139748 -426.046151) (xy 87.141304 -426.03166)
			(xy 87.141304 -425.419012) (xy 87.141727 -425.406903) (xy 87.149223 -425.383876) (xy 87.163483 -425.364302)
			(xy 87.183104 -425.350107) (xy 87.206156 -425.342687) (xy 87.218266 -425.342304) (xy 88.158066 -425.342304)
			(xy 88.17015 -425.342836) (xy 88.193144 -425.350279) (xy 88.212721 -425.36445) (xy 88.226974 -425.383968)
			(xy 88.234513 -425.40693) (xy 88.235028 -425.419012) (xy 88.235028 -427.960536) (xy 88.234615 -427.972644)
			(xy 88.227109 -427.995668) (xy 88.212845 -428.015238) (xy 88.193225 -428.029432) (xy 88.170175 -428.036857)
			(xy 88.158066 -428.037244) (xy 87.218266 -428.037244) (xy 87.206173 -428.036821) (xy 87.183169 -428.029353)
			(xy 87.163588 -428.015156) (xy 87.149339 -427.995612) (xy 87.141811 -427.972628) (xy 87.141304 -427.960536)
			(xy 87.141304 -427.348142) (xy 87.139757 -427.33365) (xy 87.138107 -427.30455) (xy 87.138002 -427.289976)
			(xy 86.235032 -427.289976) (xy 86.235032 -428.28972) (xy 89.137998 -428.28972) (xy 89.138092 -428.275146)
			(xy 89.139744 -428.246045) (xy 89.1413 -428.231554) (xy 89.1413 -427.14799) (xy 89.139757 -427.133498)
			(xy 89.138104 -427.104398) (xy 89.137998 -427.089824) (xy 89.138092 -427.07525) (xy 89.139744 -427.046149)
			(xy 89.1413 -427.031658) (xy 89.1413 -426.41901) (xy 89.14182 -426.4069) (xy 89.1493 -426.383863)
			(xy 89.163531 -426.364265) (xy 89.18312 -426.350022) (xy 89.206152 -426.342527) (xy 89.218262 -426.342048)
			(xy 90.158062 -426.342048) (xy 90.170184 -426.342492) (xy 90.193243 -426.349975) (xy 90.21286 -426.36422)
			(xy 90.227112 -426.383832) (xy 90.234603 -426.406888) (xy 90.235024 -426.41901) (xy 90.235024 -427.289976)
			(xy 125.238002 -427.289976) (xy 125.238092 -427.275402) (xy 125.239747 -427.246301) (xy 125.241304 -427.23181)
			(xy 125.241304 -426.147992) (xy 125.239761 -426.1335) (xy 125.238108 -426.1044) (xy 125.238002 -426.089826)
			(xy 125.238097 -426.075252) (xy 125.239748 -426.046151) (xy 125.241304 -426.03166) (xy 125.241304 -425.419012)
			(xy 125.241727 -425.406903) (xy 125.249223 -425.383876) (xy 125.263483 -425.364302) (xy 125.283104 -425.350107)
			(xy 125.306156 -425.342687) (xy 125.318266 -425.342304) (xy 126.258066 -425.342304) (xy 126.27015 -425.342836)
			(xy 126.293144 -425.350279) (xy 126.312721 -425.36445) (xy 126.326974 -425.383968) (xy 126.334513 -425.40693)
			(xy 126.335028 -425.419012) (xy 126.335028 -427.960536) (xy 126.334615 -427.972644) (xy 126.327109 -427.995668)
			(xy 126.312845 -428.015238) (xy 126.293225 -428.029432) (xy 126.270175 -428.036857) (xy 126.258066 -428.037244)
			(xy 125.318266 -428.037244) (xy 125.306173 -428.036821) (xy 125.283169 -428.029353) (xy 125.263588 -428.015156)
			(xy 125.249339 -427.995612) (xy 125.241811 -427.972628) (xy 125.241304 -427.960536) (xy 125.241304 -427.348142)
			(xy 125.239757 -427.33365) (xy 125.238107 -427.30455) (xy 125.238002 -427.289976) (xy 90.235024 -427.289976)
			(xy 90.235024 -428.960534) (xy 90.234669 -428.972662) (xy 90.227162 -428.995729) (xy 90.212895 -429.015347)
			(xy 90.193264 -429.029595) (xy 90.170191 -429.03708) (xy 90.158062 -429.037496) (xy 89.218262 -429.037496)
			(xy 89.206149 -429.037021) (xy 89.18311 -429.029528) (xy 89.163512 -429.015285) (xy 89.14927 -428.995686)
			(xy 89.141778 -428.972647) (xy 89.1413 -428.960534) (xy 89.1413 -428.347886) (xy 89.139757 -428.333394)
			(xy 89.138104 -428.304294) (xy 89.137998 -428.28972) (xy 86.235032 -428.28972) (xy 86.235032 -428.960534)
			(xy 86.234617 -428.972653) (xy 86.227117 -428.995703) (xy 86.212861 -429.015307) (xy 86.193245 -429.029546)
			(xy 86.17019 -429.037027) (xy 86.15807 -429.037496) (xy 85.21827 -429.037496) (xy 85.206157 -429.037014)
			(xy 85.183119 -429.029523) (xy 85.16352 -429.015282) (xy 85.149279 -428.995685) (xy 85.141786 -428.972647)
			(xy 85.141308 -428.960534) (xy 85.141308 -428.347886) (xy 85.139765 -428.333394) (xy 85.138112 -428.304294)
			(xy 85.138006 -428.28972) (xy 82.23504 -428.28972) (xy 82.23504 -428.960534) (xy 82.234617 -428.972653)
			(xy 82.227118 -428.995701) (xy 82.212864 -429.015304) (xy 82.19325 -429.029543) (xy 82.170197 -429.037026)
			(xy 82.158078 -429.037496) (xy 81.218278 -429.037496) (xy 81.206166 -429.037008) (xy 81.183127 -429.029519)
			(xy 81.163529 -429.01528) (xy 81.149287 -428.995683) (xy 81.141794 -428.972646) (xy 81.141316 -428.960534)
			(xy 81.141316 -428.347886) (xy 81.139773 -428.333394) (xy 81.13812 -428.304294) (xy 81.138014 -428.28972)
			(xy 78.235048 -428.28972) (xy 78.235048 -428.960534) (xy 78.234617 -428.972652) (xy 78.227119 -428.995698)
			(xy 78.212867 -429.015301) (xy 78.193255 -429.029541) (xy 78.170204 -429.037025) (xy 78.158086 -429.037496)
			(xy 77.218286 -429.037496) (xy 77.206174 -429.037001) (xy 77.183136 -429.029514) (xy 77.163537 -429.015277)
			(xy 77.149295 -428.995682) (xy 77.141802 -428.972646) (xy 77.141324 -428.960534) (xy 77.141324 -428.347886)
			(xy 77.139781 -428.333394) (xy 77.138128 -428.304294) (xy 77.138022 -428.28972) (xy 73.234804 -428.28972)
			(xy 73.234804 -428.960534) (xy 73.234323 -428.972621) (xy 73.226862 -428.995615) (xy 73.212677 -429.015191)
			(xy 73.19315 -429.029442) (xy 73.170181 -429.036981) (xy 73.158096 -429.037496) (xy 72.218296 -429.037496)
			(xy 72.206187 -429.037087) (xy 72.183158 -429.029586) (xy 72.163585 -429.015323) (xy 72.149391 -428.995699)
			(xy 72.141971 -428.972645) (xy 72.141588 -428.960534) (xy 72.141588 -428.349918) (xy 72.139919 -428.334925)
			(xy 72.138141 -428.304806) (xy 72.138032 -428.28972) (xy 69.234812 -428.28972) (xy 69.234812 -428.960534)
			(xy 69.234421 -428.97263) (xy 69.226949 -428.99564) (xy 69.212744 -429.015223) (xy 69.193192 -429.029471)
			(xy 69.170199 -429.036994) (xy 69.158104 -429.037496) (xy 68.218304 -429.037496) (xy 68.206195 -429.03708)
			(xy 68.183167 -429.029582) (xy 68.163593 -429.01532) (xy 68.149399 -428.995698) (xy 68.141979 -428.972644)
			(xy 68.141596 -428.960534) (xy 68.141596 -428.349918) (xy 68.139927 -428.334925) (xy 68.138149 -428.304806)
			(xy 68.13804 -428.28972) (xy 65.23482 -428.28972) (xy 65.23482 -428.960534) (xy 65.234421 -428.972629)
			(xy 65.22695 -428.995638) (xy 65.212747 -429.015221) (xy 65.193197 -429.029469) (xy 65.170206 -429.036993)
			(xy 65.158112 -429.037496) (xy 64.218312 -429.037496) (xy 64.206203 -429.037073) (xy 64.183176 -429.029577)
			(xy 64.163602 -429.015317) (xy 64.149407 -428.995696) (xy 64.141987 -428.972644) (xy 64.141604 -428.960534)
			(xy 64.141604 -428.349918) (xy 64.139935 -428.334925) (xy 64.138157 -428.304806) (xy 64.138048 -428.28972)
			(xy 61.234828 -428.28972) (xy 61.234828 -428.960534) (xy 61.234421 -428.972629) (xy 61.226951 -428.995636)
			(xy 61.21275 -429.015218) (xy 61.193202 -429.029466) (xy 61.170213 -429.036992) (xy 61.15812 -429.037496)
			(xy 60.21832 -429.037496) (xy 60.206212 -429.037066) (xy 60.183185 -429.029572) (xy 60.163611 -429.015314)
			(xy 60.149416 -428.995695) (xy 60.141995 -428.972643) (xy 60.141612 -428.960534) (xy 60.141612 -428.349918)
			(xy 60.139943 -428.334925) (xy 60.138165 -428.304806) (xy 60.138056 -428.28972) (xy 49.0054 -428.28972)
			(xy 48.932448 -428.365522) (xy 48.780383 -428.51187) (xy 48.622824 -428.652286) (xy 48.460002 -428.786564)
			(xy 48.292156 -428.914507) (xy 48.119534 -429.035927) (xy 47.942387 -429.150646) (xy 47.760976 -429.258496)
			(xy 47.575567 -429.359318) (xy 47.386432 -429.452965) (xy 47.19385 -429.539298) (xy 46.998102 -429.618192)
			(xy 46.799475 -429.68953) (xy 46.598262 -429.753207) (xy 46.394758 -429.809131) (xy 46.189261 -429.857219)
			(xy 45.982073 -429.897401) (xy 45.773498 -429.929618) (xy 45.563841 -429.953821) (xy 45.353412 -429.969977)
			(xy 45.142518 -429.978061) (xy 44.93147 -429.978061) (xy 44.720576 -429.969977) (xy 44.510147 -429.953821)
			(xy 44.30049 -429.929618) (xy 44.091915 -429.897401) (xy 43.884727 -429.857219) (xy 43.67923 -429.809131)
			(xy 43.475726 -429.753207) (xy 43.274513 -429.68953) (xy 43.075886 -429.618192) (xy 42.880138 -429.539298)
			(xy 42.687556 -429.452965) (xy 42.498421 -429.359318) (xy 42.313012 -429.258496) (xy 42.131601 -429.150646)
			(xy 41.954454 -429.035927) (xy 41.781832 -428.914507) (xy 41.613986 -428.786564) (xy 41.451164 -428.652286)
			(xy 41.293605 -428.51187) (xy 41.14154 -428.365522) (xy 40.995192 -428.213457) (xy 40.854776 -428.055898)
			(xy 40.720498 -427.893076) (xy 40.592555 -427.72523) (xy 40.471135 -427.552608) (xy 40.356416 -427.375461)
			(xy 40.248566 -427.19405) (xy 40.147744 -427.008641) (xy 40.054097 -426.819506) (xy 39.967764 -426.626924)
			(xy 39.88887 -426.431176) (xy 39.817532 -426.232549) (xy 39.753855 -426.031336) (xy 39.697931 -425.827832)
			(xy 39.649843 -425.622335) (xy 39.609661 -425.415147) (xy 39.577444 -425.206572) (xy 39.553241 -424.996915)
			(xy 39.537085 -424.786486) (xy 39.529001 -424.575592) (xy 39.528496 -424.470068) (xy 7.00913 -424.470068)
			(xy 7.00913 -430.889918) (xy 58.13806 -430.889918) (xy 58.138169 -430.874832) (xy 58.139951 -430.844714)
			(xy 58.141616 -430.82972) (xy 58.141616 -429.749966) (xy 58.139951 -429.734972) (xy 58.13817 -429.704854)
			(xy 58.13806 -429.689768) (xy 58.138174 -429.674682) (xy 58.139952 -429.644564) (xy 58.141616 -429.62957)
			(xy 58.141616 -429.018954) (xy 58.142068 -429.006864) (xy 58.149534 -428.983866) (xy 58.163726 -428.964289)
			(xy 58.18326 -428.950039) (xy 58.206236 -428.942504) (xy 58.218324 -428.941992) (xy 59.158124 -428.941992)
			(xy 59.170233 -428.942396) (xy 59.19326 -428.949901) (xy 59.212832 -428.964166) (xy 59.227026 -428.983789)
			(xy 59.234448 -429.006843) (xy 59.234832 -429.018954) (xy 59.234832 -431.560478) (xy 59.234373 -431.572569)
			(xy 59.226919 -431.595574) (xy 59.212732 -431.615156) (xy 59.193194 -431.629407) (xy 59.170214 -431.636934)
			(xy 59.158124 -431.63744) (xy 58.218324 -431.63744) (xy 58.20622 -431.636964) (xy 58.183201 -431.629476)
			(xy 58.163631 -431.615228) (xy 58.149434 -431.595622) (xy 58.142005 -431.572583) (xy 58.141616 -431.560478)
			(xy 58.141616 -430.950116) (xy 58.139947 -430.935123) (xy 58.138169 -430.905004) (xy 58.13806 -430.889918)
			(xy 7.00913 -430.889918) (xy 7.00913 -431.889916) (xy 60.138056 -431.889916) (xy 60.138165 -431.87483)
			(xy 60.139947 -431.844712) (xy 60.141612 -431.829718) (xy 60.141612 -430.749964) (xy 60.139947 -430.73497)
			(xy 60.138166 -430.704852) (xy 60.138056 -430.689766) (xy 60.13817 -430.67468) (xy 60.139948 -430.644562)
			(xy 60.141612 -430.629568) (xy 60.141612 -430.018952) (xy 60.142024 -430.006873) (xy 60.149502 -429.983901)
			(xy 60.163711 -429.964363) (xy 60.183262 -429.950171) (xy 60.206241 -429.942713) (xy 60.21832 -429.942244)
			(xy 61.15812 -429.942244) (xy 61.170191 -429.942747) (xy 61.19315 -429.950209) (xy 61.212683 -429.964397)
			(xy 61.226878 -429.983924) (xy 61.234349 -430.006881) (xy 61.234828 -430.018952) (xy 61.234828 -430.889918)
			(xy 62.138052 -430.889918) (xy 62.138161 -430.874832) (xy 62.139943 -430.844714) (xy 62.141608 -430.82972)
			(xy 62.141608 -429.749966) (xy 62.139943 -429.734972) (xy 62.138162 -429.704854) (xy 62.138052 -429.689768)
			(xy 62.138166 -429.674682) (xy 62.139944 -429.644564) (xy 62.141608 -429.62957) (xy 62.141608 -429.018954)
			(xy 62.142068 -429.006865) (xy 62.149533 -428.983868) (xy 62.163723 -428.964292) (xy 62.183255 -428.950042)
			(xy 62.206229 -428.942505) (xy 62.218316 -428.941992) (xy 63.158116 -428.941992) (xy 63.170225 -428.942402)
			(xy 63.193251 -428.949905) (xy 63.212824 -428.964169) (xy 63.227018 -428.983791) (xy 63.23444 -429.006844)
			(xy 63.234824 -429.018954) (xy 63.234824 -431.560478) (xy 63.234373 -431.57257) (xy 63.226918 -431.595576)
			(xy 63.212729 -431.615159) (xy 63.193189 -431.629409) (xy 63.170206 -431.636935) (xy 63.158116 -431.63744)
			(xy 62.218316 -431.63744) (xy 62.206212 -431.63697) (xy 62.183192 -431.62948) (xy 62.163622 -431.615231)
			(xy 62.149426 -431.595623) (xy 62.141997 -431.572583) (xy 62.141608 -431.560478) (xy 62.141608 -430.950116)
			(xy 62.139939 -430.935123) (xy 62.138161 -430.905004) (xy 62.138052 -430.889918) (xy 61.234828 -430.889918)
			(xy 61.234828 -431.889916) (xy 64.138048 -431.889916) (xy 64.138157 -431.87483) (xy 64.139939 -431.844712)
			(xy 64.141604 -431.829718) (xy 64.141604 -430.749964) (xy 64.139939 -430.73497) (xy 64.138158 -430.704852)
			(xy 64.138048 -430.689766) (xy 64.138162 -430.67468) (xy 64.13994 -430.644562) (xy 64.141604 -430.629568)
			(xy 64.141604 -430.018952) (xy 64.142023 -430.006874) (xy 64.149501 -429.983903) (xy 64.163708 -429.964366)
			(xy 64.183257 -429.950173) (xy 64.206233 -429.942714) (xy 64.218312 -429.942244) (xy 65.158112 -429.942244)
			(xy 65.170182 -429.942753) (xy 65.193142 -429.950213) (xy 65.212674 -429.9644) (xy 65.22687 -429.983926)
			(xy 65.234341 -430.006882) (xy 65.23482 -430.018952) (xy 65.23482 -430.889918) (xy 66.138044 -430.889918)
			(xy 66.138153 -430.874832) (xy 66.139935 -430.844714) (xy 66.1416 -430.82972) (xy 66.1416 -429.749966)
			(xy 66.139935 -429.734972) (xy 66.138154 -429.704854) (xy 66.138044 -429.689768) (xy 66.138158 -429.674682)
			(xy 66.139936 -429.644564) (xy 66.1416 -429.62957) (xy 66.1416 -429.018954) (xy 66.142067 -429.006866)
			(xy 66.149532 -428.983871) (xy 66.16372 -428.964295) (xy 66.18325 -428.950044) (xy 66.206222 -428.942507)
			(xy 66.218308 -428.941992) (xy 67.158108 -428.941992) (xy 67.170217 -428.942409) (xy 67.193243 -428.94991)
			(xy 67.212815 -428.964172) (xy 67.22701 -428.983792) (xy 67.234432 -429.006844) (xy 67.234816 -429.018954)
			(xy 67.234816 -431.560478) (xy 67.234373 -431.572571) (xy 67.226917 -431.595578) (xy 67.212726 -431.615162)
			(xy 67.193184 -431.629412) (xy 67.170199 -431.636937) (xy 67.158108 -431.63744) (xy 66.218308 -431.63744)
			(xy 66.206204 -431.636978) (xy 66.183183 -431.629485) (xy 66.163613 -431.615234) (xy 66.149417 -431.595625)
			(xy 66.141989 -431.572584) (xy 66.1416 -431.560478) (xy 66.1416 -430.950116) (xy 66.139931 -430.935123)
			(xy 66.138153 -430.905004) (xy 66.138044 -430.889918) (xy 65.23482 -430.889918) (xy 65.23482 -431.889916)
			(xy 68.13804 -431.889916) (xy 68.138151 -431.87483) (xy 68.139933 -431.844712) (xy 68.141596 -431.829718)
			(xy 68.141596 -430.749964) (xy 68.139931 -430.73497) (xy 68.13815 -430.704852) (xy 68.13804 -430.689766)
			(xy 68.138154 -430.67468) (xy 68.139932 -430.644562) (xy 68.141596 -430.629568) (xy 68.141596 -430.018952)
			(xy 68.142023 -430.006875) (xy 68.149499 -429.983905) (xy 68.163705 -429.964368) (xy 68.183252 -429.950176)
			(xy 68.206226 -429.942715) (xy 68.218304 -429.942244) (xy 69.158104 -429.942244) (xy 69.170174 -429.94276)
			(xy 69.193133 -429.950218) (xy 69.212666 -429.964403) (xy 69.226862 -429.983927) (xy 69.234333 -430.006882)
			(xy 69.234812 -430.018952) (xy 69.234812 -430.889918) (xy 70.138036 -430.889918) (xy 70.138147 -430.874832)
			(xy 70.139929 -430.844714) (xy 70.141592 -430.82972) (xy 70.141592 -429.749966) (xy 70.139927 -429.734972)
			(xy 70.138146 -429.704854) (xy 70.138036 -429.689768) (xy 70.138152 -429.674683) (xy 70.13993 -429.644564)
			(xy 70.141592 -429.62957) (xy 70.141592 -429.018954) (xy 70.142067 -429.006867) (xy 70.149531 -428.983873)
			(xy 70.163717 -428.964298) (xy 70.183245 -428.950047) (xy 70.206214 -428.942508) (xy 70.2183 -428.941992)
			(xy 71.1581 -428.941992) (xy 71.170208 -428.942416) (xy 71.193234 -428.949914) (xy 71.212807 -428.964174)
			(xy 71.227001 -428.983794) (xy 71.234424 -429.006845) (xy 71.234808 -429.018954) (xy 71.234808 -431.560478)
			(xy 71.234275 -431.572562) (xy 71.22683 -431.595553) (xy 71.212659 -431.61513) (xy 71.193142 -431.629383)
			(xy 71.170182 -431.636924) (xy 71.1581 -431.63744) (xy 70.2183 -431.63744) (xy 70.206195 -431.636984)
			(xy 70.183175 -431.62949) (xy 70.163605 -431.615237) (xy 70.149409 -431.595626) (xy 70.141981 -431.572584)
			(xy 70.141592 -431.560478) (xy 70.141592 -430.950116) (xy 70.139923 -430.935123) (xy 70.138145 -430.905004)
			(xy 70.138036 -430.889918) (xy 69.234812 -430.889918) (xy 69.234812 -431.889916) (xy 72.138032 -431.889916)
			(xy 72.138143 -431.87483) (xy 72.139925 -431.844712) (xy 72.141588 -431.829718) (xy 72.141588 -430.749964)
			(xy 72.139923 -430.73497) (xy 72.138142 -430.704852) (xy 72.138032 -430.689766) (xy 72.138148 -430.674681)
			(xy 72.139926 -430.644562) (xy 72.141588 -430.629568) (xy 72.141588 -430.018952) (xy 72.142023 -430.006875)
			(xy 72.149498 -429.983907) (xy 72.163703 -429.964371) (xy 72.183247 -429.950178) (xy 72.206219 -429.942716)
			(xy 72.218296 -429.942244) (xy 73.158096 -429.942244) (xy 73.170166 -429.942767) (xy 73.193124 -429.950222)
			(xy 73.212657 -429.964406) (xy 73.226854 -429.983929) (xy 73.234325 -430.006883) (xy 73.234804 -430.018952)
			(xy 73.234804 -430.889918) (xy 75.138026 -430.889918) (xy 75.13812 -430.875344) (xy 75.139772 -430.846243)
			(xy 75.141328 -430.831752) (xy 75.141328 -429.747934) (xy 75.13978 -429.733442) (xy 75.13813 -429.704342)
			(xy 75.138026 -429.689768) (xy 75.138125 -429.675194) (xy 75.139774 -429.646093) (xy 75.141328 -429.631602)
			(xy 75.141328 -429.018954) (xy 75.141772 -429.006838) (xy 75.149271 -428.983795) (xy 75.163521 -428.964195)
			(xy 75.183127 -428.949955) (xy 75.206174 -428.942467) (xy 75.21829 -428.941992) (xy 76.15809 -428.941992)
			(xy 76.170199 -428.94252) (xy 76.193235 -428.949999) (xy 76.212832 -428.964228) (xy 76.227076 -428.983815)
			(xy 76.234572 -429.006845) (xy 76.235052 -429.018954) (xy 76.235052 -431.560478) (xy 76.234621 -431.572601)
			(xy 76.227134 -431.59566) (xy 76.212885 -431.615277) (xy 76.193271 -431.629528) (xy 76.170213 -431.637019)
			(xy 76.15809 -431.63744) (xy 75.21829 -431.63744) (xy 75.206165 -431.637048) (xy 75.183102 -431.62955)
			(xy 75.163485 -431.615292) (xy 75.149235 -431.59567) (xy 75.141747 -431.572604) (xy 75.141328 -431.560478)
			(xy 75.141328 -430.948084) (xy 75.139785 -430.933592) (xy 75.138132 -430.904492) (xy 75.138026 -430.889918)
			(xy 73.234804 -430.889918) (xy 73.234804 -431.889916) (xy 77.138022 -431.889916) (xy 77.138116 -431.875342)
			(xy 77.139768 -431.846241) (xy 77.141324 -431.83175) (xy 77.141324 -430.747932) (xy 77.139776 -430.73344)
			(xy 77.138126 -430.70434) (xy 77.138022 -430.689766) (xy 77.138121 -430.675192) (xy 77.13977 -430.646091)
			(xy 77.141324 -430.6316) (xy 77.141324 -430.018952) (xy 77.141676 -430.006838) (xy 77.149191 -429.983805)
			(xy 77.163469 -429.964231) (xy 77.183105 -429.950039) (xy 77.20617 -429.942624) (xy 77.218286 -429.942244)
			(xy 78.158086 -429.942244) (xy 78.170175 -429.942719) (xy 78.193176 -429.950173) (xy 78.212757 -429.964357)
			(xy 78.227007 -429.983889) (xy 78.234539 -430.006864) (xy 78.235048 -430.018952) (xy 78.235048 -430.889918)
			(xy 79.138018 -430.889918) (xy 79.138112 -430.875344) (xy 79.139764 -430.846243) (xy 79.14132 -430.831752)
			(xy 79.14132 -429.747934) (xy 79.139772 -429.733442) (xy 79.138122 -429.704342) (xy 79.138018 -429.689768)
			(xy 79.138117 -429.675194) (xy 79.139766 -429.646093) (xy 79.14132 -429.631602) (xy 79.14132 -429.018954)
			(xy 79.141772 -429.006839) (xy 79.14927 -428.983797) (xy 79.163518 -428.964198) (xy 79.183122 -428.949957)
			(xy 79.206167 -428.942468) (xy 79.218282 -428.941992) (xy 80.158082 -428.941992) (xy 80.170191 -428.942526)
			(xy 80.193226 -428.950003) (xy 80.212824 -428.964231) (xy 80.227068 -428.983817) (xy 80.234563 -429.006845)
			(xy 80.235044 -429.018954) (xy 80.235044 -431.560478) (xy 80.234621 -431.572601) (xy 80.227133 -431.595663)
			(xy 80.212882 -431.61528) (xy 80.193266 -431.629531) (xy 80.170205 -431.63702) (xy 80.158082 -431.63744)
			(xy 79.218282 -431.63744) (xy 79.206156 -431.637055) (xy 79.183093 -431.629555) (xy 79.163476 -431.615295)
			(xy 79.149227 -431.595671) (xy 79.141739 -431.572604) (xy 79.14132 -431.560478) (xy 79.14132 -430.948084)
			(xy 79.139777 -430.933592) (xy 79.138124 -430.904492) (xy 79.138018 -430.889918) (xy 78.235048 -430.889918)
			(xy 78.235048 -431.889916) (xy 81.138014 -431.889916) (xy 81.138108 -431.875342) (xy 81.13976 -431.846241)
			(xy 81.141316 -431.83175) (xy 81.141316 -430.747932) (xy 81.139768 -430.73344) (xy 81.138118 -430.70434)
			(xy 81.138014 -430.689766) (xy 81.138112 -430.675192) (xy 81.139761 -430.646091) (xy 81.141316 -430.6316)
			(xy 81.141316 -430.018952) (xy 81.141676 -430.006839) (xy 81.14919 -429.983807) (xy 81.163466 -429.964234)
			(xy 81.1831 -429.950041) (xy 81.206163 -429.942625) (xy 81.218278 -429.942244) (xy 82.158078 -429.942244)
			(xy 82.170167 -429.942726) (xy 82.193167 -429.950177) (xy 82.212748 -429.96436) (xy 82.226999 -429.983891)
			(xy 82.234531 -430.006865) (xy 82.23504 -430.018952) (xy 82.23504 -430.889918) (xy 83.13801 -430.889918)
			(xy 83.138104 -430.875344) (xy 83.139756 -430.846243) (xy 83.141312 -430.831752) (xy 83.141312 -429.747934)
			(xy 83.139764 -429.733442) (xy 83.138114 -429.704342) (xy 83.13801 -429.689768) (xy 83.138108 -429.675194)
			(xy 83.139758 -429.646093) (xy 83.141312 -429.631602) (xy 83.141312 -429.018954) (xy 83.141772 -429.00684)
			(xy 83.149269 -428.983799) (xy 83.163515 -428.964201) (xy 83.183117 -428.94996) (xy 83.20616 -428.942469)
			(xy 83.218274 -428.941992) (xy 84.158074 -428.941992) (xy 84.170183 -428.942533) (xy 84.193217 -428.950008)
			(xy 84.212815 -428.964233) (xy 84.227059 -428.983818) (xy 84.234555 -429.006846) (xy 84.235036 -429.018954)
			(xy 84.235036 -431.560478) (xy 84.234621 -431.572602) (xy 84.227132 -431.595665) (xy 84.21288 -431.615282)
			(xy 84.193261 -431.629533) (xy 84.170198 -431.637022) (xy 84.158074 -431.63744) (xy 83.218274 -431.63744)
			(xy 83.206156 -431.63701) (xy 83.183108 -431.629513) (xy 83.163505 -431.615261) (xy 83.149265 -431.595649)
			(xy 83.141782 -431.572596) (xy 83.141312 -431.560478) (xy 83.141312 -430.948084) (xy 83.139769 -430.933592)
			(xy 83.138116 -430.904492) (xy 83.13801 -430.889918) (xy 82.23504 -430.889918) (xy 82.23504 -431.889916)
			(xy 85.138006 -431.889916) (xy 85.1381 -431.875342) (xy 85.139752 -431.846241) (xy 85.141308 -431.83175)
			(xy 85.141308 -430.747932) (xy 85.13976 -430.73344) (xy 85.13811 -430.70434) (xy 85.138006 -430.689766)
			(xy 85.138104 -430.675192) (xy 85.139753 -430.646091) (xy 85.141308 -430.6316) (xy 85.141308 -430.018952)
			(xy 85.141676 -430.00684) (xy 85.149189 -429.98381) (xy 85.163463 -429.964237) (xy 85.183095 -429.950044)
			(xy 85.206156 -429.942626) (xy 85.21827 -429.942244) (xy 86.15807 -429.942244) (xy 86.170158 -429.942733)
			(xy 86.193159 -429.950182) (xy 86.212739 -429.964363) (xy 86.226991 -429.983892) (xy 86.234523 -430.006865)
			(xy 86.235032 -430.018952) (xy 86.235032 -430.889918) (xy 87.138002 -430.889918) (xy 87.138096 -430.875344)
			(xy 87.139748 -430.846243) (xy 87.141304 -430.831752) (xy 87.141304 -429.747934) (xy 87.139756 -429.733442)
			(xy 87.138106 -429.704342) (xy 87.138002 -429.689768) (xy 87.1381 -429.675194) (xy 87.13975 -429.646093)
			(xy 87.141304 -429.631602) (xy 87.141304 -429.018954) (xy 87.141772 -429.00684) (xy 87.149268 -428.983801)
			(xy 87.163512 -428.964203) (xy 87.183112 -428.949962) (xy 87.206152 -428.94247) (xy 87.218266 -428.941992)
			(xy 88.158066 -428.941992) (xy 88.170174 -428.94254) (xy 88.193209 -428.950012) (xy 88.212807 -428.964236)
			(xy 88.227051 -428.98382) (xy 88.234547 -429.006846) (xy 88.235028 -429.018954) (xy 88.235028 -431.560478)
			(xy 88.234621 -431.572603) (xy 88.22713 -431.595667) (xy 88.212877 -431.615285) (xy 88.193256 -431.629536)
			(xy 88.170191 -431.637023) (xy 88.158066 -431.63744) (xy 87.218266 -431.63744) (xy 87.206147 -431.637017)
			(xy 87.183099 -431.629518) (xy 87.163496 -431.615264) (xy 87.149257 -431.59565) (xy 87.141774 -431.572597)
			(xy 87.141304 -431.560478) (xy 87.141304 -430.948084) (xy 87.13976 -430.933592) (xy 87.138108 -430.904492)
			(xy 87.138002 -430.889918) (xy 86.235032 -430.889918) (xy 86.235032 -431.889916) (xy 89.137998 -431.889916)
			(xy 89.138092 -431.875342) (xy 89.139744 -431.846241) (xy 89.1413 -431.83175) (xy 89.1413 -430.747932)
			(xy 89.139752 -430.73344) (xy 89.138102 -430.70434) (xy 89.137998 -430.689766) (xy 89.138096 -430.675192)
			(xy 89.139746 -430.646091) (xy 89.1413 -430.6316) (xy 89.1413 -430.018952) (xy 89.141676 -430.006841)
			(xy 89.149188 -429.983812) (xy 89.16346 -429.96424) (xy 89.18309 -429.950047) (xy 89.206149 -429.942627)
			(xy 89.218262 -429.942244) (xy 90.158062 -429.942244) (xy 90.17015 -429.94274) (xy 90.19315 -429.950187)
			(xy 90.212731 -429.964366) (xy 90.226983 -429.983894) (xy 90.234515 -430.006866) (xy 90.235024 -430.018952)
			(xy 90.235024 -431.360072) (xy 108.40466 -431.360072) (xy 108.405158 -431.275192) (xy 108.413115 -431.105619)
			(xy 108.429011 -430.936605) (xy 108.452812 -430.768522) (xy 108.484466 -430.601739) (xy 108.523902 -430.436623)
			(xy 108.571034 -430.273538) (xy 108.625758 -430.11284) (xy 108.687955 -429.954885) (xy 108.757487 -429.800018)
			(xy 108.834202 -429.648581) (xy 108.91793 -429.500905) (xy 109.008488 -429.357317) (xy 109.105677 -429.218131)
			(xy 109.209284 -429.083654) (xy 109.319079 -428.954181) (xy 109.434823 -428.829996) (xy 109.55626 -428.711373)
			(xy 109.683124 -428.598572) (xy 109.815135 -428.491842) (xy 109.952005 -428.391417) (xy 110.09343 -428.297518)
			(xy 110.239102 -428.21035) (xy 110.3887 -428.130107) (xy 110.541894 -428.056963) (xy 110.698348 -427.991081)
			(xy 110.857718 -427.932604) (xy 111.019654 -427.881662) (xy 111.1838 -427.838366) (xy 111.349795 -427.802811)
			(xy 111.517274 -427.775076) (xy 111.685869 -427.755222) (xy 111.855209 -427.743292) (xy 112.024922 -427.739313)
			(xy 112.194635 -427.743292) (xy 112.363975 -427.755222) (xy 112.53257 -427.775076) (xy 112.700049 -427.802811)
			(xy 112.866044 -427.838366) (xy 113.03019 -427.881662) (xy 113.192126 -427.932604) (xy 113.351496 -427.991081)
			(xy 113.50795 -428.056963) (xy 113.661144 -428.130107) (xy 113.810742 -428.21035) (xy 113.943382 -428.28972)
			(xy 127.237998 -428.28972) (xy 127.238092 -428.275146) (xy 127.239744 -428.246045) (xy 127.2413 -428.231554)
			(xy 127.2413 -427.14799) (xy 127.239757 -427.133498) (xy 127.238104 -427.104398) (xy 127.237998 -427.089824)
			(xy 127.238092 -427.07525) (xy 127.239744 -427.046149) (xy 127.2413 -427.031658) (xy 127.2413 -426.41901)
			(xy 127.24182 -426.4069) (xy 127.2493 -426.383863) (xy 127.263531 -426.364265) (xy 127.28312 -426.350022)
			(xy 127.306152 -426.342527) (xy 127.318262 -426.342048) (xy 128.258062 -426.342048) (xy 128.270184 -426.342492)
			(xy 128.293243 -426.349975) (xy 128.31286 -426.36422) (xy 128.327112 -426.383832) (xy 128.334603 -426.406888)
			(xy 128.335024 -426.41901) (xy 128.335024 -427.289976) (xy 129.237994 -427.289976) (xy 129.238084 -427.275402)
			(xy 129.239739 -427.246301) (xy 129.241296 -427.23181) (xy 129.241296 -426.147992) (xy 129.239753 -426.1335)
			(xy 129.2381 -426.1044) (xy 129.237994 -426.089826) (xy 129.238089 -426.075252) (xy 129.23974 -426.046151)
			(xy 129.241296 -426.03166) (xy 129.241296 -425.419012) (xy 129.241727 -425.406904) (xy 129.249222 -425.383878)
			(xy 129.26348 -425.364305) (xy 129.283099 -425.35011) (xy 129.306149 -425.342688) (xy 129.318258 -425.342304)
			(xy 130.258058 -425.342304) (xy 130.270142 -425.342842) (xy 130.293135 -425.350283) (xy 130.312713 -425.364453)
			(xy 130.326966 -425.383969) (xy 130.334505 -425.40693) (xy 130.33502 -425.419012) (xy 130.33502 -427.960536)
			(xy 130.334615 -427.972645) (xy 130.327108 -427.99567) (xy 130.312843 -428.01524) (xy 130.29322 -428.029435)
			(xy 130.270168 -428.036858) (xy 130.258058 -428.037244) (xy 129.318258 -428.037244) (xy 129.306165 -428.036828)
			(xy 129.28316 -428.029358) (xy 129.263579 -428.015159) (xy 129.249331 -427.995614) (xy 129.241803 -427.972628)
			(xy 129.241296 -427.960536) (xy 129.241296 -427.348142) (xy 129.239749 -427.33365) (xy 129.238099 -427.30455)
			(xy 129.237994 -427.289976) (xy 128.335024 -427.289976) (xy 128.335024 -428.28972) (xy 131.23799 -428.28972)
			(xy 131.238084 -428.275146) (xy 131.239736 -428.246045) (xy 131.241292 -428.231554) (xy 131.241292 -427.14799)
			(xy 131.239749 -427.133498) (xy 131.238096 -427.104398) (xy 131.23799 -427.089824) (xy 131.238085 -427.07525)
			(xy 131.239736 -427.046149) (xy 131.241292 -427.031658) (xy 131.241292 -426.41901) (xy 131.24182 -426.406901)
			(xy 131.249299 -426.383865) (xy 131.263528 -426.364268) (xy 131.283115 -426.350024) (xy 131.306145 -426.342528)
			(xy 131.318254 -426.342048) (xy 132.258054 -426.342048) (xy 132.270175 -426.342499) (xy 132.293234 -426.34998)
			(xy 132.312851 -426.364223) (xy 132.327104 -426.383833) (xy 132.334595 -426.406889) (xy 132.335016 -426.41901)
			(xy 132.335016 -427.289976) (xy 133.237986 -427.289976) (xy 133.238076 -427.275402) (xy 133.239731 -427.246301)
			(xy 133.241288 -427.23181) (xy 133.241288 -426.147992) (xy 133.239745 -426.1335) (xy 133.238092 -426.1044)
			(xy 133.237986 -426.089826) (xy 133.238081 -426.075252) (xy 133.239732 -426.046151) (xy 133.241288 -426.03166)
			(xy 133.241288 -425.419012) (xy 133.241727 -425.406905) (xy 133.249221 -425.38388) (xy 133.263477 -425.364308)
			(xy 133.283094 -425.350113) (xy 133.306142 -425.342689) (xy 133.31825 -425.342304) (xy 134.25805 -425.342304)
			(xy 134.270133 -425.342849) (xy 134.293126 -425.350288) (xy 134.312704 -425.364455) (xy 134.326958 -425.383971)
			(xy 134.334497 -425.406931) (xy 134.335012 -425.419012) (xy 134.335012 -427.960536) (xy 134.334614 -427.972646)
			(xy 134.327107 -427.995672) (xy 134.31284 -428.015243) (xy 134.293215 -428.029437) (xy 134.270161 -428.036859)
			(xy 134.25805 -428.037244) (xy 133.31825 -428.037244) (xy 133.306161 -428.03675) (xy 133.28316 -428.029305)
			(xy 133.263578 -428.015126) (xy 133.249326 -427.995597) (xy 133.241795 -427.972623) (xy 133.241288 -427.960536)
			(xy 133.241288 -427.348142) (xy 133.239741 -427.33365) (xy 133.238091 -427.30455) (xy 133.237986 -427.289976)
			(xy 132.335016 -427.289976) (xy 132.335016 -428.28972) (xy 135.237982 -428.28972) (xy 135.238076 -428.275146)
			(xy 135.239728 -428.246045) (xy 135.241284 -428.231554) (xy 135.241284 -427.14799) (xy 135.239741 -427.133498)
			(xy 135.238088 -427.104398) (xy 135.237982 -427.089824) (xy 135.238077 -427.07525) (xy 135.239728 -427.046149)
			(xy 135.241284 -427.031658) (xy 135.241284 -426.41901) (xy 135.241669 -426.406883) (xy 135.249164 -426.383817)
			(xy 135.263423 -426.364198) (xy 135.283049 -426.349948) (xy 135.306119 -426.342464) (xy 135.318246 -426.342048)
			(xy 136.258046 -426.342048) (xy 136.270164 -426.342473) (xy 136.29321 -426.349974) (xy 136.312812 -426.364228)
			(xy 136.327052 -426.38384) (xy 136.334536 -426.406892) (xy 136.335008 -426.41901) (xy 136.335008 -427.289976)
			(xy 137.237978 -427.289976) (xy 137.238068 -427.275402) (xy 137.239723 -427.246301) (xy 137.24128 -427.23181)
			(xy 137.24128 -426.147992) (xy 137.239737 -426.1335) (xy 137.238084 -426.1044) (xy 137.237978 -426.089826)
			(xy 137.238073 -426.075252) (xy 137.239724 -426.046151) (xy 137.24128 -426.03166) (xy 137.24128 -425.419012)
			(xy 137.241727 -425.406906) (xy 137.24922 -425.383882) (xy 137.263475 -425.364311) (xy 137.283089 -425.350115)
			(xy 137.306135 -425.342691) (xy 137.318242 -425.342304) (xy 138.258042 -425.342304) (xy 138.27013 -425.342771)
			(xy 138.293126 -425.350235) (xy 138.312702 -425.364423) (xy 138.326953 -425.383953) (xy 138.33449 -425.406925)
			(xy 138.335004 -425.419012) (xy 138.335004 -427.960536) (xy 138.334614 -427.972646) (xy 138.327106 -427.995674)
			(xy 138.312837 -428.015246) (xy 138.29321 -428.02944) (xy 138.270154 -428.03686) (xy 138.258042 -428.037244)
			(xy 137.318242 -428.037244) (xy 137.306153 -428.036757) (xy 137.283151 -428.029309) (xy 137.263569 -428.015129)
			(xy 137.249318 -427.995598) (xy 137.241787 -427.972623) (xy 137.24128 -427.960536) (xy 137.24128 -427.348142)
			(xy 137.239733 -427.33365) (xy 137.238083 -427.30455) (xy 137.237978 -427.289976) (xy 136.335008 -427.289976)
			(xy 136.335008 -428.28972) (xy 139.237974 -428.28972) (xy 139.238068 -428.275146) (xy 139.23972 -428.246045)
			(xy 139.241276 -428.231554) (xy 139.241276 -427.14799) (xy 139.239733 -427.133498) (xy 139.23808 -427.104398)
			(xy 139.237974 -427.089824) (xy 139.238069 -427.07525) (xy 139.23972 -427.046149) (xy 139.241276 -427.031658)
			(xy 139.241276 -426.41901) (xy 139.241669 -426.406884) (xy 139.249163 -426.383819) (xy 139.26342 -426.364201)
			(xy 139.283044 -426.34995) (xy 139.306112 -426.342465) (xy 139.318238 -426.342048) (xy 140.258038 -426.342048)
			(xy 140.270156 -426.342479) (xy 140.293202 -426.349978) (xy 140.312804 -426.36423) (xy 140.327044 -426.383841)
			(xy 140.334528 -426.406892) (xy 140.335 -426.41901) (xy 140.335 -427.289976) (xy 142.237968 -427.289976)
			(xy 142.238082 -427.274891) (xy 142.23986 -427.244772) (xy 142.241524 -427.229778) (xy 142.241524 -426.150024)
			(xy 142.239855 -426.135031) (xy 142.238077 -426.104912) (xy 142.237968 -426.089826) (xy 142.238078 -426.07474)
			(xy 142.239859 -426.044622) (xy 142.241524 -426.029628) (xy 142.241524 -425.419012) (xy 142.241924 -425.406927)
			(xy 142.249392 -425.383939) (xy 142.2636 -425.364386) (xy 142.283157 -425.350183) (xy 142.306147 -425.34272)
			(xy 142.318232 -425.342304) (xy 143.258032 -425.342304) (xy 143.270109 -425.342737) (xy 143.29308 -425.35021)
			(xy 143.312617 -425.364414) (xy 143.32681 -425.38396) (xy 143.33427 -425.406934) (xy 143.33474 -425.419012)
			(xy 143.33474 -427.960536) (xy 143.334267 -427.972609) (xy 143.326799 -427.995572) (xy 143.312603 -428.015106)
			(xy 143.293069 -428.0293) (xy 143.270105 -428.036768) (xy 143.258032 -428.037244) (xy 142.318232 -428.037244)
			(xy 142.306163 -428.036709) (xy 142.283203 -428.02926) (xy 142.263668 -428.01508) (xy 142.249471 -427.995558)
			(xy 142.242001 -427.972605) (xy 142.241524 -427.960536) (xy 142.241524 -427.350174) (xy 142.23986 -427.33518)
			(xy 142.238078 -427.305062) (xy 142.237968 -427.289976) (xy 140.335 -427.289976) (xy 140.335 -428.28972)
			(xy 144.237964 -428.28972) (xy 144.238073 -428.274634) (xy 144.239855 -428.244516) (xy 144.24152 -428.229522)
			(xy 144.24152 -427.150022) (xy 144.239851 -427.135029) (xy 144.238073 -427.10491) (xy 144.237964 -427.089824)
			(xy 144.238074 -427.074738) (xy 144.239855 -427.04462) (xy 144.24152 -427.029626) (xy 144.24152 -426.41901)
			(xy 144.242016 -426.406923) (xy 144.249467 -426.383926) (xy 144.263647 -426.364348) (xy 144.283173 -426.350096)
			(xy 144.306143 -426.34256) (xy 144.318228 -426.342048) (xy 145.258028 -426.342048) (xy 145.270133 -426.342492)
			(xy 145.293152 -426.349993) (xy 145.312721 -426.364249) (xy 145.326916 -426.383861) (xy 145.334345 -426.406904)
			(xy 145.334736 -426.41901) (xy 145.334736 -427.289976) (xy 146.23796 -427.289976) (xy 146.238074 -427.274891)
			(xy 146.239852 -427.244772) (xy 146.241516 -427.229778) (xy 146.241516 -426.150024) (xy 146.239847 -426.135031)
			(xy 146.238069 -426.104912) (xy 146.23796 -426.089826) (xy 146.23807 -426.07474) (xy 146.239851 -426.044622)
			(xy 146.241516 -426.029628) (xy 146.241516 -425.419012) (xy 146.241923 -425.406928) (xy 146.249391 -425.383941)
			(xy 146.263597 -425.364389) (xy 146.283152 -425.350185) (xy 146.306139 -425.342722) (xy 146.318224 -425.342304)
			(xy 147.258024 -425.342304) (xy 147.270101 -425.342744) (xy 147.293071 -425.350215) (xy 147.312609 -425.364417)
			(xy 147.326802 -425.383961) (xy 147.334261 -425.406935) (xy 147.334732 -425.419012) (xy 147.334732 -427.960536)
			(xy 147.334267 -427.97261) (xy 147.326798 -427.995574) (xy 147.3126 -428.015109) (xy 147.293064 -428.029303)
			(xy 147.270098 -428.036769) (xy 147.258024 -428.037244) (xy 146.318224 -428.037244) (xy 146.306154 -428.036716)
			(xy 146.283194 -428.029264) (xy 146.26366 -428.015083) (xy 146.249463 -427.99556) (xy 146.241993 -427.972605)
			(xy 146.241516 -427.960536) (xy 146.241516 -427.350174) (xy 146.239852 -427.33518) (xy 146.23807 -427.305062)
			(xy 146.23796 -427.289976) (xy 145.334736 -427.289976) (xy 145.334736 -428.28972) (xy 148.237956 -428.28972)
			(xy 148.238066 -428.274634) (xy 148.239847 -428.244516) (xy 148.241512 -428.229522) (xy 148.241512 -427.150022)
			(xy 148.239843 -427.135029) (xy 148.238065 -427.10491) (xy 148.237956 -427.089824) (xy 148.238066 -427.074738)
			(xy 148.239847 -427.04462) (xy 148.241512 -427.029626) (xy 148.241512 -426.41901) (xy 148.242015 -426.406924)
			(xy 148.249466 -426.383928) (xy 148.263644 -426.364351) (xy 148.283168 -426.350099) (xy 148.306136 -426.342562)
			(xy 148.31822 -426.342048) (xy 149.25802 -426.342048) (xy 149.270125 -426.342499) (xy 149.293144 -426.349997)
			(xy 149.312712 -426.364252) (xy 149.326908 -426.383863) (xy 149.334337 -426.406904) (xy 149.334728 -426.41901)
			(xy 149.334728 -427.289976) (xy 150.237952 -427.289976) (xy 150.238066 -427.274891) (xy 150.239844 -427.244772)
			(xy 150.241508 -427.229778) (xy 150.241508 -426.150024) (xy 150.239839 -426.135031) (xy 150.238061 -426.104912)
			(xy 150.237952 -426.089826) (xy 150.238062 -426.07474) (xy 150.239843 -426.044622) (xy 150.241508 -426.029628)
			(xy 150.241508 -425.419012) (xy 150.241923 -425.406928) (xy 150.249389 -425.383943) (xy 150.263594 -425.364392)
			(xy 150.283147 -425.350188) (xy 150.306132 -425.342723) (xy 150.318216 -425.342304) (xy 151.258016 -425.342304)
			(xy 151.270093 -425.342751) (xy 151.293062 -425.350219) (xy 151.3126 -425.36442) (xy 151.326794 -425.383963)
			(xy 151.334253 -425.406935) (xy 151.334724 -425.419012) (xy 151.334724 -427.960536) (xy 151.334267 -427.972611)
			(xy 151.326796 -427.995577) (xy 151.312597 -428.015112) (xy 151.293059 -428.029306) (xy 151.270091 -428.03677)
			(xy 151.258016 -428.037244) (xy 150.318216 -428.037244) (xy 150.306146 -428.036723) (xy 150.283185 -428.029269)
			(xy 150.263651 -428.015086) (xy 150.249455 -427.995561) (xy 150.241985 -427.972606) (xy 150.241508 -427.960536)
			(xy 150.241508 -427.350174) (xy 150.239844 -427.33518) (xy 150.238062 -427.305062) (xy 150.237952 -427.289976)
			(xy 149.334728 -427.289976) (xy 149.334728 -428.28972) (xy 152.237948 -428.28972) (xy 152.238058 -428.274634)
			(xy 152.239839 -428.244516) (xy 152.241504 -428.229522) (xy 152.241504 -427.150022) (xy 152.239835 -427.135029)
			(xy 152.238057 -427.10491) (xy 152.237948 -427.089824) (xy 152.238058 -427.074738) (xy 152.239839 -427.04462)
			(xy 152.241504 -427.029626) (xy 152.241504 -426.41901) (xy 152.242015 -426.406925) (xy 152.249465 -426.38393)
			(xy 152.263641 -426.364353) (xy 152.283163 -426.350101) (xy 152.306128 -426.342563) (xy 152.318212 -426.342048)
			(xy 153.258012 -426.342048) (xy 153.270116 -426.342505) (xy 153.293135 -426.350002) (xy 153.312704 -426.364255)
			(xy 153.3269 -426.383864) (xy 153.334329 -426.406905) (xy 153.33472 -426.41901) (xy 153.33472 -427.289976)
			(xy 154.237944 -427.289976) (xy 154.238059 -427.274891) (xy 154.239836 -427.244772) (xy 154.2415 -427.229778)
			(xy 154.2415 -426.150024) (xy 154.239831 -426.135031) (xy 154.238053 -426.104912) (xy 154.237944 -426.089826)
			(xy 154.238054 -426.07474) (xy 154.239835 -426.044622) (xy 154.2415 -426.029628) (xy 154.2415 -425.419012)
			(xy 154.241923 -425.406929) (xy 154.249388 -425.383946) (xy 154.263592 -425.364394) (xy 154.283142 -425.35019)
			(xy 154.306125 -425.342724) (xy 154.318208 -425.342304) (xy 155.258008 -425.342304) (xy 155.270092 -425.342706)
			(xy 155.293077 -425.350177) (xy 155.312629 -425.364386) (xy 155.326832 -425.383941) (xy 155.334297 -425.406928)
			(xy 155.334716 -425.419012) (xy 155.334716 -427.960536) (xy 155.334267 -427.972612) (xy 155.326795 -427.995579)
			(xy 155.312595 -428.015115) (xy 155.293054 -428.029308) (xy 155.270084 -428.036771) (xy 155.258008 -428.037244)
			(xy 154.318208 -428.037244) (xy 154.306137 -428.03673) (xy 154.283177 -428.029274) (xy 154.263643 -428.015089)
			(xy 154.249447 -427.995563) (xy 154.241977 -427.972606) (xy 154.2415 -427.960536) (xy 154.2415 -427.350174)
			(xy 154.239836 -427.33518) (xy 154.238054 -427.305062) (xy 154.237944 -427.289976) (xy 153.33472 -427.289976)
			(xy 153.33472 -428.28972) (xy 156.23794 -428.28972) (xy 156.238052 -428.274634) (xy 156.239833 -428.244516)
			(xy 156.241496 -428.229522) (xy 156.241496 -427.150022) (xy 156.239827 -427.135029) (xy 156.238049 -427.10491)
			(xy 156.23794 -427.089824) (xy 156.23805 -427.074738) (xy 156.239831 -427.04462) (xy 156.241496 -427.029626)
			(xy 156.241496 -426.41901) (xy 156.242015 -426.406925) (xy 156.249464 -426.383932) (xy 156.263639 -426.364356)
			(xy 156.283158 -426.350104) (xy 156.306121 -426.342564) (xy 156.318204 -426.342048) (xy 157.258004 -426.342048)
			(xy 157.270108 -426.342512) (xy 157.293127 -426.350006) (xy 157.312695 -426.364257) (xy 157.326891 -426.383866)
			(xy 157.334321 -426.406905) (xy 157.334712 -426.41901) (xy 157.334712 -428.960534) (xy 157.334321 -428.97263)
			(xy 157.326849 -428.99564) (xy 157.312644 -429.015223) (xy 157.293092 -429.029471) (xy 157.270099 -429.036994)
			(xy 157.258004 -429.037496) (xy 156.318204 -429.037496) (xy 156.306095 -429.03708) (xy 156.283067 -429.029582)
			(xy 156.263493 -429.01532) (xy 156.249299 -428.995698) (xy 156.241879 -428.972644) (xy 156.241496 -428.960534)
			(xy 156.241496 -428.349918) (xy 156.239827 -428.334925) (xy 156.238049 -428.304806) (xy 156.23794 -428.28972)
			(xy 153.33472 -428.28972) (xy 153.33472 -428.960534) (xy 153.334321 -428.972629) (xy 153.32685 -428.995638)
			(xy 153.312647 -429.015221) (xy 153.293097 -429.029469) (xy 153.270106 -429.036993) (xy 153.258012 -429.037496)
			(xy 152.318212 -429.037496) (xy 152.306103 -429.037073) (xy 152.283076 -429.029577) (xy 152.263502 -429.015317)
			(xy 152.249307 -428.995696) (xy 152.241887 -428.972644) (xy 152.241504 -428.960534) (xy 152.241504 -428.349918)
			(xy 152.239835 -428.334925) (xy 152.238057 -428.304806) (xy 152.237948 -428.28972) (xy 149.334728 -428.28972)
			(xy 149.334728 -428.960534) (xy 149.334321 -428.972629) (xy 149.326851 -428.995636) (xy 149.31265 -429.015218)
			(xy 149.293102 -429.029466) (xy 149.270113 -429.036992) (xy 149.25802 -429.037496) (xy 148.31822 -429.037496)
			(xy 148.306112 -429.037066) (xy 148.283085 -429.029572) (xy 148.263511 -429.015314) (xy 148.249316 -428.995695)
			(xy 148.241895 -428.972643) (xy 148.241512 -428.960534) (xy 148.241512 -428.349918) (xy 148.239843 -428.334925)
			(xy 148.238065 -428.304806) (xy 148.237956 -428.28972) (xy 145.334736 -428.28972) (xy 145.334736 -428.960534)
			(xy 145.334321 -428.972628) (xy 145.326852 -428.995634) (xy 145.312653 -429.015215) (xy 145.293107 -429.029464)
			(xy 145.27012 -429.03699) (xy 145.258028 -429.037496) (xy 144.318228 -429.037496) (xy 144.30612 -429.03706)
			(xy 144.283093 -429.029567) (xy 144.263519 -429.015311) (xy 144.249324 -428.995693) (xy 144.241903 -428.972643)
			(xy 144.24152 -428.960534) (xy 144.24152 -428.349918) (xy 144.239851 -428.334925) (xy 144.238073 -428.304806)
			(xy 144.237964 -428.28972) (xy 140.335 -428.28972) (xy 140.335 -428.960534) (xy 140.334518 -428.972647)
			(xy 140.327026 -428.995684) (xy 140.312785 -429.015282) (xy 140.293188 -429.029524) (xy 140.270151 -429.037017)
			(xy 140.258038 -429.037496) (xy 139.318238 -429.037496) (xy 139.306121 -429.037008) (xy 139.283069 -429.029531)
			(xy 139.263456 -429.015295) (xy 139.249202 -428.995696) (xy 139.241703 -428.972651) (xy 139.241276 -428.960534)
			(xy 139.241276 -428.347886) (xy 139.239733 -428.333394) (xy 139.23808 -428.304294) (xy 139.237974 -428.28972)
			(xy 136.335008 -428.28972) (xy 136.335008 -428.960534) (xy 136.334518 -428.972646) (xy 136.327027 -428.995682)
			(xy 136.312788 -429.01528) (xy 136.293193 -429.029522) (xy 136.270158 -429.037016) (xy 136.258046 -429.037496)
			(xy 135.318246 -429.037496) (xy 135.306129 -429.037002) (xy 135.283077 -429.029526) (xy 135.263464 -429.015292)
			(xy 135.249211 -428.995694) (xy 135.241711 -428.972651) (xy 135.241284 -428.960534) (xy 135.241284 -428.347886)
			(xy 135.239741 -428.333394) (xy 135.238088 -428.304294) (xy 135.237982 -428.28972) (xy 132.335016 -428.28972)
			(xy 132.335016 -428.960534) (xy 132.334668 -428.972663) (xy 132.327161 -428.995731) (xy 132.312892 -429.015349)
			(xy 132.293259 -429.029598) (xy 132.270184 -429.037081) (xy 132.258054 -429.037496) (xy 131.318254 -429.037496)
			(xy 131.30614 -429.037028) (xy 131.283101 -429.029532) (xy 131.263503 -429.015288) (xy 131.249262 -428.995688)
			(xy 131.24177 -428.972648) (xy 131.241292 -428.960534) (xy 131.241292 -428.347886) (xy 131.239749 -428.333394)
			(xy 131.238096 -428.304294) (xy 131.23799 -428.28972) (xy 128.335024 -428.28972) (xy 128.335024 -428.960534)
			(xy 128.334669 -428.972662) (xy 128.327162 -428.995729) (xy 128.312895 -429.015347) (xy 128.293264 -429.029595)
			(xy 128.270191 -429.03708) (xy 128.258062 -429.037496) (xy 127.318262 -429.037496) (xy 127.306149 -429.037021)
			(xy 127.28311 -429.029528) (xy 127.263512 -429.015285) (xy 127.24927 -428.995686) (xy 127.241778 -428.972647)
			(xy 127.2413 -428.960534) (xy 127.2413 -428.347886) (xy 127.239757 -428.333394) (xy 127.238104 -428.304294)
			(xy 127.237998 -428.28972) (xy 113.943382 -428.28972) (xy 113.956414 -428.297518) (xy 114.097839 -428.391417)
			(xy 114.234709 -428.491842) (xy 114.36672 -428.598572) (xy 114.493584 -428.711373) (xy 114.615021 -428.829996)
			(xy 114.730765 -428.954181) (xy 114.84056 -429.083654) (xy 114.944167 -429.218131) (xy 115.041356 -429.357317)
			(xy 115.131914 -429.500905) (xy 115.215642 -429.648581) (xy 115.292357 -429.800018) (xy 115.361889 -429.954885)
			(xy 115.424086 -430.11284) (xy 115.47881 -430.273538) (xy 115.525942 -430.436623) (xy 115.565378 -430.601739)
			(xy 115.597032 -430.768522) (xy 115.614222 -430.889918) (xy 125.238002 -430.889918) (xy 125.238096 -430.875344)
			(xy 125.239748 -430.846243) (xy 125.241304 -430.831752) (xy 125.241304 -429.747934) (xy 125.239756 -429.733442)
			(xy 125.238106 -429.704342) (xy 125.238002 -429.689768) (xy 125.2381 -429.675194) (xy 125.23975 -429.646093)
			(xy 125.241304 -429.631602) (xy 125.241304 -429.018954) (xy 125.241772 -429.00684) (xy 125.249268 -428.983801)
			(xy 125.263512 -428.964203) (xy 125.283112 -428.949962) (xy 125.306152 -428.94247) (xy 125.318266 -428.941992)
			(xy 126.258066 -428.941992) (xy 126.270174 -428.94254) (xy 126.293209 -428.950012) (xy 126.312807 -428.964236)
			(xy 126.327051 -428.98382) (xy 126.334547 -429.006846) (xy 126.335028 -429.018954) (xy 126.335028 -431.560478)
			(xy 126.334621 -431.572603) (xy 126.32713 -431.595667) (xy 126.312877 -431.615285) (xy 126.293256 -431.629536)
			(xy 126.270191 -431.637023) (xy 126.258066 -431.63744) (xy 125.318266 -431.63744) (xy 125.306147 -431.637017)
			(xy 125.283099 -431.629518) (xy 125.263496 -431.615264) (xy 125.249257 -431.59565) (xy 125.241774 -431.572597)
			(xy 125.241304 -431.560478) (xy 125.241304 -430.948084) (xy 125.23976 -430.933592) (xy 125.238108 -430.904492)
			(xy 125.238002 -430.889918) (xy 115.614222 -430.889918) (xy 115.620833 -430.936605) (xy 115.636729 -431.105619)
			(xy 115.644686 -431.275192) (xy 115.645184 -431.360072) (xy 115.644698 -431.445674) (xy 115.63661 -431.616688)
			(xy 115.620446 -431.787128) (xy 115.605768 -431.889916) (xy 127.237998 -431.889916) (xy 127.238092 -431.875342)
			(xy 127.239744 -431.846241) (xy 127.2413 -431.83175) (xy 127.2413 -430.747932) (xy 127.239752 -430.73344)
			(xy 127.238102 -430.70434) (xy 127.237998 -430.689766) (xy 127.238096 -430.675192) (xy 127.239746 -430.646091)
			(xy 127.2413 -430.6316) (xy 127.2413 -430.018952) (xy 127.241676 -430.006841) (xy 127.249188 -429.983812)
			(xy 127.26346 -429.96424) (xy 127.28309 -429.950047) (xy 127.306149 -429.942627) (xy 127.318262 -429.942244)
			(xy 128.258062 -429.942244) (xy 128.27015 -429.94274) (xy 128.29315 -429.950187) (xy 128.312731 -429.964366)
			(xy 128.326983 -429.983894) (xy 128.334515 -430.006866) (xy 128.335024 -430.018952) (xy 128.335024 -430.889918)
			(xy 129.237994 -430.889918) (xy 129.238088 -430.875344) (xy 129.23974 -430.846243) (xy 129.241296 -430.831752)
			(xy 129.241296 -429.747934) (xy 129.239749 -429.733442) (xy 129.238098 -429.704342) (xy 129.237994 -429.689768)
			(xy 129.238092 -429.675194) (xy 129.239742 -429.646093) (xy 129.241296 -429.631602) (xy 129.241296 -429.018954)
			(xy 129.241772 -429.006841) (xy 129.249267 -428.983804) (xy 129.263509 -428.964206) (xy 129.283107 -428.949965)
			(xy 129.306145 -428.942471) (xy 129.318258 -428.941992) (xy 130.258058 -428.941992) (xy 130.270166 -428.942547)
			(xy 130.2932 -428.950017) (xy 130.312798 -428.964239) (xy 130.327043 -428.983821) (xy 130.334539 -429.006847)
			(xy 130.33502 -429.018954) (xy 130.33502 -431.560478) (xy 130.334621 -431.572604) (xy 130.327129 -431.595669)
			(xy 130.312874 -431.615288) (xy 130.293251 -431.629538) (xy 130.270184 -431.637024) (xy 130.258058 -431.63744)
			(xy 129.318258 -431.63744) (xy 129.306139 -431.637024) (xy 129.283091 -431.629522) (xy 129.263488 -431.615267)
			(xy 129.249248 -431.595652) (xy 129.241766 -431.572597) (xy 129.241296 -431.560478) (xy 129.241296 -430.948084)
			(xy 129.239753 -430.933592) (xy 129.2381 -430.904492) (xy 129.237994 -430.889918) (xy 128.335024 -430.889918)
			(xy 128.335024 -431.889916) (xy 131.23799 -431.889916) (xy 131.238084 -431.875342) (xy 131.239736 -431.846241)
			(xy 131.241292 -431.83175) (xy 131.241292 -430.747932) (xy 131.239744 -430.73344) (xy 131.238094 -430.70434)
			(xy 131.23799 -430.689766) (xy 131.238088 -430.675192) (xy 131.239738 -430.646091) (xy 131.241292 -430.6316)
			(xy 131.241292 -430.018952) (xy 131.241675 -430.006841) (xy 131.249187 -429.983814) (xy 131.263458 -429.964242)
			(xy 131.283085 -429.950049) (xy 131.306142 -429.942628) (xy 131.318254 -429.942244) (xy 132.258054 -429.942244)
			(xy 132.270142 -429.942747) (xy 132.293141 -429.950191) (xy 132.312722 -429.964368) (xy 132.326974 -429.983895)
			(xy 132.334507 -430.006866) (xy 132.335016 -430.018952) (xy 132.335016 -430.889918) (xy 133.237986 -430.889918)
			(xy 133.23808 -430.875344) (xy 133.239732 -430.846243) (xy 133.241288 -430.831752) (xy 133.241288 -429.747934)
			(xy 133.239741 -429.733442) (xy 133.23809 -429.704342) (xy 133.237986 -429.689768) (xy 133.238084 -429.675194)
			(xy 133.239734 -429.646093) (xy 133.241288 -429.631602) (xy 133.241288 -429.018954) (xy 133.241772 -429.006842)
			(xy 133.249266 -428.983806) (xy 133.263506 -428.964209) (xy 133.283102 -428.949967) (xy 133.306138 -428.942472)
			(xy 133.31825 -428.941992) (xy 134.25805 -428.941992) (xy 134.270163 -428.942468) (xy 134.2932 -428.949964)
			(xy 134.312797 -428.964206) (xy 134.327038 -428.983804) (xy 134.334532 -429.006841) (xy 134.335012 -429.018954)
			(xy 134.335012 -431.560478) (xy 134.33447 -431.572586) (xy 134.326995 -431.59562) (xy 134.312769 -431.615218)
			(xy 134.293185 -431.629462) (xy 134.270158 -431.636959) (xy 134.25805 -431.63744) (xy 133.31825 -431.63744)
			(xy 133.306131 -431.63703) (xy 133.283082 -431.629527) (xy 133.263479 -431.615269) (xy 133.24924 -431.595653)
			(xy 133.241758 -431.572598) (xy 133.241288 -431.560478) (xy 133.241288 -430.948084) (xy 133.239745 -430.933592)
			(xy 133.238092 -430.904492) (xy 133.237986 -430.889918) (xy 132.335016 -430.889918) (xy 132.335016 -431.889916)
			(xy 135.237982 -431.889916) (xy 135.238076 -431.875342) (xy 135.239728 -431.846241) (xy 135.241284 -431.83175)
			(xy 135.241284 -430.747932) (xy 135.239736 -430.73344) (xy 135.238086 -430.70434) (xy 135.237982 -430.689766)
			(xy 135.23808 -430.675192) (xy 135.23973 -430.646091) (xy 135.241284 -430.6316) (xy 135.241284 -430.018952)
			(xy 135.241675 -430.006842) (xy 135.249186 -429.983816) (xy 135.263455 -429.964245) (xy 135.28308 -429.950052)
			(xy 135.306135 -429.942629) (xy 135.318246 -429.942244) (xy 136.258046 -429.942244) (xy 136.270138 -429.942668)
			(xy 136.293141 -429.950138) (xy 136.312721 -429.964336) (xy 136.32697 -429.983878) (xy 136.3345 -430.006861)
			(xy 136.335008 -430.018952) (xy 136.335008 -430.889918) (xy 137.237978 -430.889918) (xy 137.238072 -430.875344)
			(xy 137.239724 -430.846243) (xy 137.24128 -430.831752) (xy 137.24128 -429.747934) (xy 137.239733 -429.733442)
			(xy 137.238082 -429.704342) (xy 137.237978 -429.689768) (xy 137.238076 -429.675194) (xy 137.239726 -429.646093)
			(xy 137.24128 -429.631602) (xy 137.24128 -429.018954) (xy 137.241673 -429.006833) (xy 137.249178 -428.983781)
			(xy 137.263439 -428.964176) (xy 137.28306 -428.949938) (xy 137.30612 -428.942459) (xy 137.318242 -428.941992)
			(xy 138.258042 -428.941992) (xy 138.270154 -428.942475) (xy 138.293191 -428.949968) (xy 138.312788 -428.964209)
			(xy 138.32703 -428.983805) (xy 138.334524 -429.006842) (xy 138.335004 -429.018954) (xy 138.335004 -431.560478)
			(xy 138.33447 -431.572587) (xy 138.326994 -431.595623) (xy 138.312767 -431.615221) (xy 138.29318 -431.629465)
			(xy 138.270151 -431.63696) (xy 138.258042 -431.63744) (xy 137.318242 -431.63744) (xy 137.306119 -431.637004)
			(xy 137.283058 -431.629521) (xy 137.26344 -431.615274) (xy 137.249188 -431.59566) (xy 137.241699 -431.572601)
			(xy 137.24128 -431.560478) (xy 137.24128 -430.948084) (xy 137.239737 -430.933592) (xy 137.238084 -430.904492)
			(xy 137.237978 -430.889918) (xy 136.335008 -430.889918) (xy 136.335008 -431.889916) (xy 139.237974 -431.889916)
			(xy 139.238068 -431.875342) (xy 139.23972 -431.846241) (xy 139.241276 -431.83175) (xy 139.241276 -430.747932)
			(xy 139.239728 -430.73344) (xy 139.238078 -430.70434) (xy 139.237974 -430.689766) (xy 139.238072 -430.675192)
			(xy 139.239722 -430.646091) (xy 139.241276 -430.6316) (xy 139.241276 -430.018952) (xy 139.241675 -430.006843)
			(xy 139.249185 -429.983818) (xy 139.263452 -429.964248) (xy 139.283075 -429.950054) (xy 139.306128 -429.94263)
			(xy 139.318238 -429.942244) (xy 140.258038 -429.942244) (xy 140.27013 -429.942675) (xy 140.293133 -429.950143)
			(xy 140.312712 -429.964338) (xy 140.326961 -429.983879) (xy 140.334492 -430.006861) (xy 140.335 -430.018952)
			(xy 140.335 -430.889918) (xy 142.237968 -430.889918) (xy 142.238077 -430.874832) (xy 142.239859 -430.844714)
			(xy 142.241524 -430.82972) (xy 142.241524 -429.749966) (xy 142.239859 -429.734972) (xy 142.238078 -429.704854)
			(xy 142.237968 -429.689768) (xy 142.238082 -429.674682) (xy 142.23986 -429.644564) (xy 142.241524 -429.62957)
			(xy 142.241524 -429.018954) (xy 142.241968 -429.006864) (xy 142.249435 -428.983864) (xy 142.263628 -428.964286)
			(xy 142.283165 -428.950037) (xy 142.306143 -428.942503) (xy 142.318232 -428.941992) (xy 143.258032 -428.941992)
			(xy 143.270142 -428.942389) (xy 143.293169 -428.949896) (xy 143.312741 -428.964163) (xy 143.326934 -428.983788)
			(xy 143.334356 -429.006843) (xy 143.33474 -429.018954) (xy 143.33474 -431.560478) (xy 143.334273 -431.572568)
			(xy 143.32682 -431.595572) (xy 143.312634 -431.615154) (xy 143.293099 -431.629404) (xy 143.270121 -431.636933)
			(xy 143.258032 -431.63744) (xy 142.318232 -431.63744) (xy 142.306129 -431.636957) (xy 142.283109 -431.629471)
			(xy 142.263539 -431.615225) (xy 142.249342 -431.59562) (xy 142.241913 -431.572582) (xy 142.241524 -431.560478)
			(xy 142.241524 -430.950116) (xy 142.239855 -430.935123) (xy 142.238077 -430.905004) (xy 142.237968 -430.889918)
			(xy 140.335 -430.889918) (xy 140.335 -431.889916) (xy 144.237964 -431.889916) (xy 144.238073 -431.87483)
			(xy 144.239855 -431.844712) (xy 144.24152 -431.829718) (xy 144.24152 -430.749964) (xy 144.239855 -430.73497)
			(xy 144.238074 -430.704852) (xy 144.237964 -430.689766) (xy 144.238078 -430.67468) (xy 144.239856 -430.644562)
			(xy 144.24152 -430.629568) (xy 144.24152 -430.018952) (xy 144.241924 -430.006872) (xy 144.249403 -429.983899)
			(xy 144.263614 -429.96436) (xy 144.283167 -429.950168) (xy 144.306148 -429.942712) (xy 144.318228 -429.942244)
			(xy 145.258028 -429.942244) (xy 145.270099 -429.942739) (xy 145.293059 -429.950204) (xy 145.312592 -429.964394)
			(xy 145.326787 -429.983923) (xy 145.334258 -430.006881) (xy 145.334736 -430.018952) (xy 145.334736 -430.889918)
			(xy 146.23796 -430.889918) (xy 146.238069 -430.874832) (xy 146.239851 -430.844714) (xy 146.241516 -430.82972)
			(xy 146.241516 -429.749966) (xy 146.239851 -429.734972) (xy 146.23807 -429.704854) (xy 146.23796 -429.689768)
			(xy 146.238074 -429.674682) (xy 146.239852 -429.644564) (xy 146.241516 -429.62957) (xy 146.241516 -429.018954)
			(xy 146.241968 -429.006864) (xy 146.249434 -428.983866) (xy 146.263626 -428.964289) (xy 146.28316 -428.950039)
			(xy 146.306136 -428.942504) (xy 146.318224 -428.941992) (xy 147.258024 -428.941992) (xy 147.270133 -428.942396)
			(xy 147.29316 -428.949901) (xy 147.312732 -428.964166) (xy 147.326926 -428.983789) (xy 147.334348 -429.006843)
			(xy 147.334732 -429.018954) (xy 147.334732 -431.560478) (xy 147.334273 -431.572569) (xy 147.326819 -431.595574)
			(xy 147.312632 -431.615156) (xy 147.293094 -431.629407) (xy 147.270114 -431.636934) (xy 147.258024 -431.63744)
			(xy 146.318224 -431.63744) (xy 146.30612 -431.636964) (xy 146.283101 -431.629476) (xy 146.263531 -431.615228)
			(xy 146.249334 -431.595622) (xy 146.241905 -431.572583) (xy 146.241516 -431.560478) (xy 146.241516 -430.950116)
			(xy 146.239847 -430.935123) (xy 146.238069 -430.905004) (xy 146.23796 -430.889918) (xy 145.334736 -430.889918)
			(xy 145.334736 -431.889916) (xy 148.237956 -431.889916) (xy 148.238065 -431.87483) (xy 148.239847 -431.844712)
			(xy 148.241512 -431.829718) (xy 148.241512 -430.749964) (xy 148.239847 -430.73497) (xy 148.238066 -430.704852)
			(xy 148.237956 -430.689766) (xy 148.23807 -430.67468) (xy 148.239848 -430.644562) (xy 148.241512 -430.629568)
			(xy 148.241512 -430.018952) (xy 148.241924 -430.006873) (xy 148.249402 -429.983901) (xy 148.263611 -429.964363)
			(xy 148.283162 -429.950171) (xy 148.306141 -429.942713) (xy 148.31822 -429.942244) (xy 149.25802 -429.942244)
			(xy 149.270091 -429.942747) (xy 149.29305 -429.950209) (xy 149.312583 -429.964397) (xy 149.326778 -429.983924)
			(xy 149.334249 -430.006881) (xy 149.334728 -430.018952) (xy 149.334728 -430.889918) (xy 150.237952 -430.889918)
			(xy 150.238061 -430.874832) (xy 150.239843 -430.844714) (xy 150.241508 -430.82972) (xy 150.241508 -429.749966)
			(xy 150.239843 -429.734972) (xy 150.238062 -429.704854) (xy 150.237952 -429.689768) (xy 150.238066 -429.674682)
			(xy 150.239844 -429.644564) (xy 150.241508 -429.62957) (xy 150.241508 -429.018954) (xy 150.241968 -429.006865)
			(xy 150.249433 -428.983868) (xy 150.263623 -428.964292) (xy 150.283155 -428.950042) (xy 150.306129 -428.942505)
			(xy 150.318216 -428.941992) (xy 151.258016 -428.941992) (xy 151.270125 -428.942402) (xy 151.293151 -428.949905)
			(xy 151.312724 -428.964169) (xy 151.326918 -428.983791) (xy 151.33434 -429.006844) (xy 151.334724 -429.018954)
			(xy 151.334724 -431.560478) (xy 151.334273 -431.57257) (xy 151.326818 -431.595576) (xy 151.312629 -431.615159)
			(xy 151.293089 -431.629409) (xy 151.270106 -431.636935) (xy 151.258016 -431.63744) (xy 150.318216 -431.63744)
			(xy 150.306112 -431.63697) (xy 150.283092 -431.62948) (xy 150.263522 -431.615231) (xy 150.249326 -431.595623)
			(xy 150.241897 -431.572583) (xy 150.241508 -431.560478) (xy 150.241508 -430.950116) (xy 150.239839 -430.935123)
			(xy 150.238061 -430.905004) (xy 150.237952 -430.889918) (xy 149.334728 -430.889918) (xy 149.334728 -431.889916)
			(xy 152.237948 -431.889916) (xy 152.238057 -431.87483) (xy 152.239839 -431.844712) (xy 152.241504 -431.829718)
			(xy 152.241504 -430.749964) (xy 152.239839 -430.73497) (xy 152.238058 -430.704852) (xy 152.237948 -430.689766)
			(xy 152.238062 -430.67468) (xy 152.23984 -430.644562) (xy 152.241504 -430.629568) (xy 152.241504 -430.018952)
			(xy 152.241923 -430.006874) (xy 152.249401 -429.983903) (xy 152.263608 -429.964366) (xy 152.283157 -429.950173)
			(xy 152.306133 -429.942714) (xy 152.318212 -429.942244) (xy 153.258012 -429.942244) (xy 153.270082 -429.942753)
			(xy 153.293042 -429.950213) (xy 153.312574 -429.9644) (xy 153.32677 -429.983926) (xy 153.334241 -430.006882)
			(xy 153.33472 -430.018952) (xy 153.33472 -430.889918) (xy 154.237944 -430.889918) (xy 154.238053 -430.874832)
			(xy 154.239835 -430.844714) (xy 154.2415 -430.82972) (xy 154.2415 -429.749966) (xy 154.239835 -429.734972)
			(xy 154.238054 -429.704854) (xy 154.237944 -429.689768) (xy 154.238058 -429.674682) (xy 154.239836 -429.644564)
			(xy 154.2415 -429.62957) (xy 154.2415 -429.018954) (xy 154.241967 -429.006866) (xy 154.249432 -428.983871)
			(xy 154.26362 -428.964295) (xy 154.28315 -428.950044) (xy 154.306122 -428.942507) (xy 154.318208 -428.941992)
			(xy 155.258008 -428.941992) (xy 155.270117 -428.942409) (xy 155.293143 -428.94991) (xy 155.312715 -428.964172)
			(xy 155.32691 -428.983792) (xy 155.334332 -429.006844) (xy 155.334716 -429.018954) (xy 155.334716 -431.560478)
			(xy 155.334273 -431.572571) (xy 155.326817 -431.595578) (xy 155.312626 -431.615162) (xy 155.293084 -431.629412)
			(xy 155.270099 -431.636937) (xy 155.258008 -431.63744) (xy 154.318208 -431.63744) (xy 154.306104 -431.636978)
			(xy 154.283083 -431.629485) (xy 154.263513 -431.615234) (xy 154.249317 -431.595625) (xy 154.241889 -431.572584)
			(xy 154.2415 -431.560478) (xy 154.2415 -430.950116) (xy 154.239831 -430.935123) (xy 154.238053 -430.905004)
			(xy 154.237944 -430.889918) (xy 153.33472 -430.889918) (xy 153.33472 -431.889916) (xy 156.23794 -431.889916)
			(xy 156.238051 -431.87483) (xy 156.239833 -431.844712) (xy 156.241496 -431.829718) (xy 156.241496 -430.749964)
			(xy 156.239831 -430.73497) (xy 156.23805 -430.704852) (xy 156.23794 -430.689766) (xy 156.238054 -430.67468)
			(xy 156.239832 -430.644562) (xy 156.241496 -430.629568) (xy 156.241496 -430.018952) (xy 156.241923 -430.006875)
			(xy 156.249399 -429.983905) (xy 156.263605 -429.964368) (xy 156.283152 -429.950176) (xy 156.306126 -429.942715)
			(xy 156.318204 -429.942244) (xy 157.258004 -429.942244) (xy 157.270074 -429.94276) (xy 157.293033 -429.950218)
			(xy 157.312566 -429.964403) (xy 157.326762 -429.983927) (xy 157.334233 -430.006882) (xy 157.334712 -430.018952)
			(xy 157.334712 -432.560476) (xy 157.334267 -432.572557) (xy 157.326806 -432.595538) (xy 157.312609 -432.615089)
			(xy 157.293063 -432.629294) (xy 157.270085 -432.636762) (xy 157.258004 -432.637184) (xy 156.318204 -432.637184)
			(xy 156.306119 -432.636784) (xy 156.283132 -432.629314) (xy 156.26358 -432.615106) (xy 156.249376 -432.59555)
			(xy 156.241913 -432.572561) (xy 156.241496 -432.560476) (xy 156.241496 -431.950114) (xy 156.239826 -431.935121)
			(xy 156.238049 -431.905002) (xy 156.23794 -431.889916) (xy 153.33472 -431.889916) (xy 153.33472 -432.560476)
			(xy 153.334267 -432.572556) (xy 153.326807 -432.595536) (xy 153.312611 -432.615086) (xy 153.293068 -432.629291)
			(xy 153.270092 -432.636761) (xy 153.258012 -432.637184) (xy 152.318212 -432.637184) (xy 152.306128 -432.636777)
			(xy 152.283141 -432.629309) (xy 152.263589 -432.615103) (xy 152.249385 -432.595548) (xy 152.241922 -432.572561)
			(xy 152.241504 -432.560476) (xy 152.241504 -431.950114) (xy 152.239834 -431.935121) (xy 152.238057 -431.905002)
			(xy 152.237948 -431.889916) (xy 149.334728 -431.889916) (xy 149.334728 -432.560476) (xy 149.334267 -432.572555)
			(xy 149.326809 -432.595534) (xy 149.312614 -432.615083) (xy 149.293073 -432.629288) (xy 149.270099 -432.63676)
			(xy 149.25802 -432.637184) (xy 148.31822 -432.637184) (xy 148.306136 -432.63677) (xy 148.28315 -432.629305)
			(xy 148.263597 -432.6151) (xy 148.249393 -432.595547) (xy 148.24193 -432.57256) (xy 148.241512 -432.560476)
			(xy 148.241512 -431.950114) (xy 148.239842 -431.935121) (xy 148.238065 -431.905002) (xy 148.237956 -431.889916)
			(xy 145.334736 -431.889916) (xy 145.334736 -432.560476) (xy 145.334216 -432.572547) (xy 145.326763 -432.595508)
			(xy 145.31258 -432.615043) (xy 145.293055 -432.62924) (xy 145.270098 -432.636708) (xy 145.258028 -432.637184)
			(xy 144.318228 -432.637184) (xy 144.306144 -432.636763) (xy 144.283159 -432.6293) (xy 144.263606 -432.615097)
			(xy 144.249402 -432.595545) (xy 144.241938 -432.57256) (xy 144.24152 -432.560476) (xy 144.24152 -431.950114)
			(xy 144.23985 -431.935121) (xy 144.238073 -431.905002) (xy 144.237964 -431.889916) (xy 140.335 -431.889916)
			(xy 140.335 -432.560476) (xy 140.334563 -432.572584) (xy 140.32707 -432.59561) (xy 140.312814 -432.615184)
			(xy 140.293196 -432.629379) (xy 140.270147 -432.6368) (xy 140.258038 -432.637184) (xy 139.318238 -432.637184)
			(xy 139.306153 -432.636661) (xy 139.283157 -432.629217) (xy 139.263579 -432.615044) (xy 139.249326 -432.595524)
			(xy 139.241789 -432.572559) (xy 139.241276 -432.560476) (xy 139.241276 -431.948082) (xy 139.239733 -431.93359)
			(xy 139.23808 -431.90449) (xy 139.237974 -431.889916) (xy 136.335008 -431.889916) (xy 136.335008 -432.560476)
			(xy 136.334563 -432.572583) (xy 136.327071 -432.595608) (xy 136.312817 -432.615181) (xy 136.293201 -432.629376)
			(xy 136.270154 -432.636799) (xy 136.258046 -432.637184) (xy 135.318246 -432.637184) (xy 135.306161 -432.636654)
			(xy 135.283166 -432.629213) (xy 135.263587 -432.615042) (xy 135.249334 -432.595522) (xy 135.241797 -432.572559)
			(xy 135.241284 -432.560476) (xy 135.241284 -431.948082) (xy 135.239741 -431.93359) (xy 135.238088 -431.90449)
			(xy 135.237982 -431.889916) (xy 132.335016 -431.889916) (xy 132.335016 -432.560476) (xy 132.334563 -432.572582)
			(xy 132.327072 -432.595606) (xy 132.31282 -432.615178) (xy 132.293206 -432.629374) (xy 132.270161 -432.636798)
			(xy 132.258054 -432.637184) (xy 131.318254 -432.637184) (xy 131.306164 -432.636732) (xy 131.283166 -432.629266)
			(xy 131.263589 -432.615074) (xy 131.249339 -432.59554) (xy 131.241804 -432.572564) (xy 131.241292 -432.560476)
			(xy 131.241292 -431.948082) (xy 131.239749 -431.93359) (xy 131.238096 -431.90449) (xy 131.23799 -431.889916)
			(xy 128.335024 -431.889916) (xy 128.335024 -432.560476) (xy 128.334563 -432.572581) (xy 128.327074 -432.595604)
			(xy 128.312823 -432.615175) (xy 128.293212 -432.629371) (xy 128.270168 -432.636797) (xy 128.258062 -432.637184)
			(xy 127.318262 -432.637184) (xy 127.306173 -432.636726) (xy 127.283175 -432.629261) (xy 127.263598 -432.615072)
			(xy 127.249348 -432.595538) (xy 127.241812 -432.572564) (xy 127.2413 -432.560476) (xy 127.2413 -431.948082)
			(xy 127.239756 -431.93359) (xy 127.238104 -431.90449) (xy 127.237998 -431.889916) (xy 115.605768 -431.889916)
			(xy 115.596243 -431.956613) (xy 115.564055 -432.124765) (xy 115.523953 -432.291207) (xy 115.476027 -432.455567)
			(xy 115.420385 -432.617477) (xy 115.35715 -432.776576) (xy 115.286464 -432.932508) (xy 115.208486 -433.084923)
			(xy 115.12339 -433.233482) (xy 115.031365 -433.377851) (xy 114.932619 -433.517709) (xy 114.82737 -433.652742)
			(xy 114.715856 -433.782648) (xy 114.598325 -433.907137) (xy 114.47504 -434.02593) (xy 114.346277 -434.138763)
			(xy 114.212324 -434.245381) (xy 114.07348 -434.345548) (xy 113.930056 -434.439039) (xy 113.843394 -434.48986)
			(xy 125.218444 -434.48986) (xy 125.218914 -434.457303) (xy 125.226865 -434.392677) (xy 125.242654 -434.329506)
			(xy 125.266045 -434.268739) (xy 125.296688 -434.211286) (xy 125.334122 -434.158009) (xy 125.377788 -434.109706)
			(xy 125.402086 -434.088032) (xy 125.482858 -433.923186) (xy 125.487554 -433.912668) (xy 125.491043 -433.889911)
			(xy 125.487561 -433.867153) (xy 125.482858 -433.856638) (xy 125.402086 -433.691792) (xy 125.377801 -433.670106)
			(xy 125.334148 -433.621797) (xy 125.296723 -433.568519) (xy 125.266085 -433.511068) (xy 125.242694 -433.450305)
			(xy 125.2269 -433.38714) (xy 125.21894 -433.322519) (xy 125.218444 -433.289964) (xy 125.219136 -433.250837)
			(xy 125.230616 -433.173431) (xy 125.241304 -433.135786) (xy 125.241304 -432.618896) (xy 125.241713 -432.606787)
			(xy 125.249214 -432.583758) (xy 125.263477 -432.564185) (xy 125.283101 -432.549991) (xy 125.306155 -432.542571)
			(xy 125.318266 -432.542188) (xy 126.258066 -432.542188) (xy 126.270159 -432.542637) (xy 126.293166 -432.55009)
			(xy 126.312751 -432.56428) (xy 126.327001 -432.583821) (xy 126.334525 -432.606805) (xy 126.335028 -432.618896)
			(xy 126.335028 -435.16042) (xy 126.334601 -435.172527) (xy 126.3271 -435.19555) (xy 126.31284 -435.215121)
			(xy 126.293222 -435.229316) (xy 126.270174 -435.236741) (xy 126.258066 -435.237128) (xy 125.318266 -435.237128)
			(xy 125.306171 -435.236721) (xy 125.283164 -435.229251) (xy 125.263582 -435.21505) (xy 125.249334 -435.195502)
			(xy 125.241808 -435.172513) (xy 125.241304 -435.16042) (xy 125.241304 -434.644038) (xy 125.230608 -434.606395)
			(xy 125.219137 -434.528987) (xy 125.218444 -434.48986) (xy 113.843394 -434.48986) (xy 113.782372 -434.525645)
			(xy 113.630759 -434.605172) (xy 113.475556 -434.677443) (xy 113.396522 -434.710332) (xy 113.382851 -434.716444)
			(xy 113.359598 -434.735293) (xy 113.342813 -434.760077) (xy 113.333939 -434.788665) (xy 113.333741 -434.818598)
			(xy 113.342235 -434.847301) (xy 113.358691 -434.872305) (xy 113.369852 -434.88229) (xy 113.419298 -434.924299)
			(xy 113.513487 -435.013553) (xy 113.601975 -435.108462) (xy 113.684422 -435.208663) (xy 113.760513 -435.313772)
			(xy 113.829956 -435.423387) (xy 113.866512 -435.489858) (xy 127.21844 -435.489858) (xy 127.21891 -435.457301)
			(xy 127.226861 -435.392675) (xy 127.24265 -435.329504) (xy 127.266042 -435.268737) (xy 127.296684 -435.211284)
			(xy 127.334119 -435.158007) (xy 127.377784 -435.109705) (xy 127.402082 -435.08803) (xy 127.482854 -434.923184)
			(xy 127.487552 -434.912666) (xy 127.49104 -434.889909) (xy 127.487557 -434.867151) (xy 127.482854 -434.856636)
			(xy 127.402082 -434.69179) (xy 127.377795 -434.670106) (xy 127.334142 -434.621797) (xy 127.296717 -434.568518)
			(xy 127.26608 -434.511067) (xy 127.24269 -434.450303) (xy 127.226896 -434.387138) (xy 127.218936 -434.322517)
			(xy 127.21844 -434.289962) (xy 127.219132 -434.250835) (xy 127.230612 -434.173429) (xy 127.2413 -434.135784)
			(xy 127.2413 -433.618894) (xy 127.241806 -433.606783) (xy 127.24929 -433.583746) (xy 127.263525 -433.564148)
			(xy 127.283117 -433.549905) (xy 127.306151 -433.542411) (xy 127.318262 -433.541932) (xy 128.258062 -433.541932)
			(xy 128.270182 -433.542392) (xy 128.293239 -433.549873) (xy 128.312854 -433.564115) (xy 128.327107 -433.583722)
			(xy 128.334601 -433.606774) (xy 128.335024 -433.618894) (xy 128.335024 -434.48986) (xy 129.218436 -434.48986)
			(xy 129.218909 -434.457303) (xy 129.226859 -434.392677) (xy 129.242648 -434.329507) (xy 129.266039 -434.26874)
			(xy 129.296681 -434.211287) (xy 129.334115 -434.15801) (xy 129.37778 -434.109707) (xy 129.402078 -434.088032)
			(xy 129.48285 -433.923186) (xy 129.487547 -433.912668) (xy 129.491035 -433.889911) (xy 129.487553 -433.867153)
			(xy 129.48285 -433.856638) (xy 129.402078 -433.691792) (xy 129.377811 -433.670085) (xy 129.334154 -433.621783)
			(xy 129.296724 -433.568509) (xy 129.266083 -433.511061) (xy 129.242689 -433.450301) (xy 129.226893 -433.387138)
			(xy 129.218932 -433.322518) (xy 129.218436 -433.289964) (xy 129.219128 -433.250837) (xy 129.230608 -433.173431)
			(xy 129.241296 -433.135786) (xy 129.241296 -432.618896) (xy 129.241713 -432.606787) (xy 129.249213 -432.583761)
			(xy 129.263474 -432.564188) (xy 129.283096 -432.549993) (xy 129.306148 -432.542572) (xy 129.318258 -432.542188)
			(xy 130.258058 -432.542188) (xy 130.27015 -432.542644) (xy 130.293158 -432.550095) (xy 130.312742 -432.564283)
			(xy 130.326993 -432.583822) (xy 130.334517 -432.606805) (xy 130.33502 -432.618896) (xy 130.33502 -435.16042)
			(xy 130.334601 -435.172528) (xy 130.327099 -435.195552) (xy 130.312837 -435.215123) (xy 130.293217 -435.229318)
			(xy 130.270167 -435.236742) (xy 130.258058 -435.237128) (xy 129.318258 -435.237128) (xy 129.306163 -435.236728)
			(xy 129.283156 -435.229256) (xy 129.263574 -435.215053) (xy 129.249326 -435.195504) (xy 129.2418 -435.172514)
			(xy 129.241296 -435.16042) (xy 129.241296 -434.644038) (xy 129.2306 -434.606395) (xy 129.219129 -434.528987)
			(xy 129.218436 -434.48986) (xy 128.335024 -434.48986) (xy 128.335024 -435.489858) (xy 131.218432 -435.489858)
			(xy 131.218905 -435.457301) (xy 131.226855 -435.392675) (xy 131.242645 -435.329505) (xy 131.266036 -435.268738)
			(xy 131.296678 -435.211285) (xy 131.334112 -435.158008) (xy 131.377776 -435.109705) (xy 131.402074 -435.08803)
			(xy 131.482846 -434.923184) (xy 131.487544 -434.912667) (xy 131.491033 -434.889909) (xy 131.48755 -434.867151)
			(xy 131.482846 -434.856636) (xy 131.402074 -434.69179) (xy 131.377805 -434.670085) (xy 131.334148 -434.621782)
			(xy 131.296719 -434.568508) (xy 131.266078 -434.51106) (xy 131.242685 -434.450299) (xy 131.226889 -434.387136)
			(xy 131.218928 -434.322516) (xy 131.218432 -434.289962) (xy 131.219124 -434.250835) (xy 131.230604 -434.173429)
			(xy 131.241292 -434.135784) (xy 131.241292 -433.618894) (xy 131.241806 -433.606784) (xy 131.249289 -433.583748)
			(xy 131.263522 -433.564151) (xy 131.283112 -433.549908) (xy 131.306144 -433.542412) (xy 131.318254 -433.541932)
			(xy 132.258054 -433.541932) (xy 132.270174 -433.542399) (xy 132.29323 -433.549878) (xy 132.312846 -433.564117)
			(xy 132.327098 -433.583723) (xy 132.334593 -433.606775) (xy 132.335016 -433.618894) (xy 132.335016 -434.48986)
			(xy 133.218428 -434.48986) (xy 133.218903 -434.457303) (xy 133.226854 -434.392677) (xy 133.242643 -434.329507)
			(xy 133.266033 -434.26874) (xy 133.296675 -434.211287) (xy 133.334108 -434.15801) (xy 133.377772 -434.109707)
			(xy 133.40207 -434.088032) (xy 133.482842 -433.923186) (xy 133.487539 -433.912668) (xy 133.491028 -433.889911)
			(xy 133.487546 -433.867153) (xy 133.482842 -433.856638) (xy 133.40207 -433.691792) (xy 133.377802 -433.670087)
			(xy 133.334145 -433.621784) (xy 133.296716 -433.56851) (xy 133.266075 -433.511062) (xy 133.242681 -433.450301)
			(xy 133.226885 -433.387138) (xy 133.218924 -433.322518) (xy 133.218428 -433.289964) (xy 133.219121 -433.250837)
			(xy 133.2306 -433.173431) (xy 133.241288 -433.135786) (xy 133.241288 -432.618896) (xy 133.241713 -432.606788)
			(xy 133.249212 -432.583763) (xy 133.263472 -432.564191) (xy 133.283091 -432.549996) (xy 133.306141 -432.542573)
			(xy 133.31825 -432.542188) (xy 134.25805 -432.542188) (xy 134.270142 -432.542651) (xy 134.293149 -432.5501)
			(xy 134.312734 -432.564285) (xy 134.326984 -432.583823) (xy 134.334509 -432.606806) (xy 134.335012 -432.618896)
			(xy 134.335012 -435.16042) (xy 134.334601 -435.172529) (xy 134.327097 -435.195555) (xy 134.312834 -435.215126)
			(xy 134.293212 -435.229321) (xy 134.27016 -435.236743) (xy 134.25805 -435.237128) (xy 133.31825 -435.237128)
			(xy 133.30616 -435.23665) (xy 133.283155 -435.229203) (xy 133.263572 -435.21502) (xy 133.249321 -435.195487)
			(xy 133.241793 -435.172508) (xy 133.241288 -435.16042) (xy 133.241288 -434.644038) (xy 133.230592 -434.606395)
			(xy 133.219121 -434.528987) (xy 133.218428 -434.48986) (xy 132.335016 -434.48986) (xy 132.335016 -435.489858)
			(xy 135.218424 -435.489858) (xy 135.218899 -435.457301) (xy 135.22685 -435.392675) (xy 135.242639 -435.329505)
			(xy 135.266029 -435.268738) (xy 135.296671 -435.211286) (xy 135.334105 -435.158008) (xy 135.377768 -435.109705)
			(xy 135.402066 -435.08803) (xy 135.482838 -434.923184) (xy 135.487537 -434.912667) (xy 135.491026 -434.889909)
			(xy 135.487542 -434.867151) (xy 135.482838 -434.856636) (xy 135.402066 -434.69179) (xy 135.377796 -434.670087)
			(xy 135.334139 -434.621784) (xy 135.29671 -434.568509) (xy 135.26607 -434.511061) (xy 135.242676 -434.4503)
			(xy 135.226881 -434.387136) (xy 135.21892 -434.322516) (xy 135.218424 -434.289962) (xy 135.219116 -434.250835)
			(xy 135.230596 -434.173429) (xy 135.241284 -434.135784) (xy 135.241284 -433.618894) (xy 135.241656 -433.606766)
			(xy 135.249155 -433.5837) (xy 135.263418 -433.564081) (xy 135.283046 -433.549831) (xy 135.306118 -433.542348)
			(xy 135.318246 -433.541932) (xy 136.258046 -433.541932) (xy 136.270162 -433.542372) (xy 136.293206 -433.549872)
			(xy 136.312807 -433.564122) (xy 136.327047 -433.58373) (xy 136.334534 -433.606777) (xy 136.335008 -433.618894)
			(xy 136.335008 -434.48986) (xy 137.21842 -434.48986) (xy 137.218898 -434.457303) (xy 137.226848 -434.392678)
			(xy 137.242637 -434.329508) (xy 137.266027 -434.268741) (xy 137.296668 -434.211288) (xy 137.334101 -434.158011)
			(xy 137.377765 -434.109707) (xy 137.402062 -434.088032) (xy 137.482834 -433.923186) (xy 137.487531 -433.912668)
			(xy 137.491021 -433.889911) (xy 137.487538 -433.867153) (xy 137.482834 -433.856638) (xy 137.402062 -433.691792)
			(xy 137.377792 -433.670089) (xy 137.334135 -433.621785) (xy 137.296707 -433.568511) (xy 137.266066 -433.511062)
			(xy 137.242673 -433.450302) (xy 137.226877 -433.387138) (xy 137.218916 -433.322518) (xy 137.21842 -433.289964)
			(xy 137.219113 -433.250837) (xy 137.230592 -433.173431) (xy 137.24128 -433.135786) (xy 137.24128 -432.618896)
			(xy 137.241712 -432.606789) (xy 137.249211 -432.583765) (xy 137.263469 -432.564194) (xy 137.283086 -432.549998)
			(xy 137.306134 -432.542574) (xy 137.318242 -432.542188) (xy 138.258042 -432.542188) (xy 138.270139 -432.542572)
			(xy 138.293149 -432.550047) (xy 138.312732 -432.564253) (xy 138.326979 -432.583806) (xy 138.334502 -432.606801)
			(xy 138.335004 -432.618896) (xy 138.335004 -435.16042) (xy 138.334601 -435.17253) (xy 138.327096 -435.195557)
			(xy 138.312831 -435.215129) (xy 138.293207 -435.229323) (xy 138.270153 -435.236744) (xy 138.258042 -435.237128)
			(xy 137.318242 -435.237128) (xy 137.306151 -435.236656) (xy 137.283147 -435.229207) (xy 137.263563 -435.215023)
			(xy 137.249313 -435.195488) (xy 137.241785 -435.172509) (xy 137.24128 -435.16042) (xy 137.24128 -434.644038)
			(xy 137.230583 -434.606395) (xy 137.219112 -434.528987) (xy 137.21842 -434.48986) (xy 136.335008 -434.48986)
			(xy 136.335008 -435.489858) (xy 139.218416 -435.489858) (xy 139.218894 -435.457301) (xy 139.226845 -435.392676)
			(xy 139.242633 -435.329506) (xy 139.266023 -435.268739) (xy 139.296665 -435.211286) (xy 139.334097 -435.158009)
			(xy 139.377761 -435.109705) (xy 139.402058 -435.08803) (xy 139.48283 -434.923184) (xy 139.487529 -434.912667)
			(xy 139.491018 -434.889909) (xy 139.487534 -434.86715) (xy 139.48283 -434.856636) (xy 139.402058 -434.69179)
			(xy 139.377786 -434.670089) (xy 139.33413 -434.621785) (xy 139.296701 -434.56851) (xy 139.266061 -434.511061)
			(xy 139.242668 -434.4503) (xy 139.226873 -434.387136) (xy 139.218912 -434.322516) (xy 139.218416 -434.289962)
			(xy 139.219105 -434.250835) (xy 139.230586 -434.173429) (xy 139.241276 -434.135784) (xy 139.241276 -433.618894)
			(xy 139.241656 -433.606767) (xy 139.249154 -433.583702) (xy 139.263415 -433.564084) (xy 139.283041 -433.549834)
			(xy 139.306111 -433.542349) (xy 139.318238 -433.541932) (xy 140.258038 -433.541932) (xy 140.270154 -433.542379)
			(xy 140.293197 -433.549876) (xy 140.312798 -433.564125) (xy 140.327038 -433.583731) (xy 140.334526 -433.606778)
			(xy 140.335 -433.618894) (xy 140.335 -434.48986) (xy 142.21841 -434.48986) (xy 142.218892 -434.457304)
			(xy 142.226842 -434.392678) (xy 142.24263 -434.329508) (xy 142.26602 -434.268742) (xy 142.29666 -434.211289)
			(xy 142.334092 -434.158011) (xy 142.377755 -434.109707) (xy 142.402052 -434.088032) (xy 142.482824 -433.923186)
			(xy 142.487522 -433.912668) (xy 142.491012 -433.889911) (xy 142.487529 -433.867152) (xy 142.482824 -433.856638)
			(xy 142.402052 -433.691792) (xy 142.37778 -433.670091) (xy 142.334124 -433.621787) (xy 142.296696 -433.568512)
			(xy 142.266055 -433.511063) (xy 142.242663 -433.450302) (xy 142.226867 -433.387138) (xy 142.218906 -433.322518)
			(xy 142.21841 -433.289964) (xy 142.219137 -433.250639) (xy 142.230742 -433.172849) (xy 142.241524 -433.135024)
			(xy 142.241524 -432.618896) (xy 142.24191 -432.60681) (xy 142.249382 -432.583822) (xy 142.263594 -432.564268)
			(xy 142.283154 -432.550066) (xy 142.306146 -432.542604) (xy 142.318232 -432.542188) (xy 143.258032 -432.542188)
			(xy 143.270108 -432.542637) (xy 143.293075 -432.550108) (xy 143.312612 -432.564308) (xy 143.326805 -432.58385)
			(xy 143.334268 -432.60682) (xy 143.33474 -432.618896) (xy 143.33474 -435.16042) (xy 143.334253 -435.172492)
			(xy 143.326789 -435.195455) (xy 143.312597 -435.214989) (xy 143.293065 -435.229184) (xy 143.270104 -435.236651)
			(xy 143.258032 -435.237128) (xy 142.318232 -435.237128) (xy 142.306153 -435.23666) (xy 142.283175 -435.229204)
			(xy 142.263626 -435.215011) (xy 142.24942 -435.195472) (xy 142.241948 -435.172499) (xy 142.241524 -435.16042)
			(xy 142.241524 -434.6448) (xy 142.230717 -434.606981) (xy 142.219115 -434.529187) (xy 142.21841 -434.48986)
			(xy 140.335 -434.48986) (xy 140.335 -435.489858) (xy 144.218406 -435.489858) (xy 144.218888 -435.457302)
			(xy 144.226838 -435.392676) (xy 144.242626 -435.329506) (xy 144.266016 -435.26874) (xy 144.296657 -435.211287)
			(xy 144.334089 -435.158009) (xy 144.377751 -435.109705) (xy 144.402048 -435.08803) (xy 144.48282 -434.923184)
			(xy 144.48752 -434.912667) (xy 144.491009 -434.889909) (xy 144.487525 -434.86715) (xy 144.48282 -434.856636)
			(xy 144.402048 -434.69179) (xy 144.377774 -434.670091) (xy 144.334118 -434.621786) (xy 144.29669 -434.568511)
			(xy 144.266051 -434.511062) (xy 144.242658 -434.450301) (xy 144.226863 -434.387137) (xy 144.218902 -434.322516)
			(xy 144.218406 -434.289962) (xy 144.219132 -434.250637) (xy 144.230738 -434.172847) (xy 144.24152 -434.135022)
			(xy 144.24152 -433.618894) (xy 144.242002 -433.606806) (xy 144.249458 -433.583809) (xy 144.263641 -433.564231)
			(xy 144.28317 -433.54998) (xy 144.306142 -433.542444) (xy 144.318228 -433.541932) (xy 145.258028 -433.541932)
			(xy 145.270142 -433.542293) (xy 145.293175 -433.549804) (xy 145.312751 -433.564079) (xy 145.326943 -433.583714)
			(xy 145.334357 -433.606779) (xy 145.334736 -433.618894) (xy 145.334736 -434.48986) (xy 146.218402 -434.48986)
			(xy 146.218886 -434.457304) (xy 146.226836 -434.392678) (xy 146.242624 -434.329509) (xy 146.266014 -434.268742)
			(xy 146.296654 -434.211289) (xy 146.334085 -434.158012) (xy 146.377747 -434.109707) (xy 146.402044 -434.088032)
			(xy 146.482816 -433.923186) (xy 146.487514 -433.912668) (xy 146.491005 -433.889911) (xy 146.487521 -433.867152)
			(xy 146.482816 -433.856638) (xy 146.402044 -433.691792) (xy 146.37777 -433.670093) (xy 146.334115 -433.621788)
			(xy 146.296687 -433.568513) (xy 146.266047 -433.511064) (xy 146.242654 -433.450302) (xy 146.226859 -433.387139)
			(xy 146.218898 -433.322518) (xy 146.218402 -433.289964) (xy 146.219129 -433.250639) (xy 146.230734 -433.172849)
			(xy 146.241516 -433.135024) (xy 146.241516 -432.618896) (xy 146.241909 -432.606811) (xy 146.249381 -432.583824)
			(xy 146.263591 -432.564271) (xy 146.283149 -432.550068) (xy 146.306138 -432.542605) (xy 146.318224 -432.542188)
			(xy 147.258024 -432.542188) (xy 147.270099 -432.542644) (xy 147.293067 -432.550113) (xy 147.312603 -432.564311)
			(xy 147.326797 -432.583851) (xy 147.334259 -432.606821) (xy 147.334732 -432.618896) (xy 147.334732 -435.16042)
			(xy 147.334253 -435.172493) (xy 147.326788 -435.195457) (xy 147.312594 -435.214991) (xy 147.29306 -435.229186)
			(xy 147.270097 -435.236652) (xy 147.258024 -435.237128) (xy 146.318224 -435.237128) (xy 146.306145 -435.236667)
			(xy 146.283166 -435.229209) (xy 146.263617 -435.215014) (xy 146.249412 -435.195473) (xy 146.24194 -435.172499)
			(xy 146.241516 -435.16042) (xy 146.241516 -434.6448) (xy 146.230709 -434.606981) (xy 146.219107 -434.529187)
			(xy 146.218402 -434.48986) (xy 145.334736 -434.48986) (xy 145.334736 -435.489858) (xy 148.218398 -435.489858)
			(xy 148.218882 -435.457302) (xy 148.226832 -435.392676) (xy 148.242621 -435.329507) (xy 148.26601 -435.26874)
			(xy 148.29665 -435.211287) (xy 148.334082 -435.15801) (xy 148.377743 -435.109706) (xy 148.40204 -435.08803)
			(xy 148.482812 -434.923184) (xy 148.487512 -434.912667) (xy 148.491002 -434.889909) (xy 148.487517 -434.86715)
			(xy 148.482812 -434.856636) (xy 148.40204 -434.69179) (xy 148.377765 -434.670093) (xy 148.334109 -434.621788)
			(xy 148.296681 -434.568512) (xy 148.266042 -434.511063) (xy 148.24265 -434.450301) (xy 148.226855 -434.387137)
			(xy 148.218894 -434.322516) (xy 148.218398 -434.289962) (xy 148.219125 -434.250637) (xy 148.23073 -434.172847)
			(xy 148.241512 -434.135022) (xy 148.241512 -433.618894) (xy 148.242002 -433.606807) (xy 148.249457 -433.583811)
			(xy 148.263639 -433.564234) (xy 148.283165 -433.549982) (xy 148.306135 -433.542445) (xy 148.31822 -433.541932)
			(xy 149.25802 -433.541932) (xy 149.270133 -433.5423) (xy 149.293167 -433.549808) (xy 149.312742 -433.564081)
			(xy 149.326935 -433.583715) (xy 149.334349 -433.606779) (xy 149.334728 -433.618894) (xy 149.334728 -434.48986)
			(xy 150.218394 -434.48986) (xy 150.218847 -434.457302) (xy 150.226798 -434.392675) (xy 150.242589 -434.329503)
			(xy 150.265983 -434.268735) (xy 150.296629 -434.211283) (xy 150.334067 -434.158006) (xy 150.377736 -434.109705)
			(xy 150.402036 -434.088032) (xy 150.482808 -433.923186) (xy 150.487506 -433.912668) (xy 150.490997 -433.889911)
			(xy 150.487513 -433.867152) (xy 150.482808 -433.856638) (xy 150.402036 -433.691792) (xy 150.377761 -433.670095)
			(xy 150.334105 -433.62179) (xy 150.296678 -433.568513) (xy 150.266038 -433.511064) (xy 150.242646 -433.450303)
			(xy 150.226851 -433.387139) (xy 150.21889 -433.322518) (xy 150.218394 -433.289964) (xy 150.219121 -433.250639)
			(xy 150.230726 -433.172849) (xy 150.241508 -433.135024) (xy 150.241508 -432.618896) (xy 150.241909 -432.606811)
			(xy 150.24938 -432.583826) (xy 150.263588 -432.564274) (xy 150.283144 -432.550071) (xy 150.306131 -432.542606)
			(xy 150.318216 -432.542188) (xy 151.258016 -432.542188) (xy 151.270091 -432.542651) (xy 151.293058 -432.550117)
			(xy 151.312594 -432.564314) (xy 151.326788 -432.583853) (xy 151.334251 -432.606821) (xy 151.334724 -432.618896)
			(xy 151.334724 -435.16042) (xy 151.334253 -435.172494) (xy 151.326787 -435.195459) (xy 151.312591 -435.214994)
			(xy 151.293055 -435.229189) (xy 151.27009 -435.236654) (xy 151.258016 -435.237128) (xy 150.318216 -435.237128)
			(xy 150.306144 -435.236622) (xy 150.283181 -435.229167) (xy 150.263645 -435.21498) (xy 150.24945 -435.195451)
			(xy 150.241983 -435.172492) (xy 150.241508 -435.16042) (xy 150.241508 -434.6448) (xy 150.230701 -434.606981)
			(xy 150.219099 -434.529187) (xy 150.218394 -434.48986) (xy 149.334728 -434.48986) (xy 149.334728 -435.489858)
			(xy 152.21839 -435.489858) (xy 152.218843 -435.4573) (xy 152.226794 -435.392673) (xy 152.242585 -435.329501)
			(xy 152.265979 -435.268734) (xy 152.296625 -435.211281) (xy 152.334063 -435.158004) (xy 152.377732 -435.109703)
			(xy 152.402032 -435.08803) (xy 152.482804 -434.923184) (xy 152.487504 -434.912667) (xy 152.490995 -434.889909)
			(xy 152.487509 -434.86715) (xy 152.482804 -434.856636) (xy 152.402032 -434.69179) (xy 152.377755 -434.670095)
			(xy 152.3341 -434.621789) (xy 152.296673 -434.568512) (xy 152.266033 -434.511063) (xy 152.242641 -434.450301)
			(xy 152.226847 -434.387137) (xy 152.218886 -434.322516) (xy 152.21839 -434.289962) (xy 152.219117 -434.250637)
			(xy 152.230722 -434.172847) (xy 152.241504 -434.135022) (xy 152.241504 -433.618894) (xy 152.242002 -433.606808)
			(xy 152.249456 -433.583813) (xy 152.263636 -433.564236) (xy 152.28316 -433.549985) (xy 152.306128 -433.542447)
			(xy 152.318212 -433.541932) (xy 153.258012 -433.541932) (xy 153.270125 -433.542306) (xy 153.293158 -433.549813)
			(xy 153.312734 -433.564084) (xy 153.326927 -433.583717) (xy 153.334341 -433.60678) (xy 153.33472 -433.618894)
			(xy 153.33472 -434.48986) (xy 154.218386 -434.48986) (xy 154.218842 -434.457302) (xy 154.226793 -434.392675)
			(xy 154.242584 -434.329504) (xy 154.265977 -434.268736) (xy 154.296622 -434.211283) (xy 154.33406 -434.158007)
			(xy 154.377728 -434.109705) (xy 154.402028 -434.088032) (xy 154.4828 -433.923186) (xy 154.487499 -433.912668)
			(xy 154.49099 -433.889911) (xy 154.487505 -433.867152) (xy 154.4828 -433.856638) (xy 154.402028 -433.691792)
			(xy 154.377751 -433.670097) (xy 154.334096 -433.621791) (xy 154.296669 -433.568514) (xy 154.26603 -433.511065)
			(xy 154.242638 -433.450303) (xy 154.226843 -433.387139) (xy 154.218882 -433.322518) (xy 154.218386 -433.289964)
			(xy 154.219114 -433.250639) (xy 154.230718 -433.172849) (xy 154.2415 -433.135024) (xy 154.2415 -432.618896)
			(xy 154.241909 -432.606812) (xy 154.249379 -432.583828) (xy 154.263586 -432.564277) (xy 154.283139 -432.550073)
			(xy 154.306124 -432.542607) (xy 154.318208 -432.542188) (xy 155.258008 -432.542188) (xy 155.270083 -432.542657)
			(xy 155.293049 -432.550122) (xy 155.312586 -432.564317) (xy 155.32678 -432.583854) (xy 155.334243 -432.606821)
			(xy 155.334716 -432.618896) (xy 155.334716 -433.130695) (xy 197.035917 -433.130695) (xy 197.035917 -432.953425)
			(xy 197.04387 -432.776334) (xy 197.059761 -432.599778) (xy 197.083556 -432.424113) (xy 197.115209 -432.249692)
			(xy 197.154655 -432.076867) (xy 197.201815 -431.905986) (xy 197.256594 -431.737392) (xy 197.318882 -431.571427)
			(xy 197.388554 -431.408422) (xy 197.465468 -431.248708) (xy 197.549471 -431.092605) (xy 197.640392 -430.940428)
			(xy 197.738049 -430.792484) (xy 197.842246 -430.64907) (xy 197.952772 -430.510475) (xy 198.069404 -430.376978)
			(xy 198.191909 -430.248849) (xy 198.320038 -430.126344) (xy 198.453535 -430.009712) (xy 198.59213 -429.899186)
			(xy 198.735544 -429.794989) (xy 198.883488 -429.697332) (xy 199.035665 -429.606411) (xy 199.191768 -429.522408)
			(xy 199.351482 -429.445494) (xy 199.514487 -429.375822) (xy 199.680452 -429.313534) (xy 199.849046 -429.258755)
			(xy 200.019927 -429.211595) (xy 200.192752 -429.172149) (xy 200.367173 -429.140496) (xy 200.542838 -429.116701)
			(xy 200.719394 -429.10081) (xy 200.896485 -429.092857) (xy 201.073755 -429.092857) (xy 201.250846 -429.10081)
			(xy 201.427402 -429.116701) (xy 201.603067 -429.140496) (xy 201.777488 -429.172149) (xy 201.950313 -429.211595)
			(xy 202.121194 -429.258755) (xy 202.289788 -429.313534) (xy 202.455753 -429.375822) (xy 202.618758 -429.445494)
			(xy 202.778472 -429.522408) (xy 202.934575 -429.606411) (xy 203.086752 -429.697332) (xy 203.234696 -429.794989)
			(xy 203.37811 -429.899186) (xy 203.516705 -430.009712) (xy 203.650202 -430.126344) (xy 203.778331 -430.248849)
			(xy 203.900836 -430.376978) (xy 204.017468 -430.510475) (xy 204.127994 -430.64907) (xy 204.232191 -430.792484)
			(xy 204.329848 -430.940428) (xy 204.420769 -431.092605) (xy 204.504772 -431.248708) (xy 204.581686 -431.408422)
			(xy 204.651358 -431.571427) (xy 204.713646 -431.737392) (xy 204.768425 -431.905986) (xy 204.815585 -432.076867)
			(xy 204.855031 -432.249692) (xy 204.886684 -432.424113) (xy 204.910479 -432.599778) (xy 204.92637 -432.776334)
			(xy 204.934323 -432.953425) (xy 204.93482 -433.04206) (xy 204.934323 -433.130695) (xy 204.92637 -433.307786)
			(xy 204.910479 -433.484342) (xy 204.886684 -433.660007) (xy 204.855031 -433.834428) (xy 204.815585 -434.007253)
			(xy 204.768425 -434.178134) (xy 204.713646 -434.346728) (xy 204.651358 -434.512693) (xy 204.581686 -434.675698)
			(xy 204.504772 -434.835412) (xy 204.420769 -434.991515) (xy 204.329848 -435.143692) (xy 204.232191 -435.291636)
			(xy 204.127994 -435.43505) (xy 204.057751 -435.523132) (xy 205.85684 -435.523132) (xy 205.85684 -415.567368)
			(xy 205.857337 -415.542419) (xy 205.865152 -415.493137) (xy 205.88057 -415.44568) (xy 205.903211 -415.401214)
			(xy 205.93252 -415.360831) (xy 205.949804 -415.342832) (xy 206.989172 -414.303464) (xy 207.007169 -414.286175)
			(xy 207.047542 -414.256843) (xy 207.092007 -414.234188) (xy 207.139468 -414.218769) (xy 207.188756 -414.210963)
			(xy 207.213708 -414.2105) (xy 232.807256 -414.2105) (xy 239.488472 -407.529284) (xy 239.506473 -407.512)
			(xy 239.546848 -407.482676) (xy 239.591312 -407.460027) (xy 239.638771 -407.444612) (xy 239.688058 -407.436808)
			(xy 239.713008 -407.43632) (xy 280.100532 -407.43632) (xy 280.125481 -407.436823) (xy 280.174763 -407.444637)
			(xy 280.222219 -407.460054) (xy 280.266685 -407.482694) (xy 280.307069 -407.512001) (xy 280.325068 -407.529284)
			(xy 280.739596 -407.943812) (xy 280.756896 -407.961798) (xy 280.786219 -408.002177) (xy 280.808865 -408.046645)
			(xy 280.824276 -408.094108) (xy 280.832075 -408.143397) (xy 280.83256 -408.168348) (xy 280.83256 -410.057453)
			(xy 304.945246 -410.057453) (xy 304.945246 -410.002947) (xy 304.953003 -409.948996) (xy 304.968358 -409.896698)
			(xy 304.991001 -409.847117) (xy 305.020468 -409.801263) (xy 305.056162 -409.76007) (xy 305.097354 -409.724375)
			(xy 305.143207 -409.694906) (xy 305.192786 -409.672263) (xy 305.245084 -409.656905) (xy 305.299035 -409.649147)
			(xy 305.326288 -409.64866) (xy 306.189888 -409.64866) (xy 306.217139 -409.649186) (xy 306.271087 -409.656941)
			(xy 306.323382 -409.672295) (xy 306.372959 -409.694935) (xy 306.41881 -409.7244) (xy 306.460001 -409.760091)
			(xy 306.495693 -409.80128) (xy 306.525159 -409.84713) (xy 306.547801 -409.896707) (xy 306.563156 -409.949001)
			(xy 306.570913 -410.002949) (xy 306.570913 -410.057451) (xy 306.570912 -410.057456) (xy 308.008423 -410.057456)
			(xy 308.008423 -410.002944) (xy 308.016181 -409.948986) (xy 308.03154 -409.896681) (xy 308.054187 -409.847095)
			(xy 308.08366 -409.801236) (xy 308.119359 -409.76004) (xy 308.160559 -409.724343) (xy 308.206419 -409.694873)
			(xy 308.256007 -409.67223) (xy 308.308313 -409.656875) (xy 308.362272 -409.649121) (xy 308.389528 -409.64866)
			(xy 309.253128 -409.64866) (xy 309.280376 -409.649212) (xy 309.334316 -409.656971) (xy 309.386603 -409.672327)
			(xy 309.436172 -409.694968) (xy 309.482015 -409.724433) (xy 309.523199 -409.760121) (xy 309.558884 -409.801307)
			(xy 309.588345 -409.847152) (xy 309.610982 -409.896724) (xy 309.626335 -409.949012) (xy 309.63409 -410.002952)
			(xy 309.63409 -410.057448) (xy 309.634089 -410.057452) (xy 311.071746 -410.057452) (xy 311.071746 -410.002948)
			(xy 311.079502 -409.948998) (xy 311.094857 -409.896702) (xy 311.117498 -409.847123) (xy 311.146963 -409.80127)
			(xy 311.182654 -409.760077) (xy 311.223844 -409.724383) (xy 311.269695 -409.694913) (xy 311.319272 -409.672268)
			(xy 311.371567 -409.656909) (xy 311.425516 -409.649148) (xy 311.452768 -409.64866) (xy 312.316368 -409.64866)
			(xy 312.34362 -409.649185) (xy 312.39757 -409.656938) (xy 312.449867 -409.67229) (xy 312.499447 -409.694928)
			(xy 312.545301 -409.724393) (xy 312.586494 -409.760084) (xy 312.622188 -409.801274) (xy 312.651656 -409.847125)
			(xy 312.674299 -409.896703) (xy 312.689655 -409.948999) (xy 312.697413 -410.002948) (xy 312.697413 -410.057452)
			(xy 312.697412 -410.057456) (xy 314.134923 -410.057456) (xy 314.134923 -410.002944) (xy 314.142681 -409.948988)
			(xy 314.158039 -409.896685) (xy 314.180684 -409.8471) (xy 314.210155 -409.801243) (xy 314.245852 -409.760047)
			(xy 314.287049 -409.72435) (xy 314.332907 -409.69488) (xy 314.382493 -409.672236) (xy 314.434796 -409.656879)
			(xy 314.488752 -409.649122) (xy 314.516008 -409.64866) (xy 315.379608 -409.64866) (xy 315.406857 -409.649211)
			(xy 315.460799 -409.656968) (xy 315.513088 -409.672322) (xy 315.56266 -409.694962) (xy 315.608506 -409.724426)
			(xy 315.649691 -409.760114) (xy 315.685379 -409.801301) (xy 315.714842 -409.847147) (xy 315.737481 -409.896719)
			(xy 315.752834 -409.949009) (xy 315.76059 -410.002951) (xy 315.76059 -410.057449) (xy 315.760589 -410.057457)
			(xy 317.198123 -410.057457) (xy 317.198123 -410.002943) (xy 317.205882 -409.948983) (xy 317.221242 -409.896677)
			(xy 317.24389 -409.847089) (xy 317.273365 -409.80123) (xy 317.309066 -409.760033) (xy 317.350268 -409.724336)
			(xy 317.396131 -409.694867) (xy 317.445722 -409.672225) (xy 317.49803 -409.656872) (xy 317.551991 -409.64912)
			(xy 317.579248 -409.64866) (xy 318.442848 -409.64866) (xy 318.470095 -409.649213) (xy 318.524033 -409.656975)
			(xy 318.576317 -409.672333) (xy 318.625884 -409.694975) (xy 318.671725 -409.72444) (xy 318.712906 -409.760128)
			(xy 318.748589 -409.801314) (xy 318.778048 -409.847158) (xy 318.800684 -409.896728) (xy 318.816035 -409.949014)
			(xy 318.82379 -410.002953) (xy 318.82379 -410.057447) (xy 318.823789 -410.057453) (xy 320.261446 -410.057453)
			(xy 320.261446 -410.002947) (xy 320.269203 -409.948996) (xy 320.284558 -409.896698) (xy 320.307201 -409.847117)
			(xy 320.336668 -409.801263) (xy 320.372362 -409.76007) (xy 320.413554 -409.724375) (xy 320.459407 -409.694906)
			(xy 320.508986 -409.672263) (xy 320.561284 -409.656905) (xy 320.615235 -409.649147) (xy 320.642488 -409.64866)
			(xy 321.506088 -409.64866) (xy 321.533339 -409.649186) (xy 321.587287 -409.656941) (xy 321.639582 -409.672295)
			(xy 321.689159 -409.694935) (xy 321.73501 -409.7244) (xy 321.776201 -409.760091) (xy 321.811893 -409.80128)
			(xy 321.841359 -409.84713) (xy 321.864001 -409.896707) (xy 321.879356 -409.949001) (xy 321.887113 -410.002949)
			(xy 321.887113 -410.057451) (xy 321.887112 -410.057456) (xy 323.324623 -410.057456) (xy 323.324623 -410.002944)
			(xy 323.332381 -409.948986) (xy 323.34774 -409.896681) (xy 323.370387 -409.847095) (xy 323.39986 -409.801236)
			(xy 323.435559 -409.76004) (xy 323.476759 -409.724343) (xy 323.522619 -409.694873) (xy 323.572207 -409.67223)
			(xy 323.624513 -409.656875) (xy 323.678472 -409.649121) (xy 323.705728 -409.64866) (xy 324.569328 -409.64866)
			(xy 324.596576 -409.649212) (xy 324.650516 -409.656971) (xy 324.702803 -409.672327) (xy 324.752372 -409.694968)
			(xy 324.798215 -409.724433) (xy 324.839399 -409.760121) (xy 324.875084 -409.801307) (xy 324.904545 -409.847152)
			(xy 324.927182 -409.896724) (xy 324.942535 -409.949012) (xy 324.95029 -410.002952) (xy 324.95029 -410.057448)
			(xy 324.950289 -410.057452) (xy 326.387946 -410.057452) (xy 326.387946 -410.002948) (xy 326.395702 -409.948998)
			(xy 326.411057 -409.896702) (xy 326.433698 -409.847123) (xy 326.463163 -409.80127) (xy 326.498854 -409.760077)
			(xy 326.540044 -409.724383) (xy 326.585895 -409.694913) (xy 326.635472 -409.672268) (xy 326.687767 -409.656909)
			(xy 326.741716 -409.649148) (xy 326.768968 -409.64866) (xy 327.632568 -409.64866) (xy 327.65982 -409.649185)
			(xy 327.71377 -409.656938) (xy 327.766067 -409.67229) (xy 327.815647 -409.694928) (xy 327.861501 -409.724393)
			(xy 327.902694 -409.760084) (xy 327.938388 -409.801274) (xy 327.967856 -409.847125) (xy 327.990499 -409.896703)
			(xy 328.005855 -409.948999) (xy 328.013613 -410.002948) (xy 328.013613 -410.057452) (xy 328.013612 -410.057456)
			(xy 329.451123 -410.057456) (xy 329.451123 -410.002944) (xy 329.458881 -409.948988) (xy 329.474239 -409.896685)
			(xy 329.496884 -409.8471) (xy 329.526355 -409.801243) (xy 329.562052 -409.760047) (xy 329.603249 -409.72435)
			(xy 329.649107 -409.69488) (xy 329.698693 -409.672236) (xy 329.750996 -409.656879) (xy 329.804952 -409.649122)
			(xy 329.832208 -409.64866) (xy 330.695808 -409.64866) (xy 330.723057 -409.649211) (xy 330.776999 -409.656968)
			(xy 330.829288 -409.672322) (xy 330.87886 -409.694962) (xy 330.924706 -409.724426) (xy 330.965891 -409.760114)
			(xy 331.001579 -409.801301) (xy 331.031042 -409.847147) (xy 331.053681 -409.896719) (xy 331.069034 -409.949009)
			(xy 331.07679 -410.002951) (xy 331.07679 -410.057449) (xy 331.076789 -410.057457) (xy 332.514323 -410.057457)
			(xy 332.514323 -410.002943) (xy 332.522082 -409.948983) (xy 332.537442 -409.896677) (xy 332.56009 -409.847089)
			(xy 332.589565 -409.80123) (xy 332.625266 -409.760033) (xy 332.666468 -409.724336) (xy 332.712331 -409.694867)
			(xy 332.761922 -409.672225) (xy 332.81423 -409.656872) (xy 332.868191 -409.64912) (xy 332.895448 -409.64866)
			(xy 333.759048 -409.64866) (xy 333.786295 -409.649213) (xy 333.840233 -409.656975) (xy 333.892517 -409.672333)
			(xy 333.942084 -409.694975) (xy 333.987925 -409.72444) (xy 334.029106 -409.760128) (xy 334.064789 -409.801314)
			(xy 334.094248 -409.847158) (xy 334.116884 -409.896728) (xy 334.132235 -409.949014) (xy 334.13999 -410.002953)
			(xy 334.13999 -410.057447) (xy 334.139989 -410.057453) (xy 335.577646 -410.057453) (xy 335.577646 -410.002947)
			(xy 335.585403 -409.948996) (xy 335.600758 -409.896698) (xy 335.623401 -409.847117) (xy 335.652868 -409.801263)
			(xy 335.688562 -409.76007) (xy 335.729754 -409.724375) (xy 335.775607 -409.694906) (xy 335.825186 -409.672263)
			(xy 335.877484 -409.656905) (xy 335.931435 -409.649147) (xy 335.958688 -409.64866) (xy 336.822288 -409.64866)
			(xy 336.849539 -409.649186) (xy 336.903487 -409.656941) (xy 336.955782 -409.672295) (xy 337.005359 -409.694935)
			(xy 337.05121 -409.7244) (xy 337.092401 -409.760091) (xy 337.128093 -409.80128) (xy 337.157559 -409.84713)
			(xy 337.180201 -409.896707) (xy 337.195556 -409.949001) (xy 337.203313 -410.002949) (xy 337.203313 -410.057451)
			(xy 337.203312 -410.057456) (xy 338.640823 -410.057456) (xy 338.640823 -410.002944) (xy 338.648581 -409.948986)
			(xy 338.66394 -409.896681) (xy 338.686587 -409.847095) (xy 338.71606 -409.801236) (xy 338.751759 -409.76004)
			(xy 338.792959 -409.724343) (xy 338.838819 -409.694873) (xy 338.888407 -409.67223) (xy 338.940713 -409.656875)
			(xy 338.994672 -409.649121) (xy 339.021928 -409.64866) (xy 339.885528 -409.64866) (xy 339.912776 -409.649212)
			(xy 339.966716 -409.656971) (xy 340.019003 -409.672327) (xy 340.068572 -409.694968) (xy 340.114415 -409.724433)
			(xy 340.155599 -409.760121) (xy 340.191284 -409.801307) (xy 340.220745 -409.847152) (xy 340.243382 -409.896724)
			(xy 340.258735 -409.949012) (xy 340.26649 -410.002952) (xy 340.26649 -410.057448) (xy 340.266489 -410.057452)
			(xy 341.704146 -410.057452) (xy 341.704146 -410.002948) (xy 341.711902 -409.948998) (xy 341.727257 -409.896702)
			(xy 341.749898 -409.847123) (xy 341.779363 -409.80127) (xy 341.815054 -409.760077) (xy 341.856244 -409.724383)
			(xy 341.902095 -409.694913) (xy 341.951672 -409.672268) (xy 342.003967 -409.656909) (xy 342.057916 -409.649148)
			(xy 342.085168 -409.64866) (xy 342.948768 -409.64866) (xy 342.97602 -409.649185) (xy 343.02997 -409.656938)
			(xy 343.082267 -409.67229) (xy 343.131847 -409.694928) (xy 343.177701 -409.724393) (xy 343.218894 -409.760084)
			(xy 343.254588 -409.801274) (xy 343.284056 -409.847125) (xy 343.306699 -409.896703) (xy 343.322055 -409.948999)
			(xy 343.329813 -410.002948) (xy 343.329813 -410.057452) (xy 343.329812 -410.057456) (xy 344.767323 -410.057456)
			(xy 344.767323 -410.002944) (xy 344.775081 -409.948988) (xy 344.790439 -409.896685) (xy 344.813084 -409.8471)
			(xy 344.842555 -409.801243) (xy 344.878252 -409.760047) (xy 344.919449 -409.72435) (xy 344.965307 -409.69488)
			(xy 345.014893 -409.672236) (xy 345.067196 -409.656879) (xy 345.121152 -409.649122) (xy 345.148408 -409.64866)
			(xy 346.012008 -409.64866) (xy 346.039257 -409.649211) (xy 346.093199 -409.656968) (xy 346.145488 -409.672322)
			(xy 346.19506 -409.694962) (xy 346.240906 -409.724426) (xy 346.282091 -409.760114) (xy 346.317779 -409.801301)
			(xy 346.347242 -409.847147) (xy 346.369881 -409.896719) (xy 346.385234 -409.949009) (xy 346.39299 -410.002951)
			(xy 346.39299 -410.057449) (xy 346.392989 -410.057457) (xy 347.830523 -410.057457) (xy 347.830523 -410.002943)
			(xy 347.838282 -409.948983) (xy 347.853642 -409.896677) (xy 347.87629 -409.847089) (xy 347.905765 -409.80123)
			(xy 347.941466 -409.760033) (xy 347.982668 -409.724336) (xy 348.028531 -409.694867) (xy 348.078122 -409.672225)
			(xy 348.13043 -409.656872) (xy 348.184391 -409.64912) (xy 348.211648 -409.64866) (xy 349.075248 -409.64866)
			(xy 349.102495 -409.649213) (xy 349.156433 -409.656975) (xy 349.208717 -409.672333) (xy 349.258284 -409.694975)
			(xy 349.304125 -409.72444) (xy 349.345306 -409.760128) (xy 349.380989 -409.801314) (xy 349.410448 -409.847158)
			(xy 349.433084 -409.896728) (xy 349.448435 -409.949014) (xy 349.45619 -410.002953) (xy 349.45619 -410.057447)
			(xy 349.456189 -410.057453) (xy 350.893846 -410.057453) (xy 350.893846 -410.002947) (xy 350.901603 -409.948996)
			(xy 350.916958 -409.896698) (xy 350.939601 -409.847117) (xy 350.969068 -409.801263) (xy 351.004762 -409.76007)
			(xy 351.045954 -409.724375) (xy 351.091807 -409.694906) (xy 351.141386 -409.672263) (xy 351.193684 -409.656905)
			(xy 351.247635 -409.649147) (xy 351.274888 -409.64866) (xy 352.138488 -409.64866) (xy 352.165739 -409.649186)
			(xy 352.219687 -409.656941) (xy 352.271982 -409.672295) (xy 352.321559 -409.694935) (xy 352.36741 -409.7244)
			(xy 352.408601 -409.760091) (xy 352.444293 -409.80128) (xy 352.473759 -409.84713) (xy 352.496401 -409.896707)
			(xy 352.511756 -409.949001) (xy 352.519513 -410.002949) (xy 352.519513 -410.057451) (xy 352.519512 -410.057457)
			(xy 372.388023 -410.057457) (xy 372.388023 -410.002943) (xy 372.395781 -409.948985) (xy 372.41114 -409.896681)
			(xy 372.433787 -409.847094) (xy 372.46326 -409.801236) (xy 372.49896 -409.760039) (xy 372.54016 -409.724342)
			(xy 372.586021 -409.694872) (xy 372.635609 -409.67223) (xy 372.687915 -409.656875) (xy 372.741873 -409.649121)
			(xy 372.76913 -409.64866) (xy 373.63273 -409.64866) (xy 373.659978 -409.649212) (xy 373.713917 -409.656972)
			(xy 373.766204 -409.672328) (xy 373.815773 -409.694969) (xy 373.861616 -409.724434) (xy 373.902799 -409.760122)
			(xy 373.938484 -409.801308) (xy 373.967945 -409.847153) (xy 373.990583 -409.896724) (xy 374.005935 -409.949012)
			(xy 374.01369 -410.002952) (xy 374.01369 -410.057448) (xy 374.013689 -410.057452) (xy 375.451346 -410.057452)
			(xy 375.451346 -410.002948) (xy 375.459102 -409.948998) (xy 375.474457 -409.896701) (xy 375.497098 -409.847122)
			(xy 375.526564 -409.801269) (xy 375.562255 -409.760076) (xy 375.603445 -409.724382) (xy 375.649296 -409.694912)
			(xy 375.698873 -409.672268) (xy 375.751169 -409.656909) (xy 375.805118 -409.649148) (xy 375.83237 -409.64866)
			(xy 376.69597 -409.64866) (xy 376.723222 -409.649185) (xy 376.777172 -409.656938) (xy 376.829469 -409.67229)
			(xy 376.879048 -409.694929) (xy 376.924901 -409.724394) (xy 376.966094 -409.760084) (xy 377.001788 -409.801274)
			(xy 377.031257 -409.847125) (xy 377.053899 -409.896703) (xy 377.069256 -409.948999) (xy 377.077013 -410.002948)
			(xy 377.077013 -410.057452) (xy 377.077012 -410.057456) (xy 378.514523 -410.057456) (xy 378.514523 -410.002944)
			(xy 378.522281 -409.948988) (xy 378.537639 -409.896685) (xy 378.560284 -409.8471) (xy 378.589755 -409.801242)
			(xy 378.625453 -409.760046) (xy 378.66665 -409.724349) (xy 378.712509 -409.694879) (xy 378.762094 -409.672235)
			(xy 378.814398 -409.656879) (xy 378.868354 -409.649122) (xy 378.89561 -409.64866) (xy 379.75921 -409.64866)
			(xy 379.786458 -409.649211) (xy 379.840401 -409.656968) (xy 379.89269 -409.672323) (xy 379.942261 -409.694962)
			(xy 379.988107 -409.724426) (xy 380.029292 -409.760115) (xy 380.06498 -409.801301) (xy 380.094442 -409.847147)
			(xy 380.117081 -409.89672) (xy 380.132434 -409.949009) (xy 380.14019 -410.002952) (xy 380.14019 -410.057448)
			(xy 380.14019 -410.057451) (xy 381.577846 -410.057451) (xy 381.577846 -410.002949) (xy 381.585602 -409.949001)
			(xy 381.600955 -409.896706) (xy 381.623595 -409.847128) (xy 381.653059 -409.801276) (xy 381.688748 -409.760083)
			(xy 381.729936 -409.724389) (xy 381.775784 -409.694919) (xy 381.825359 -409.672273) (xy 381.877652 -409.656912)
			(xy 381.931599 -409.649149) (xy 381.95885 -409.64866) (xy 382.82245 -409.64866) (xy 382.849703 -409.649184)
			(xy 382.903655 -409.656934) (xy 382.955954 -409.672285) (xy 383.005536 -409.694923) (xy 383.051392 -409.724387)
			(xy 383.092587 -409.760077) (xy 383.128283 -409.801268) (xy 383.157753 -409.84712) (xy 383.180398 -409.896699)
			(xy 383.195755 -409.948996) (xy 383.203513 -410.002947) (xy 383.203513 -410.057453) (xy 384.641046 -410.057453)
			(xy 384.641046 -410.002947) (xy 384.648803 -409.948996) (xy 384.664159 -409.896697) (xy 384.686801 -409.847117)
			(xy 384.716269 -409.801263) (xy 384.751962 -409.760069) (xy 384.793155 -409.724375) (xy 384.839008 -409.694906)
			(xy 384.888588 -409.672262) (xy 384.940886 -409.656905) (xy 384.994837 -409.649147) (xy 385.02209 -409.64866)
			(xy 385.88569 -409.64866) (xy 385.912941 -409.649187) (xy 385.966889 -409.656942) (xy 386.019183 -409.672296)
			(xy 386.06876 -409.694936) (xy 386.114611 -409.724401) (xy 386.155801 -409.760092) (xy 386.191493 -409.801281)
			(xy 386.22096 -409.847131) (xy 386.243601 -409.896707) (xy 386.258956 -409.949002) (xy 386.266713 -410.002949)
			(xy 386.266713 -410.057451) (xy 386.266712 -410.057457) (xy 387.704223 -410.057457) (xy 387.704223 -410.002943)
			(xy 387.711981 -409.948985) (xy 387.72734 -409.896681) (xy 387.749987 -409.847094) (xy 387.77946 -409.801236)
			(xy 387.81516 -409.760039) (xy 387.85636 -409.724342) (xy 387.902221 -409.694872) (xy 387.951809 -409.67223)
			(xy 388.004115 -409.656875) (xy 388.058073 -409.649121) (xy 388.08533 -409.64866) (xy 388.94893 -409.64866)
			(xy 388.976178 -409.649212) (xy 389.030117 -409.656972) (xy 389.082404 -409.672328) (xy 389.131973 -409.694969)
			(xy 389.177816 -409.724434) (xy 389.218999 -409.760122) (xy 389.254684 -409.801308) (xy 389.284145 -409.847153)
			(xy 389.306783 -409.896724) (xy 389.322135 -409.949012) (xy 389.32989 -410.002952) (xy 389.32989 -410.057448)
			(xy 389.329889 -410.057452) (xy 390.767546 -410.057452) (xy 390.767546 -410.002948) (xy 390.775302 -409.948998)
			(xy 390.790657 -409.896701) (xy 390.813298 -409.847122) (xy 390.842764 -409.801269) (xy 390.878455 -409.760076)
			(xy 390.919645 -409.724382) (xy 390.965496 -409.694912) (xy 391.015073 -409.672268) (xy 391.067369 -409.656909)
			(xy 391.121318 -409.649148) (xy 391.14857 -409.64866) (xy 392.01217 -409.64866) (xy 392.039422 -409.649185)
			(xy 392.093372 -409.656938) (xy 392.145669 -409.67229) (xy 392.195248 -409.694929) (xy 392.241101 -409.724394)
			(xy 392.282294 -409.760084) (xy 392.317988 -409.801274) (xy 392.347457 -409.847125) (xy 392.370099 -409.896703)
			(xy 392.385456 -409.948999) (xy 392.393213 -410.002948) (xy 392.393213 -410.057452) (xy 392.393212 -410.057456)
			(xy 393.830723 -410.057456) (xy 393.830723 -410.002944) (xy 393.838481 -409.948988) (xy 393.853839 -409.896685)
			(xy 393.876484 -409.8471) (xy 393.905955 -409.801242) (xy 393.941653 -409.760046) (xy 393.98285 -409.724349)
			(xy 394.028709 -409.694879) (xy 394.078294 -409.672235) (xy 394.130598 -409.656879) (xy 394.184554 -409.649122)
			(xy 394.21181 -409.64866) (xy 395.07541 -409.64866) (xy 395.102658 -409.649211) (xy 395.156601 -409.656968)
			(xy 395.20889 -409.672323) (xy 395.258461 -409.694962) (xy 395.304307 -409.724426) (xy 395.345492 -409.760115)
			(xy 395.38118 -409.801301) (xy 395.410642 -409.847147) (xy 395.433281 -409.89672) (xy 395.448634 -409.949009)
			(xy 395.45639 -410.002952) (xy 395.45639 -410.057448) (xy 395.45639 -410.057451) (xy 396.894046 -410.057451)
			(xy 396.894046 -410.002949) (xy 396.901802 -409.949001) (xy 396.917155 -409.896706) (xy 396.939795 -409.847128)
			(xy 396.969259 -409.801276) (xy 397.004948 -409.760083) (xy 397.046136 -409.724389) (xy 397.091984 -409.694919)
			(xy 397.141559 -409.672273) (xy 397.193852 -409.656912) (xy 397.247799 -409.649149) (xy 397.27505 -409.64866)
			(xy 398.13865 -409.64866) (xy 398.165903 -409.649184) (xy 398.219855 -409.656934) (xy 398.272154 -409.672285)
			(xy 398.321736 -409.694923) (xy 398.367592 -409.724387) (xy 398.408787 -409.760077) (xy 398.444483 -409.801268)
			(xy 398.473953 -409.84712) (xy 398.496598 -409.896699) (xy 398.511955 -409.948996) (xy 398.519713 -410.002947)
			(xy 398.519713 -410.057453) (xy 399.957246 -410.057453) (xy 399.957246 -410.002947) (xy 399.965003 -409.948996)
			(xy 399.980359 -409.896697) (xy 400.003001 -409.847117) (xy 400.032469 -409.801263) (xy 400.068162 -409.760069)
			(xy 400.109355 -409.724375) (xy 400.155208 -409.694906) (xy 400.204788 -409.672262) (xy 400.257086 -409.656905)
			(xy 400.311037 -409.649147) (xy 400.33829 -409.64866) (xy 401.20189 -409.64866) (xy 401.229141 -409.649187)
			(xy 401.283089 -409.656942) (xy 401.335383 -409.672296) (xy 401.38496 -409.694936) (xy 401.430811 -409.724401)
			(xy 401.472001 -409.760092) (xy 401.507693 -409.801281) (xy 401.53716 -409.847131) (xy 401.559801 -409.896707)
			(xy 401.575156 -409.949002) (xy 401.582913 -410.002949) (xy 401.582913 -410.057451) (xy 401.582912 -410.057457)
			(xy 403.020423 -410.057457) (xy 403.020423 -410.002943) (xy 403.028181 -409.948985) (xy 403.04354 -409.896681)
			(xy 403.066187 -409.847094) (xy 403.09566 -409.801236) (xy 403.13136 -409.760039) (xy 403.17256 -409.724342)
			(xy 403.218421 -409.694872) (xy 403.268009 -409.67223) (xy 403.320315 -409.656875) (xy 403.374273 -409.649121)
			(xy 403.40153 -409.64866) (xy 404.26513 -409.64866) (xy 404.292378 -409.649212) (xy 404.346317 -409.656972)
			(xy 404.398604 -409.672328) (xy 404.448173 -409.694969) (xy 404.494016 -409.724434) (xy 404.535199 -409.760122)
			(xy 404.570884 -409.801308) (xy 404.600345 -409.847153) (xy 404.622983 -409.896724) (xy 404.638335 -409.949012)
			(xy 404.64609 -410.002952) (xy 404.64609 -410.057448) (xy 404.646089 -410.057452) (xy 406.083746 -410.057452)
			(xy 406.083746 -410.002948) (xy 406.091502 -409.948998) (xy 406.106857 -409.896701) (xy 406.129498 -409.847122)
			(xy 406.158964 -409.801269) (xy 406.194655 -409.760076) (xy 406.235845 -409.724382) (xy 406.281696 -409.694912)
			(xy 406.331273 -409.672268) (xy 406.383569 -409.656909) (xy 406.437518 -409.649148) (xy 406.46477 -409.64866)
			(xy 407.32837 -409.64866) (xy 407.355622 -409.649185) (xy 407.409572 -409.656938) (xy 407.461869 -409.67229)
			(xy 407.511448 -409.694929) (xy 407.557301 -409.724394) (xy 407.598494 -409.760084) (xy 407.634188 -409.801274)
			(xy 407.663657 -409.847125) (xy 407.686299 -409.896703) (xy 407.701656 -409.948999) (xy 407.709413 -410.002948)
			(xy 407.709413 -410.057452) (xy 407.709412 -410.057456) (xy 409.146923 -410.057456) (xy 409.146923 -410.002944)
			(xy 409.154681 -409.948988) (xy 409.170039 -409.896685) (xy 409.192684 -409.8471) (xy 409.222155 -409.801242)
			(xy 409.257853 -409.760046) (xy 409.29905 -409.724349) (xy 409.344909 -409.694879) (xy 409.394494 -409.672235)
			(xy 409.446798 -409.656879) (xy 409.500754 -409.649122) (xy 409.52801 -409.64866) (xy 410.39161 -409.64866)
			(xy 410.418858 -409.649211) (xy 410.472801 -409.656968) (xy 410.52509 -409.672323) (xy 410.574661 -409.694962)
			(xy 410.620507 -409.724426) (xy 410.661692 -409.760115) (xy 410.69738 -409.801301) (xy 410.726842 -409.847147)
			(xy 410.749481 -409.89672) (xy 410.764834 -409.949009) (xy 410.77259 -410.002952) (xy 410.77259 -410.057448)
			(xy 410.77259 -410.057451) (xy 412.210246 -410.057451) (xy 412.210246 -410.002949) (xy 412.218002 -409.949001)
			(xy 412.233355 -409.896706) (xy 412.255995 -409.847128) (xy 412.285459 -409.801276) (xy 412.321148 -409.760083)
			(xy 412.362336 -409.724389) (xy 412.408184 -409.694919) (xy 412.457759 -409.672273) (xy 412.510052 -409.656912)
			(xy 412.563999 -409.649149) (xy 412.59125 -409.64866) (xy 413.45485 -409.64866) (xy 413.482103 -409.649184)
			(xy 413.536055 -409.656934) (xy 413.588354 -409.672285) (xy 413.637936 -409.694923) (xy 413.683792 -409.724387)
			(xy 413.724987 -409.760077) (xy 413.760683 -409.801268) (xy 413.790153 -409.84712) (xy 413.812798 -409.896699)
			(xy 413.828155 -409.948996) (xy 413.835913 -410.002947) (xy 413.835913 -410.057453) (xy 415.273446 -410.057453)
			(xy 415.273446 -410.002947) (xy 415.281203 -409.948996) (xy 415.296559 -409.896697) (xy 415.319201 -409.847117)
			(xy 415.348669 -409.801263) (xy 415.384362 -409.760069) (xy 415.425555 -409.724375) (xy 415.471408 -409.694906)
			(xy 415.520988 -409.672262) (xy 415.573286 -409.656905) (xy 415.627237 -409.649147) (xy 415.65449 -409.64866)
			(xy 416.51809 -409.64866) (xy 416.545341 -409.649187) (xy 416.599289 -409.656942) (xy 416.651583 -409.672296)
			(xy 416.70116 -409.694936) (xy 416.747011 -409.724401) (xy 416.788201 -409.760092) (xy 416.823893 -409.801281)
			(xy 416.85336 -409.847131) (xy 416.876001 -409.896707) (xy 416.891356 -409.949002) (xy 416.899113 -410.002949)
			(xy 416.899113 -410.057451) (xy 416.899112 -410.057457) (xy 418.336623 -410.057457) (xy 418.336623 -410.002943)
			(xy 418.344381 -409.948985) (xy 418.35974 -409.896681) (xy 418.382387 -409.847094) (xy 418.41186 -409.801236)
			(xy 418.44756 -409.760039) (xy 418.48876 -409.724342) (xy 418.534621 -409.694872) (xy 418.584209 -409.67223)
			(xy 418.636515 -409.656875) (xy 418.690473 -409.649121) (xy 418.71773 -409.64866) (xy 419.58133 -409.64866)
			(xy 419.608578 -409.649212) (xy 419.662517 -409.656972) (xy 419.714804 -409.672328) (xy 419.764373 -409.694969)
			(xy 419.810216 -409.724434) (xy 419.851399 -409.760122) (xy 419.887084 -409.801308) (xy 419.916545 -409.847153)
			(xy 419.939183 -409.896724) (xy 419.954535 -409.949012) (xy 419.96229 -410.002952) (xy 419.96229 -410.057448)
			(xy 419.954535 -410.111388) (xy 419.939183 -410.163676) (xy 419.916545 -410.213247) (xy 419.887084 -410.259092)
			(xy 419.851399 -410.300278) (xy 419.810216 -410.335966) (xy 419.764373 -410.365431) (xy 419.714804 -410.388072)
			(xy 419.662517 -410.403428) (xy 419.608578 -410.411188) (xy 419.58133 -410.411676) (xy 418.71773 -410.411676)
			(xy 418.690473 -410.411279) (xy 418.636515 -410.403525) (xy 418.584209 -410.38817) (xy 418.534621 -410.365528)
			(xy 418.48876 -410.336058) (xy 418.44756 -410.300361) (xy 418.41186 -410.259164) (xy 418.382387 -410.213306)
			(xy 418.35974 -410.163719) (xy 418.344381 -410.111415) (xy 418.336623 -410.057457) (xy 416.899112 -410.057457)
			(xy 416.891356 -410.111398) (xy 416.876001 -410.163693) (xy 416.85336 -410.213269) (xy 416.823893 -410.259119)
			(xy 416.788201 -410.300308) (xy 416.747011 -410.335999) (xy 416.70116 -410.365464) (xy 416.651583 -410.388104)
			(xy 416.599289 -410.403458) (xy 416.545341 -410.411213) (xy 416.51809 -410.411676) (xy 415.65449 -410.411676)
			(xy 415.627237 -410.411253) (xy 415.573286 -410.403495) (xy 415.520988 -410.388138) (xy 415.471408 -410.365494)
			(xy 415.425555 -410.336025) (xy 415.384362 -410.300331) (xy 415.348669 -410.259137) (xy 415.319201 -410.213283)
			(xy 415.296559 -410.163703) (xy 415.281203 -410.111404) (xy 415.273446 -410.057453) (xy 413.835913 -410.057453)
			(xy 413.828155 -410.111404) (xy 413.812798 -410.163701) (xy 413.790153 -410.21328) (xy 413.760683 -410.259132)
			(xy 413.724987 -410.300323) (xy 413.683792 -410.336013) (xy 413.637936 -410.365477) (xy 413.588354 -410.388115)
			(xy 413.536055 -410.403466) (xy 413.482103 -410.411216) (xy 413.45485 -410.411676) (xy 412.59125 -410.411676)
			(xy 412.563999 -410.411251) (xy 412.510052 -410.403488) (xy 412.457759 -410.388127) (xy 412.408184 -410.365481)
			(xy 412.362336 -410.336011) (xy 412.321148 -410.300317) (xy 412.285459 -410.259124) (xy 412.255995 -410.213272)
			(xy 412.233355 -410.163694) (xy 412.218002 -410.111399) (xy 412.210246 -410.057451) (xy 410.77259 -410.057451)
			(xy 410.764834 -410.111391) (xy 410.749481 -410.16368) (xy 410.726842 -410.213253) (xy 410.69738 -410.259099)
			(xy 410.661692 -410.300285) (xy 410.620507 -410.335974) (xy 410.574661 -410.365438) (xy 410.52509 -410.388077)
			(xy 410.472801 -410.403432) (xy 410.418858 -410.411189) (xy 410.39161 -410.411676) (xy 409.52801 -410.411676)
			(xy 409.500754 -410.411278) (xy 409.446798 -410.403521) (xy 409.394494 -410.388165) (xy 409.344909 -410.365521)
			(xy 409.29905 -410.336051) (xy 409.257853 -410.300354) (xy 409.222155 -410.259158) (xy 409.192684 -410.2133)
			(xy 409.170039 -410.163715) (xy 409.154681 -410.111412) (xy 409.146923 -410.057456) (xy 407.709412 -410.057456)
			(xy 407.701656 -410.111401) (xy 407.686299 -410.163697) (xy 407.663657 -410.213275) (xy 407.634188 -410.259126)
			(xy 407.598494 -410.300316) (xy 407.557301 -410.336006) (xy 407.511448 -410.365471) (xy 407.461869 -410.38811)
			(xy 407.409572 -410.403462) (xy 407.355622 -410.411215) (xy 407.32837 -410.411676) (xy 406.46477 -410.411676)
			(xy 406.437518 -410.411252) (xy 406.383569 -410.403491) (xy 406.331273 -410.388132) (xy 406.281696 -410.365488)
			(xy 406.235845 -410.336018) (xy 406.194655 -410.300324) (xy 406.158964 -410.259131) (xy 406.129498 -410.213278)
			(xy 406.106857 -410.163699) (xy 406.091502 -410.111402) (xy 406.083746 -410.057452) (xy 404.646089 -410.057452)
			(xy 404.638335 -410.111388) (xy 404.622983 -410.163676) (xy 404.600345 -410.213247) (xy 404.570884 -410.259092)
			(xy 404.535199 -410.300278) (xy 404.494016 -410.335966) (xy 404.448173 -410.365431) (xy 404.398604 -410.388072)
			(xy 404.346317 -410.403428) (xy 404.292378 -410.411188) (xy 404.26513 -410.411676) (xy 403.40153 -410.411676)
			(xy 403.374273 -410.411279) (xy 403.320315 -410.403525) (xy 403.268009 -410.38817) (xy 403.218421 -410.365528)
			(xy 403.17256 -410.336058) (xy 403.13136 -410.300361) (xy 403.09566 -410.259164) (xy 403.066187 -410.213306)
			(xy 403.04354 -410.163719) (xy 403.028181 -410.111415) (xy 403.020423 -410.057457) (xy 401.582912 -410.057457)
			(xy 401.575156 -410.111398) (xy 401.559801 -410.163693) (xy 401.53716 -410.213269) (xy 401.507693 -410.259119)
			(xy 401.472001 -410.300308) (xy 401.430811 -410.335999) (xy 401.38496 -410.365464) (xy 401.335383 -410.388104)
			(xy 401.283089 -410.403458) (xy 401.229141 -410.411213) (xy 401.20189 -410.411676) (xy 400.33829 -410.411676)
			(xy 400.311037 -410.411253) (xy 400.257086 -410.403495) (xy 400.204788 -410.388138) (xy 400.155208 -410.365494)
			(xy 400.109355 -410.336025) (xy 400.068162 -410.300331) (xy 400.032469 -410.259137) (xy 400.003001 -410.213283)
			(xy 399.980359 -410.163703) (xy 399.965003 -410.111404) (xy 399.957246 -410.057453) (xy 398.519713 -410.057453)
			(xy 398.511955 -410.111404) (xy 398.496598 -410.163701) (xy 398.473953 -410.21328) (xy 398.444483 -410.259132)
			(xy 398.408787 -410.300323) (xy 398.367592 -410.336013) (xy 398.321736 -410.365477) (xy 398.272154 -410.388115)
			(xy 398.219855 -410.403466) (xy 398.165903 -410.411216) (xy 398.13865 -410.411676) (xy 397.27505 -410.411676)
			(xy 397.247799 -410.411251) (xy 397.193852 -410.403488) (xy 397.141559 -410.388127) (xy 397.091984 -410.365481)
			(xy 397.046136 -410.336011) (xy 397.004948 -410.300317) (xy 396.969259 -410.259124) (xy 396.939795 -410.213272)
			(xy 396.917155 -410.163694) (xy 396.901802 -410.111399) (xy 396.894046 -410.057451) (xy 395.45639 -410.057451)
			(xy 395.448634 -410.111391) (xy 395.433281 -410.16368) (xy 395.410642 -410.213253) (xy 395.38118 -410.259099)
			(xy 395.345492 -410.300285) (xy 395.304307 -410.335974) (xy 395.258461 -410.365438) (xy 395.20889 -410.388077)
			(xy 395.156601 -410.403432) (xy 395.102658 -410.411189) (xy 395.07541 -410.411676) (xy 394.21181 -410.411676)
			(xy 394.184554 -410.411278) (xy 394.130598 -410.403521) (xy 394.078294 -410.388165) (xy 394.028709 -410.365521)
			(xy 393.98285 -410.336051) (xy 393.941653 -410.300354) (xy 393.905955 -410.259158) (xy 393.876484 -410.2133)
			(xy 393.853839 -410.163715) (xy 393.838481 -410.111412) (xy 393.830723 -410.057456) (xy 392.393212 -410.057456)
			(xy 392.385456 -410.111401) (xy 392.370099 -410.163697) (xy 392.347457 -410.213275) (xy 392.317988 -410.259126)
			(xy 392.282294 -410.300316) (xy 392.241101 -410.336006) (xy 392.195248 -410.365471) (xy 392.145669 -410.38811)
			(xy 392.093372 -410.403462) (xy 392.039422 -410.411215) (xy 392.01217 -410.411676) (xy 391.14857 -410.411676)
			(xy 391.121318 -410.411252) (xy 391.067369 -410.403491) (xy 391.015073 -410.388132) (xy 390.965496 -410.365488)
			(xy 390.919645 -410.336018) (xy 390.878455 -410.300324) (xy 390.842764 -410.259131) (xy 390.813298 -410.213278)
			(xy 390.790657 -410.163699) (xy 390.775302 -410.111402) (xy 390.767546 -410.057452) (xy 389.329889 -410.057452)
			(xy 389.322135 -410.111388) (xy 389.306783 -410.163676) (xy 389.284145 -410.213247) (xy 389.254684 -410.259092)
			(xy 389.218999 -410.300278) (xy 389.177816 -410.335966) (xy 389.131973 -410.365431) (xy 389.082404 -410.388072)
			(xy 389.030117 -410.403428) (xy 388.976178 -410.411188) (xy 388.94893 -410.411676) (xy 388.08533 -410.411676)
			(xy 388.058073 -410.411279) (xy 388.004115 -410.403525) (xy 387.951809 -410.38817) (xy 387.902221 -410.365528)
			(xy 387.85636 -410.336058) (xy 387.81516 -410.300361) (xy 387.77946 -410.259164) (xy 387.749987 -410.213306)
			(xy 387.72734 -410.163719) (xy 387.711981 -410.111415) (xy 387.704223 -410.057457) (xy 386.266712 -410.057457)
			(xy 386.258956 -410.111398) (xy 386.243601 -410.163693) (xy 386.22096 -410.213269) (xy 386.191493 -410.259119)
			(xy 386.155801 -410.300308) (xy 386.114611 -410.335999) (xy 386.06876 -410.365464) (xy 386.019183 -410.388104)
			(xy 385.966889 -410.403458) (xy 385.912941 -410.411213) (xy 385.88569 -410.411676) (xy 385.02209 -410.411676)
			(xy 384.994837 -410.411253) (xy 384.940886 -410.403495) (xy 384.888588 -410.388138) (xy 384.839008 -410.365494)
			(xy 384.793155 -410.336025) (xy 384.751962 -410.300331) (xy 384.716269 -410.259137) (xy 384.686801 -410.213283)
			(xy 384.664159 -410.163703) (xy 384.648803 -410.111404) (xy 384.641046 -410.057453) (xy 383.203513 -410.057453)
			(xy 383.195755 -410.111404) (xy 383.180398 -410.163701) (xy 383.157753 -410.21328) (xy 383.128283 -410.259132)
			(xy 383.092587 -410.300323) (xy 383.051392 -410.336013) (xy 383.005536 -410.365477) (xy 382.955954 -410.388115)
			(xy 382.903655 -410.403466) (xy 382.849703 -410.411216) (xy 382.82245 -410.411676) (xy 381.95885 -410.411676)
			(xy 381.931599 -410.411251) (xy 381.877652 -410.403488) (xy 381.825359 -410.388127) (xy 381.775784 -410.365481)
			(xy 381.729936 -410.336011) (xy 381.688748 -410.300317) (xy 381.653059 -410.259124) (xy 381.623595 -410.213272)
			(xy 381.600955 -410.163694) (xy 381.585602 -410.111399) (xy 381.577846 -410.057451) (xy 380.14019 -410.057451)
			(xy 380.132434 -410.111391) (xy 380.117081 -410.16368) (xy 380.094442 -410.213253) (xy 380.06498 -410.259099)
			(xy 380.029292 -410.300285) (xy 379.988107 -410.335974) (xy 379.942261 -410.365438) (xy 379.89269 -410.388077)
			(xy 379.840401 -410.403432) (xy 379.786458 -410.411189) (xy 379.75921 -410.411676) (xy 378.89561 -410.411676)
			(xy 378.868354 -410.411278) (xy 378.814398 -410.403521) (xy 378.762094 -410.388165) (xy 378.712509 -410.365521)
			(xy 378.66665 -410.336051) (xy 378.625453 -410.300354) (xy 378.589755 -410.259158) (xy 378.560284 -410.2133)
			(xy 378.537639 -410.163715) (xy 378.522281 -410.111412) (xy 378.514523 -410.057456) (xy 377.077012 -410.057456)
			(xy 377.069256 -410.111401) (xy 377.053899 -410.163697) (xy 377.031257 -410.213275) (xy 377.001788 -410.259126)
			(xy 376.966094 -410.300316) (xy 376.924901 -410.336006) (xy 376.879048 -410.365471) (xy 376.829469 -410.38811)
			(xy 376.777172 -410.403462) (xy 376.723222 -410.411215) (xy 376.69597 -410.411676) (xy 375.83237 -410.411676)
			(xy 375.805118 -410.411252) (xy 375.751169 -410.403491) (xy 375.698873 -410.388132) (xy 375.649296 -410.365488)
			(xy 375.603445 -410.336018) (xy 375.562255 -410.300324) (xy 375.526564 -410.259131) (xy 375.497098 -410.213278)
			(xy 375.474457 -410.163699) (xy 375.459102 -410.111402) (xy 375.451346 -410.057452) (xy 374.013689 -410.057452)
			(xy 374.005935 -410.111388) (xy 373.990583 -410.163676) (xy 373.967945 -410.213247) (xy 373.938484 -410.259092)
			(xy 373.902799 -410.300278) (xy 373.861616 -410.335966) (xy 373.815773 -410.365431) (xy 373.766204 -410.388072)
			(xy 373.713917 -410.403428) (xy 373.659978 -410.411188) (xy 373.63273 -410.411676) (xy 372.76913 -410.411676)
			(xy 372.741873 -410.411279) (xy 372.687915 -410.403525) (xy 372.635609 -410.38817) (xy 372.586021 -410.365528)
			(xy 372.54016 -410.336058) (xy 372.49896 -410.300361) (xy 372.46326 -410.259164) (xy 372.433787 -410.213306)
			(xy 372.41114 -410.163719) (xy 372.395781 -410.111415) (xy 372.388023 -410.057457) (xy 352.519512 -410.057457)
			(xy 352.511756 -410.111399) (xy 352.496401 -410.163693) (xy 352.473759 -410.21327) (xy 352.444293 -410.25912)
			(xy 352.408601 -410.300309) (xy 352.36741 -410.336) (xy 352.321559 -410.365465) (xy 352.271982 -410.388105)
			(xy 352.219687 -410.403459) (xy 352.165739 -410.411214) (xy 352.138488 -410.411676) (xy 351.274888 -410.411676)
			(xy 351.247635 -410.411253) (xy 351.193684 -410.403495) (xy 351.141386 -410.388137) (xy 351.091807 -410.365494)
			(xy 351.045954 -410.336025) (xy 351.004762 -410.30033) (xy 350.969068 -410.259137) (xy 350.939601 -410.213283)
			(xy 350.916958 -410.163702) (xy 350.901603 -410.111404) (xy 350.893846 -410.057453) (xy 349.456189 -410.057453)
			(xy 349.448435 -410.111386) (xy 349.433084 -410.163672) (xy 349.410448 -410.213242) (xy 349.380989 -410.259086)
			(xy 349.345306 -410.300272) (xy 349.304125 -410.33596) (xy 349.258284 -410.365425) (xy 349.208717 -410.388067)
			(xy 349.156433 -410.403425) (xy 349.102495 -410.411187) (xy 349.075248 -410.411676) (xy 348.211648 -410.411676)
			(xy 348.184391 -410.41128) (xy 348.13043 -410.403528) (xy 348.078122 -410.388175) (xy 348.028531 -410.365533)
			(xy 347.982668 -410.336064) (xy 347.941466 -410.300367) (xy 347.905765 -410.25917) (xy 347.87629 -410.213311)
			(xy 347.853642 -410.163723) (xy 347.838282 -410.111417) (xy 347.830523 -410.057457) (xy 346.392989 -410.057457)
			(xy 346.385234 -410.111391) (xy 346.369881 -410.163681) (xy 346.347242 -410.213253) (xy 346.317779 -410.259099)
			(xy 346.282091 -410.300286) (xy 346.240906 -410.335974) (xy 346.19506 -410.365438) (xy 346.145488 -410.388078)
			(xy 346.093199 -410.403432) (xy 346.039257 -410.411189) (xy 346.012008 -410.411676) (xy 345.148408 -410.411676)
			(xy 345.121152 -410.411278) (xy 345.067196 -410.403521) (xy 345.014893 -410.388164) (xy 344.965307 -410.36552)
			(xy 344.919449 -410.33605) (xy 344.878252 -410.300353) (xy 344.842555 -410.259157) (xy 344.813084 -410.2133)
			(xy 344.790439 -410.163715) (xy 344.775081 -410.111412) (xy 344.767323 -410.057456) (xy 343.329812 -410.057456)
			(xy 343.322055 -410.111401) (xy 343.306699 -410.163697) (xy 343.284056 -410.213275) (xy 343.254588 -410.259126)
			(xy 343.218894 -410.300316) (xy 343.177701 -410.336007) (xy 343.131847 -410.365472) (xy 343.082267 -410.38811)
			(xy 343.02997 -410.403462) (xy 342.97602 -410.411215) (xy 342.948768 -410.411676) (xy 342.085168 -410.411676)
			(xy 342.057916 -410.411252) (xy 342.003967 -410.403491) (xy 341.951672 -410.388132) (xy 341.902095 -410.365487)
			(xy 341.856244 -410.336017) (xy 341.815054 -410.300323) (xy 341.779363 -410.25913) (xy 341.749898 -410.213277)
			(xy 341.727257 -410.163698) (xy 341.711902 -410.111402) (xy 341.704146 -410.057452) (xy 340.266489 -410.057452)
			(xy 340.258735 -410.111388) (xy 340.243382 -410.163676) (xy 340.220745 -410.213248) (xy 340.191284 -410.259093)
			(xy 340.155599 -410.300279) (xy 340.114415 -410.335967) (xy 340.068572 -410.365432) (xy 340.019003 -410.388073)
			(xy 339.966716 -410.403429) (xy 339.912776 -410.411188) (xy 339.885528 -410.411676) (xy 339.021928 -410.411676)
			(xy 338.994672 -410.411279) (xy 338.940713 -410.403525) (xy 338.888407 -410.38817) (xy 338.838819 -410.365527)
			(xy 338.792959 -410.336057) (xy 338.751759 -410.30036) (xy 338.71606 -410.259164) (xy 338.686587 -410.213305)
			(xy 338.66394 -410.163719) (xy 338.648581 -410.111414) (xy 338.640823 -410.057456) (xy 337.203312 -410.057456)
			(xy 337.195556 -410.111399) (xy 337.180201 -410.163693) (xy 337.157559 -410.21327) (xy 337.128093 -410.25912)
			(xy 337.092401 -410.300309) (xy 337.05121 -410.336) (xy 337.005359 -410.365465) (xy 336.955782 -410.388105)
			(xy 336.903487 -410.403459) (xy 336.849539 -410.411214) (xy 336.822288 -410.411676) (xy 335.958688 -410.411676)
			(xy 335.931435 -410.411253) (xy 335.877484 -410.403495) (xy 335.825186 -410.388137) (xy 335.775607 -410.365494)
			(xy 335.729754 -410.336025) (xy 335.688562 -410.30033) (xy 335.652868 -410.259137) (xy 335.623401 -410.213283)
			(xy 335.600758 -410.163702) (xy 335.585403 -410.111404) (xy 335.577646 -410.057453) (xy 334.139989 -410.057453)
			(xy 334.132235 -410.111386) (xy 334.116884 -410.163672) (xy 334.094248 -410.213242) (xy 334.064789 -410.259086)
			(xy 334.029106 -410.300272) (xy 333.987925 -410.33596) (xy 333.942084 -410.365425) (xy 333.892517 -410.388067)
			(xy 333.840233 -410.403425) (xy 333.786295 -410.411187) (xy 333.759048 -410.411676) (xy 332.895448 -410.411676)
			(xy 332.868191 -410.41128) (xy 332.81423 -410.403528) (xy 332.761922 -410.388175) (xy 332.712331 -410.365533)
			(xy 332.666468 -410.336064) (xy 332.625266 -410.300367) (xy 332.589565 -410.25917) (xy 332.56009 -410.213311)
			(xy 332.537442 -410.163723) (xy 332.522082 -410.111417) (xy 332.514323 -410.057457) (xy 331.076789 -410.057457)
			(xy 331.069034 -410.111391) (xy 331.053681 -410.163681) (xy 331.031042 -410.213253) (xy 331.001579 -410.259099)
			(xy 330.965891 -410.300286) (xy 330.924706 -410.335974) (xy 330.87886 -410.365438) (xy 330.829288 -410.388078)
			(xy 330.776999 -410.403432) (xy 330.723057 -410.411189) (xy 330.695808 -410.411676) (xy 329.832208 -410.411676)
			(xy 329.804952 -410.411278) (xy 329.750996 -410.403521) (xy 329.698693 -410.388164) (xy 329.649107 -410.36552)
			(xy 329.603249 -410.33605) (xy 329.562052 -410.300353) (xy 329.526355 -410.259157) (xy 329.496884 -410.2133)
			(xy 329.474239 -410.163715) (xy 329.458881 -410.111412) (xy 329.451123 -410.057456) (xy 328.013612 -410.057456)
			(xy 328.005855 -410.111401) (xy 327.990499 -410.163697) (xy 327.967856 -410.213275) (xy 327.938388 -410.259126)
			(xy 327.902694 -410.300316) (xy 327.861501 -410.336007) (xy 327.815647 -410.365472) (xy 327.766067 -410.38811)
			(xy 327.71377 -410.403462) (xy 327.65982 -410.411215) (xy 327.632568 -410.411676) (xy 326.768968 -410.411676)
			(xy 326.741716 -410.411252) (xy 326.687767 -410.403491) (xy 326.635472 -410.388132) (xy 326.585895 -410.365487)
			(xy 326.540044 -410.336017) (xy 326.498854 -410.300323) (xy 326.463163 -410.25913) (xy 326.433698 -410.213277)
			(xy 326.411057 -410.163698) (xy 326.395702 -410.111402) (xy 326.387946 -410.057452) (xy 324.950289 -410.057452)
			(xy 324.942535 -410.111388) (xy 324.927182 -410.163676) (xy 324.904545 -410.213248) (xy 324.875084 -410.259093)
			(xy 324.839399 -410.300279) (xy 324.798215 -410.335967) (xy 324.752372 -410.365432) (xy 324.702803 -410.388073)
			(xy 324.650516 -410.403429) (xy 324.596576 -410.411188) (xy 324.569328 -410.411676) (xy 323.705728 -410.411676)
			(xy 323.678472 -410.411279) (xy 323.624513 -410.403525) (xy 323.572207 -410.38817) (xy 323.522619 -410.365527)
			(xy 323.476759 -410.336057) (xy 323.435559 -410.30036) (xy 323.39986 -410.259164) (xy 323.370387 -410.213305)
			(xy 323.34774 -410.163719) (xy 323.332381 -410.111414) (xy 323.324623 -410.057456) (xy 321.887112 -410.057456)
			(xy 321.879356 -410.111399) (xy 321.864001 -410.163693) (xy 321.841359 -410.21327) (xy 321.811893 -410.25912)
			(xy 321.776201 -410.300309) (xy 321.73501 -410.336) (xy 321.689159 -410.365465) (xy 321.639582 -410.388105)
			(xy 321.587287 -410.403459) (xy 321.533339 -410.411214) (xy 321.506088 -410.411676) (xy 320.642488 -410.411676)
			(xy 320.615235 -410.411253) (xy 320.561284 -410.403495) (xy 320.508986 -410.388137) (xy 320.459407 -410.365494)
			(xy 320.413554 -410.336025) (xy 320.372362 -410.30033) (xy 320.336668 -410.259137) (xy 320.307201 -410.213283)
			(xy 320.284558 -410.163702) (xy 320.269203 -410.111404) (xy 320.261446 -410.057453) (xy 318.823789 -410.057453)
			(xy 318.816035 -410.111386) (xy 318.800684 -410.163672) (xy 318.778048 -410.213242) (xy 318.748589 -410.259086)
			(xy 318.712906 -410.300272) (xy 318.671725 -410.33596) (xy 318.625884 -410.365425) (xy 318.576317 -410.388067)
			(xy 318.524033 -410.403425) (xy 318.470095 -410.411187) (xy 318.442848 -410.411676) (xy 317.579248 -410.411676)
			(xy 317.551991 -410.41128) (xy 317.49803 -410.403528) (xy 317.445722 -410.388175) (xy 317.396131 -410.365533)
			(xy 317.350268 -410.336064) (xy 317.309066 -410.300367) (xy 317.273365 -410.25917) (xy 317.24389 -410.213311)
			(xy 317.221242 -410.163723) (xy 317.205882 -410.111417) (xy 317.198123 -410.057457) (xy 315.760589 -410.057457)
			(xy 315.752834 -410.111391) (xy 315.737481 -410.163681) (xy 315.714842 -410.213253) (xy 315.685379 -410.259099)
			(xy 315.649691 -410.300286) (xy 315.608506 -410.335974) (xy 315.56266 -410.365438) (xy 315.513088 -410.388078)
			(xy 315.460799 -410.403432) (xy 315.406857 -410.411189) (xy 315.379608 -410.411676) (xy 314.516008 -410.411676)
			(xy 314.488752 -410.411278) (xy 314.434796 -410.403521) (xy 314.382493 -410.388164) (xy 314.332907 -410.36552)
			(xy 314.287049 -410.33605) (xy 314.245852 -410.300353) (xy 314.210155 -410.259157) (xy 314.180684 -410.2133)
			(xy 314.158039 -410.163715) (xy 314.142681 -410.111412) (xy 314.134923 -410.057456) (xy 312.697412 -410.057456)
			(xy 312.689655 -410.111401) (xy 312.674299 -410.163697) (xy 312.651656 -410.213275) (xy 312.622188 -410.259126)
			(xy 312.586494 -410.300316) (xy 312.545301 -410.336007) (xy 312.499447 -410.365472) (xy 312.449867 -410.38811)
			(xy 312.39757 -410.403462) (xy 312.34362 -410.411215) (xy 312.316368 -410.411676) (xy 311.452768 -410.411676)
			(xy 311.425516 -410.411252) (xy 311.371567 -410.403491) (xy 311.319272 -410.388132) (xy 311.269695 -410.365487)
			(xy 311.223844 -410.336017) (xy 311.182654 -410.300323) (xy 311.146963 -410.25913) (xy 311.117498 -410.213277)
			(xy 311.094857 -410.163698) (xy 311.079502 -410.111402) (xy 311.071746 -410.057452) (xy 309.634089 -410.057452)
			(xy 309.626335 -410.111388) (xy 309.610982 -410.163676) (xy 309.588345 -410.213248) (xy 309.558884 -410.259093)
			(xy 309.523199 -410.300279) (xy 309.482015 -410.335967) (xy 309.436172 -410.365432) (xy 309.386603 -410.388073)
			(xy 309.334316 -410.403429) (xy 309.280376 -410.411188) (xy 309.253128 -410.411676) (xy 308.389528 -410.411676)
			(xy 308.362272 -410.411279) (xy 308.308313 -410.403525) (xy 308.256007 -410.38817) (xy 308.206419 -410.365527)
			(xy 308.160559 -410.336057) (xy 308.119359 -410.30036) (xy 308.08366 -410.259164) (xy 308.054187 -410.213305)
			(xy 308.03154 -410.163719) (xy 308.016181 -410.111414) (xy 308.008423 -410.057456) (xy 306.570912 -410.057456)
			(xy 306.563156 -410.111399) (xy 306.547801 -410.163693) (xy 306.525159 -410.21327) (xy 306.495693 -410.25912)
			(xy 306.460001 -410.300309) (xy 306.41881 -410.336) (xy 306.372959 -410.365465) (xy 306.323382 -410.388105)
			(xy 306.271087 -410.403459) (xy 306.217139 -410.411214) (xy 306.189888 -410.411676) (xy 305.326288 -410.411676)
			(xy 305.299035 -410.411253) (xy 305.245084 -410.403495) (xy 305.192786 -410.388137) (xy 305.143207 -410.365494)
			(xy 305.097354 -410.336025) (xy 305.056162 -410.30033) (xy 305.020468 -410.259137) (xy 304.991001 -410.213283)
			(xy 304.968358 -410.163702) (xy 304.953003 -410.111404) (xy 304.945246 -410.057453) (xy 280.83256 -410.057453)
			(xy 280.83256 -415.172652) (xy 280.832075 -415.197601) (xy 280.824257 -415.246884) (xy 280.808837 -415.294341)
			(xy 280.786193 -415.338807) (xy 280.756881 -415.37919) (xy 280.739596 -415.397188) (xy 280.152348 -415.984436)
			(xy 280.134386 -416.001764) (xy 280.094003 -416.03109) (xy 280.04953 -416.053738) (xy 280.002061 -416.069148)
			(xy 279.952766 -416.076943) (xy 279.927812 -416.0774) (xy 275.825712 -416.0774) (xy 270.719296 -421.183816)
			(xy 270.701309 -421.201115) (xy 270.660931 -421.230437) (xy 270.616463 -421.253083) (xy 270.569 -421.268495)
			(xy 270.519711 -421.276294) (xy 270.49476 -421.27678) (xy 233.339132 -421.27678) (xy 231.01554 -423.600372)
			(xy 231.01554 -424.804386) (xy 357.679233 -424.804386) (xy 357.679233 -424.675246) (xy 357.687183 -424.546351)
			(xy 357.703053 -424.418191) (xy 357.726782 -424.29125) (xy 357.758281 -424.166011) (xy 357.79743 -424.042948)
			(xy 357.844081 -423.922529) (xy 357.898056 -423.80521) (xy 357.959151 -423.691436) (xy 358.027134 -423.581639)
			(xy 358.101748 -423.476236) (xy 358.182709 -423.375626) (xy 358.269709 -423.280191) (xy 358.36242 -423.190292)
			(xy 358.46049 -423.106271) (xy 358.563545 -423.028447) (xy 358.671196 -422.957115) (xy 358.783035 -422.892545)
			(xy 358.898636 -422.834983) (xy 359.017561 -422.784646) (xy 359.13936 -422.741726) (xy 359.26357 -422.706385)
			(xy 359.389719 -422.678758) (xy 359.517331 -422.658949) (xy 359.64592 -422.647033) (xy 359.774998 -422.643057)
			(xy 359.904076 -422.647033) (xy 360.032665 -422.658949) (xy 360.160277 -422.678758) (xy 360.286426 -422.706385)
			(xy 360.410636 -422.741726) (xy 360.532435 -422.784646) (xy 360.65136 -422.834983) (xy 360.766961 -422.892545)
			(xy 360.8788 -422.957115) (xy 360.986451 -423.028447) (xy 361.089506 -423.106271) (xy 361.187576 -423.190292)
			(xy 361.280287 -423.280191) (xy 361.367287 -423.375626) (xy 361.448248 -423.476236) (xy 361.522862 -423.581639)
			(xy 361.590845 -423.691436) (xy 361.65194 -423.80521) (xy 361.705915 -423.922529) (xy 361.752566 -424.042948)
			(xy 361.791715 -424.166011) (xy 361.823214 -424.29125) (xy 361.846943 -424.418191) (xy 361.853367 -424.470068)
			(xy 421.270176 -424.470068) (xy 421.270176 -417.770056) (xy 421.270681 -417.664527) (xy 421.278765 -417.453623)
			(xy 421.294922 -417.243184) (xy 421.319127 -417.033518) (xy 421.351345 -416.824934) (xy 421.391528 -416.617736)
			(xy 421.439619 -416.412229) (xy 421.495545 -416.208716) (xy 421.559226 -416.007493) (xy 421.630567 -415.808858)
			(xy 421.709464 -415.613101) (xy 421.795802 -415.420509) (xy 421.889452 -415.231366) (xy 421.990279 -415.045949)
			(xy 422.098134 -414.864529) (xy 422.212858 -414.687374) (xy 422.334284 -414.514743) (xy 422.462233 -414.34689)
			(xy 422.596517 -414.184061) (xy 422.73694 -414.026495) (xy 422.883295 -413.874423) (xy 423.035367 -413.728068)
			(xy 423.192933 -413.587645) (xy 423.355762 -413.453361) (xy 423.523615 -413.325412) (xy 423.696246 -413.203986)
			(xy 423.873401 -413.089262) (xy 424.054821 -412.981407) (xy 424.240238 -412.88058) (xy 424.429381 -412.78693)
			(xy 424.621973 -412.700592) (xy 424.81773 -412.621695) (xy 425.016365 -412.550354) (xy 425.217588 -412.486673)
			(xy 425.421101 -412.430747) (xy 425.626608 -412.382656) (xy 425.833806 -412.342473) (xy 426.04239 -412.310255)
			(xy 426.252056 -412.28605) (xy 426.462495 -412.269893) (xy 426.673399 -412.261809) (xy 426.884457 -412.261809)
			(xy 427.095361 -412.269893) (xy 427.3058 -412.28605) (xy 427.515466 -412.310255) (xy 427.72405 -412.342473)
			(xy 427.931248 -412.382656) (xy 428.136755 -412.430747) (xy 428.340268 -412.486673) (xy 428.541491 -412.550354)
			(xy 428.740126 -412.621695) (xy 428.935883 -412.700592) (xy 429.128475 -412.78693) (xy 429.317618 -412.88058)
			(xy 429.503035 -412.981407) (xy 429.684455 -413.089262) (xy 429.86161 -413.203986) (xy 430.034241 -413.325412)
			(xy 430.202094 -413.453361) (xy 430.364923 -413.587645) (xy 430.522489 -413.728068) (xy 430.674561 -413.874423)
			(xy 430.820916 -414.026495) (xy 430.961339 -414.184061) (xy 431.095623 -414.34689) (xy 431.223572 -414.514743)
			(xy 431.344998 -414.687374) (xy 431.459722 -414.864529) (xy 431.567577 -415.045949) (xy 431.668404 -415.231366)
			(xy 431.762054 -415.420509) (xy 431.848392 -415.613101) (xy 431.927289 -415.808858) (xy 431.99863 -416.007493)
			(xy 432.062311 -416.208716) (xy 432.118237 -416.412229) (xy 432.166328 -416.617736) (xy 432.206511 -416.824934)
			(xy 432.238729 -417.033518) (xy 432.262934 -417.243184) (xy 432.279091 -417.453623) (xy 432.287175 -417.664527)
			(xy 432.28768 -417.770056) (xy 432.28768 -424.470068) (xy 432.287175 -424.575597) (xy 432.279091 -424.786501)
			(xy 432.262934 -424.99694) (xy 432.238729 -425.206606) (xy 432.206511 -425.41519) (xy 432.166328 -425.622388)
			(xy 432.118237 -425.827895) (xy 432.062311 -426.031408) (xy 431.99863 -426.232631) (xy 431.927289 -426.431266)
			(xy 431.848392 -426.627023) (xy 431.762054 -426.819615) (xy 431.668404 -427.008758) (xy 431.567577 -427.194175)
			(xy 431.459722 -427.375595) (xy 431.344998 -427.55275) (xy 431.223572 -427.725381) (xy 431.095623 -427.893234)
			(xy 430.961339 -428.056063) (xy 430.820916 -428.213629) (xy 430.674561 -428.365701) (xy 430.522489 -428.512056)
			(xy 430.364923 -428.652479) (xy 430.202094 -428.786763) (xy 430.034241 -428.914712) (xy 429.86161 -429.036138)
			(xy 429.684455 -429.150862) (xy 429.503035 -429.258717) (xy 429.317618 -429.359544) (xy 429.128475 -429.453194)
			(xy 428.935883 -429.539532) (xy 428.740126 -429.618429) (xy 428.541491 -429.68977) (xy 428.340268 -429.753451)
			(xy 428.136755 -429.809377) (xy 427.931248 -429.857468) (xy 427.72405 -429.897651) (xy 427.515466 -429.929869)
			(xy 427.3058 -429.954074) (xy 427.095361 -429.970231) (xy 426.884457 -429.978315) (xy 426.673399 -429.978315)
			(xy 426.462495 -429.970231) (xy 426.252056 -429.954074) (xy 426.04239 -429.929869) (xy 425.833806 -429.897651)
			(xy 425.626608 -429.857468) (xy 425.421101 -429.809377) (xy 425.217588 -429.753451) (xy 425.016365 -429.68977)
			(xy 424.81773 -429.618429) (xy 424.621973 -429.539532) (xy 424.429381 -429.453194) (xy 424.240238 -429.359544)
			(xy 424.054821 -429.258717) (xy 423.873401 -429.150862) (xy 423.696246 -429.036138) (xy 423.523615 -428.914712)
			(xy 423.355762 -428.786763) (xy 423.192933 -428.652479) (xy 423.035367 -428.512056) (xy 422.883295 -428.365701)
			(xy 422.73694 -428.213629) (xy 422.596517 -428.056063) (xy 422.462233 -427.893234) (xy 422.334284 -427.725381)
			(xy 422.212858 -427.55275) (xy 422.098134 -427.375595) (xy 421.990279 -427.194175) (xy 421.889452 -427.008758)
			(xy 421.795802 -426.819615) (xy 421.709464 -426.627023) (xy 421.630567 -426.431266) (xy 421.559226 -426.232631)
			(xy 421.495545 -426.031408) (xy 421.439619 -425.827895) (xy 421.391528 -425.622388) (xy 421.351345 -425.41519)
			(xy 421.319127 -425.206606) (xy 421.294922 -424.99694) (xy 421.278765 -424.786501) (xy 421.270681 -424.575597)
			(xy 421.270176 -424.470068) (xy 361.853367 -424.470068) (xy 361.862813 -424.546351) (xy 361.870763 -424.675246)
			(xy 361.87126 -424.739816) (xy 361.870763 -424.804386) (xy 361.862813 -424.933281) (xy 361.846943 -425.061441)
			(xy 361.823214 -425.188382) (xy 361.791715 -425.313621) (xy 361.752566 -425.436684) (xy 361.705915 -425.557103)
			(xy 361.65194 -425.674422) (xy 361.590845 -425.788196) (xy 361.522862 -425.897993) (xy 361.448248 -426.003396)
			(xy 361.367287 -426.104006) (xy 361.280287 -426.199441) (xy 361.187576 -426.28934) (xy 361.089506 -426.373361)
			(xy 360.986451 -426.451185) (xy 360.8788 -426.522517) (xy 360.766961 -426.587087) (xy 360.65136 -426.644649)
			(xy 360.532435 -426.694986) (xy 360.410636 -426.737906) (xy 360.286426 -426.773247) (xy 360.160277 -426.800874)
			(xy 360.032665 -426.820683) (xy 359.904076 -426.832599) (xy 359.774998 -426.836576) (xy 359.64592 -426.832599)
			(xy 359.517331 -426.820683) (xy 359.389719 -426.800874) (xy 359.26357 -426.773247) (xy 359.13936 -426.737906)
			(xy 359.017561 -426.694986) (xy 358.898636 -426.644649) (xy 358.783035 -426.587087) (xy 358.671196 -426.522517)
			(xy 358.563545 -426.451185) (xy 358.46049 -426.373361) (xy 358.36242 -426.28934) (xy 358.269709 -426.199441)
			(xy 358.182709 -426.104006) (xy 358.101748 -426.003396) (xy 358.027134 -425.897993) (xy 357.959151 -425.788196)
			(xy 357.898056 -425.674422) (xy 357.844081 -425.557103) (xy 357.79743 -425.436684) (xy 357.758281 -425.313621)
			(xy 357.726782 -425.188382) (xy 357.703053 -425.061441) (xy 357.687183 -424.933281) (xy 357.679233 -424.804386)
			(xy 231.01554 -424.804386) (xy 231.01554 -427.289976) (xy 314.138056 -427.289976) (xy 314.13817 -427.274891)
			(xy 314.139948 -427.244772) (xy 314.141612 -427.229778) (xy 314.141612 -426.150024) (xy 314.139943 -426.135031)
			(xy 314.138165 -426.104912) (xy 314.138056 -426.089826) (xy 314.138166 -426.07474) (xy 314.139947 -426.044622)
			(xy 314.141612 -426.029628) (xy 314.141612 -425.419012) (xy 314.142023 -425.406928) (xy 314.14949 -425.383942)
			(xy 314.163696 -425.36439) (xy 314.183249 -425.350186) (xy 314.206236 -425.342722) (xy 314.21832 -425.342304)
			(xy 315.15812 -425.342304) (xy 315.170197 -425.342748) (xy 315.193167 -425.350217) (xy 315.212704 -425.364419)
			(xy 315.226898 -425.383962) (xy 315.234357 -425.406935) (xy 315.234828 -425.419012) (xy 315.234828 -427.960536)
			(xy 315.234367 -427.97261) (xy 315.226897 -427.995576) (xy 315.212699 -428.01511) (xy 315.193161 -428.029304)
			(xy 315.170195 -428.036769) (xy 315.15812 -428.037244) (xy 314.21832 -428.037244) (xy 314.20625 -428.036719)
			(xy 314.18329 -428.029267) (xy 314.163755 -428.015085) (xy 314.149559 -427.995561) (xy 314.142089 -427.972606)
			(xy 314.141612 -427.960536) (xy 314.141612 -427.350174) (xy 314.139948 -427.33518) (xy 314.138166 -427.305062)
			(xy 314.138056 -427.289976) (xy 231.01554 -427.289976) (xy 231.01554 -428.28972) (xy 316.138052 -428.28972)
			(xy 316.138162 -428.274634) (xy 316.139943 -428.244516) (xy 316.141608 -428.229522) (xy 316.141608 -427.150022)
			(xy 316.139939 -427.135029) (xy 316.138161 -427.10491) (xy 316.138052 -427.089824) (xy 316.138162 -427.074738)
			(xy 316.139943 -427.04462) (xy 316.141608 -427.029626) (xy 316.141608 -426.41901) (xy 316.142115 -426.406924)
			(xy 316.149565 -426.383929) (xy 316.163743 -426.364352) (xy 316.183266 -426.3501) (xy 316.206232 -426.342562)
			(xy 316.218316 -426.342048) (xy 317.158116 -426.342048) (xy 317.170221 -426.342502) (xy 317.193239 -426.349999)
			(xy 317.212808 -426.364253) (xy 317.227004 -426.383863) (xy 317.234433 -426.406904) (xy 317.234824 -426.41901)
			(xy 317.234824 -427.289976) (xy 318.138048 -427.289976) (xy 318.138162 -427.274891) (xy 318.13994 -427.244772)
			(xy 318.141604 -427.229778) (xy 318.141604 -426.150024) (xy 318.139935 -426.135031) (xy 318.138157 -426.104912)
			(xy 318.138048 -426.089826) (xy 318.138158 -426.07474) (xy 318.139939 -426.044622) (xy 318.141604 -426.029628)
			(xy 318.141604 -425.419012) (xy 318.142023 -425.406929) (xy 318.149489 -425.383944) (xy 318.163693 -425.364393)
			(xy 318.183244 -425.350189) (xy 318.206229 -425.342723) (xy 318.218312 -425.342304) (xy 319.158112 -425.342304)
			(xy 319.170188 -425.342754) (xy 319.193158 -425.350222) (xy 319.212696 -425.364421) (xy 319.226889 -425.383964)
			(xy 319.234349 -425.406935) (xy 319.23482 -425.419012) (xy 319.23482 -427.960536) (xy 319.234367 -427.972611)
			(xy 319.226896 -427.995578) (xy 319.212696 -428.015113) (xy 319.193156 -428.029307) (xy 319.170187 -428.036771)
			(xy 319.158112 -428.037244) (xy 318.218312 -428.037244) (xy 318.206242 -428.036726) (xy 318.183281 -428.029271)
			(xy 318.163747 -428.015087) (xy 318.149551 -427.995562) (xy 318.142081 -427.972606) (xy 318.141604 -427.960536)
			(xy 318.141604 -427.350174) (xy 318.13994 -427.33518) (xy 318.138158 -427.305062) (xy 318.138048 -427.289976)
			(xy 317.234824 -427.289976) (xy 317.234824 -428.28972) (xy 320.138044 -428.28972) (xy 320.138154 -428.274634)
			(xy 320.139935 -428.244516) (xy 320.1416 -428.229522) (xy 320.1416 -427.150022) (xy 320.139931 -427.135029)
			(xy 320.138153 -427.10491) (xy 320.138044 -427.089824) (xy 320.138154 -427.074738) (xy 320.139935 -427.04462)
			(xy 320.1416 -427.029626) (xy 320.1416 -426.41901) (xy 320.142115 -426.406925) (xy 320.149564 -426.383931)
			(xy 320.16374 -426.364355) (xy 320.183261 -426.350103) (xy 320.206225 -426.342563) (xy 320.218308 -426.342048)
			(xy 321.158108 -426.342048) (xy 321.170212 -426.342509) (xy 321.193231 -426.350004) (xy 321.212799 -426.364256)
			(xy 321.226996 -426.383865) (xy 321.234425 -426.406905) (xy 321.234816 -426.41901) (xy 321.234816 -427.289976)
			(xy 322.13804 -427.289976) (xy 322.138155 -427.274891) (xy 322.139932 -427.244772) (xy 322.141596 -427.229778)
			(xy 322.141596 -426.150024) (xy 322.139927 -426.135031) (xy 322.138149 -426.104912) (xy 322.13804 -426.089826)
			(xy 322.13815 -426.07474) (xy 322.139931 -426.044622) (xy 322.141596 -426.029628) (xy 322.141596 -425.419012)
			(xy 322.142023 -425.40693) (xy 322.149488 -425.383947) (xy 322.16369 -425.364396) (xy 322.183239 -425.350191)
			(xy 322.206222 -425.342724) (xy 322.218304 -425.342304) (xy 323.158104 -425.342304) (xy 323.170188 -425.342709)
			(xy 323.193173 -425.350179) (xy 323.212724 -425.364387) (xy 323.226928 -425.383941) (xy 323.234393 -425.406928)
			(xy 323.234812 -425.419012) (xy 323.234812 -427.960536) (xy 323.234367 -427.972612) (xy 323.226895 -427.99558)
			(xy 323.212693 -428.015116) (xy 323.193151 -428.029309) (xy 323.17018 -428.036772) (xy 323.158104 -428.037244)
			(xy 322.218304 -428.037244) (xy 322.206233 -428.036733) (xy 322.183272 -428.029276) (xy 322.163738 -428.01509)
			(xy 322.149542 -427.995564) (xy 322.142073 -427.972607) (xy 322.141596 -427.960536) (xy 322.141596 -427.350174)
			(xy 322.139932 -427.33518) (xy 322.13815 -427.305062) (xy 322.13804 -427.289976) (xy 321.234816 -427.289976)
			(xy 321.234816 -428.28972) (xy 324.138036 -428.28972) (xy 324.138148 -428.274634) (xy 324.139929 -428.244516)
			(xy 324.141592 -428.229522) (xy 324.141592 -427.150022) (xy 324.139923 -427.135029) (xy 324.138145 -427.10491)
			(xy 324.138036 -427.089824) (xy 324.138148 -427.074738) (xy 324.139929 -427.04462) (xy 324.141592 -427.029626)
			(xy 324.141592 -426.41901) (xy 324.142115 -426.406926) (xy 324.149563 -426.383934) (xy 324.163737 -426.364358)
			(xy 324.183256 -426.350105) (xy 324.206218 -426.342564) (xy 324.2183 -426.342048) (xy 325.1581 -426.342048)
			(xy 325.170204 -426.342515) (xy 325.193222 -426.350009) (xy 325.212791 -426.364259) (xy 325.226987 -426.383866)
			(xy 325.234417 -426.406905) (xy 325.234808 -426.41901) (xy 325.234808 -427.289976) (xy 326.138032 -427.289976)
			(xy 326.138149 -427.274891) (xy 326.139927 -427.244772) (xy 326.141588 -427.229778) (xy 326.141588 -426.150024)
			(xy 326.139919 -426.135031) (xy 326.138141 -426.104912) (xy 326.138032 -426.089826) (xy 326.138144 -426.07474)
			(xy 326.139925 -426.044622) (xy 326.141588 -426.029628) (xy 326.141588 -425.419012) (xy 326.142023 -425.40693)
			(xy 326.149487 -425.383949) (xy 326.163687 -425.364399) (xy 326.183234 -425.350194) (xy 326.206214 -425.342726)
			(xy 326.218296 -425.342304) (xy 327.158096 -425.342304) (xy 327.17018 -425.342716) (xy 327.193164 -425.350184)
			(xy 327.212716 -425.36439) (xy 327.22692 -425.383943) (xy 327.234385 -425.406928) (xy 327.234804 -425.419012)
			(xy 327.234804 -427.960536) (xy 327.234367 -427.972613) (xy 327.226894 -427.995582) (xy 327.21269 -428.015119)
			(xy 327.193146 -428.029312) (xy 327.170173 -428.036773) (xy 327.158096 -428.037244) (xy 326.218296 -428.037244)
			(xy 326.206225 -428.03674) (xy 326.183264 -428.02928) (xy 326.16373 -428.015093) (xy 326.149534 -427.995565)
			(xy 326.142065 -427.972607) (xy 326.141588 -427.960536) (xy 326.141588 -427.350174) (xy 326.139924 -427.33518)
			(xy 326.138142 -427.305062) (xy 326.138032 -427.289976) (xy 325.234808 -427.289976) (xy 325.234808 -428.28972)
			(xy 328.138028 -428.28972) (xy 328.13814 -428.274634) (xy 328.139921 -428.244516) (xy 328.141584 -428.229522)
			(xy 328.141584 -427.150022) (xy 328.139915 -427.135029) (xy 328.138137 -427.10491) (xy 328.138028 -427.089824)
			(xy 328.13814 -427.074738) (xy 328.139921 -427.04462) (xy 328.141584 -427.029626) (xy 328.141584 -426.41901)
			(xy 328.142017 -426.406917) (xy 328.149476 -426.383909) (xy 328.16367 -426.364325) (xy 328.183214 -426.350076)
			(xy 328.2062 -426.342551) (xy 328.218292 -426.342048) (xy 329.158092 -426.342048) (xy 329.170195 -426.342522)
			(xy 329.193214 -426.350013) (xy 329.212782 -426.364262) (xy 329.226979 -426.383868) (xy 329.234409 -426.406906)
			(xy 329.2348 -426.41901) (xy 329.2348 -427.289976) (xy 331.138022 -427.289976) (xy 331.138113 -427.275402)
			(xy 331.139767 -427.246301) (xy 331.141324 -427.23181) (xy 331.141324 -426.147992) (xy 331.139781 -426.1335)
			(xy 331.138128 -426.1044) (xy 331.138022 -426.089826) (xy 331.138117 -426.075252) (xy 331.139769 -426.046151)
			(xy 331.141324 -426.03166) (xy 331.141324 -425.419012) (xy 331.141727 -425.406901) (xy 331.149226 -425.38387)
			(xy 331.16349 -425.364295) (xy 331.183116 -425.350101) (xy 331.206174 -425.342684) (xy 331.218286 -425.342304)
			(xy 332.158086 -425.342304) (xy 332.170171 -425.342819) (xy 332.193165 -425.350267) (xy 332.212742 -425.364443)
			(xy 332.226995 -425.383964) (xy 332.234533 -425.406929) (xy 332.235048 -425.419012) (xy 332.235048 -427.960536)
			(xy 332.234615 -427.972642) (xy 332.227111 -427.995662) (xy 332.212852 -428.01523) (xy 332.193238 -428.029426)
			(xy 332.170193 -428.036854) (xy 332.158086 -428.037244) (xy 331.218286 -428.037244) (xy 331.206194 -428.036804)
			(xy 331.18319 -428.029342) (xy 331.163609 -428.015149) (xy 331.14936 -427.995609) (xy 331.141831 -427.972627)
			(xy 331.141324 -427.960536) (xy 331.141324 -427.348142) (xy 331.139777 -427.33365) (xy 331.138127 -427.30455)
			(xy 331.138022 -427.289976) (xy 329.2348 -427.289976) (xy 329.2348 -428.28972) (xy 333.138018 -428.28972)
			(xy 333.138113 -428.275146) (xy 333.139764 -428.246045) (xy 333.14132 -428.231554) (xy 333.14132 -427.14799)
			(xy 333.139777 -427.133498) (xy 333.138124 -427.104398) (xy 333.138018 -427.089824) (xy 333.138113 -427.07525)
			(xy 333.139765 -427.046149) (xy 333.14132 -427.031658) (xy 333.14132 -426.41901) (xy 333.14182 -426.406898)
			(xy 333.149302 -426.383858) (xy 333.163538 -426.364258) (xy 333.183133 -426.350015) (xy 333.20617 -426.342525)
			(xy 333.218282 -426.342048) (xy 334.158082 -426.342048) (xy 334.170205 -426.342475) (xy 334.193265 -426.349964)
			(xy 334.212881 -426.364213) (xy 334.227132 -426.383828) (xy 334.234623 -426.406887) (xy 334.235044 -426.41901)
			(xy 334.235044 -427.289976) (xy 335.138014 -427.289976) (xy 335.138104 -427.275402) (xy 335.139759 -427.246301)
			(xy 335.141316 -427.23181) (xy 335.141316 -426.147992) (xy 335.139773 -426.1335) (xy 335.13812 -426.1044)
			(xy 335.138014 -426.089826) (xy 335.138109 -426.075252) (xy 335.13976 -426.046151) (xy 335.141316 -426.03166)
			(xy 335.141316 -425.419012) (xy 335.141727 -425.406902) (xy 335.149225 -425.383873) (xy 335.163487 -425.364298)
			(xy 335.183111 -425.350104) (xy 335.206167 -425.342685) (xy 335.218278 -425.342304) (xy 336.158078 -425.342304)
			(xy 336.170163 -425.342825) (xy 336.193157 -425.350272) (xy 336.212734 -425.364446) (xy 336.226986 -425.383966)
			(xy 336.234525 -425.406929) (xy 336.23504 -425.419012) (xy 336.23504 -427.960536) (xy 336.234615 -427.972643)
			(xy 336.22711 -427.995664) (xy 336.21285 -428.015233) (xy 336.193233 -428.029428) (xy 336.170186 -428.036855)
			(xy 336.158078 -428.037244) (xy 335.218278 -428.037244) (xy 335.206186 -428.036811) (xy 335.183182 -428.029347)
			(xy 335.163601 -428.015152) (xy 335.149351 -427.99561) (xy 335.141823 -427.972627) (xy 335.141316 -427.960536)
			(xy 335.141316 -427.348142) (xy 335.139769 -427.33365) (xy 335.138119 -427.30455) (xy 335.138014 -427.289976)
			(xy 334.235044 -427.289976) (xy 334.235044 -428.28972) (xy 337.13801 -428.28972) (xy 337.138104 -428.275146)
			(xy 337.139756 -428.246045) (xy 337.141312 -428.231554) (xy 337.141312 -427.14799) (xy 337.139769 -427.133498)
			(xy 337.138116 -427.104398) (xy 337.13801 -427.089824) (xy 337.138104 -427.07525) (xy 337.139756 -427.046149)
			(xy 337.141312 -427.031658) (xy 337.141312 -426.41901) (xy 337.14182 -426.406899) (xy 337.149301 -426.38386)
			(xy 337.163535 -426.36426) (xy 337.183128 -426.350018) (xy 337.206163 -426.342526) (xy 337.218274 -426.342048)
			(xy 338.158074 -426.342048) (xy 338.170196 -426.342482) (xy 338.193256 -426.349969) (xy 338.212872 -426.364216)
			(xy 338.227124 -426.38383) (xy 338.234615 -426.406888) (xy 338.235036 -426.41901) (xy 338.235036 -427.289976)
			(xy 339.138006 -427.289976) (xy 339.138096 -427.275402) (xy 339.139751 -427.246301) (xy 339.141308 -427.23181)
			(xy 339.141308 -426.147992) (xy 339.139765 -426.1335) (xy 339.138112 -426.1044) (xy 339.138006 -426.089826)
			(xy 339.138101 -426.075252) (xy 339.139752 -426.046151) (xy 339.141308 -426.03166) (xy 339.141308 -425.419012)
			(xy 339.141727 -425.406903) (xy 339.149224 -425.383875) (xy 339.163485 -425.364301) (xy 339.183106 -425.350106)
			(xy 339.20616 -425.342687) (xy 339.21827 -425.342304) (xy 340.15807 -425.342304) (xy 340.170154 -425.342832)
			(xy 340.193148 -425.350276) (xy 340.212725 -425.364448) (xy 340.226978 -425.383967) (xy 340.234517 -425.40693)
			(xy 340.235032 -425.419012) (xy 340.235032 -427.960536) (xy 340.234615 -427.972644) (xy 340.227109 -427.995667)
			(xy 340.212847 -428.015236) (xy 340.193228 -428.029431) (xy 340.170179 -428.036856) (xy 340.15807 -428.037244)
			(xy 339.21827 -428.037244) (xy 339.206177 -428.036818) (xy 339.183173 -428.029351) (xy 339.163592 -428.015154)
			(xy 339.149343 -427.995612) (xy 339.141815 -427.972627) (xy 339.141308 -427.960536) (xy 339.141308 -427.348142)
			(xy 339.139761 -427.33365) (xy 339.138111 -427.30455) (xy 339.138006 -427.289976) (xy 338.235036 -427.289976)
			(xy 338.235036 -428.28972) (xy 341.138002 -428.28972) (xy 341.138096 -428.275146) (xy 341.139748 -428.246045)
			(xy 341.141304 -428.231554) (xy 341.141304 -427.14799) (xy 341.139761 -427.133498) (xy 341.138108 -427.104398)
			(xy 341.138002 -427.089824) (xy 341.138096 -427.07525) (xy 341.139748 -427.046149) (xy 341.141304 -427.031658)
			(xy 341.141304 -426.41901) (xy 341.14182 -426.406899) (xy 341.1493 -426.383862) (xy 341.163532 -426.364263)
			(xy 341.183123 -426.35002) (xy 341.206156 -426.342527) (xy 341.218266 -426.342048) (xy 342.158066 -426.342048)
			(xy 342.170188 -426.342489) (xy 342.193247 -426.349973) (xy 342.212864 -426.364219) (xy 342.227116 -426.383831)
			(xy 342.234607 -426.406888) (xy 342.235028 -426.41901) (xy 342.235028 -427.289976) (xy 343.137998 -427.289976)
			(xy 343.138088 -427.275402) (xy 343.139743 -427.246301) (xy 343.1413 -427.23181) (xy 343.1413 -426.147992)
			(xy 343.139757 -426.1335) (xy 343.138104 -426.1044) (xy 343.137998 -426.089826) (xy 343.138093 -426.075252)
			(xy 343.139744 -426.046151) (xy 343.1413 -426.03166) (xy 343.1413 -425.419012) (xy 343.141727 -425.406904)
			(xy 343.149223 -425.383877) (xy 343.163482 -425.364304) (xy 343.183101 -425.350109) (xy 343.206152 -425.342688)
			(xy 343.218262 -425.342304) (xy 344.158062 -425.342304) (xy 344.170146 -425.342839) (xy 344.193139 -425.350281)
			(xy 344.212717 -425.364451) (xy 344.22697 -425.383968) (xy 344.234509 -425.40693) (xy 344.235024 -425.419012)
			(xy 344.235024 -427.960536) (xy 344.234615 -427.972644) (xy 344.227108 -427.995669) (xy 344.212844 -428.015239)
			(xy 344.193223 -428.029433) (xy 344.170172 -428.036857) (xy 344.158062 -428.037244) (xy 343.218262 -428.037244)
			(xy 343.206169 -428.036825) (xy 343.183164 -428.029356) (xy 343.163584 -428.015157) (xy 343.149335 -427.995613)
			(xy 343.141807 -427.972628) (xy 343.1413 -427.960536) (xy 343.1413 -427.348142) (xy 343.139753 -427.33365)
			(xy 343.138103 -427.30455) (xy 343.137998 -427.289976) (xy 342.235028 -427.289976) (xy 342.235028 -428.28972)
			(xy 345.137994 -428.28972) (xy 345.138088 -428.275146) (xy 345.13974 -428.246045) (xy 345.141296 -428.231554)
			(xy 345.141296 -427.14799) (xy 345.139753 -427.133498) (xy 345.1381 -427.104398) (xy 345.137994 -427.089824)
			(xy 345.138088 -427.07525) (xy 345.13974 -427.046149) (xy 345.141296 -427.031658) (xy 345.141296 -426.41901)
			(xy 345.14182 -426.4069) (xy 345.149299 -426.383864) (xy 345.163529 -426.364266) (xy 345.183118 -426.350023)
			(xy 345.206148 -426.342528) (xy 345.218258 -426.342048) (xy 346.158058 -426.342048) (xy 346.17018 -426.342496)
			(xy 346.193239 -426.349978) (xy 346.212855 -426.364222) (xy 346.227108 -426.383833) (xy 346.234599 -426.406889)
			(xy 346.23502 -426.41901) (xy 346.23502 -427.289976) (xy 381.237998 -427.289976) (xy 381.238088 -427.275402)
			(xy 381.239743 -427.246301) (xy 381.2413 -427.23181) (xy 381.2413 -426.147992) (xy 381.239757 -426.1335)
			(xy 381.238104 -426.1044) (xy 381.237998 -426.089826) (xy 381.238093 -426.075252) (xy 381.239744 -426.046151)
			(xy 381.2413 -426.03166) (xy 381.2413 -425.419012) (xy 381.241727 -425.406904) (xy 381.249223 -425.383877)
			(xy 381.263482 -425.364304) (xy 381.283101 -425.350109) (xy 381.306152 -425.342688) (xy 381.318262 -425.342304)
			(xy 382.258062 -425.342304) (xy 382.270146 -425.342839) (xy 382.293139 -425.350281) (xy 382.312717 -425.364451)
			(xy 382.32697 -425.383968) (xy 382.334509 -425.40693) (xy 382.335024 -425.419012) (xy 382.335024 -427.960536)
			(xy 382.334615 -427.972644) (xy 382.327108 -427.995669) (xy 382.312844 -428.015239) (xy 382.293223 -428.029433)
			(xy 382.270172 -428.036857) (xy 382.258062 -428.037244) (xy 381.318262 -428.037244) (xy 381.306169 -428.036825)
			(xy 381.283164 -428.029356) (xy 381.263584 -428.015157) (xy 381.249335 -427.995613) (xy 381.241807 -427.972628)
			(xy 381.2413 -427.960536) (xy 381.2413 -427.348142) (xy 381.239753 -427.33365) (xy 381.238103 -427.30455)
			(xy 381.237998 -427.289976) (xy 346.23502 -427.289976) (xy 346.23502 -428.960534) (xy 346.234669 -428.972663)
			(xy 346.227162 -428.99573) (xy 346.212894 -429.015348) (xy 346.193262 -429.029597) (xy 346.170187 -429.03708)
			(xy 346.158058 -429.037496) (xy 345.218258 -429.037496) (xy 345.206145 -429.037025) (xy 345.183106 -429.02953)
			(xy 345.163508 -429.015287) (xy 345.149266 -428.995687) (xy 345.141774 -428.972647) (xy 345.141296 -428.960534)
			(xy 345.141296 -428.347886) (xy 345.139753 -428.333394) (xy 345.1381 -428.304294) (xy 345.137994 -428.28972)
			(xy 342.235028 -428.28972) (xy 342.235028 -428.960534) (xy 342.234617 -428.972654) (xy 342.227116 -428.995704)
			(xy 342.21286 -429.015308) (xy 342.193243 -429.029547) (xy 342.170186 -429.037027) (xy 342.158066 -429.037496)
			(xy 341.218266 -429.037496) (xy 341.206153 -429.037018) (xy 341.183114 -429.029525) (xy 341.163516 -429.015284)
			(xy 341.149275 -428.995686) (xy 341.141782 -428.972647) (xy 341.141304 -428.960534) (xy 341.141304 -428.347886)
			(xy 341.139761 -428.333394) (xy 341.138108 -428.304294) (xy 341.138002 -428.28972) (xy 338.235036 -428.28972)
			(xy 338.235036 -428.960534) (xy 338.234617 -428.972653) (xy 338.227117 -428.995702) (xy 338.212862 -429.015305)
			(xy 338.193248 -429.029545) (xy 338.170193 -429.037026) (xy 338.158074 -429.037496) (xy 337.218274 -429.037496)
			(xy 337.206161 -429.037011) (xy 337.183123 -429.029521) (xy 337.163525 -429.015281) (xy 337.149283 -428.995684)
			(xy 337.14179 -428.972646) (xy 337.141312 -428.960534) (xy 337.141312 -428.347886) (xy 337.139769 -428.333394)
			(xy 337.138116 -428.304294) (xy 337.13801 -428.28972) (xy 334.235044 -428.28972) (xy 334.235044 -428.960534)
			(xy 334.234617 -428.972652) (xy 334.227118 -428.9957) (xy 334.212865 -429.015302) (xy 334.193253 -429.029542)
			(xy 334.1702 -429.037025) (xy 334.158082 -429.037496) (xy 333.218282 -429.037496) (xy 333.20617 -429.037004)
			(xy 333.183132 -429.029516) (xy 333.163533 -429.015278) (xy 333.149291 -428.995683) (xy 333.141798 -428.972646)
			(xy 333.14132 -428.960534) (xy 333.14132 -428.347886) (xy 333.139777 -428.333394) (xy 333.138124 -428.304294)
			(xy 333.138018 -428.28972) (xy 329.2348 -428.28972) (xy 329.2348 -428.960534) (xy 329.234322 -428.972621)
			(xy 329.226861 -428.995616) (xy 329.212676 -429.015192) (xy 329.193148 -429.029443) (xy 329.170178 -429.036981)
			(xy 329.158092 -429.037496) (xy 328.218292 -429.037496) (xy 328.206182 -429.037091) (xy 328.183154 -429.029588)
			(xy 328.163581 -429.015324) (xy 328.149386 -428.9957) (xy 328.141967 -428.972645) (xy 328.141584 -428.960534)
			(xy 328.141584 -428.349918) (xy 328.139915 -428.334925) (xy 328.138137 -428.304806) (xy 328.138028 -428.28972)
			(xy 325.234808 -428.28972) (xy 325.234808 -428.960534) (xy 325.234323 -428.972621) (xy 325.226862 -428.995614)
			(xy 325.212679 -429.01519) (xy 325.193153 -429.029441) (xy 325.170185 -429.03698) (xy 325.1581 -429.037496)
			(xy 324.2183 -429.037496) (xy 324.206191 -429.037084) (xy 324.183163 -429.029584) (xy 324.163589 -429.015321)
			(xy 324.149395 -428.995699) (xy 324.141975 -428.972645) (xy 324.141592 -428.960534) (xy 324.141592 -428.349918)
			(xy 324.139923 -428.334925) (xy 324.138145 -428.304806) (xy 324.138036 -428.28972) (xy 321.234816 -428.28972)
			(xy 321.234816 -428.960534) (xy 321.234421 -428.97263) (xy 321.226949 -428.995639) (xy 321.212746 -429.015222)
			(xy 321.193195 -429.02947) (xy 321.170203 -429.036993) (xy 321.158108 -429.037496) (xy 320.218308 -429.037496)
			(xy 320.206199 -429.037077) (xy 320.183171 -429.029579) (xy 320.163598 -429.015319) (xy 320.149403 -428.995697)
			(xy 320.141983 -428.972644) (xy 320.1416 -428.960534) (xy 320.1416 -428.349918) (xy 320.139931 -428.334925)
			(xy 320.138153 -428.304806) (xy 320.138044 -428.28972) (xy 317.234824 -428.28972) (xy 317.234824 -428.960534)
			(xy 317.234421 -428.972629) (xy 317.226951 -428.995637) (xy 317.212749 -429.015219) (xy 317.1932 -429.029467)
			(xy 317.17021 -429.036992) (xy 317.158116 -429.037496) (xy 316.218316 -429.037496) (xy 316.206208 -429.03707)
			(xy 316.18318 -429.029574) (xy 316.163607 -429.015315) (xy 316.149412 -428.995695) (xy 316.141991 -428.972644)
			(xy 316.141608 -428.960534) (xy 316.141608 -428.349918) (xy 316.139939 -428.334925) (xy 316.138161 -428.304806)
			(xy 316.138052 -428.28972) (xy 231.01554 -428.28972) (xy 231.01554 -433.130695) (xy 266.885917 -433.130695)
			(xy 266.885917 -432.953425) (xy 266.89387 -432.776334) (xy 266.909761 -432.599778) (xy 266.933556 -432.424113)
			(xy 266.965209 -432.249692) (xy 267.004655 -432.076867) (xy 267.051815 -431.905986) (xy 267.106594 -431.737392)
			(xy 267.168882 -431.571427) (xy 267.238554 -431.408422) (xy 267.315468 -431.248708) (xy 267.399471 -431.092605)
			(xy 267.490392 -430.940428) (xy 267.588049 -430.792484) (xy 267.692246 -430.64907) (xy 267.802772 -430.510475)
			(xy 267.919404 -430.376978) (xy 268.041909 -430.248849) (xy 268.170038 -430.126344) (xy 268.303535 -430.009712)
			(xy 268.44213 -429.899186) (xy 268.585544 -429.794989) (xy 268.733488 -429.697332) (xy 268.885665 -429.606411)
			(xy 269.041768 -429.522408) (xy 269.201482 -429.445494) (xy 269.364487 -429.375822) (xy 269.530452 -429.313534)
			(xy 269.699046 -429.258755) (xy 269.869927 -429.211595) (xy 270.042752 -429.172149) (xy 270.217173 -429.140496)
			(xy 270.392838 -429.116701) (xy 270.569394 -429.10081) (xy 270.746485 -429.092857) (xy 270.923755 -429.092857)
			(xy 271.100846 -429.10081) (xy 271.277402 -429.116701) (xy 271.453067 -429.140496) (xy 271.627488 -429.172149)
			(xy 271.800313 -429.211595) (xy 271.971194 -429.258755) (xy 272.139788 -429.313534) (xy 272.305753 -429.375822)
			(xy 272.468758 -429.445494) (xy 272.628472 -429.522408) (xy 272.784575 -429.606411) (xy 272.936752 -429.697332)
			(xy 273.084696 -429.794989) (xy 273.22811 -429.899186) (xy 273.366705 -430.009712) (xy 273.500202 -430.126344)
			(xy 273.628331 -430.248849) (xy 273.750836 -430.376978) (xy 273.867468 -430.510475) (xy 273.977994 -430.64907)
			(xy 274.082191 -430.792484) (xy 274.146507 -430.889918) (xy 314.138056 -430.889918) (xy 314.138165 -430.874832)
			(xy 314.139947 -430.844714) (xy 314.141612 -430.82972) (xy 314.141612 -429.749966) (xy 314.139947 -429.734972)
			(xy 314.138166 -429.704854) (xy 314.138056 -429.689768) (xy 314.13817 -429.674682) (xy 314.139948 -429.644564)
			(xy 314.141612 -429.62957) (xy 314.141612 -429.018954) (xy 314.142068 -429.006865) (xy 314.149534 -428.983867)
			(xy 314.163724 -428.964291) (xy 314.183258 -428.950041) (xy 314.206232 -428.942505) (xy 314.21832 -428.941992)
			(xy 315.15812 -428.941992) (xy 315.170229 -428.942399) (xy 315.193256 -428.949903) (xy 315.212828 -428.964167)
			(xy 315.227022 -428.98379) (xy 315.234444 -429.006843) (xy 315.234828 -429.018954) (xy 315.234828 -431.560478)
			(xy 315.234373 -431.57257) (xy 315.226919 -431.595575) (xy 315.21273 -431.615158) (xy 315.193192 -431.629408)
			(xy 315.17021 -431.636935) (xy 315.15812 -431.63744) (xy 314.21832 -431.63744) (xy 314.206216 -431.636967)
			(xy 314.183196 -431.629478) (xy 314.163627 -431.61523) (xy 314.14943 -431.595622) (xy 314.142001 -431.572583)
			(xy 314.141612 -431.560478) (xy 314.141612 -430.950116) (xy 314.139943 -430.935123) (xy 314.138165 -430.905004)
			(xy 314.138056 -430.889918) (xy 274.146507 -430.889918) (xy 274.179848 -430.940428) (xy 274.270769 -431.092605)
			(xy 274.354772 -431.248708) (xy 274.431686 -431.408422) (xy 274.501358 -431.571427) (xy 274.563646 -431.737392)
			(xy 274.613204 -431.889916) (xy 316.138052 -431.889916) (xy 316.138161 -431.87483) (xy 316.139943 -431.844712)
			(xy 316.141608 -431.829718) (xy 316.141608 -430.749964) (xy 316.139943 -430.73497) (xy 316.138162 -430.704852)
			(xy 316.138052 -430.689766) (xy 316.138166 -430.67468) (xy 316.139944 -430.644562) (xy 316.141608 -430.629568)
			(xy 316.141608 -430.018952) (xy 316.142023 -430.006873) (xy 316.149501 -429.983902) (xy 316.16371 -429.964364)
			(xy 316.183259 -429.950172) (xy 316.206237 -429.942713) (xy 316.218316 -429.942244) (xy 317.158116 -429.942244)
			(xy 317.170187 -429.94275) (xy 317.193146 -429.950211) (xy 317.212679 -429.964399) (xy 317.226874 -429.983925)
			(xy 317.234345 -430.006882) (xy 317.234824 -430.018952) (xy 317.234824 -430.889918) (xy 318.138048 -430.889918)
			(xy 318.138157 -430.874832) (xy 318.139939 -430.844714) (xy 318.141604 -430.82972) (xy 318.141604 -429.749966)
			(xy 318.139939 -429.734972) (xy 318.138158 -429.704854) (xy 318.138048 -429.689768) (xy 318.138162 -429.674682)
			(xy 318.13994 -429.644564) (xy 318.141604 -429.62957) (xy 318.141604 -429.018954) (xy 318.142067 -429.006866)
			(xy 318.149532 -428.98387) (xy 318.163721 -428.964293) (xy 318.183253 -428.950043) (xy 318.206225 -428.942506)
			(xy 318.218312 -428.941992) (xy 319.158112 -428.941992) (xy 319.170221 -428.942406) (xy 319.193247 -428.949908)
			(xy 319.212819 -428.96417) (xy 319.227014 -428.983792) (xy 319.234436 -429.006844) (xy 319.23482 -429.018954)
			(xy 319.23482 -431.560478) (xy 319.234373 -431.57257) (xy 319.226918 -431.595577) (xy 319.212727 -431.615161)
			(xy 319.193187 -431.629411) (xy 319.170203 -431.636936) (xy 319.158112 -431.63744) (xy 318.218312 -431.63744)
			(xy 318.206208 -431.636974) (xy 318.183188 -431.629483) (xy 318.163618 -431.615232) (xy 318.149422 -431.595624)
			(xy 318.141993 -431.572583) (xy 318.141604 -431.560478) (xy 318.141604 -430.950116) (xy 318.139935 -430.935123)
			(xy 318.138157 -430.905004) (xy 318.138048 -430.889918) (xy 317.234824 -430.889918) (xy 317.234824 -431.889916)
			(xy 320.138044 -431.889916) (xy 320.138153 -431.87483) (xy 320.139935 -431.844712) (xy 320.1416 -431.829718)
			(xy 320.1416 -430.749964) (xy 320.139935 -430.73497) (xy 320.138154 -430.704852) (xy 320.138044 -430.689766)
			(xy 320.138158 -430.67468) (xy 320.139936 -430.644562) (xy 320.1416 -430.629568) (xy 320.1416 -430.018952)
			(xy 320.142023 -430.006874) (xy 320.1495 -429.983904) (xy 320.163707 -429.964367) (xy 320.183254 -429.950174)
			(xy 320.20623 -429.942714) (xy 320.218308 -429.942244) (xy 321.158108 -429.942244) (xy 321.170178 -429.942757)
			(xy 321.193137 -429.950216) (xy 321.21267 -429.964401) (xy 321.226866 -429.983927) (xy 321.234337 -430.006882)
			(xy 321.234816 -430.018952) (xy 321.234816 -430.889918) (xy 322.13804 -430.889918) (xy 322.138151 -430.874832)
			(xy 322.139933 -430.844714) (xy 322.141596 -430.82972) (xy 322.141596 -429.749966) (xy 322.139931 -429.734972)
			(xy 322.13815 -429.704854) (xy 322.13804 -429.689768) (xy 322.138154 -429.674682) (xy 322.139932 -429.644564)
			(xy 322.141596 -429.62957) (xy 322.141596 -429.018954) (xy 322.142067 -429.006866) (xy 322.149531 -428.983872)
			(xy 322.163718 -428.964296) (xy 322.183248 -428.950046) (xy 322.206218 -428.942507) (xy 322.218304 -428.941992)
			(xy 323.158104 -428.941992) (xy 323.170212 -428.942413) (xy 323.193238 -428.949912) (xy 323.212811 -428.964173)
			(xy 323.227006 -428.983793) (xy 323.234428 -429.006844) (xy 323.234812 -429.018954) (xy 323.234812 -431.560478)
			(xy 323.234373 -431.572571) (xy 323.226916 -431.595579) (xy 323.212724 -431.615164) (xy 323.193182 -431.629413)
			(xy 323.170196 -431.636937) (xy 323.158104 -431.63744) (xy 322.218304 -431.63744) (xy 322.206199 -431.636981)
			(xy 322.183179 -431.629488) (xy 322.163609 -431.615236) (xy 322.149413 -431.595625) (xy 322.141985 -431.572584)
			(xy 322.141596 -431.560478) (xy 322.141596 -430.950116) (xy 322.139927 -430.935123) (xy 322.138149 -430.905004)
			(xy 322.13804 -430.889918) (xy 321.234816 -430.889918) (xy 321.234816 -431.889916) (xy 324.138036 -431.889916)
			(xy 324.138147 -431.87483) (xy 324.139929 -431.844712) (xy 324.141592 -431.829718) (xy 324.141592 -430.749964)
			(xy 324.139927 -430.73497) (xy 324.138146 -430.704852) (xy 324.138036 -430.689766) (xy 324.138152 -430.674681)
			(xy 324.13993 -430.644562) (xy 324.141592 -430.629568) (xy 324.141592 -430.018952) (xy 324.142023 -430.006875)
			(xy 324.149499 -429.983906) (xy 324.163704 -429.96437) (xy 324.183249 -429.950177) (xy 324.206223 -429.942716)
			(xy 324.2183 -429.942244) (xy 325.1581 -429.942244) (xy 325.17017 -429.942764) (xy 325.193129 -429.95022)
			(xy 325.212662 -429.964404) (xy 325.226858 -429.983928) (xy 325.234329 -430.006883) (xy 325.234808 -430.018952)
			(xy 325.234808 -430.889918) (xy 326.138032 -430.889918) (xy 326.138143 -430.874832) (xy 326.139925 -430.844714)
			(xy 326.141588 -430.82972) (xy 326.141588 -429.749966) (xy 326.139923 -429.734972) (xy 326.138142 -429.704854)
			(xy 326.138032 -429.689768) (xy 326.138148 -429.674683) (xy 326.139926 -429.644564) (xy 326.141588 -429.62957)
			(xy 326.141588 -429.018954) (xy 326.141969 -429.006857) (xy 326.149444 -428.983847) (xy 326.163651 -428.964264)
			(xy 326.183205 -428.950016) (xy 326.2062 -428.942494) (xy 326.218296 -428.941992) (xy 327.158096 -428.941992)
			(xy 327.170204 -428.942419) (xy 327.19323 -428.949917) (xy 327.212802 -428.964176) (xy 327.226997 -428.983795)
			(xy 327.23442 -429.006845) (xy 327.234804 -429.018954) (xy 327.234804 -431.560478) (xy 327.234275 -431.572562)
			(xy 327.226829 -431.595555) (xy 327.212657 -431.615131) (xy 327.19314 -431.629384) (xy 327.170178 -431.636924)
			(xy 327.158096 -431.63744) (xy 326.218296 -431.63744) (xy 326.206191 -431.636988) (xy 326.18317 -431.629492)
			(xy 326.163601 -431.615238) (xy 326.149405 -431.595627) (xy 326.141977 -431.572584) (xy 326.141588 -431.560478)
			(xy 326.141588 -430.950116) (xy 326.139919 -430.935123) (xy 326.138141 -430.905004) (xy 326.138032 -430.889918)
			(xy 325.234808 -430.889918) (xy 325.234808 -431.889916) (xy 328.138028 -431.889916) (xy 328.138139 -431.87483)
			(xy 328.139921 -431.844712) (xy 328.141584 -431.829718) (xy 328.141584 -430.749964) (xy 328.139919 -430.73497)
			(xy 328.138138 -430.704852) (xy 328.138028 -430.689766) (xy 328.138144 -430.674681) (xy 328.139922 -430.644562)
			(xy 328.141584 -430.629568) (xy 328.141584 -430.018952) (xy 328.142023 -430.006876) (xy 328.149498 -429.983908)
			(xy 328.163701 -429.964373) (xy 328.183244 -429.95018) (xy 328.206215 -429.942717) (xy 328.218292 -429.942244)
			(xy 329.158092 -429.942244) (xy 329.170161 -429.94277) (xy 329.19312 -429.950225) (xy 329.212653 -429.964407)
			(xy 329.22685 -429.98393) (xy 329.234321 -430.006883) (xy 329.2348 -430.018952) (xy 329.2348 -430.889918)
			(xy 331.138022 -430.889918) (xy 331.138116 -430.875344) (xy 331.139768 -430.846243) (xy 331.141324 -430.831752)
			(xy 331.141324 -429.747934) (xy 331.139776 -429.733442) (xy 331.138126 -429.704342) (xy 331.138022 -429.689768)
			(xy 331.138121 -429.675194) (xy 331.13977 -429.646093) (xy 331.141324 -429.631602) (xy 331.141324 -429.018954)
			(xy 331.141772 -429.006838) (xy 331.14927 -428.983796) (xy 331.163519 -428.964196) (xy 331.183125 -428.949956)
			(xy 331.20617 -428.942467) (xy 331.218286 -428.941992) (xy 332.158086 -428.941992) (xy 332.170195 -428.942523)
			(xy 332.19323 -428.950001) (xy 332.212828 -428.964229) (xy 332.227072 -428.983816) (xy 332.234568 -429.006845)
			(xy 332.235048 -429.018954) (xy 332.235048 -431.560478) (xy 332.234621 -431.572601) (xy 332.227133 -431.595662)
			(xy 332.212884 -431.615278) (xy 332.193269 -431.62953) (xy 332.170209 -431.63702) (xy 332.158086 -431.63744)
			(xy 331.218286 -431.63744) (xy 331.20616 -431.637051) (xy 331.183097 -431.629553) (xy 331.163481 -431.615294)
			(xy 331.149231 -431.59567) (xy 331.141743 -431.572604) (xy 331.141324 -431.560478) (xy 331.141324 -430.948084)
			(xy 331.139781 -430.933592) (xy 331.138128 -430.904492) (xy 331.138022 -430.889918) (xy 329.2348 -430.889918)
			(xy 329.2348 -431.889916) (xy 333.138018 -431.889916) (xy 333.138112 -431.875342) (xy 333.139764 -431.846241)
			(xy 333.14132 -431.83175) (xy 333.14132 -430.747932) (xy 333.139772 -430.73344) (xy 333.138122 -430.70434)
			(xy 333.138018 -430.689766) (xy 333.138117 -430.675192) (xy 333.139766 -430.646091) (xy 333.14132 -430.6316)
			(xy 333.14132 -430.018952) (xy 333.141676 -430.006839) (xy 333.149191 -429.983806) (xy 333.163467 -429.964232)
			(xy 333.183103 -429.95004) (xy 333.206167 -429.942624) (xy 333.218282 -429.942244) (xy 334.158082 -429.942244)
			(xy 334.170171 -429.942723) (xy 334.193172 -429.950175) (xy 334.212752 -429.964358) (xy 334.227003 -429.98389)
			(xy 334.234535 -430.006865) (xy 334.235044 -430.018952) (xy 334.235044 -430.889918) (xy 335.138014 -430.889918)
			(xy 335.138108 -430.875344) (xy 335.13976 -430.846243) (xy 335.141316 -430.831752) (xy 335.141316 -429.747934)
			(xy 335.139768 -429.733442) (xy 335.138118 -429.704342) (xy 335.138014 -429.689768) (xy 335.138112 -429.675194)
			(xy 335.139762 -429.646093) (xy 335.141316 -429.631602) (xy 335.141316 -429.018954) (xy 335.141772 -429.006839)
			(xy 335.149269 -428.983798) (xy 335.163516 -428.964199) (xy 335.18312 -428.949958) (xy 335.206163 -428.942468)
			(xy 335.218278 -428.941992) (xy 336.158078 -428.941992) (xy 336.170187 -428.94253) (xy 336.193222 -428.950005)
			(xy 336.21282 -428.964232) (xy 336.227064 -428.983817) (xy 336.234559 -429.006846) (xy 336.23504 -429.018954)
			(xy 336.23504 -431.560478) (xy 336.234621 -431.572602) (xy 336.227132 -431.595664) (xy 336.212881 -431.615281)
			(xy 336.193264 -431.629532) (xy 336.170202 -431.637021) (xy 336.158078 -431.63744) (xy 335.218278 -431.63744)
			(xy 335.20616 -431.637007) (xy 335.183112 -431.629511) (xy 335.163509 -431.61526) (xy 335.149269 -431.595648)
			(xy 335.141786 -431.572596) (xy 335.141316 -431.560478) (xy 335.141316 -430.948084) (xy 335.139773 -430.933592)
			(xy 335.13812 -430.904492) (xy 335.138014 -430.889918) (xy 334.235044 -430.889918) (xy 334.235044 -431.889916)
			(xy 337.13801 -431.889916) (xy 337.138104 -431.875342) (xy 337.139756 -431.846241) (xy 337.141312 -431.83175)
			(xy 337.141312 -430.747932) (xy 337.139764 -430.73344) (xy 337.138114 -430.70434) (xy 337.13801 -430.689766)
			(xy 337.138108 -430.675192) (xy 337.139757 -430.646091) (xy 337.141312 -430.6316) (xy 337.141312 -430.018952)
			(xy 337.141676 -430.006839) (xy 337.14919 -429.983809) (xy 337.163465 -429.964235) (xy 337.183098 -429.950043)
			(xy 337.20616 -429.942625) (xy 337.218274 -429.942244) (xy 338.158074 -429.942244) (xy 338.170163 -429.94273)
			(xy 338.193163 -429.95018) (xy 338.212744 -429.964361) (xy 338.226995 -429.983891) (xy 338.234527 -430.006865)
			(xy 338.235036 -430.018952) (xy 338.235036 -430.889918) (xy 339.138006 -430.889918) (xy 339.1381 -430.875344)
			(xy 339.139752 -430.846243) (xy 339.141308 -430.831752) (xy 339.141308 -429.747934) (xy 339.13976 -429.733442)
			(xy 339.13811 -429.704342) (xy 339.138006 -429.689768) (xy 339.138104 -429.675194) (xy 339.139754 -429.646093)
			(xy 339.141308 -429.631602) (xy 339.141308 -429.018954) (xy 339.141772 -429.00684) (xy 339.149268 -428.9838)
			(xy 339.163513 -428.964202) (xy 339.183115 -428.949961) (xy 339.206156 -428.94247) (xy 339.21827 -428.941992)
			(xy 340.15807 -428.941992) (xy 340.170178 -428.942537) (xy 340.193213 -428.95001) (xy 340.212811 -428.964235)
			(xy 340.227055 -428.983819) (xy 340.234551 -429.006846) (xy 340.235032 -429.018954) (xy 340.235032 -431.560478)
			(xy 340.234621 -431.572603) (xy 340.227131 -431.595666) (xy 340.212878 -431.615284) (xy 340.193259 -431.629535)
			(xy 340.170195 -431.637022) (xy 340.15807 -431.63744) (xy 339.21827 -431.63744) (xy 339.206152 -431.637014)
			(xy 339.183104 -431.629515) (xy 339.163501 -431.615262) (xy 339.149261 -431.59565) (xy 339.141778 -431.572597)
			(xy 339.141308 -431.560478) (xy 339.141308 -430.948084) (xy 339.139764 -430.933592) (xy 339.138112 -430.904492)
			(xy 339.138006 -430.889918) (xy 338.235036 -430.889918) (xy 338.235036 -431.889916) (xy 341.138002 -431.889916)
			(xy 341.138096 -431.875342) (xy 341.139748 -431.846241) (xy 341.141304 -431.83175) (xy 341.141304 -430.747932)
			(xy 341.139756 -430.73344) (xy 341.138106 -430.70434) (xy 341.138002 -430.689766) (xy 341.1381 -430.675192)
			(xy 341.13975 -430.646091) (xy 341.141304 -430.6316) (xy 341.141304 -430.018952) (xy 341.141676 -430.00684)
			(xy 341.149189 -429.983811) (xy 341.163462 -429.964238) (xy 341.183093 -429.950045) (xy 341.206153 -429.942626)
			(xy 341.218266 -429.942244) (xy 342.158066 -429.942244) (xy 342.170154 -429.942736) (xy 342.193154 -429.950184)
			(xy 342.212735 -429.964364) (xy 342.226987 -429.983893) (xy 342.234519 -430.006866) (xy 342.235028 -430.018952)
			(xy 342.235028 -430.889918) (xy 343.137998 -430.889918) (xy 343.138092 -430.875344) (xy 343.139744 -430.846243)
			(xy 343.1413 -430.831752) (xy 343.1413 -429.747934) (xy 343.139752 -429.733442) (xy 343.138102 -429.704342)
			(xy 343.137998 -429.689768) (xy 343.138096 -429.675194) (xy 343.139746 -429.646093) (xy 343.1413 -429.631602)
			(xy 343.1413 -429.018954) (xy 343.141772 -429.006841) (xy 343.149267 -428.983803) (xy 343.163511 -428.964205)
			(xy 343.18311 -428.949964) (xy 343.206149 -428.942471) (xy 343.218262 -428.941992) (xy 344.158062 -428.941992)
			(xy 344.17017 -428.942543) (xy 344.193204 -428.950015) (xy 344.212803 -428.964238) (xy 344.227047 -428.98382)
			(xy 344.234543 -429.006847) (xy 344.235024 -429.018954) (xy 344.235024 -431.560478) (xy 344.234621 -431.572603)
			(xy 344.22713 -431.595668) (xy 344.212875 -431.615287) (xy 344.193254 -431.629537) (xy 344.170187 -431.637023)
			(xy 344.158062 -431.63744) (xy 343.218262 -431.63744) (xy 343.206143 -431.63702) (xy 343.183095 -431.62952)
			(xy 343.163492 -431.615265) (xy 343.149253 -431.595651) (xy 343.14177 -431.572597) (xy 343.1413 -431.560478)
			(xy 343.1413 -430.948084) (xy 343.139756 -430.933592) (xy 343.138104 -430.904492) (xy 343.137998 -430.889918)
			(xy 342.235028 -430.889918) (xy 342.235028 -431.889916) (xy 345.137994 -431.889916) (xy 345.138088 -431.875342)
			(xy 345.13974 -431.846241) (xy 345.141296 -431.83175) (xy 345.141296 -430.747932) (xy 345.139748 -430.73344)
			(xy 345.138098 -430.70434) (xy 345.137994 -430.689766) (xy 345.138092 -430.675192) (xy 345.139742 -430.646091)
			(xy 345.141296 -430.6316) (xy 345.141296 -430.018952) (xy 345.141676 -430.006841) (xy 345.149188 -429.983813)
			(xy 345.163459 -429.964241) (xy 345.183088 -429.950048) (xy 345.206145 -429.942628) (xy 345.218258 -429.942244)
			(xy 346.158058 -429.942244) (xy 346.170146 -429.942743) (xy 346.193146 -429.950189) (xy 346.212727 -429.964367)
			(xy 346.226979 -429.983894) (xy 346.234511 -430.006866) (xy 346.23502 -430.018952) (xy 346.23502 -431.359818)
			(xy 356.154736 -431.359818) (xy 356.155234 -431.274938) (xy 356.163191 -431.105365) (xy 356.179087 -430.936351)
			(xy 356.202888 -430.768268) (xy 356.234542 -430.601485) (xy 356.273978 -430.436369) (xy 356.32111 -430.273284)
			(xy 356.375834 -430.112586) (xy 356.438031 -429.954631) (xy 356.507563 -429.799764) (xy 356.584278 -429.648327)
			(xy 356.668006 -429.500651) (xy 356.758564 -429.357063) (xy 356.855753 -429.217877) (xy 356.95936 -429.0834)
			(xy 357.069155 -428.953927) (xy 357.184899 -428.829742) (xy 357.306336 -428.711119) (xy 357.4332 -428.598318)
			(xy 357.565211 -428.491588) (xy 357.702081 -428.391163) (xy 357.843506 -428.297264) (xy 357.989178 -428.210096)
			(xy 358.138776 -428.129853) (xy 358.29197 -428.056709) (xy 358.448424 -427.990827) (xy 358.607794 -427.93235)
			(xy 358.76973 -427.881408) (xy 358.933876 -427.838112) (xy 359.099871 -427.802557) (xy 359.26735 -427.774822)
			(xy 359.435945 -427.754968) (xy 359.605285 -427.743038) (xy 359.774998 -427.739059) (xy 359.944711 -427.743038)
			(xy 360.114051 -427.754968) (xy 360.282646 -427.774822) (xy 360.450125 -427.802557) (xy 360.61612 -427.838112)
			(xy 360.780266 -427.881408) (xy 360.942202 -427.93235) (xy 361.101572 -427.990827) (xy 361.258026 -428.056709)
			(xy 361.41122 -428.129853) (xy 361.560818 -428.210096) (xy 361.693883 -428.28972) (xy 383.237994 -428.28972)
			(xy 383.238088 -428.275146) (xy 383.23974 -428.246045) (xy 383.241296 -428.231554) (xy 383.241296 -427.14799)
			(xy 383.239753 -427.133498) (xy 383.2381 -427.104398) (xy 383.237994 -427.089824) (xy 383.238088 -427.07525)
			(xy 383.23974 -427.046149) (xy 383.241296 -427.031658) (xy 383.241296 -426.41901) (xy 383.24182 -426.4069)
			(xy 383.249299 -426.383864) (xy 383.263529 -426.364266) (xy 383.283118 -426.350023) (xy 383.306148 -426.342528)
			(xy 383.318258 -426.342048) (xy 384.258058 -426.342048) (xy 384.27018 -426.342496) (xy 384.293239 -426.349978)
			(xy 384.312855 -426.364222) (xy 384.327108 -426.383833) (xy 384.334599 -426.406889) (xy 384.33502 -426.41901)
			(xy 384.33502 -427.289976) (xy 385.23799 -427.289976) (xy 385.23808 -427.275402) (xy 385.239735 -427.246301)
			(xy 385.241292 -427.23181) (xy 385.241292 -426.147992) (xy 385.239749 -426.1335) (xy 385.238096 -426.1044)
			(xy 385.23799 -426.089826) (xy 385.238085 -426.075252) (xy 385.239736 -426.046151) (xy 385.241292 -426.03166)
			(xy 385.241292 -425.419012) (xy 385.241727 -425.406905) (xy 385.249222 -425.383879) (xy 385.263479 -425.364307)
			(xy 385.283096 -425.350111) (xy 385.306145 -425.342689) (xy 385.318254 -425.342304) (xy 386.258054 -425.342304)
			(xy 386.270138 -425.342846) (xy 386.293131 -425.350286) (xy 386.312708 -425.364454) (xy 386.326962 -425.38397)
			(xy 386.334501 -425.40693) (xy 386.335016 -425.419012) (xy 386.335016 -427.960536) (xy 386.334615 -427.972645)
			(xy 386.327107 -427.995671) (xy 386.312841 -428.015242) (xy 386.293218 -428.029436) (xy 386.270165 -428.036859)
			(xy 386.258054 -428.037244) (xy 385.318254 -428.037244) (xy 385.30616 -428.036832) (xy 385.283156 -428.02936)
			(xy 385.263575 -428.01516) (xy 385.249327 -427.995615) (xy 385.241799 -427.972628) (xy 385.241292 -427.960536)
			(xy 385.241292 -427.348142) (xy 385.239745 -427.33365) (xy 385.238095 -427.30455) (xy 385.23799 -427.289976)
			(xy 384.33502 -427.289976) (xy 384.33502 -428.28972) (xy 387.237986 -428.28972) (xy 387.23808 -428.275146)
			(xy 387.239732 -428.246045) (xy 387.241288 -428.231554) (xy 387.241288 -427.14799) (xy 387.239745 -427.133498)
			(xy 387.238092 -427.104398) (xy 387.237986 -427.089824) (xy 387.238081 -427.07525) (xy 387.239732 -427.046149)
			(xy 387.241288 -427.031658) (xy 387.241288 -426.41901) (xy 387.24182 -426.406901) (xy 387.249298 -426.383867)
			(xy 387.263526 -426.364269) (xy 387.283113 -426.350025) (xy 387.306141 -426.342529) (xy 387.31825 -426.342048)
			(xy 388.25805 -426.342048) (xy 388.270168 -426.342469) (xy 388.293215 -426.349972) (xy 388.312816 -426.364226)
			(xy 388.327056 -426.383839) (xy 388.33454 -426.406891) (xy 388.335012 -426.41901) (xy 388.335012 -427.289976)
			(xy 389.237982 -427.289976) (xy 389.238072 -427.275402) (xy 389.239727 -427.246301) (xy 389.241284 -427.23181)
			(xy 389.241284 -426.147992) (xy 389.239741 -426.1335) (xy 389.238088 -426.1044) (xy 389.237982 -426.089826)
			(xy 389.238077 -426.075252) (xy 389.239728 -426.046151) (xy 389.241284 -426.03166) (xy 389.241284 -425.419012)
			(xy 389.241727 -425.406905) (xy 389.249221 -425.383881) (xy 389.263476 -425.364309) (xy 389.283091 -425.350114)
			(xy 389.306138 -425.34269) (xy 389.318246 -425.342304) (xy 390.258046 -425.342304) (xy 390.270134 -425.342767)
			(xy 390.29313 -425.350232) (xy 390.312707 -425.364421) (xy 390.326957 -425.383953) (xy 390.334494 -425.406925)
			(xy 390.335008 -425.419012) (xy 390.335008 -427.960536) (xy 390.334614 -427.972646) (xy 390.327106 -427.995673)
			(xy 390.312838 -428.015245) (xy 390.293213 -428.029438) (xy 390.270157 -428.03686) (xy 390.258046 -428.037244)
			(xy 389.318246 -428.037244) (xy 389.306157 -428.036753) (xy 389.283155 -428.029307) (xy 389.263573 -428.015127)
			(xy 389.249322 -427.995597) (xy 389.241791 -427.972623) (xy 389.241284 -427.960536) (xy 389.241284 -427.348142)
			(xy 389.239737 -427.33365) (xy 389.238087 -427.30455) (xy 389.237982 -427.289976) (xy 388.335012 -427.289976)
			(xy 388.335012 -428.28972) (xy 391.237978 -428.28972) (xy 391.238072 -428.275146) (xy 391.239724 -428.246045)
			(xy 391.24128 -428.231554) (xy 391.24128 -427.14799) (xy 391.239737 -427.133498) (xy 391.238084 -427.104398)
			(xy 391.237978 -427.089824) (xy 391.238073 -427.07525) (xy 391.239724 -427.046149) (xy 391.24128 -427.031658)
			(xy 391.24128 -426.41901) (xy 391.241669 -426.406884) (xy 391.249164 -426.383818) (xy 391.263422 -426.364199)
			(xy 391.283047 -426.349949) (xy 391.306115 -426.342464) (xy 391.318242 -426.342048) (xy 392.258042 -426.342048)
			(xy 392.27016 -426.342476) (xy 392.293206 -426.349976) (xy 392.312808 -426.364229) (xy 392.327048 -426.383841)
			(xy 392.334532 -426.406892) (xy 392.335004 -426.41901) (xy 392.335004 -427.289976) (xy 393.237974 -427.289976)
			(xy 393.238064 -427.275402) (xy 393.239719 -427.246301) (xy 393.241276 -427.23181) (xy 393.241276 -426.147992)
			(xy 393.239733 -426.1335) (xy 393.23808 -426.1044) (xy 393.237974 -426.089826) (xy 393.238069 -426.075252)
			(xy 393.23972 -426.046151) (xy 393.241276 -426.03166) (xy 393.241276 -425.419012) (xy 393.241726 -425.406906)
			(xy 393.24922 -425.383883) (xy 393.263473 -425.364312) (xy 393.283086 -425.350116) (xy 393.306131 -425.342691)
			(xy 393.318238 -425.342304) (xy 394.258038 -425.342304) (xy 394.270126 -425.342774) (xy 394.293122 -425.350237)
			(xy 394.312698 -425.364424) (xy 394.326949 -425.383954) (xy 394.334486 -425.406926) (xy 394.335 -425.419012)
			(xy 394.335 -427.960536) (xy 394.334614 -427.972647) (xy 394.327105 -427.995675) (xy 394.312835 -428.015248)
			(xy 394.293208 -428.029441) (xy 394.27015 -428.036861) (xy 394.258038 -428.037244) (xy 393.318238 -428.037244)
			(xy 393.306149 -428.03676) (xy 393.283147 -428.029312) (xy 393.263565 -428.01513) (xy 393.249314 -427.995599)
			(xy 393.241783 -427.972623) (xy 393.241276 -427.960536) (xy 393.241276 -427.348142) (xy 393.239729 -427.33365)
			(xy 393.238079 -427.30455) (xy 393.237974 -427.289976) (xy 392.335004 -427.289976) (xy 392.335004 -428.28972)
			(xy 395.23797 -428.28972) (xy 395.238064 -428.275146) (xy 395.239716 -428.246045) (xy 395.241272 -428.231554)
			(xy 395.241272 -427.14799) (xy 395.239729 -427.133498) (xy 395.238076 -427.104398) (xy 395.23797 -427.089824)
			(xy 395.238065 -427.07525) (xy 395.239716 -427.046149) (xy 395.241272 -427.031658) (xy 395.241272 -426.41901)
			(xy 395.241669 -426.406884) (xy 395.249163 -426.38382) (xy 395.263419 -426.364202) (xy 395.283042 -426.349952)
			(xy 395.306108 -426.342465) (xy 395.318234 -426.342048) (xy 396.258034 -426.342048) (xy 396.270151 -426.342483)
			(xy 396.293197 -426.349981) (xy 396.312799 -426.364232) (xy 396.327039 -426.383842) (xy 396.334524 -426.406892)
			(xy 396.334996 -426.41901) (xy 396.334996 -427.289976) (xy 398.237964 -427.289976) (xy 398.238078 -427.274891)
			(xy 398.239856 -427.244772) (xy 398.24152 -427.229778) (xy 398.24152 -426.150024) (xy 398.239851 -426.135031)
			(xy 398.238073 -426.104912) (xy 398.237964 -426.089826) (xy 398.238074 -426.07474) (xy 398.239855 -426.044622)
			(xy 398.24152 -426.029628) (xy 398.24152 -425.419012) (xy 398.241924 -425.406927) (xy 398.249391 -425.38394)
			(xy 398.263599 -425.364387) (xy 398.283154 -425.350184) (xy 398.306143 -425.342721) (xy 398.318228 -425.342304)
			(xy 399.258028 -425.342304) (xy 399.270105 -425.34274) (xy 399.293075 -425.350212) (xy 399.312613 -425.364415)
			(xy 399.326806 -425.38396) (xy 399.334266 -425.406935) (xy 399.334736 -425.419012) (xy 399.334736 -427.960536)
			(xy 399.334267 -427.97261) (xy 399.326798 -427.995573) (xy 399.312602 -428.015107) (xy 399.293066 -428.029302)
			(xy 399.270102 -428.036768) (xy 399.258028 -428.037244) (xy 398.318228 -428.037244) (xy 398.306158 -428.036713)
			(xy 398.283198 -428.029262) (xy 398.263664 -428.015082) (xy 398.249467 -427.995559) (xy 398.241997 -427.972605)
			(xy 398.24152 -427.960536) (xy 398.24152 -427.350174) (xy 398.239856 -427.33518) (xy 398.238074 -427.305062)
			(xy 398.237964 -427.289976) (xy 396.334996 -427.289976) (xy 396.334996 -428.28972) (xy 400.23796 -428.28972)
			(xy 400.238069 -428.274634) (xy 400.239851 -428.244516) (xy 400.241516 -428.229522) (xy 400.241516 -427.150022)
			(xy 400.239847 -427.135029) (xy 400.238069 -427.10491) (xy 400.23796 -427.089824) (xy 400.23807 -427.074738)
			(xy 400.239851 -427.04462) (xy 400.241516 -427.029626) (xy 400.241516 -426.41901) (xy 400.242016 -426.406923)
			(xy 400.249467 -426.383927) (xy 400.263646 -426.364349) (xy 400.283171 -426.350097) (xy 400.306139 -426.342561)
			(xy 400.318224 -426.342048) (xy 401.258024 -426.342048) (xy 401.270129 -426.342495) (xy 401.293148 -426.349995)
			(xy 401.312716 -426.36425) (xy 401.326912 -426.383862) (xy 401.334341 -426.406904) (xy 401.334732 -426.41901)
			(xy 401.334732 -427.289976) (xy 402.237956 -427.289976) (xy 402.23807 -427.274891) (xy 402.239848 -427.244772)
			(xy 402.241512 -427.229778) (xy 402.241512 -426.150024) (xy 402.239843 -426.135031) (xy 402.238065 -426.104912)
			(xy 402.237956 -426.089826) (xy 402.238066 -426.07474) (xy 402.239847 -426.044622) (xy 402.241512 -426.029628)
			(xy 402.241512 -425.419012) (xy 402.241923 -425.406928) (xy 402.24939 -425.383942) (xy 402.263596 -425.36439)
			(xy 402.283149 -425.350186) (xy 402.306136 -425.342722) (xy 402.31822 -425.342304) (xy 403.25802 -425.342304)
			(xy 403.270097 -425.342748) (xy 403.293067 -425.350217) (xy 403.312604 -425.364419) (xy 403.326798 -425.383962)
			(xy 403.334257 -425.406935) (xy 403.334728 -425.419012) (xy 403.334728 -427.960536) (xy 403.334267 -427.97261)
			(xy 403.326797 -427.995576) (xy 403.312599 -428.01511) (xy 403.293061 -428.029304) (xy 403.270095 -428.036769)
			(xy 403.25802 -428.037244) (xy 402.31822 -428.037244) (xy 402.30615 -428.036719) (xy 402.28319 -428.029267)
			(xy 402.263655 -428.015085) (xy 402.249459 -427.995561) (xy 402.241989 -427.972606) (xy 402.241512 -427.960536)
			(xy 402.241512 -427.350174) (xy 402.239848 -427.33518) (xy 402.238066 -427.305062) (xy 402.237956 -427.289976)
			(xy 401.334732 -427.289976) (xy 401.334732 -428.28972) (xy 404.237952 -428.28972) (xy 404.238062 -428.274634)
			(xy 404.239843 -428.244516) (xy 404.241508 -428.229522) (xy 404.241508 -427.150022) (xy 404.239839 -427.135029)
			(xy 404.238061 -427.10491) (xy 404.237952 -427.089824) (xy 404.238062 -427.074738) (xy 404.239843 -427.04462)
			(xy 404.241508 -427.029626) (xy 404.241508 -426.41901) (xy 404.242015 -426.406924) (xy 404.249465 -426.383929)
			(xy 404.263643 -426.364352) (xy 404.283166 -426.3501) (xy 404.306132 -426.342562) (xy 404.318216 -426.342048)
			(xy 405.258016 -426.342048) (xy 405.270121 -426.342502) (xy 405.293139 -426.349999) (xy 405.312708 -426.364253)
			(xy 405.326904 -426.383863) (xy 405.334333 -426.406904) (xy 405.334724 -426.41901) (xy 405.334724 -427.289976)
			(xy 406.237948 -427.289976) (xy 406.238062 -427.274891) (xy 406.23984 -427.244772) (xy 406.241504 -427.229778)
			(xy 406.241504 -426.150024) (xy 406.239835 -426.135031) (xy 406.238057 -426.104912) (xy 406.237948 -426.089826)
			(xy 406.238058 -426.07474) (xy 406.239839 -426.044622) (xy 406.241504 -426.029628) (xy 406.241504 -425.419012)
			(xy 406.241923 -425.406929) (xy 406.249389 -425.383944) (xy 406.263593 -425.364393) (xy 406.283144 -425.350189)
			(xy 406.306129 -425.342723) (xy 406.318212 -425.342304) (xy 407.258012 -425.342304) (xy 407.270088 -425.342754)
			(xy 407.293058 -425.350222) (xy 407.312596 -425.364421) (xy 407.326789 -425.383964) (xy 407.334249 -425.406935)
			(xy 407.33472 -425.419012) (xy 407.33472 -427.960536) (xy 407.334267 -427.972611) (xy 407.326796 -427.995578)
			(xy 407.312596 -428.015113) (xy 407.293056 -428.029307) (xy 407.270087 -428.036771) (xy 407.258012 -428.037244)
			(xy 406.318212 -428.037244) (xy 406.306142 -428.036726) (xy 406.283181 -428.029271) (xy 406.263647 -428.015087)
			(xy 406.249451 -427.995562) (xy 406.241981 -427.972606) (xy 406.241504 -427.960536) (xy 406.241504 -427.350174)
			(xy 406.23984 -427.33518) (xy 406.238058 -427.305062) (xy 406.237948 -427.289976) (xy 405.334724 -427.289976)
			(xy 405.334724 -428.28972) (xy 408.237944 -428.28972) (xy 408.238054 -428.274634) (xy 408.239835 -428.244516)
			(xy 408.2415 -428.229522) (xy 408.2415 -427.150022) (xy 408.239831 -427.135029) (xy 408.238053 -427.10491)
			(xy 408.237944 -427.089824) (xy 408.238054 -427.074738) (xy 408.239835 -427.04462) (xy 408.2415 -427.029626)
			(xy 408.2415 -426.41901) (xy 408.242015 -426.406925) (xy 408.249464 -426.383931) (xy 408.26364 -426.364355)
			(xy 408.283161 -426.350103) (xy 408.306125 -426.342563) (xy 408.318208 -426.342048) (xy 409.258008 -426.342048)
			(xy 409.270112 -426.342509) (xy 409.293131 -426.350004) (xy 409.312699 -426.364256) (xy 409.326896 -426.383865)
			(xy 409.334325 -426.406905) (xy 409.334716 -426.41901) (xy 409.334716 -427.289976) (xy 410.23794 -427.289976)
			(xy 410.238055 -427.274891) (xy 410.239832 -427.244772) (xy 410.241496 -427.229778) (xy 410.241496 -426.150024)
			(xy 410.239827 -426.135031) (xy 410.238049 -426.104912) (xy 410.23794 -426.089826) (xy 410.23805 -426.07474)
			(xy 410.239831 -426.044622) (xy 410.241496 -426.029628) (xy 410.241496 -425.419012) (xy 410.241923 -425.40693)
			(xy 410.249388 -425.383947) (xy 410.26359 -425.364396) (xy 410.283139 -425.350191) (xy 410.306122 -425.342724)
			(xy 410.318204 -425.342304) (xy 411.258004 -425.342304) (xy 411.270088 -425.342709) (xy 411.293073 -425.350179)
			(xy 411.312624 -425.364387) (xy 411.326828 -425.383941) (xy 411.334293 -425.406928) (xy 411.334712 -425.419012)
			(xy 411.334712 -427.960536) (xy 411.334267 -427.972612) (xy 411.326795 -427.99558) (xy 411.312593 -428.015116)
			(xy 411.293051 -428.029309) (xy 411.27008 -428.036772) (xy 411.258004 -428.037244) (xy 410.318204 -428.037244)
			(xy 410.306133 -428.036733) (xy 410.283172 -428.029276) (xy 410.263638 -428.01509) (xy 410.249442 -427.995564)
			(xy 410.241973 -427.972607) (xy 410.241496 -427.960536) (xy 410.241496 -427.350174) (xy 410.239832 -427.33518)
			(xy 410.23805 -427.305062) (xy 410.23794 -427.289976) (xy 409.334716 -427.289976) (xy 409.334716 -428.28972)
			(xy 412.237936 -428.28972) (xy 412.238048 -428.274634) (xy 412.239829 -428.244516) (xy 412.241492 -428.229522)
			(xy 412.241492 -427.150022) (xy 412.239823 -427.135029) (xy 412.238045 -427.10491) (xy 412.237936 -427.089824)
			(xy 412.238048 -427.074738) (xy 412.239829 -427.04462) (xy 412.241492 -427.029626) (xy 412.241492 -426.41901)
			(xy 412.242015 -426.406926) (xy 412.249463 -426.383934) (xy 412.263637 -426.364358) (xy 412.283156 -426.350105)
			(xy 412.306118 -426.342564) (xy 412.3182 -426.342048) (xy 413.258 -426.342048) (xy 413.270104 -426.342515)
			(xy 413.293122 -426.350009) (xy 413.312691 -426.364259) (xy 413.326887 -426.383866) (xy 413.334317 -426.406905)
			(xy 413.334708 -426.41901) (xy 413.334708 -428.960534) (xy 413.334223 -428.972621) (xy 413.326762 -428.995614)
			(xy 413.312579 -429.01519) (xy 413.293053 -429.029441) (xy 413.270085 -429.03698) (xy 413.258 -429.037496)
			(xy 412.3182 -429.037496) (xy 412.306091 -429.037084) (xy 412.283063 -429.029584) (xy 412.263489 -429.015321)
			(xy 412.249295 -428.995699) (xy 412.241875 -428.972645) (xy 412.241492 -428.960534) (xy 412.241492 -428.349918)
			(xy 412.239823 -428.334925) (xy 412.238045 -428.304806) (xy 412.237936 -428.28972) (xy 409.334716 -428.28972)
			(xy 409.334716 -428.960534) (xy 409.334321 -428.97263) (xy 409.326849 -428.995639) (xy 409.312646 -429.015222)
			(xy 409.293095 -429.02947) (xy 409.270103 -429.036993) (xy 409.258008 -429.037496) (xy 408.318208 -429.037496)
			(xy 408.306099 -429.037077) (xy 408.283071 -429.029579) (xy 408.263498 -429.015319) (xy 408.249303 -428.995697)
			(xy 408.241883 -428.972644) (xy 408.2415 -428.960534) (xy 408.2415 -428.349918) (xy 408.239831 -428.334925)
			(xy 408.238053 -428.304806) (xy 408.237944 -428.28972) (xy 405.334724 -428.28972) (xy 405.334724 -428.960534)
			(xy 405.334321 -428.972629) (xy 405.326851 -428.995637) (xy 405.312649 -429.015219) (xy 405.2931 -429.029467)
			(xy 405.27011 -429.036992) (xy 405.258016 -429.037496) (xy 404.318216 -429.037496) (xy 404.306108 -429.03707)
			(xy 404.28308 -429.029574) (xy 404.263507 -429.015315) (xy 404.249312 -428.995695) (xy 404.241891 -428.972644)
			(xy 404.241508 -428.960534) (xy 404.241508 -428.349918) (xy 404.239839 -428.334925) (xy 404.238061 -428.304806)
			(xy 404.237952 -428.28972) (xy 401.334732 -428.28972) (xy 401.334732 -428.960534) (xy 401.334321 -428.972628)
			(xy 401.326852 -428.995635) (xy 401.312652 -429.015216) (xy 401.293105 -429.029465) (xy 401.270117 -429.036991)
			(xy 401.258024 -429.037496) (xy 400.318224 -429.037496) (xy 400.306116 -429.037063) (xy 400.283089 -429.02957)
			(xy 400.263515 -429.015313) (xy 400.24932 -428.995694) (xy 400.241899 -428.972643) (xy 400.241516 -428.960534)
			(xy 400.241516 -428.349918) (xy 400.239847 -428.334925) (xy 400.238069 -428.304806) (xy 400.23796 -428.28972)
			(xy 396.334996 -428.28972) (xy 396.334996 -428.960534) (xy 396.334518 -428.972647) (xy 396.327025 -428.995686)
			(xy 396.312784 -429.015284) (xy 396.293186 -429.029525) (xy 396.270147 -429.037018) (xy 396.258034 -429.037496)
			(xy 395.318234 -429.037496) (xy 395.306125 -429.03696) (xy 395.283088 -429.029486) (xy 395.263489 -429.01526)
			(xy 395.249245 -428.995673) (xy 395.241751 -428.972643) (xy 395.241272 -428.960534) (xy 395.241272 -428.347886)
			(xy 395.239729 -428.333394) (xy 395.238076 -428.304294) (xy 395.23797 -428.28972) (xy 392.335004 -428.28972)
			(xy 392.335004 -428.960534) (xy 392.334518 -428.972646) (xy 392.327027 -428.995683) (xy 392.312787 -429.015281)
			(xy 392.293191 -429.029523) (xy 392.270154 -429.037017) (xy 392.258042 -429.037496) (xy 391.318242 -429.037496)
			(xy 391.306125 -429.037005) (xy 391.283073 -429.029528) (xy 391.26346 -429.015294) (xy 391.249206 -428.995695)
			(xy 391.241707 -428.972651) (xy 391.24128 -428.960534) (xy 391.24128 -428.347886) (xy 391.239737 -428.333394)
			(xy 391.238084 -428.304294) (xy 391.237978 -428.28972) (xy 388.335012 -428.28972) (xy 388.335012 -428.960534)
			(xy 388.334518 -428.972645) (xy 388.327028 -428.995681) (xy 388.31279 -429.015278) (xy 388.293196 -429.02952)
			(xy 388.270161 -429.037016) (xy 388.25805 -429.037496) (xy 387.31825 -429.037496) (xy 387.306136 -429.037031)
			(xy 387.283097 -429.029535) (xy 387.263499 -429.015289) (xy 387.249258 -428.995689) (xy 387.241766 -428.972648)
			(xy 387.241288 -428.960534) (xy 387.241288 -428.347886) (xy 387.239745 -428.333394) (xy 387.238092 -428.304294)
			(xy 387.237986 -428.28972) (xy 384.33502 -428.28972) (xy 384.33502 -428.960534) (xy 384.334669 -428.972663)
			(xy 384.327162 -428.99573) (xy 384.312894 -429.015348) (xy 384.293262 -429.029597) (xy 384.270187 -429.03708)
			(xy 384.258058 -429.037496) (xy 383.318258 -429.037496) (xy 383.306145 -429.037025) (xy 383.283106 -429.02953)
			(xy 383.263508 -429.015287) (xy 383.249266 -428.995687) (xy 383.241774 -428.972647) (xy 383.241296 -428.960534)
			(xy 383.241296 -428.347886) (xy 383.239753 -428.333394) (xy 383.2381 -428.304294) (xy 383.237994 -428.28972)
			(xy 361.693883 -428.28972) (xy 361.70649 -428.297264) (xy 361.847915 -428.391163) (xy 361.984785 -428.491588)
			(xy 362.116796 -428.598318) (xy 362.24366 -428.711119) (xy 362.365097 -428.829742) (xy 362.480841 -428.953927)
			(xy 362.590636 -429.0834) (xy 362.694243 -429.217877) (xy 362.791432 -429.357063) (xy 362.88199 -429.500651)
			(xy 362.965718 -429.648327) (xy 363.042433 -429.799764) (xy 363.111965 -429.954631) (xy 363.174162 -430.112586)
			(xy 363.228886 -430.273284) (xy 363.276018 -430.436369) (xy 363.315454 -430.601485) (xy 363.347108 -430.768268)
			(xy 363.364334 -430.889918) (xy 381.237998 -430.889918) (xy 381.238092 -430.875344) (xy 381.239744 -430.846243)
			(xy 381.2413 -430.831752) (xy 381.2413 -429.747934) (xy 381.239752 -429.733442) (xy 381.238102 -429.704342)
			(xy 381.237998 -429.689768) (xy 381.238096 -429.675194) (xy 381.239746 -429.646093) (xy 381.2413 -429.631602)
			(xy 381.2413 -429.018954) (xy 381.241772 -429.006841) (xy 381.249267 -428.983803) (xy 381.263511 -428.964205)
			(xy 381.28311 -428.949964) (xy 381.306149 -428.942471) (xy 381.318262 -428.941992) (xy 382.258062 -428.941992)
			(xy 382.27017 -428.942543) (xy 382.293204 -428.950015) (xy 382.312803 -428.964238) (xy 382.327047 -428.98382)
			(xy 382.334543 -429.006847) (xy 382.335024 -429.018954) (xy 382.335024 -431.560478) (xy 382.334621 -431.572603)
			(xy 382.32713 -431.595668) (xy 382.312875 -431.615287) (xy 382.293254 -431.629537) (xy 382.270187 -431.637023)
			(xy 382.258062 -431.63744) (xy 381.318262 -431.63744) (xy 381.306143 -431.63702) (xy 381.283095 -431.62952)
			(xy 381.263492 -431.615265) (xy 381.249253 -431.595651) (xy 381.24177 -431.572597) (xy 381.2413 -431.560478)
			(xy 381.2413 -430.948084) (xy 381.239756 -430.933592) (xy 381.238104 -430.904492) (xy 381.237998 -430.889918)
			(xy 363.364334 -430.889918) (xy 363.370909 -430.936351) (xy 363.386805 -431.105365) (xy 363.394762 -431.274938)
			(xy 363.39526 -431.359818) (xy 363.39483 -431.445421) (xy 363.38674 -431.616436) (xy 363.370574 -431.786877)
			(xy 363.355859 -431.889916) (xy 383.237994 -431.889916) (xy 383.238088 -431.875342) (xy 383.23974 -431.846241)
			(xy 383.241296 -431.83175) (xy 383.241296 -430.747932) (xy 383.239748 -430.73344) (xy 383.238098 -430.70434)
			(xy 383.237994 -430.689766) (xy 383.238092 -430.675192) (xy 383.239742 -430.646091) (xy 383.241296 -430.6316)
			(xy 383.241296 -430.018952) (xy 383.241676 -430.006841) (xy 383.249188 -429.983813) (xy 383.263459 -429.964241)
			(xy 383.283088 -429.950048) (xy 383.306145 -429.942628) (xy 383.318258 -429.942244) (xy 384.258058 -429.942244)
			(xy 384.270146 -429.942743) (xy 384.293146 -429.950189) (xy 384.312727 -429.964367) (xy 384.326979 -429.983894)
			(xy 384.334511 -430.006866) (xy 384.33502 -430.018952) (xy 384.33502 -430.889918) (xy 385.23799 -430.889918)
			(xy 385.238084 -430.875344) (xy 385.239736 -430.846243) (xy 385.241292 -430.831752) (xy 385.241292 -429.747934)
			(xy 385.239745 -429.733442) (xy 385.238094 -429.704342) (xy 385.23799 -429.689768) (xy 385.238088 -429.675194)
			(xy 385.239738 -429.646093) (xy 385.241292 -429.631602) (xy 385.241292 -429.018954) (xy 385.241772 -429.006842)
			(xy 385.249266 -428.983805) (xy 385.263508 -428.964208) (xy 385.283105 -428.949966) (xy 385.306142 -428.942472)
			(xy 385.318254 -428.941992) (xy 386.258054 -428.941992) (xy 386.270162 -428.94255) (xy 386.293196 -428.950019)
			(xy 386.312794 -428.96424) (xy 386.327039 -428.983822) (xy 386.334535 -429.006847) (xy 386.335016 -429.018954)
			(xy 386.335016 -431.560478) (xy 386.334621 -431.572604) (xy 386.327129 -431.59567) (xy 386.312872 -431.61529)
			(xy 386.293249 -431.62954) (xy 386.27018 -431.637024) (xy 386.258054 -431.63744) (xy 385.318254 -431.63744)
			(xy 385.306135 -431.637027) (xy 385.283086 -431.629525) (xy 385.263484 -431.615268) (xy 385.249244 -431.595653)
			(xy 385.241762 -431.572598) (xy 385.241292 -431.560478) (xy 385.241292 -430.948084) (xy 385.239749 -430.933592)
			(xy 385.238096 -430.904492) (xy 385.23799 -430.889918) (xy 384.33502 -430.889918) (xy 384.33502 -431.889916)
			(xy 387.237986 -431.889916) (xy 387.23808 -431.875342) (xy 387.239732 -431.846241) (xy 387.241288 -431.83175)
			(xy 387.241288 -430.747932) (xy 387.23974 -430.73344) (xy 387.23809 -430.70434) (xy 387.237986 -430.689766)
			(xy 387.238084 -430.675192) (xy 387.239734 -430.646091) (xy 387.241288 -430.6316) (xy 387.241288 -430.018952)
			(xy 387.241675 -430.006842) (xy 387.249187 -429.983815) (xy 387.263456 -429.964244) (xy 387.283083 -429.95005)
			(xy 387.306138 -429.942629) (xy 387.31825 -429.942244) (xy 388.25805 -429.942244) (xy 388.270137 -429.94275)
			(xy 388.293137 -429.950193) (xy 388.312718 -429.96437) (xy 388.32697 -429.983896) (xy 388.334503 -430.006866)
			(xy 388.335012 -430.018952) (xy 388.335012 -430.889918) (xy 389.237982 -430.889918) (xy 389.238076 -430.875344)
			(xy 389.239728 -430.846243) (xy 389.241284 -430.831752) (xy 389.241284 -429.747934) (xy 389.239737 -429.733442)
			(xy 389.238086 -429.704342) (xy 389.237982 -429.689768) (xy 389.23808 -429.675194) (xy 389.23973 -429.646093)
			(xy 389.241284 -429.631602) (xy 389.241284 -429.018954) (xy 389.241673 -429.006832) (xy 389.249179 -428.98378)
			(xy 389.26344 -428.964175) (xy 389.283062 -428.949937) (xy 389.306124 -428.942459) (xy 389.318246 -428.941992)
			(xy 390.258046 -428.941992) (xy 390.270158 -428.942472) (xy 390.293195 -428.949966) (xy 390.312792 -428.964208)
			(xy 390.327034 -428.983805) (xy 390.334528 -429.006842) (xy 390.335008 -429.018954) (xy 390.335008 -431.560478)
			(xy 390.33447 -431.572587) (xy 390.326995 -431.595622) (xy 390.312768 -431.61522) (xy 390.293183 -431.629464)
			(xy 390.270154 -431.636959) (xy 390.258046 -431.63744) (xy 389.318246 -431.63744) (xy 389.306123 -431.637001)
			(xy 389.283062 -431.629518) (xy 389.263445 -431.615273) (xy 389.249193 -431.595659) (xy 389.241703 -431.5726)
			(xy 389.241284 -431.560478) (xy 389.241284 -430.948084) (xy 389.239741 -430.933592) (xy 389.238088 -430.904492)
			(xy 389.237982 -430.889918) (xy 388.335012 -430.889918) (xy 388.335012 -431.889916) (xy 391.237978 -431.889916)
			(xy 391.238072 -431.875342) (xy 391.239724 -431.846241) (xy 391.24128 -431.83175) (xy 391.24128 -430.747932)
			(xy 391.239732 -430.73344) (xy 391.238082 -430.70434) (xy 391.237978 -430.689766) (xy 391.238076 -430.675192)
			(xy 391.239726 -430.646091) (xy 391.24128 -430.6316) (xy 391.24128 -430.018952) (xy 391.241675 -430.006843)
			(xy 391.249186 -429.983817) (xy 391.263453 -429.964247) (xy 391.283077 -429.950053) (xy 391.306131 -429.94263)
			(xy 391.318242 -429.942244) (xy 392.258042 -429.942244) (xy 392.270134 -429.942672) (xy 392.293137 -429.95014)
			(xy 392.312716 -429.964337) (xy 392.326965 -429.983879) (xy 392.334496 -430.006861) (xy 392.335004 -430.018952)
			(xy 392.335004 -430.889918) (xy 393.237974 -430.889918) (xy 393.238068 -430.875344) (xy 393.23972 -430.846243)
			(xy 393.241276 -430.831752) (xy 393.241276 -429.747934) (xy 393.239729 -429.733442) (xy 393.238078 -429.704342)
			(xy 393.237974 -429.689768) (xy 393.238072 -429.675194) (xy 393.239722 -429.646093) (xy 393.241276 -429.631602)
			(xy 393.241276 -429.018954) (xy 393.241673 -429.006833) (xy 393.249178 -428.983782) (xy 393.263438 -428.964178)
			(xy 393.283057 -428.949939) (xy 393.306117 -428.94246) (xy 393.318238 -428.941992) (xy 394.258038 -428.941992)
			(xy 394.27015 -428.942479) (xy 394.293187 -428.949971) (xy 394.312784 -428.964211) (xy 394.327026 -428.983806)
			(xy 394.33452 -429.006842) (xy 394.335 -429.018954) (xy 394.335 -431.560478) (xy 394.33447 -431.572588)
			(xy 394.326994 -431.595624) (xy 394.312765 -431.615223) (xy 394.293177 -431.629466) (xy 394.270147 -431.636961)
			(xy 394.258038 -431.63744) (xy 393.318238 -431.63744) (xy 393.306115 -431.637007) (xy 393.283054 -431.629523)
			(xy 393.263436 -431.615275) (xy 393.249184 -431.595661) (xy 393.241695 -431.572601) (xy 393.241276 -431.560478)
			(xy 393.241276 -430.948084) (xy 393.239733 -430.933592) (xy 393.23808 -430.904492) (xy 393.237974 -430.889918)
			(xy 392.335004 -430.889918) (xy 392.335004 -431.889916) (xy 395.23797 -431.889916) (xy 395.238064 -431.875342)
			(xy 395.239716 -431.846241) (xy 395.241272 -431.83175) (xy 395.241272 -430.747932) (xy 395.239724 -430.73344)
			(xy 395.238074 -430.70434) (xy 395.23797 -430.689766) (xy 395.238068 -430.675192) (xy 395.239718 -430.646091)
			(xy 395.241272 -430.6316) (xy 395.241272 -430.018952) (xy 395.241675 -430.006843) (xy 395.249184 -429.983819)
			(xy 395.26345 -429.96425) (xy 395.283072 -429.950056) (xy 395.306124 -429.942631) (xy 395.318234 -429.942244)
			(xy 396.258034 -429.942244) (xy 396.270126 -429.942678) (xy 396.293128 -429.950145) (xy 396.312708 -429.96434)
			(xy 396.326957 -429.98388) (xy 396.334488 -430.006862) (xy 396.334996 -430.018952) (xy 396.334996 -430.889918)
			(xy 398.237964 -430.889918) (xy 398.238073 -430.874832) (xy 398.239855 -430.844714) (xy 398.24152 -430.82972)
			(xy 398.24152 -429.749966) (xy 398.239855 -429.734972) (xy 398.238074 -429.704854) (xy 398.237964 -429.689768)
			(xy 398.238078 -429.674682) (xy 398.239856 -429.644564) (xy 398.24152 -429.62957) (xy 398.24152 -429.018954)
			(xy 398.241968 -429.006864) (xy 398.249435 -428.983865) (xy 398.263627 -428.964288) (xy 398.283163 -428.950038)
			(xy 398.306139 -428.942504) (xy 398.318228 -428.941992) (xy 399.258028 -428.941992) (xy 399.270138 -428.942392)
			(xy 399.293164 -428.949899) (xy 399.312736 -428.964165) (xy 399.32693 -428.983789) (xy 399.334352 -429.006843)
			(xy 399.334736 -429.018954) (xy 399.334736 -431.560478) (xy 399.334273 -431.572569) (xy 399.32682 -431.595573)
			(xy 399.312633 -431.615155) (xy 399.293097 -431.629405) (xy 399.270117 -431.636934) (xy 399.258028 -431.63744)
			(xy 398.318228 -431.63744) (xy 398.306125 -431.63696) (xy 398.283105 -431.629473) (xy 398.263535 -431.615227)
			(xy 398.249338 -431.595621) (xy 398.241909 -431.572582) (xy 398.24152 -431.560478) (xy 398.24152 -430.950116)
			(xy 398.239851 -430.935123) (xy 398.238073 -430.905004) (xy 398.237964 -430.889918) (xy 396.334996 -430.889918)
			(xy 396.334996 -431.889916) (xy 400.23796 -431.889916) (xy 400.238069 -431.87483) (xy 400.239851 -431.844712)
			(xy 400.241516 -431.829718) (xy 400.241516 -430.749964) (xy 400.239851 -430.73497) (xy 400.23807 -430.704852)
			(xy 400.23796 -430.689766) (xy 400.238074 -430.67468) (xy 400.239852 -430.644562) (xy 400.241516 -430.629568)
			(xy 400.241516 -430.018952) (xy 400.241924 -430.006873) (xy 400.249402 -429.9839) (xy 400.263613 -429.964361)
			(xy 400.283164 -429.950169) (xy 400.306144 -429.942712) (xy 400.318224 -429.942244) (xy 401.258024 -429.942244)
			(xy 401.270095 -429.942743) (xy 401.293055 -429.950206) (xy 401.312587 -429.964396) (xy 401.326783 -429.983924)
			(xy 401.334253 -430.006881) (xy 401.334732 -430.018952) (xy 401.334732 -430.889918) (xy 402.237956 -430.889918)
			(xy 402.238065 -430.874832) (xy 402.239847 -430.844714) (xy 402.241512 -430.82972) (xy 402.241512 -429.749966)
			(xy 402.239847 -429.734972) (xy 402.238066 -429.704854) (xy 402.237956 -429.689768) (xy 402.23807 -429.674682)
			(xy 402.239848 -429.644564) (xy 402.241512 -429.62957) (xy 402.241512 -429.018954) (xy 402.241968 -429.006865)
			(xy 402.249434 -428.983867) (xy 402.263624 -428.964291) (xy 402.283158 -428.950041) (xy 402.306132 -428.942505)
			(xy 402.31822 -428.941992) (xy 403.25802 -428.941992) (xy 403.270129 -428.942399) (xy 403.293156 -428.949903)
			(xy 403.312728 -428.964167) (xy 403.326922 -428.98379) (xy 403.334344 -429.006843) (xy 403.334728 -429.018954)
			(xy 403.334728 -431.560478) (xy 403.334273 -431.57257) (xy 403.326819 -431.595575) (xy 403.31263 -431.615158)
			(xy 403.293092 -431.629408) (xy 403.27011 -431.636935) (xy 403.25802 -431.63744) (xy 402.31822 -431.63744)
			(xy 402.306116 -431.636967) (xy 402.283096 -431.629478) (xy 402.263527 -431.61523) (xy 402.24933 -431.595622)
			(xy 402.241901 -431.572583) (xy 402.241512 -431.560478) (xy 402.241512 -430.950116) (xy 402.239843 -430.935123)
			(xy 402.238065 -430.905004) (xy 402.237956 -430.889918) (xy 401.334732 -430.889918) (xy 401.334732 -431.889916)
			(xy 404.237952 -431.889916) (xy 404.238061 -431.87483) (xy 404.239843 -431.844712) (xy 404.241508 -431.829718)
			(xy 404.241508 -430.749964) (xy 404.239843 -430.73497) (xy 404.238062 -430.704852) (xy 404.237952 -430.689766)
			(xy 404.238066 -430.67468) (xy 404.239844 -430.644562) (xy 404.241508 -430.629568) (xy 404.241508 -430.018952)
			(xy 404.241923 -430.006873) (xy 404.249401 -429.983902) (xy 404.26361 -429.964364) (xy 404.283159 -429.950172)
			(xy 404.306137 -429.942713) (xy 404.318216 -429.942244) (xy 405.258016 -429.942244) (xy 405.270087 -429.94275)
			(xy 405.293046 -429.950211) (xy 405.312579 -429.964399) (xy 405.326774 -429.983925) (xy 405.334245 -430.006882)
			(xy 405.334724 -430.018952) (xy 405.334724 -430.889918) (xy 406.237948 -430.889918) (xy 406.238057 -430.874832)
			(xy 406.239839 -430.844714) (xy 406.241504 -430.82972) (xy 406.241504 -429.749966) (xy 406.239839 -429.734972)
			(xy 406.238058 -429.704854) (xy 406.237948 -429.689768) (xy 406.238062 -429.674682) (xy 406.23984 -429.644564)
			(xy 406.241504 -429.62957) (xy 406.241504 -429.018954) (xy 406.241967 -429.006866) (xy 406.249432 -428.98387)
			(xy 406.263621 -428.964293) (xy 406.283153 -428.950043) (xy 406.306125 -428.942506) (xy 406.318212 -428.941992)
			(xy 407.258012 -428.941992) (xy 407.270121 -428.942406) (xy 407.293147 -428.949908) (xy 407.312719 -428.96417)
			(xy 407.326914 -428.983792) (xy 407.334336 -429.006844) (xy 407.33472 -429.018954) (xy 407.33472 -431.560478)
			(xy 407.334273 -431.57257) (xy 407.326818 -431.595577) (xy 407.312627 -431.615161) (xy 407.293087 -431.629411)
			(xy 407.270103 -431.636936) (xy 407.258012 -431.63744) (xy 406.318212 -431.63744) (xy 406.306108 -431.636974)
			(xy 406.283088 -431.629483) (xy 406.263518 -431.615232) (xy 406.249322 -431.595624) (xy 406.241893 -431.572583)
			(xy 406.241504 -431.560478) (xy 406.241504 -430.950116) (xy 406.239835 -430.935123) (xy 406.238057 -430.905004)
			(xy 406.237948 -430.889918) (xy 405.334724 -430.889918) (xy 405.334724 -431.889916) (xy 408.237944 -431.889916)
			(xy 408.238053 -431.87483) (xy 408.239835 -431.844712) (xy 408.2415 -431.829718) (xy 408.2415 -430.749964)
			(xy 408.239835 -430.73497) (xy 408.238054 -430.704852) (xy 408.237944 -430.689766) (xy 408.238058 -430.67468)
			(xy 408.239836 -430.644562) (xy 408.2415 -430.629568) (xy 408.2415 -430.018952) (xy 408.241923 -430.006874)
			(xy 408.2494 -429.983904) (xy 408.263607 -429.964367) (xy 408.283154 -429.950174) (xy 408.30613 -429.942714)
			(xy 408.318208 -429.942244) (xy 409.258008 -429.942244) (xy 409.270078 -429.942757) (xy 409.293037 -429.950216)
			(xy 409.31257 -429.964401) (xy 409.326766 -429.983927) (xy 409.334237 -430.006882) (xy 409.334716 -430.018952)
			(xy 409.334716 -430.889918) (xy 410.23794 -430.889918) (xy 410.238051 -430.874832) (xy 410.239833 -430.844714)
			(xy 410.241496 -430.82972) (xy 410.241496 -429.749966) (xy 410.239831 -429.734972) (xy 410.23805 -429.704854)
			(xy 410.23794 -429.689768) (xy 410.238054 -429.674682) (xy 410.239832 -429.644564) (xy 410.241496 -429.62957)
			(xy 410.241496 -429.018954) (xy 410.241967 -429.006866) (xy 410.249431 -428.983872) (xy 410.263618 -428.964296)
			(xy 410.283148 -428.950046) (xy 410.306118 -428.942507) (xy 410.318204 -428.941992) (xy 411.258004 -428.941992)
			(xy 411.270112 -428.942413) (xy 411.293138 -428.949912) (xy 411.312711 -428.964173) (xy 411.326906 -428.983793)
			(xy 411.334328 -429.006844) (xy 411.334712 -429.018954) (xy 411.334712 -431.560478) (xy 411.334273 -431.572571)
			(xy 411.326816 -431.595579) (xy 411.312624 -431.615164) (xy 411.293082 -431.629413) (xy 411.270096 -431.636937)
			(xy 411.258004 -431.63744) (xy 410.318204 -431.63744) (xy 410.306099 -431.636981) (xy 410.283079 -431.629488)
			(xy 410.263509 -431.615236) (xy 410.249313 -431.595625) (xy 410.241885 -431.572584) (xy 410.241496 -431.560478)
			(xy 410.241496 -430.950116) (xy 410.239827 -430.935123) (xy 410.238049 -430.905004) (xy 410.23794 -430.889918)
			(xy 409.334716 -430.889918) (xy 409.334716 -431.889916) (xy 412.237936 -431.889916) (xy 412.238047 -431.87483)
			(xy 412.239829 -431.844712) (xy 412.241492 -431.829718) (xy 412.241492 -430.749964) (xy 412.239827 -430.73497)
			(xy 412.238046 -430.704852) (xy 412.237936 -430.689766) (xy 412.238052 -430.674681) (xy 412.23983 -430.644562)
			(xy 412.241492 -430.629568) (xy 412.241492 -430.018952) (xy 412.241923 -430.006875) (xy 412.249399 -429.983906)
			(xy 412.263604 -429.96437) (xy 412.283149 -429.950177) (xy 412.306123 -429.942716) (xy 412.3182 -429.942244)
			(xy 413.258 -429.942244) (xy 413.27007 -429.942764) (xy 413.293029 -429.95022) (xy 413.312562 -429.964404)
			(xy 413.326758 -429.983928) (xy 413.334229 -430.006883) (xy 413.334708 -430.018952) (xy 413.334708 -432.560476)
			(xy 413.334267 -432.572557) (xy 413.326806 -432.595539) (xy 413.312607 -432.61509) (xy 413.293061 -432.629295)
			(xy 413.270081 -432.636763) (xy 413.258 -432.637184) (xy 412.3182 -432.637184) (xy 412.306115 -432.636787)
			(xy 412.283128 -432.629317) (xy 412.263576 -432.615107) (xy 412.249372 -432.59555) (xy 412.241909 -432.572561)
			(xy 412.241492 -432.560476) (xy 412.241492 -431.950114) (xy 412.239822 -431.935121) (xy 412.238045 -431.905002)
			(xy 412.237936 -431.889916) (xy 409.334716 -431.889916) (xy 409.334716 -432.560476) (xy 409.334267 -432.572557)
			(xy 409.326807 -432.595537) (xy 409.31261 -432.615087) (xy 409.293066 -432.629292) (xy 409.270088 -432.636762)
			(xy 409.258008 -432.637184) (xy 408.318208 -432.637184) (xy 408.306123 -432.63678) (xy 408.283137 -432.629312)
			(xy 408.263584 -432.615105) (xy 408.249381 -432.595549) (xy 408.241917 -432.572561) (xy 408.2415 -432.560476)
			(xy 408.2415 -431.950114) (xy 408.23983 -431.935121) (xy 408.238053 -431.905002) (xy 408.237944 -431.889916)
			(xy 405.334724 -431.889916) (xy 405.334724 -432.560476) (xy 405.334267 -432.572556) (xy 405.326808 -432.595535)
			(xy 405.312613 -432.615084) (xy 405.293071 -432.62929) (xy 405.270096 -432.636761) (xy 405.258016 -432.637184)
			(xy 404.318216 -432.637184) (xy 404.306132 -432.636773) (xy 404.283146 -432.629307) (xy 404.263593 -432.615101)
			(xy 404.249389 -432.595547) (xy 404.241926 -432.57256) (xy 404.241508 -432.560476) (xy 404.241508 -431.950114)
			(xy 404.239838 -431.935121) (xy 404.238061 -431.905002) (xy 404.237952 -431.889916) (xy 401.334732 -431.889916)
			(xy 401.334732 -432.560476) (xy 401.334216 -432.572547) (xy 401.326763 -432.595509) (xy 401.312579 -432.615045)
			(xy 401.293052 -432.629241) (xy 401.270095 -432.636708) (xy 401.258024 -432.637184) (xy 400.318224 -432.637184)
			(xy 400.30614 -432.636766) (xy 400.283154 -432.629303) (xy 400.263601 -432.615099) (xy 400.249397 -432.595546)
			(xy 400.241934 -432.57256) (xy 400.241516 -432.560476) (xy 400.241516 -431.950114) (xy 400.239846 -431.935121)
			(xy 400.238069 -431.905002) (xy 400.23796 -431.889916) (xy 396.334996 -431.889916) (xy 396.334996 -432.560476)
			(xy 396.334563 -432.572584) (xy 396.32707 -432.595611) (xy 396.312813 -432.615185) (xy 396.293194 -432.62938)
			(xy 396.270143 -432.636801) (xy 396.258034 -432.637184) (xy 395.318234 -432.637184) (xy 395.306149 -432.636664)
			(xy 395.283153 -432.62922) (xy 395.263575 -432.615046) (xy 395.249322 -432.595525) (xy 395.241785 -432.572559)
			(xy 395.241272 -432.560476) (xy 395.241272 -431.948082) (xy 395.239729 -431.93359) (xy 395.238076 -431.90449)
			(xy 395.23797 -431.889916) (xy 392.335004 -431.889916) (xy 392.335004 -432.560476) (xy 392.334563 -432.572583)
			(xy 392.327071 -432.595609) (xy 392.312815 -432.615182) (xy 392.293199 -432.629378) (xy 392.27015 -432.6368)
			(xy 392.258042 -432.637184) (xy 391.318242 -432.637184) (xy 391.306157 -432.636657) (xy 391.283162 -432.629215)
			(xy 391.263583 -432.615043) (xy 391.24933 -432.595523) (xy 391.241793 -432.572559) (xy 391.24128 -432.560476)
			(xy 391.24128 -431.948082) (xy 391.239737 -431.93359) (xy 391.238084 -431.90449) (xy 391.237978 -431.889916)
			(xy 388.335012 -431.889916) (xy 388.335012 -432.560476) (xy 388.334563 -432.572582) (xy 388.327072 -432.595607)
			(xy 388.312818 -432.615179) (xy 388.293204 -432.629375) (xy 388.270158 -432.636799) (xy 388.25805 -432.637184)
			(xy 387.31825 -432.637184) (xy 387.306165 -432.636651) (xy 387.28317 -432.62921) (xy 387.263592 -432.61504)
			(xy 387.249339 -432.595522) (xy 387.241801 -432.572559) (xy 387.241288 -432.560476) (xy 387.241288 -431.948082)
			(xy 387.239745 -431.93359) (xy 387.238092 -431.90449) (xy 387.237986 -431.889916) (xy 384.33502 -431.889916)
			(xy 384.33502 -432.560476) (xy 384.334563 -432.572582) (xy 384.327073 -432.595605) (xy 384.312821 -432.615176)
			(xy 384.293209 -432.629373) (xy 384.270165 -432.636797) (xy 384.258058 -432.637184) (xy 383.318258 -432.637184)
			(xy 383.306169 -432.636729) (xy 383.283171 -432.629264) (xy 383.263593 -432.615073) (xy 383.249343 -432.595539)
			(xy 383.241808 -432.572564) (xy 383.241296 -432.560476) (xy 383.241296 -431.948082) (xy 383.239753 -431.93359)
			(xy 383.2381 -431.90449) (xy 383.237994 -431.889916) (xy 363.355859 -431.889916) (xy 363.346369 -431.956363)
			(xy 363.314178 -432.124516) (xy 363.274074 -432.290959) (xy 363.226145 -432.455319) (xy 363.170501 -432.61723)
			(xy 363.107264 -432.776329) (xy 363.036576 -432.932261) (xy 362.958595 -433.084677) (xy 362.873496 -433.233236)
			(xy 362.781469 -433.377605) (xy 362.68272 -433.517463) (xy 362.577469 -433.652495) (xy 362.465953 -433.782401)
			(xy 362.348419 -433.90689) (xy 362.225132 -434.025683) (xy 362.096367 -434.138515) (xy 361.962411 -434.245133)
			(xy 361.823565 -434.345299) (xy 361.680139 -434.438789) (xy 361.593049 -434.48986) (xy 381.21844 -434.48986)
			(xy 381.218911 -434.457303) (xy 381.226862 -434.392677) (xy 381.242651 -434.329506) (xy 381.266042 -434.268739)
			(xy 381.296685 -434.211287) (xy 381.334119 -434.158009) (xy 381.377784 -434.109707) (xy 381.402082 -434.088032)
			(xy 381.482854 -433.923186) (xy 381.48755 -433.912668) (xy 381.491039 -433.889911) (xy 381.487557 -433.867153)
			(xy 381.482854 -433.856638) (xy 381.402082 -433.691792) (xy 381.377796 -433.670107) (xy 381.334143 -433.621798)
			(xy 381.296718 -433.568519) (xy 381.266081 -433.511068) (xy 381.24269 -433.450305) (xy 381.226896 -433.38714)
			(xy 381.218936 -433.322519) (xy 381.21844 -433.289964) (xy 381.219132 -433.250837) (xy 381.230612 -433.173431)
			(xy 381.2413 -433.135786) (xy 381.2413 -432.618896) (xy 381.241713 -432.606787) (xy 381.249213 -432.583759)
			(xy 381.263476 -432.564186) (xy 381.283098 -432.549992) (xy 381.306152 -432.542571) (xy 381.318262 -432.542188)
			(xy 382.258062 -432.542188) (xy 382.270154 -432.542641) (xy 382.293162 -432.550093) (xy 382.312747 -432.564281)
			(xy 382.326997 -432.583821) (xy 382.334521 -432.606805) (xy 382.335024 -432.618896) (xy 382.335024 -435.16042)
			(xy 382.334601 -435.172528) (xy 382.327099 -435.195551) (xy 382.312838 -435.215122) (xy 382.29322 -435.229317)
			(xy 382.270171 -435.236741) (xy 382.258062 -435.237128) (xy 381.318262 -435.237128) (xy 381.306167 -435.236724)
			(xy 381.28316 -435.229253) (xy 381.263578 -435.215052) (xy 381.24933 -435.195503) (xy 381.241804 -435.172514)
			(xy 381.2413 -435.16042) (xy 381.2413 -434.644038) (xy 381.230604 -434.606395) (xy 381.219133 -434.528987)
			(xy 381.21844 -434.48986) (xy 361.593049 -434.48986) (xy 361.532453 -434.525394) (xy 361.380838 -434.60492)
			(xy 361.225633 -434.67719) (xy 361.146598 -434.710078) (xy 361.132966 -434.716266) (xy 361.109724 -434.735103)
			(xy 361.092944 -434.759873) (xy 361.084069 -434.788444) (xy 361.083862 -434.818361) (xy 361.092341 -434.847052)
			(xy 361.108777 -434.872051) (xy 361.119928 -434.882036) (xy 361.169374 -434.924045) (xy 361.263563 -435.013299)
			(xy 361.352051 -435.108208) (xy 361.434498 -435.208409) (xy 361.510589 -435.313518) (xy 361.580032 -435.423133)
			(xy 361.616728 -435.489858) (xy 383.218436 -435.489858) (xy 383.218907 -435.457301) (xy 383.226858 -435.392675)
			(xy 383.242647 -435.329505) (xy 383.266039 -435.268738) (xy 383.296681 -435.211285) (xy 383.334115 -435.158008)
			(xy 383.37778 -435.109705) (xy 383.402078 -435.08803) (xy 383.48285 -434.923184) (xy 383.487548 -434.912666)
			(xy 383.491036 -434.889909) (xy 383.487553 -434.867151) (xy 383.48285 -434.856636) (xy 383.402078 -434.69179)
			(xy 383.37781 -434.670084) (xy 383.334153 -434.621782) (xy 383.296724 -434.568507) (xy 383.266083 -434.51106)
			(xy 383.242689 -434.450299) (xy 383.226893 -434.387136) (xy 383.218932 -434.322516) (xy 383.218436 -434.289962)
			(xy 383.219128 -434.250835) (xy 383.230608 -434.173429) (xy 383.241296 -434.135784) (xy 383.241296 -433.618894)
			(xy 383.241806 -433.606783) (xy 383.24929 -433.583747) (xy 383.263524 -433.564149) (xy 383.283115 -433.549906)
			(xy 383.306148 -433.542412) (xy 383.318258 -433.541932) (xy 384.258058 -433.541932) (xy 384.270178 -433.542396)
			(xy 384.293234 -433.549876) (xy 384.31285 -433.564116) (xy 384.327103 -433.583722) (xy 384.334597 -433.606774)
			(xy 384.33502 -433.618894) (xy 384.33502 -434.48986) (xy 385.218432 -434.48986) (xy 385.218906 -434.457303)
			(xy 385.226856 -434.392677) (xy 385.242645 -434.329507) (xy 385.266036 -434.26874) (xy 385.296678 -434.211287)
			(xy 385.334112 -434.15801) (xy 385.377776 -434.109707) (xy 385.402074 -434.088032) (xy 385.482846 -433.923186)
			(xy 385.487543 -433.912668) (xy 385.491032 -433.889911) (xy 385.487549 -433.867153) (xy 385.482846 -433.856638)
			(xy 385.402074 -433.691792) (xy 385.377806 -433.670086) (xy 385.334149 -433.621783) (xy 385.29672 -433.568509)
			(xy 385.266079 -433.511062) (xy 385.242685 -433.450301) (xy 385.226889 -433.387138) (xy 385.218928 -433.322518)
			(xy 385.218432 -433.289964) (xy 385.219124 -433.250837) (xy 385.230604 -433.173431) (xy 385.241292 -433.135786)
			(xy 385.241292 -432.618896) (xy 385.241713 -432.606788) (xy 385.249212 -432.583762) (xy 385.263473 -432.564189)
			(xy 385.283093 -432.549994) (xy 385.306144 -432.542572) (xy 385.318254 -432.542188) (xy 386.258054 -432.542188)
			(xy 386.270146 -432.542647) (xy 386.293153 -432.550097) (xy 386.312738 -432.564284) (xy 386.326988 -432.583823)
			(xy 386.334513 -432.606806) (xy 386.335016 -432.618896) (xy 386.335016 -435.16042) (xy 386.334601 -435.172528)
			(xy 386.327098 -435.195554) (xy 386.312836 -435.215125) (xy 386.293215 -435.229319) (xy 386.270164 -435.236743)
			(xy 386.258054 -435.237128) (xy 385.318254 -435.237128) (xy 385.306159 -435.236731) (xy 385.283151 -435.229258)
			(xy 385.263569 -435.215054) (xy 385.249322 -435.195505) (xy 385.241796 -435.172514) (xy 385.241292 -435.16042)
			(xy 385.241292 -434.644038) (xy 385.230596 -434.606395) (xy 385.219125 -434.528987) (xy 385.218432 -434.48986)
			(xy 384.33502 -434.48986) (xy 384.33502 -435.489858) (xy 387.218428 -435.489858) (xy 387.218902 -435.457301)
			(xy 387.226853 -435.392675) (xy 387.242642 -435.329505) (xy 387.266033 -435.268738) (xy 387.296674 -435.211285)
			(xy 387.334108 -435.158008) (xy 387.377772 -435.109705) (xy 387.40207 -435.08803) (xy 387.482842 -434.923184)
			(xy 387.48754 -434.912667) (xy 387.491029 -434.889909) (xy 387.487546 -434.867151) (xy 387.482842 -434.856636)
			(xy 387.40207 -434.69179) (xy 387.377801 -434.670086) (xy 387.334144 -434.621783) (xy 387.296715 -434.568508)
			(xy 387.266074 -434.51106) (xy 387.242681 -434.4503) (xy 387.226885 -434.387136) (xy 387.218924 -434.322516)
			(xy 387.218428 -434.289962) (xy 387.21912 -434.250835) (xy 387.2306 -434.173429) (xy 387.241288 -434.135784)
			(xy 387.241288 -433.618894) (xy 387.241806 -433.606784) (xy 387.249289 -433.583749) (xy 387.263521 -433.564152)
			(xy 387.28311 -433.549909) (xy 387.30614 -433.542413) (xy 387.31825 -433.541932) (xy 388.25805 -433.541932)
			(xy 388.270167 -433.542369) (xy 388.29321 -433.549869) (xy 388.312811 -433.564121) (xy 388.327051 -433.583729)
			(xy 388.334538 -433.606777) (xy 388.335012 -433.618894) (xy 388.335012 -434.48986) (xy 389.218424 -434.48986)
			(xy 389.218901 -434.457303) (xy 389.226851 -434.392677) (xy 389.24264 -434.329507) (xy 389.26603 -434.268741)
			(xy 389.296672 -434.211288) (xy 389.334105 -434.15801) (xy 389.377768 -434.109707) (xy 389.402066 -434.088032)
			(xy 389.482838 -433.923186) (xy 389.487535 -433.912668) (xy 389.491025 -433.889911) (xy 389.487542 -433.867153)
			(xy 389.482838 -433.856638) (xy 389.402066 -433.691792) (xy 389.377797 -433.670088) (xy 389.33414 -433.621785)
			(xy 389.296711 -433.56851) (xy 389.26607 -433.511062) (xy 389.242677 -433.450301) (xy 389.226881 -433.387138)
			(xy 389.21892 -433.322518) (xy 389.218424 -433.289964) (xy 389.219117 -433.250837) (xy 389.230596 -433.173431)
			(xy 389.241284 -433.135786) (xy 389.241284 -432.618896) (xy 389.241713 -432.606789) (xy 389.249211 -432.583764)
			(xy 389.26347 -432.564192) (xy 389.283088 -432.549997) (xy 389.306137 -432.542573) (xy 389.318246 -432.542188)
			(xy 390.258046 -432.542188) (xy 390.270143 -432.542569) (xy 390.293153 -432.550044) (xy 390.312736 -432.564251)
			(xy 390.326984 -432.583805) (xy 390.334506 -432.6068) (xy 390.335008 -432.618896) (xy 390.335008 -435.16042)
			(xy 390.334601 -435.172529) (xy 390.327097 -435.195556) (xy 390.312833 -435.215128) (xy 390.29321 -435.229322)
			(xy 390.270157 -435.236744) (xy 390.258046 -435.237128) (xy 389.318246 -435.237128) (xy 389.306156 -435.236653)
			(xy 389.283151 -435.229205) (xy 389.263568 -435.215022) (xy 389.249317 -435.195487) (xy 389.241789 -435.172509)
			(xy 389.241284 -435.16042) (xy 389.241284 -434.644038) (xy 389.230588 -434.606395) (xy 389.219117 -434.528987)
			(xy 389.218424 -434.48986) (xy 388.335012 -434.48986) (xy 388.335012 -435.489858) (xy 391.21842 -435.489858)
			(xy 391.218897 -435.457301) (xy 391.226847 -435.392675) (xy 391.242636 -435.329506) (xy 391.266026 -435.268739)
			(xy 391.296668 -435.211286) (xy 391.334101 -435.158008) (xy 391.377765 -435.109705) (xy 391.402062 -435.08803)
			(xy 391.482834 -434.923184) (xy 391.487533 -434.912667) (xy 391.491022 -434.889909) (xy 391.487538 -434.867151)
			(xy 391.482834 -434.856636) (xy 391.402062 -434.69179) (xy 391.377791 -434.670088) (xy 391.334135 -434.621784)
			(xy 391.296706 -434.568509) (xy 391.266065 -434.511061) (xy 391.242672 -434.4503) (xy 391.226877 -434.387136)
			(xy 391.218916 -434.322516) (xy 391.21842 -434.289962) (xy 391.219112 -434.250835) (xy 391.230592 -434.173429)
			(xy 391.24128 -434.135784) (xy 391.24128 -433.618894) (xy 391.241656 -433.606767) (xy 391.249155 -433.583701)
			(xy 391.263416 -433.564082) (xy 391.283044 -433.549833) (xy 391.306115 -433.542348) (xy 391.318242 -433.541932)
			(xy 392.258042 -433.541932) (xy 392.270158 -433.542376) (xy 392.293202 -433.549874) (xy 392.312802 -433.564123)
			(xy 392.327043 -433.583731) (xy 392.33453 -433.606778) (xy 392.335004 -433.618894) (xy 392.335004 -434.48986)
			(xy 393.218416 -434.48986) (xy 393.218896 -434.457303) (xy 393.226846 -434.392678) (xy 393.242634 -434.329508)
			(xy 393.266024 -434.268741) (xy 393.296665 -434.211288) (xy 393.334098 -434.158011) (xy 393.377761 -434.109707)
			(xy 393.402058 -434.088032) (xy 393.48283 -433.923186) (xy 393.487528 -433.912668) (xy 393.491017 -433.889911)
			(xy 393.487534 -433.867152) (xy 393.48283 -433.856638) (xy 393.402058 -433.691792) (xy 393.377787 -433.67009)
			(xy 393.334131 -433.621786) (xy 393.296702 -433.568511) (xy 393.266062 -433.511063) (xy 393.242669 -433.450302)
			(xy 393.226873 -433.387138) (xy 393.218912 -433.322518) (xy 393.218416 -433.289964) (xy 393.219105 -433.250837)
			(xy 393.230587 -433.173431) (xy 393.241276 -433.135786) (xy 393.241276 -432.618896) (xy 393.241712 -432.606789)
			(xy 393.24921 -432.583766) (xy 393.263467 -432.564195) (xy 393.283083 -432.55) (xy 393.30613 -432.542575)
			(xy 393.318238 -432.542188) (xy 394.258038 -432.542188) (xy 394.270134 -432.542576) (xy 394.293144 -432.550049)
			(xy 394.312728 -432.564254) (xy 394.326975 -432.583807) (xy 394.334498 -432.606801) (xy 394.335 -432.618896)
			(xy 394.335 -435.16042) (xy 394.334601 -435.17253) (xy 394.327096 -435.195558) (xy 394.31283 -435.215131)
			(xy 394.293205 -435.229325) (xy 394.270149 -435.236745) (xy 394.258038 -435.237128) (xy 393.318238 -435.237128)
			(xy 393.306147 -435.23666) (xy 393.283142 -435.22921) (xy 393.263559 -435.215024) (xy 393.249308 -435.195489)
			(xy 393.241781 -435.172509) (xy 393.241276 -435.16042) (xy 393.241276 -434.644038) (xy 393.230579 -434.606395)
			(xy 393.219108 -434.528987) (xy 393.218416 -434.48986) (xy 392.335004 -434.48986) (xy 392.335004 -435.489858)
			(xy 395.218412 -435.489858) (xy 395.218892 -435.457301) (xy 395.226842 -435.392676) (xy 395.24263 -435.329506)
			(xy 395.26602 -435.268739) (xy 395.296661 -435.211286) (xy 395.334094 -435.158009) (xy 395.377757 -435.109705)
			(xy 395.402054 -435.08803) (xy 395.482826 -434.923184) (xy 395.487525 -434.912667) (xy 395.491015 -434.889909)
			(xy 395.487531 -434.86715) (xy 395.482826 -434.856636) (xy 395.402054 -434.69179) (xy 395.377781 -434.67009)
			(xy 395.334125 -434.621785) (xy 395.296697 -434.56851) (xy 395.266057 -434.511062) (xy 395.242664 -434.4503)
			(xy 395.226869 -434.387137) (xy 395.218908 -434.322516) (xy 395.218412 -434.289962) (xy 395.219101 -434.250835)
			(xy 395.230583 -434.173429) (xy 395.241272 -434.135784) (xy 395.241272 -433.618894) (xy 395.241656 -433.606768)
			(xy 395.249154 -433.583703) (xy 395.263413 -433.564085) (xy 395.283039 -433.549835) (xy 395.306107 -433.542349)
			(xy 395.318234 -433.541932) (xy 396.258034 -433.541932) (xy 396.27015 -433.542383) (xy 396.293193 -433.549878)
			(xy 396.312794 -433.564126) (xy 396.327034 -433.583732) (xy 396.334522 -433.606778) (xy 396.334996 -433.618894)
			(xy 396.334996 -434.48986) (xy 398.218406 -434.48986) (xy 398.218889 -434.457304) (xy 398.226839 -434.392678)
			(xy 398.242627 -434.329508) (xy 398.266017 -434.268742) (xy 398.296657 -434.211289) (xy 398.334089 -434.158011)
			(xy 398.377751 -434.109707) (xy 398.402048 -434.088032) (xy 398.48282 -433.923186) (xy 398.487518 -433.912668)
			(xy 398.491008 -433.889911) (xy 398.487525 -433.867152) (xy 398.48282 -433.856638) (xy 398.402048 -433.691792)
			(xy 398.377775 -433.670092) (xy 398.334119 -433.621788) (xy 398.296691 -433.568512) (xy 398.266051 -433.511063)
			(xy 398.242658 -433.450302) (xy 398.226863 -433.387139) (xy 398.218902 -433.322518) (xy 398.218406 -433.289964)
			(xy 398.219133 -433.250639) (xy 398.230738 -433.172849) (xy 398.24152 -433.135024) (xy 398.24152 -432.618896)
			(xy 398.241909 -432.60681) (xy 398.249382 -432.583823) (xy 398.263593 -432.56427) (xy 398.283151 -432.550067)
			(xy 398.306142 -432.542604) (xy 398.318228 -432.542188) (xy 399.258028 -432.542188) (xy 399.270104 -432.54264)
			(xy 399.293071 -432.55011) (xy 399.312607 -432.56431) (xy 399.326801 -432.58385) (xy 399.334264 -432.60682)
			(xy 399.334736 -432.618896) (xy 399.334736 -435.16042) (xy 399.334253 -435.172493) (xy 399.326788 -435.195456)
			(xy 399.312596 -435.21499) (xy 399.293063 -435.229185) (xy 399.270101 -435.236652) (xy 399.258028 -435.237128)
			(xy 398.318228 -435.237128) (xy 398.306149 -435.236664) (xy 398.28317 -435.229206) (xy 398.263621 -435.215013)
			(xy 398.249416 -435.195473) (xy 398.241944 -435.172499) (xy 398.24152 -435.16042) (xy 398.24152 -434.6448)
			(xy 398.230713 -434.606981) (xy 398.219111 -434.529187) (xy 398.218406 -434.48986) (xy 396.334996 -434.48986)
			(xy 396.334996 -435.489858) (xy 400.218402 -435.489858) (xy 400.218885 -435.457302) (xy 400.226835 -435.392676)
			(xy 400.242623 -435.329507) (xy 400.266013 -435.26874) (xy 400.296653 -435.211287) (xy 400.334085 -435.158009)
			(xy 400.377747 -435.109705) (xy 400.402044 -435.08803) (xy 400.482816 -434.923184) (xy 400.487516 -434.912667)
			(xy 400.491006 -434.889909) (xy 400.487521 -434.86715) (xy 400.482816 -434.856636) (xy 400.402044 -434.69179)
			(xy 400.377769 -434.670092) (xy 400.334114 -434.621787) (xy 400.296686 -434.568511) (xy 400.266046 -434.511062)
			(xy 400.242654 -434.450301) (xy 400.226859 -434.387137) (xy 400.218898 -434.322516) (xy 400.218402 -434.289962)
			(xy 400.219129 -434.250637) (xy 400.230734 -434.172847) (xy 400.241516 -434.135022) (xy 400.241516 -433.618894)
			(xy 400.242002 -433.606807) (xy 400.249457 -433.58381) (xy 400.26364 -433.564232) (xy 400.283168 -433.549981)
			(xy 400.306138 -433.542445) (xy 400.318224 -433.541932) (xy 401.258024 -433.541932) (xy 401.270137 -433.542296)
			(xy 401.293171 -433.549806) (xy 401.312746 -433.56408) (xy 401.326939 -433.583715) (xy 401.334353 -433.606779)
			(xy 401.334732 -433.618894) (xy 401.334732 -434.48986) (xy 402.218398 -434.48986) (xy 402.218884 -434.457304)
			(xy 402.226834 -434.392678) (xy 402.242621 -434.329509) (xy 402.266011 -434.268742) (xy 402.296651 -434.21129)
			(xy 402.334082 -434.158012) (xy 402.377744 -434.109708) (xy 402.40204 -434.088032) (xy 402.482812 -433.923186)
			(xy 402.48751 -433.912668) (xy 402.491001 -433.889911) (xy 402.487517 -433.867152) (xy 402.482812 -433.856638)
			(xy 402.40204 -433.691792) (xy 402.377765 -433.670094) (xy 402.33411 -433.621789) (xy 402.296682 -433.568513)
			(xy 402.266043 -433.511064) (xy 402.24265 -433.450303) (xy 402.226855 -433.387139) (xy 402.218894 -433.322518)
			(xy 402.218398 -433.289964) (xy 402.219125 -433.250639) (xy 402.23073 -433.172849) (xy 402.241512 -433.135024)
			(xy 402.241512 -432.618896) (xy 402.241909 -432.606811) (xy 402.24938 -432.583825) (xy 402.26359 -432.564273)
			(xy 402.283146 -432.550069) (xy 402.306135 -432.542606) (xy 402.31822 -432.542188) (xy 403.25802 -432.542188)
			(xy 403.270095 -432.542647) (xy 403.293062 -432.550115) (xy 403.312599 -432.564313) (xy 403.326793 -432.583852)
			(xy 403.334255 -432.606821) (xy 403.334728 -432.618896) (xy 403.334728 -435.16042) (xy 403.334253 -435.172494)
			(xy 403.326787 -435.195458) (xy 403.312593 -435.214993) (xy 403.293058 -435.229187) (xy 403.270094 -435.236653)
			(xy 403.25802 -435.237128) (xy 402.31822 -435.237128) (xy 402.306148 -435.236619) (xy 402.283185 -435.229165)
			(xy 402.26365 -435.214979) (xy 402.249454 -435.195451) (xy 402.241987 -435.172491) (xy 402.241512 -435.16042)
			(xy 402.241512 -434.6448) (xy 402.230705 -434.606981) (xy 402.219103 -434.529187) (xy 402.218398 -434.48986)
			(xy 401.334732 -434.48986) (xy 401.334732 -435.489858) (xy 404.218394 -435.489858) (xy 404.218845 -435.4573)
			(xy 404.226797 -435.392672) (xy 404.242588 -435.329501) (xy 404.265982 -435.268733) (xy 404.296628 -435.211281)
			(xy 404.334066 -435.158004) (xy 404.377736 -435.109703) (xy 404.402036 -435.08803) (xy 404.482808 -434.923184)
			(xy 404.487508 -434.912667) (xy 404.490998 -434.889909) (xy 404.487513 -434.86715) (xy 404.482808 -434.856636)
			(xy 404.402036 -434.69179) (xy 404.37776 -434.670094) (xy 404.334105 -434.621788) (xy 404.296677 -434.568512)
			(xy 404.266038 -434.511063) (xy 404.242645 -434.450301) (xy 404.226851 -434.387137) (xy 404.21889 -434.322516)
			(xy 404.218394 -434.289962) (xy 404.219121 -434.250637) (xy 404.230726 -434.172847) (xy 404.241508 -434.135022)
			(xy 404.241508 -433.618894) (xy 404.242002 -433.606807) (xy 404.249456 -433.583812) (xy 404.263637 -433.564235)
			(xy 404.283163 -433.549984) (xy 404.306131 -433.542446) (xy 404.318216 -433.541932) (xy 405.258016 -433.541932)
			(xy 405.270129 -433.542303) (xy 405.293162 -433.549811) (xy 405.312738 -433.564083) (xy 405.326931 -433.583716)
			(xy 405.334345 -433.606779) (xy 405.334724 -433.618894) (xy 405.334724 -434.48986) (xy 406.21839 -434.48986)
			(xy 406.218844 -434.457302) (xy 406.226796 -434.392675) (xy 406.242586 -434.329503) (xy 406.26598 -434.268736)
			(xy 406.296625 -434.211283) (xy 406.334063 -434.158007) (xy 406.377732 -434.109705) (xy 406.402032 -434.088032)
			(xy 406.482804 -433.923186) (xy 406.487503 -433.912668) (xy 406.490994 -433.889911) (xy 406.487509 -433.867152)
			(xy 406.482804 -433.856638) (xy 406.402032 -433.691792) (xy 406.377756 -433.670096) (xy 406.334101 -433.62179)
			(xy 406.296673 -433.568514) (xy 406.266034 -433.511065) (xy 406.242642 -433.450303) (xy 406.226847 -433.387139)
			(xy 406.218886 -433.322518) (xy 406.21839 -433.289964) (xy 406.219118 -433.250639) (xy 406.230722 -433.172849)
			(xy 406.241504 -433.135024) (xy 406.241504 -432.618896) (xy 406.241909 -432.606812) (xy 406.249379 -432.583827)
			(xy 406.263587 -432.564276) (xy 406.283141 -432.550072) (xy 406.306128 -432.542607) (xy 406.318212 -432.542188)
			(xy 407.258012 -432.542188) (xy 407.270087 -432.542654) (xy 407.293054 -432.550119) (xy 407.31259 -432.564316)
			(xy 407.326784 -432.583854) (xy 407.334247 -432.606821) (xy 407.33472 -432.618896) (xy 407.33472 -435.16042)
			(xy 407.334253 -435.172494) (xy 407.326786 -435.19546) (xy 407.31259 -435.214996) (xy 407.293053 -435.22919)
			(xy 407.270086 -435.236654) (xy 407.258012 -435.237128) (xy 406.318212 -435.237128) (xy 406.30614 -435.236626)
			(xy 406.283177 -435.229169) (xy 406.263641 -435.214982) (xy 406.249446 -435.195452) (xy 406.241979 -435.172492)
			(xy 406.241504 -435.16042) (xy 406.241504 -434.6448) (xy 406.230697 -434.606981) (xy 406.219095 -434.529187)
			(xy 406.21839 -434.48986) (xy 405.334724 -434.48986) (xy 405.334724 -435.489858) (xy 408.218386 -435.489858)
			(xy 408.21884 -435.4573) (xy 408.226792 -435.392673) (xy 408.242583 -435.329502) (xy 408.265976 -435.268734)
			(xy 408.296622 -435.211281) (xy 408.334059 -435.158005) (xy 408.377728 -435.109703) (xy 408.402028 -435.08803)
			(xy 408.4828 -434.923184) (xy 408.4875 -434.912667) (xy 408.490991 -434.889909) (xy 408.487506 -434.86715)
			(xy 408.4828 -434.856636) (xy 408.402028 -434.69179) (xy 408.37775 -434.670096) (xy 408.334095 -434.62179)
			(xy 408.296668 -434.568513) (xy 408.266029 -434.511063) (xy 408.242637 -434.450301) (xy 408.226842 -434.387137)
			(xy 408.218882 -434.322517) (xy 408.218386 -434.289962) (xy 408.219113 -434.250637) (xy 408.230718 -434.172847)
			(xy 408.2415 -434.135022) (xy 408.2415 -433.618894) (xy 408.242002 -433.606808) (xy 408.249455 -433.583814)
			(xy 408.263634 -433.564238) (xy 408.283158 -433.549986) (xy 408.306124 -433.542447) (xy 408.318208 -433.541932)
			(xy 409.258008 -433.541932) (xy 409.270121 -433.54231) (xy 409.293154 -433.549815) (xy 409.312729 -433.564086)
			(xy 409.326923 -433.583717) (xy 409.334337 -433.60678) (xy 409.334716 -433.618894) (xy 409.334716 -434.48986)
			(xy 410.218382 -434.48986) (xy 410.218839 -434.457303) (xy 410.22679 -434.392675) (xy 410.242581 -434.329504)
			(xy 410.265974 -434.268736) (xy 410.296619 -434.211284) (xy 410.334056 -434.158007) (xy 410.377724 -434.109706)
			(xy 410.402024 -434.088032) (xy 410.482796 -433.923186) (xy 410.487495 -433.912668) (xy 410.490986 -433.889911)
			(xy 410.487502 -433.867152) (xy 410.482796 -433.856638) (xy 410.402024 -433.691792) (xy 410.377746 -433.670097)
			(xy 410.334092 -433.621791) (xy 410.296665 -433.568515) (xy 410.266026 -433.511065) (xy 410.242634 -433.450303)
			(xy 410.226839 -433.387139) (xy 410.218878 -433.322518) (xy 410.218382 -433.289964) (xy 410.21911 -433.250639)
			(xy 410.230714 -433.172849) (xy 410.241496 -433.135024) (xy 410.241496 -432.618896) (xy 410.241961 -432.606821)
			(xy 410.249425 -432.583853) (xy 410.263621 -432.564316) (xy 410.28316 -432.550121) (xy 410.306129 -432.54266)
			(xy 410.318204 -432.542188) (xy 411.258004 -432.542188) (xy 411.270078 -432.542661) (xy 411.293045 -432.550124)
			(xy 411.312582 -432.564318) (xy 411.326776 -432.583855) (xy 411.334239 -432.606822) (xy 411.334712 -432.618896)
			(xy 411.334712 -435.16042) (xy 411.334253 -435.172495) (xy 411.326785 -435.195462) (xy 411.312587 -435.214999)
			(xy 411.293048 -435.229193) (xy 411.270079 -435.236655) (xy 411.258004 -435.237128) (xy 410.318204 -435.237128)
			(xy 410.306132 -435.236633) (xy 410.283168 -435.229174) (xy 410.263633 -435.214984) (xy 410.249437 -435.195454)
			(xy 410.241971 -435.172492) (xy 410.241496 -435.16042) (xy 410.241496 -434.6448) (xy 410.230688 -434.606981)
			(xy 410.219087 -434.529187) (xy 410.218382 -434.48986) (xy 409.334716 -434.48986) (xy 409.334716 -435.489858)
			(xy 412.218378 -435.489858) (xy 412.218835 -435.457301) (xy 412.226786 -435.392673) (xy 412.242577 -435.329502)
			(xy 412.26597 -435.268734) (xy 412.296615 -435.211282) (xy 412.334052 -435.158005) (xy 412.37772 -435.109704)
			(xy 412.40202 -435.08803) (xy 412.482792 -434.923184) (xy 412.487493 -434.912667) (xy 412.490984 -434.889909)
			(xy 412.487498 -434.86715) (xy 412.482792 -434.856636) (xy 412.40202 -434.69179) (xy 412.37774 -434.670097)
			(xy 412.334086 -434.621791) (xy 412.296659 -434.568514) (xy 412.266021 -434.511064) (xy 412.242629 -434.450302)
			(xy 412.226834 -434.387137) (xy 412.218874 -434.322517) (xy 412.218378 -434.289962) (xy 412.219106 -434.250637)
			(xy 412.23071 -434.172847) (xy 412.241492 -434.135022) (xy 412.241492 -433.618894) (xy 412.242002 -433.606809)
			(xy 412.249454 -433.583816) (xy 412.263631 -433.564241) (xy 412.283153 -433.549989) (xy 412.306117 -433.542448)
			(xy 412.3182 -433.541932) (xy 413.258 -433.541932) (xy 413.270112 -433.542317) (xy 413.293145 -433.54982)
			(xy 413.312721 -433.564088) (xy 413.326914 -433.583719) (xy 413.334329 -433.60678) (xy 413.334708 -433.618894)
			(xy 413.334708 -436.160418) (xy 413.334209 -436.172504) (xy 413.326753 -436.195497) (xy 413.312573 -436.215072)
			(xy 413.29305 -436.229324) (xy 413.270084 -436.236864) (xy 413.258 -436.23738) (xy 412.3182 -436.23738)
			(xy 412.306089 -436.236984) (xy 412.283058 -436.229482) (xy 412.263483 -436.215216) (xy 412.24929 -436.195589)
			(xy 412.241872 -436.17253) (xy 412.241492 -436.160418) (xy 412.241492 -435.644798) (xy 412.230684 -435.606979)
			(xy 412.219083 -435.529185) (xy 412.218378 -435.489858) (xy 409.334716 -435.489858) (xy 409.334716 -436.160418)
			(xy 409.334307 -436.172513) (xy 409.32684 -436.195522) (xy 409.31264 -436.215105) (xy 409.293092 -436.229353)
			(xy 409.270102 -436.236877) (xy 409.258008 -436.23738) (xy 408.318208 -436.23738) (xy 408.306098 -436.236977)
			(xy 408.283067 -436.229477) (xy 408.263492 -436.215213) (xy 408.249298 -436.195587) (xy 408.24188 -436.17253)
			(xy 408.2415 -436.160418) (xy 408.2415 -435.644798) (xy 408.230692 -435.606979) (xy 408.219091 -435.529185)
			(xy 408.218386 -435.489858) (xy 405.334724 -435.489858) (xy 405.334724 -436.160418) (xy 405.334307 -436.172512)
			(xy 405.326841 -436.195519) (xy 405.312643 -436.215102) (xy 405.293097 -436.229351) (xy 405.270109 -436.236876)
			(xy 405.258016 -436.23738) (xy 404.318216 -436.23738) (xy 404.306106 -436.23697) (xy 404.283076 -436.229472)
			(xy 404.263501 -436.21521) (xy 404.249306 -436.195585) (xy 404.241889 -436.172529) (xy 404.241508 -436.160418)
			(xy 404.241508 -435.644798) (xy 404.2307 -435.606979) (xy 404.219099 -435.529185) (xy 404.218394 -435.489858)
			(xy 401.334732 -435.489858) (xy 401.334732 -436.160418) (xy 401.334308 -436.172511) (xy 401.326843 -436.195517)
			(xy 401.312646 -436.215099) (xy 401.293102 -436.229348) (xy 401.270116 -436.236875) (xy 401.258024 -436.23738)
			(xy 400.318224 -436.23738) (xy 400.306114 -436.236963) (xy 400.283085 -436.229468) (xy 400.263509 -436.215207)
			(xy 400.249315 -436.195584) (xy 400.241897 -436.172529) (xy 400.241516 -436.160418) (xy 400.241516 -435.644798)
			(xy 400.230708 -435.606979) (xy 400.219107 -435.529185) (xy 400.218402 -435.489858) (xy 396.334996 -435.489858)
			(xy 396.334996 -436.160418) (xy 396.334504 -436.17253) (xy 396.327016 -436.195568) (xy 396.312778 -436.215167)
			(xy 396.293183 -436.229409) (xy 396.270146 -436.236902) (xy 396.258034 -436.23738) (xy 395.318234 -436.23738)
			(xy 395.306115 -436.236911) (xy 395.28306 -436.229431) (xy 395.263446 -436.215191) (xy 395.249193 -436.195587)
			(xy 395.241697 -436.172537) (xy 395.241272 -436.160418) (xy 395.241272 -435.644036) (xy 395.230575 -435.606394)
			(xy 395.219104 -435.528985) (xy 395.218412 -435.489858) (xy 392.335004 -435.489858) (xy 392.335004 -436.160418)
			(xy 392.334504 -436.172529) (xy 392.327017 -436.195566) (xy 392.312781 -436.215164) (xy 392.293188 -436.229406)
			(xy 392.270153 -436.236901) (xy 392.258042 -436.23738) (xy 391.318242 -436.23738) (xy 391.306123 -436.236905)
			(xy 391.283069 -436.229426) (xy 391.263455 -436.215188) (xy 391.249201 -436.195585) (xy 391.241705 -436.172536)
			(xy 391.24128 -436.160418) (xy 391.24128 -435.644036) (xy 391.230583 -435.606394) (xy 391.219112 -435.528985)
			(xy 391.21842 -435.489858) (xy 388.335012 -435.489858) (xy 388.335012 -436.160418) (xy 388.334505 -436.172529)
			(xy 388.327018 -436.195564) (xy 388.312784 -436.215161) (xy 388.293193 -436.229404) (xy 388.27016 -436.2369)
			(xy 388.25805 -436.23738) (xy 387.31825 -436.23738) (xy 387.306135 -436.236931) (xy 387.283093 -436.229432)
			(xy 387.263493 -436.215184) (xy 387.249253 -436.195578) (xy 387.241764 -436.172534) (xy 387.241288 -436.160418)
			(xy 387.241288 -435.644036) (xy 387.230591 -435.606393) (xy 387.21912 -435.528985) (xy 387.218428 -435.489858)
			(xy 384.33502 -435.489858) (xy 384.33502 -436.160418) (xy 384.334654 -436.172546) (xy 384.327152 -436.195612)
			(xy 384.312888 -436.215231) (xy 384.293258 -436.22948) (xy 384.270186 -436.236964) (xy 384.258058 -436.23738)
			(xy 383.318258 -436.23738) (xy 383.306143 -436.236924) (xy 383.283101 -436.229428) (xy 383.263502 -436.215181)
			(xy 383.249261 -436.195577) (xy 383.241772 -436.172533) (xy 383.241296 -436.160418) (xy 383.241296 -435.644036)
			(xy 383.230599 -435.606393) (xy 383.219128 -435.528985) (xy 383.218436 -435.489858) (xy 361.616728 -435.489858)
			(xy 361.642562 -435.536833) (xy 361.697938 -435.654184) (xy 361.74595 -435.774736) (xy 361.786412 -435.898026)
			(xy 361.81917 -436.023584) (xy 361.844098 -436.150927) (xy 361.861101 -436.279569) (xy 361.870114 -436.409016)
			(xy 361.871103 -436.538773) (xy 361.864062 -436.668342) (xy 361.849021 -436.797228) (xy 361.826035 -436.924936)
			(xy 361.795194 -437.050978) (xy 361.756614 -437.174871) (xy 361.710445 -437.29614) (xy 361.656862 -437.41432)
			(xy 361.596072 -437.52896) (xy 361.528306 -437.63962) (xy 361.453825 -437.745876) (xy 361.372914 -437.847321)
			(xy 361.285882 -437.943567) (xy 361.193064 -438.034245) (xy 361.128666 -438.089802) (xy 381.237998 -438.089802)
			(xy 381.238091 -438.075228) (xy 381.239744 -438.046127) (xy 381.2413 -438.031636) (xy 381.2413 -436.948072)
			(xy 381.239755 -436.93358) (xy 381.238103 -436.90448) (xy 381.237998 -436.889906) (xy 381.238091 -436.875332)
			(xy 381.239744 -436.846231) (xy 381.2413 -436.83174) (xy 381.2413 -436.219092) (xy 381.241709 -436.206983)
			(xy 381.249211 -436.183955) (xy 381.263474 -436.164382) (xy 381.283097 -436.150188) (xy 381.306151 -436.142767)
			(xy 381.318262 -436.142384) (xy 382.258062 -436.142384) (xy 382.270154 -436.142841) (xy 382.293161 -436.150292)
			(xy 382.312745 -436.16448) (xy 382.326995 -436.184019) (xy 382.334521 -436.207002) (xy 382.335024 -436.219092)
			(xy 382.335024 -438.760616) (xy 382.334598 -438.772723) (xy 382.327097 -438.795747) (xy 382.312837 -438.815318)
			(xy 382.293219 -438.829513) (xy 382.270171 -438.836937) (xy 382.258062 -438.837324) (xy 381.318262 -438.837324)
			(xy 381.306167 -438.836924) (xy 381.283159 -438.829453) (xy 381.263577 -438.81525) (xy 381.249329 -438.795701)
			(xy 381.241804 -438.77271) (xy 381.2413 -438.760616) (xy 381.2413 -438.147968) (xy 381.239755 -438.133476)
			(xy 381.238103 -438.104376) (xy 381.237998 -438.089802) (xy 361.128666 -438.089802) (xy 361.094814 -438.119007)
			(xy 360.991508 -438.19753) (xy 360.883543 -438.269512) (xy 360.771333 -438.334677) (xy 360.655306 -438.392776)
			(xy 360.535907 -438.443587) (xy 360.413594 -438.486915) (xy 360.288835 -438.522593) (xy 360.162108 -438.550485)
			(xy 360.033898 -438.570485) (xy 359.904696 -438.582516) (xy 359.774998 -438.586531) (xy 359.6453 -438.582516)
			(xy 359.516098 -438.570485) (xy 359.387888 -438.550485) (xy 359.261161 -438.522593) (xy 359.136402 -438.486915)
			(xy 359.014089 -438.443587) (xy 358.89469 -438.392776) (xy 358.778663 -438.334677) (xy 358.666453 -438.269512)
			(xy 358.558488 -438.19753) (xy 358.455182 -438.119007) (xy 358.356932 -438.034245) (xy 358.264114 -437.943567)
			(xy 358.177082 -437.847321) (xy 358.096171 -437.745876) (xy 358.02169 -437.63962) (xy 357.953924 -437.52896)
			(xy 357.893134 -437.41432) (xy 357.839551 -437.29614) (xy 357.793382 -437.174871) (xy 357.754802 -437.050978)
			(xy 357.723961 -436.924936) (xy 357.700975 -436.797228) (xy 357.685934 -436.668342) (xy 357.678893 -436.538773)
			(xy 357.679882 -436.409016) (xy 357.688895 -436.279569) (xy 357.705898 -436.150927) (xy 357.730826 -436.023584)
			(xy 357.763584 -435.898026) (xy 357.804046 -435.774736) (xy 357.852058 -435.654184) (xy 357.907434 -435.536833)
			(xy 357.969964 -435.423133) (xy 358.039407 -435.313518) (xy 358.115498 -435.208409) (xy 358.197945 -435.108208)
			(xy 358.286433 -435.013299) (xy 358.380622 -434.924045) (xy 358.430068 -434.882036) (xy 358.441235 -434.872067)
			(xy 358.457661 -434.847056) (xy 358.466134 -434.818358) (xy 358.465926 -434.788437) (xy 358.457055 -434.759859)
			(xy 358.440283 -434.735079) (xy 358.417049 -434.716224) (xy 358.403398 -434.710078) (xy 358.324356 -434.677212)
			(xy 358.169157 -434.604934) (xy 358.017549 -434.5254) (xy 357.869871 -434.438788) (xy 357.726451 -434.345291)
			(xy 357.587612 -434.24512) (xy 357.453663 -434.138498) (xy 357.324904 -434.025662) (xy 357.201623 -433.906867)
			(xy 357.084096 -433.782376) (xy 356.972584 -433.652469) (xy 356.867339 -433.517435) (xy 356.768594 -433.377578)
			(xy 356.676571 -433.233209) (xy 356.591476 -433.084651) (xy 356.513498 -432.932237) (xy 356.442812 -432.776307)
			(xy 356.379576 -432.61721) (xy 356.323932 -432.455301) (xy 356.276004 -432.290943) (xy 356.235899 -432.124503)
			(xy 356.203706 -431.956354) (xy 356.179498 -431.78687) (xy 356.163329 -431.616432) (xy 356.155235 -431.44542)
			(xy 356.154736 -431.359818) (xy 346.23502 -431.359818) (xy 346.23502 -432.560476) (xy 346.234563 -432.572582)
			(xy 346.227073 -432.595605) (xy 346.212821 -432.615176) (xy 346.193209 -432.629373) (xy 346.170165 -432.636797)
			(xy 346.158058 -432.637184) (xy 345.218258 -432.637184) (xy 345.206169 -432.636729) (xy 345.183171 -432.629264)
			(xy 345.163593 -432.615073) (xy 345.149343 -432.595539) (xy 345.141808 -432.572564) (xy 345.141296 -432.560476)
			(xy 345.141296 -431.948082) (xy 345.139753 -431.93359) (xy 345.1381 -431.90449) (xy 345.137994 -431.889916)
			(xy 342.235028 -431.889916) (xy 342.235028 -432.560476) (xy 342.234563 -432.572581) (xy 342.227074 -432.595602)
			(xy 342.212824 -432.615174) (xy 342.193214 -432.62937) (xy 342.170172 -432.636796) (xy 342.158066 -432.637184)
			(xy 341.218266 -432.637184) (xy 341.206177 -432.636722) (xy 341.183179 -432.629259) (xy 341.163602 -432.61507)
			(xy 341.149352 -432.595538) (xy 341.141816 -432.572563) (xy 341.141304 -432.560476) (xy 341.141304 -431.948082)
			(xy 341.13976 -431.93359) (xy 341.138108 -431.90449) (xy 341.138002 -431.889916) (xy 338.235036 -431.889916)
			(xy 338.235036 -432.560476) (xy 338.234564 -432.57258) (xy 338.227075 -432.5956) (xy 338.212827 -432.615171)
			(xy 338.193219 -432.629367) (xy 338.170179 -432.636795) (xy 338.158074 -432.637184) (xy 337.218274 -432.637184)
			(xy 337.206185 -432.636715) (xy 337.183188 -432.629254) (xy 337.163611 -432.615067) (xy 337.14936 -432.595536)
			(xy 337.141824 -432.572563) (xy 337.141312 -432.560476) (xy 337.141312 -431.948082) (xy 337.139768 -431.93359)
			(xy 337.138116 -431.90449) (xy 337.13801 -431.889916) (xy 334.235044 -431.889916) (xy 334.235044 -432.560476)
			(xy 334.234564 -432.572579) (xy 334.227076 -432.595598) (xy 334.21283 -432.615168) (xy 334.193224 -432.629365)
			(xy 334.170186 -432.636794) (xy 334.158082 -432.637184) (xy 333.218282 -432.637184) (xy 333.206194 -432.636709)
			(xy 333.183197 -432.62925) (xy 333.163619 -432.615065) (xy 333.149368 -432.595535) (xy 333.141832 -432.572563)
			(xy 333.14132 -432.560476) (xy 333.14132 -431.948082) (xy 333.139776 -431.93359) (xy 333.138124 -431.90449)
			(xy 333.138018 -431.889916) (xy 329.2348 -431.889916) (xy 329.2348 -432.560476) (xy 329.234367 -432.572558)
			(xy 329.226905 -432.595542) (xy 329.212704 -432.615093) (xy 329.193156 -432.629297) (xy 329.170174 -432.636764)
			(xy 329.158092 -432.637184) (xy 328.218292 -432.637184) (xy 328.206206 -432.636794) (xy 328.183219 -432.629321)
			(xy 328.163667 -432.61511) (xy 328.149464 -432.595552) (xy 328.142001 -432.572562) (xy 328.141584 -432.560476)
			(xy 328.141584 -431.950114) (xy 328.139914 -431.935121) (xy 328.138137 -431.905002) (xy 328.138028 -431.889916)
			(xy 325.234808 -431.889916) (xy 325.234808 -432.560476) (xy 325.234367 -432.572557) (xy 325.226906 -432.595539)
			(xy 325.212707 -432.61509) (xy 325.193161 -432.629295) (xy 325.170181 -432.636763) (xy 325.1581 -432.637184)
			(xy 324.2183 -432.637184) (xy 324.206215 -432.636787) (xy 324.183228 -432.629317) (xy 324.163676 -432.615107)
			(xy 324.149472 -432.59555) (xy 324.142009 -432.572561) (xy 324.141592 -432.560476) (xy 324.141592 -431.950114)
			(xy 324.139922 -431.935121) (xy 324.138145 -431.905002) (xy 324.138036 -431.889916) (xy 321.234816 -431.889916)
			(xy 321.234816 -432.560476) (xy 321.234367 -432.572557) (xy 321.226907 -432.595537) (xy 321.21271 -432.615087)
			(xy 321.193166 -432.629292) (xy 321.170188 -432.636762) (xy 321.158108 -432.637184) (xy 320.218308 -432.637184)
			(xy 320.206223 -432.63678) (xy 320.183237 -432.629312) (xy 320.163684 -432.615105) (xy 320.149481 -432.595549)
			(xy 320.142017 -432.572561) (xy 320.1416 -432.560476) (xy 320.1416 -431.950114) (xy 320.13993 -431.935121)
			(xy 320.138153 -431.905002) (xy 320.138044 -431.889916) (xy 317.234824 -431.889916) (xy 317.234824 -432.560476)
			(xy 317.234367 -432.572556) (xy 317.226908 -432.595535) (xy 317.212713 -432.615084) (xy 317.193171 -432.62929)
			(xy 317.170196 -432.636761) (xy 317.158116 -432.637184) (xy 316.218316 -432.637184) (xy 316.206232 -432.636773)
			(xy 316.183246 -432.629307) (xy 316.163693 -432.615101) (xy 316.149489 -432.595547) (xy 316.142026 -432.57256)
			(xy 316.141608 -432.560476) (xy 316.141608 -431.950114) (xy 316.139938 -431.935121) (xy 316.138161 -431.905002)
			(xy 316.138052 -431.889916) (xy 274.613204 -431.889916) (xy 274.618425 -431.905986) (xy 274.665585 -432.076867)
			(xy 274.705031 -432.249692) (xy 274.736684 -432.424113) (xy 274.760479 -432.599778) (xy 274.77637 -432.776334)
			(xy 274.784323 -432.953425) (xy 274.78482 -433.04206) (xy 274.784323 -433.130695) (xy 274.77637 -433.307786)
			(xy 274.760479 -433.484342) (xy 274.736684 -433.660007) (xy 274.705031 -433.834428) (xy 274.665585 -434.007253)
			(xy 274.618425 -434.178134) (xy 274.563646 -434.346728) (xy 274.509927 -434.48986) (xy 314.138056 -434.48986)
			(xy 314.138169 -434.474774) (xy 314.139948 -434.444656) (xy 314.141612 -434.429662) (xy 314.141612 -433.350162)
			(xy 314.139947 -433.335168) (xy 314.138166 -433.30505) (xy 314.138056 -433.289964) (xy 314.138169 -433.274878)
			(xy 314.139948 -433.24476) (xy 314.141612 -433.229766) (xy 314.141612 -432.618896) (xy 314.142009 -432.606811)
			(xy 314.14948 -432.583825) (xy 314.16369 -432.564273) (xy 314.183246 -432.550069) (xy 314.206235 -432.542606)
			(xy 314.21832 -432.542188) (xy 315.15812 -432.542188) (xy 315.170195 -432.542647) (xy 315.193162 -432.550115)
			(xy 315.212699 -432.564313) (xy 315.226893 -432.583852) (xy 315.234355 -432.606821) (xy 315.234828 -432.618896)
			(xy 315.234828 -435.16042) (xy 315.234353 -435.172494) (xy 315.226887 -435.195458) (xy 315.212693 -435.214993)
			(xy 315.193158 -435.229187) (xy 315.170194 -435.236653) (xy 315.15812 -435.237128) (xy 314.21832 -435.237128)
			(xy 314.206248 -435.236619) (xy 314.183285 -435.229165) (xy 314.16375 -435.214979) (xy 314.149554 -435.195451)
			(xy 314.142087 -435.172491) (xy 314.141612 -435.16042) (xy 314.141612 -434.550058) (xy 314.139946 -434.535064)
			(xy 314.138166 -434.504946) (xy 314.138056 -434.48986) (xy 274.509927 -434.48986) (xy 274.501358 -434.512693)
			(xy 274.431686 -434.675698) (xy 274.354772 -434.835412) (xy 274.270769 -434.991515) (xy 274.179848 -435.143692)
			(xy 274.082191 -435.291636) (xy 273.977994 -435.43505) (xy 273.934286 -435.489858) (xy 316.138052 -435.489858)
			(xy 316.138165 -435.474772) (xy 316.139944 -435.444654) (xy 316.141608 -435.42966) (xy 316.141608 -434.35016)
			(xy 316.139943 -434.335166) (xy 316.138162 -434.305048) (xy 316.138052 -434.289962) (xy 316.138165 -434.274876)
			(xy 316.139944 -434.244758) (xy 316.141608 -434.229764) (xy 316.141608 -433.618894) (xy 316.142102 -433.606807)
			(xy 316.149556 -433.583812) (xy 316.163737 -433.564235) (xy 316.183263 -433.549984) (xy 316.206231 -433.542446)
			(xy 316.218316 -433.541932) (xy 317.158116 -433.541932) (xy 317.170229 -433.542303) (xy 317.193262 -433.549811)
			(xy 317.212838 -433.564083) (xy 317.227031 -433.583716) (xy 317.234445 -433.606779) (xy 317.234824 -433.618894)
			(xy 317.234824 -434.48986) (xy 318.138048 -434.48986) (xy 318.138161 -434.474774) (xy 318.13994 -434.444656)
			(xy 318.141604 -434.429662) (xy 318.141604 -433.350162) (xy 318.139939 -433.335168) (xy 318.138158 -433.30505)
			(xy 318.138048 -433.289964) (xy 318.138161 -433.274878) (xy 318.13994 -433.24476) (xy 318.141604 -433.229766)
			(xy 318.141604 -432.618896) (xy 318.142009 -432.606812) (xy 318.149479 -432.583827) (xy 318.163687 -432.564276)
			(xy 318.183241 -432.550072) (xy 318.206228 -432.542607) (xy 318.218312 -432.542188) (xy 319.158112 -432.542188)
			(xy 319.170187 -432.542654) (xy 319.193154 -432.550119) (xy 319.21269 -432.564316) (xy 319.226884 -432.583854)
			(xy 319.234347 -432.606821) (xy 319.23482 -432.618896) (xy 319.23482 -435.16042) (xy 319.234353 -435.172494)
			(xy 319.226886 -435.19546) (xy 319.21269 -435.214996) (xy 319.193153 -435.22919) (xy 319.170186 -435.236654)
			(xy 319.158112 -435.237128) (xy 318.218312 -435.237128) (xy 318.20624 -435.236626) (xy 318.183277 -435.229169)
			(xy 318.163741 -435.214982) (xy 318.149546 -435.195452) (xy 318.142079 -435.172492) (xy 318.141604 -435.16042)
			(xy 318.141604 -434.550058) (xy 318.139938 -434.535064) (xy 318.138158 -434.504946) (xy 318.138048 -434.48986)
			(xy 317.234824 -434.48986) (xy 317.234824 -435.489858) (xy 320.138044 -435.489858) (xy 320.138157 -435.474772)
			(xy 320.139936 -435.444654) (xy 320.1416 -435.42966) (xy 320.1416 -434.35016) (xy 320.139934 -434.335166)
			(xy 320.138154 -434.305048) (xy 320.138044 -434.289962) (xy 320.138157 -434.274876) (xy 320.139936 -434.244758)
			(xy 320.1416 -434.229764) (xy 320.1416 -433.618894) (xy 320.142102 -433.606808) (xy 320.149555 -433.583814)
			(xy 320.163734 -433.564238) (xy 320.183258 -433.549986) (xy 320.206224 -433.542447) (xy 320.218308 -433.541932)
			(xy 321.158108 -433.541932) (xy 321.170221 -433.54231) (xy 321.193254 -433.549815) (xy 321.212829 -433.564086)
			(xy 321.227023 -433.583717) (xy 321.234437 -433.60678) (xy 321.234816 -433.618894) (xy 321.234816 -434.48986)
			(xy 322.13804 -434.48986) (xy 322.138153 -434.474774) (xy 322.139932 -434.444656) (xy 322.141596 -434.429662)
			(xy 322.141596 -433.350162) (xy 322.139931 -433.335168) (xy 322.13815 -433.30505) (xy 322.13804 -433.289964)
			(xy 322.138153 -433.274878) (xy 322.139932 -433.24476) (xy 322.141596 -433.229766) (xy 322.141596 -432.618896)
			(xy 322.142061 -432.606821) (xy 322.149525 -432.583853) (xy 322.163721 -432.564316) (xy 322.18326 -432.550121)
			(xy 322.206229 -432.54266) (xy 322.218304 -432.542188) (xy 323.158104 -432.542188) (xy 323.170178 -432.542661)
			(xy 323.193145 -432.550124) (xy 323.212682 -432.564318) (xy 323.226876 -432.583855) (xy 323.234339 -432.606822)
			(xy 323.234812 -432.618896) (xy 323.234812 -435.16042) (xy 323.234353 -435.172495) (xy 323.226885 -435.195462)
			(xy 323.212687 -435.214999) (xy 323.193148 -435.229193) (xy 323.170179 -435.236655) (xy 323.158104 -435.237128)
			(xy 322.218304 -435.237128) (xy 322.206232 -435.236633) (xy 322.183268 -435.229174) (xy 322.163733 -435.214984)
			(xy 322.149537 -435.195454) (xy 322.142071 -435.172492) (xy 322.141596 -435.16042) (xy 322.141596 -434.550058)
			(xy 322.13993 -434.535064) (xy 322.13815 -434.504946) (xy 322.13804 -434.48986) (xy 321.234816 -434.48986)
			(xy 321.234816 -435.489858) (xy 324.138036 -435.489858) (xy 324.138151 -435.474773) (xy 324.13993 -435.444654)
			(xy 324.141592 -435.42966) (xy 324.141592 -434.35016) (xy 324.139926 -434.335166) (xy 324.138146 -434.305048)
			(xy 324.138036 -434.289962) (xy 324.138151 -434.274877) (xy 324.13993 -434.244758) (xy 324.141592 -434.229764)
			(xy 324.141592 -433.618894) (xy 324.142102 -433.606809) (xy 324.149554 -433.583816) (xy 324.163731 -433.564241)
			(xy 324.183253 -433.549989) (xy 324.206217 -433.542448) (xy 324.2183 -433.541932) (xy 325.1581 -433.541932)
			(xy 325.170212 -433.542317) (xy 325.193245 -433.54982) (xy 325.212821 -433.564088) (xy 325.227014 -433.583719)
			(xy 325.234429 -433.60678) (xy 325.234808 -433.618894) (xy 325.234808 -434.48986) (xy 326.138032 -434.48986)
			(xy 326.138147 -434.474775) (xy 326.139926 -434.444656) (xy 326.141588 -434.429662) (xy 326.141588 -433.350162)
			(xy 326.139923 -433.335168) (xy 326.138142 -433.30505) (xy 326.138032 -433.289964) (xy 326.138148 -433.274879)
			(xy 326.139926 -433.24476) (xy 326.141588 -433.229766) (xy 326.141588 -432.618896) (xy 326.142061 -432.606822)
			(xy 326.149524 -432.583855) (xy 326.163718 -432.564318) (xy 326.183255 -432.550124) (xy 326.206222 -432.542661)
			(xy 326.218296 -432.542188) (xy 327.158096 -432.542188) (xy 327.17017 -432.542668) (xy 327.193136 -432.550129)
			(xy 327.212673 -432.564321) (xy 327.226868 -432.583857) (xy 327.234331 -432.606822) (xy 327.234804 -432.618896)
			(xy 327.234804 -435.16042) (xy 327.234353 -435.172496) (xy 327.226884 -435.195464) (xy 327.212684 -435.215001)
			(xy 327.193143 -435.229195) (xy 327.170172 -435.236656) (xy 327.158096 -435.237128) (xy 326.218296 -435.237128)
			(xy 326.206223 -435.236639) (xy 326.183259 -435.229178) (xy 326.163724 -435.214987) (xy 326.149529 -435.195455)
			(xy 326.142063 -435.172493) (xy 326.141588 -435.16042) (xy 326.141588 -434.550058) (xy 326.139922 -434.535064)
			(xy 326.138142 -434.504946) (xy 326.138032 -434.48986) (xy 325.234808 -434.48986) (xy 325.234808 -435.489858)
			(xy 328.138028 -435.489858) (xy 328.138143 -435.474773) (xy 328.139922 -435.444654) (xy 328.141584 -435.42966)
			(xy 328.141584 -434.35016) (xy 328.139918 -434.335166) (xy 328.138138 -434.305048) (xy 328.138028 -434.289962)
			(xy 328.138143 -434.274877) (xy 328.139922 -434.244758) (xy 328.141584 -434.229764) (xy 328.141584 -433.618894)
			(xy 328.142003 -433.6068) (xy 328.149467 -433.583792) (xy 328.163664 -433.564208) (xy 328.183211 -433.549959)
			(xy 328.206199 -433.542435) (xy 328.218292 -433.541932) (xy 329.158092 -433.541932) (xy 329.170204 -433.542323)
			(xy 329.193236 -433.549824) (xy 329.212812 -433.564091) (xy 329.227006 -433.58372) (xy 329.234421 -433.606781)
			(xy 329.2348 -433.618894) (xy 329.2348 -434.48986) (xy 331.138022 -434.48986) (xy 331.13812 -434.475286)
			(xy 331.13977 -434.446185) (xy 331.141324 -434.431694) (xy 331.141324 -433.34813) (xy 331.139776 -433.333638)
			(xy 331.138126 -433.304538) (xy 331.138022 -433.289964) (xy 331.13812 -433.27539) (xy 331.13977 -433.246289)
			(xy 331.141324 -433.231798) (xy 331.141324 -432.618896) (xy 331.141713 -432.606785) (xy 331.149217 -432.583753)
			(xy 331.163484 -432.564178) (xy 331.183113 -432.549984) (xy 331.206173 -432.542568) (xy 331.218286 -432.542188)
			(xy 332.158086 -432.542188) (xy 332.17018 -432.54262) (xy 332.193188 -432.550079) (xy 332.212772 -432.564273)
			(xy 332.227021 -432.583817) (xy 332.234545 -432.606804) (xy 332.235048 -432.618896) (xy 332.235048 -435.16042)
			(xy 332.234601 -435.172525) (xy 332.227102 -435.195545) (xy 332.212847 -435.215113) (xy 332.193235 -435.229309)
			(xy 332.170192 -435.236738) (xy 332.158086 -435.237128) (xy 331.218286 -435.237128) (xy 331.206192 -435.236704)
			(xy 331.183186 -435.22924) (xy 331.163603 -435.215043) (xy 331.149354 -435.195499) (xy 331.141828 -435.172512)
			(xy 331.141324 -435.16042) (xy 331.141324 -434.548026) (xy 331.139776 -434.533534) (xy 331.138126 -434.504434)
			(xy 331.138022 -434.48986) (xy 329.2348 -434.48986) (xy 329.2348 -435.489858) (xy 333.138018 -435.489858)
			(xy 333.138116 -435.475284) (xy 333.139766 -435.446183) (xy 333.14132 -435.431692) (xy 333.14132 -434.348128)
			(xy 333.139772 -434.333636) (xy 333.138122 -434.304536) (xy 333.138018 -434.289962) (xy 333.138116 -434.275388)
			(xy 333.139766 -434.246287) (xy 333.14132 -434.231796) (xy 333.14132 -433.618894) (xy 333.141807 -433.606781)
			(xy 333.149293 -433.583741) (xy 333.163532 -433.564141) (xy 333.18313 -433.549899) (xy 333.206169 -433.542408)
			(xy 333.218282 -433.541932) (xy 334.158082 -433.541932) (xy 334.170203 -433.542375) (xy 334.19326 -433.549862)
			(xy 334.212875 -433.564108) (xy 334.227127 -433.583718) (xy 334.234621 -433.606773) (xy 334.235044 -433.618894)
			(xy 334.235044 -434.48986) (xy 335.138014 -434.48986) (xy 335.138111 -434.475286) (xy 335.139761 -434.446185)
			(xy 335.141316 -434.431694) (xy 335.141316 -433.34813) (xy 335.139768 -433.333638) (xy 335.138118 -433.304538)
			(xy 335.138014 -433.289964) (xy 335.138112 -433.27539) (xy 335.139761 -433.246289) (xy 335.141316 -433.231798)
			(xy 335.141316 -432.618896) (xy 335.141713 -432.606785) (xy 335.149215 -432.583755) (xy 335.163481 -432.564181)
			(xy 335.183108 -432.549987) (xy 335.206166 -432.542569) (xy 335.218278 -432.542188) (xy 336.158078 -432.542188)
			(xy 336.170171 -432.542627) (xy 336.193179 -432.550084) (xy 336.212764 -432.564276) (xy 336.227013 -432.583818)
			(xy 336.234537 -432.606804) (xy 336.23504 -432.618896) (xy 336.23504 -435.16042) (xy 336.234601 -435.172526)
			(xy 336.227101 -435.195547) (xy 336.212844 -435.215116) (xy 336.19323 -435.229312) (xy 336.170185 -435.236739)
			(xy 336.158078 -435.237128) (xy 335.218278 -435.237128) (xy 335.206184 -435.236711) (xy 335.183177 -435.229244)
			(xy 335.163595 -435.215046) (xy 335.149346 -435.1955) (xy 335.14182 -435.172513) (xy 335.141316 -435.16042)
			(xy 335.141316 -434.548026) (xy 335.139768 -434.533534) (xy 335.138118 -434.504434) (xy 335.138014 -434.48986)
			(xy 334.235044 -434.48986) (xy 334.235044 -435.489858) (xy 337.13801 -435.489858) (xy 337.138107 -435.475284)
			(xy 337.139757 -435.446183) (xy 337.141312 -435.431692) (xy 337.141312 -434.348128) (xy 337.139764 -434.333636)
			(xy 337.138114 -434.304536) (xy 337.13801 -434.289962) (xy 337.138108 -434.275388) (xy 337.139757 -434.246287)
			(xy 337.141312 -434.231796) (xy 337.141312 -433.618894) (xy 337.141806 -433.606782) (xy 337.149292 -433.583743)
			(xy 337.163529 -433.564143) (xy 337.183125 -433.549901) (xy 337.206162 -433.54241) (xy 337.218274 -433.541932)
			(xy 338.158074 -433.541932) (xy 338.170195 -433.542382) (xy 338.193252 -433.549866) (xy 338.212867 -433.56411)
			(xy 338.227119 -433.58372) (xy 338.234613 -433.606773) (xy 338.235036 -433.618894) (xy 338.235036 -434.48986)
			(xy 339.138006 -434.48986) (xy 339.138104 -434.475286) (xy 339.139753 -434.446185) (xy 339.141308 -434.431694)
			(xy 339.141308 -433.34813) (xy 339.13976 -433.333638) (xy 339.13811 -433.304538) (xy 339.138006 -433.289964)
			(xy 339.138104 -433.27539) (xy 339.139753 -433.246289) (xy 339.141308 -433.231798) (xy 339.141308 -432.618896)
			(xy 339.141713 -432.606786) (xy 339.149214 -432.583757) (xy 339.163479 -432.564184) (xy 339.183103 -432.549989)
			(xy 339.206159 -432.54257) (xy 339.21827 -432.542188) (xy 340.15807 -432.542188) (xy 340.170163 -432.542634)
			(xy 340.19317 -432.550088) (xy 340.212755 -432.564278) (xy 340.227005 -432.58382) (xy 340.234529 -432.606805)
			(xy 340.235032 -432.618896) (xy 340.235032 -435.16042) (xy 340.234601 -435.172527) (xy 340.2271 -435.195549)
			(xy 340.212841 -435.215119) (xy 340.193225 -435.229314) (xy 340.170178 -435.23674) (xy 340.15807 -435.237128)
			(xy 339.21827 -435.237128) (xy 339.206176 -435.236718) (xy 339.183169 -435.229249) (xy 339.163586 -435.215049)
			(xy 339.149338 -435.195502) (xy 339.141812 -435.172513) (xy 339.141308 -435.16042) (xy 339.141308 -434.548026)
			(xy 339.13976 -434.533534) (xy 339.13811 -434.504434) (xy 339.138006 -434.48986) (xy 338.235036 -434.48986)
			(xy 338.235036 -435.489858) (xy 341.138002 -435.489858) (xy 341.138099 -435.475284) (xy 341.139749 -435.446183)
			(xy 341.141304 -435.431692) (xy 341.141304 -434.348128) (xy 341.139756 -434.333636) (xy 341.138106 -434.304536)
			(xy 341.138002 -434.289962) (xy 341.1381 -434.275388) (xy 341.139749 -434.246287) (xy 341.141304 -434.231796)
			(xy 341.141304 -433.618894) (xy 341.141806 -433.606783) (xy 341.149291 -433.583745) (xy 341.163526 -433.564146)
			(xy 341.18312 -433.549904) (xy 341.206155 -433.542411) (xy 341.218266 -433.541932) (xy 342.158066 -433.541932)
			(xy 342.170186 -433.542389) (xy 342.193243 -433.549871) (xy 342.212858 -433.564113) (xy 342.227111 -433.583721)
			(xy 342.234605 -433.606774) (xy 342.235028 -433.618894) (xy 342.235028 -434.48986) (xy 343.137998 -434.48986)
			(xy 343.138096 -434.475286) (xy 343.139745 -434.446185) (xy 343.1413 -434.431694) (xy 343.1413 -433.34813)
			(xy 343.139752 -433.333638) (xy 343.138102 -433.304538) (xy 343.137998 -433.289964) (xy 343.138096 -433.27539)
			(xy 343.139745 -433.246289) (xy 343.1413 -433.231798) (xy 343.1413 -432.618896) (xy 343.141713 -432.606787)
			(xy 343.149213 -432.583759) (xy 343.163476 -432.564186) (xy 343.183098 -432.549992) (xy 343.206152 -432.542571)
			(xy 343.218262 -432.542188) (xy 344.158062 -432.542188) (xy 344.170154 -432.542641) (xy 344.193162 -432.550093)
			(xy 344.212747 -432.564281) (xy 344.226997 -432.583821) (xy 344.234521 -432.606805) (xy 344.235024 -432.618896)
			(xy 344.235024 -435.16042) (xy 344.234601 -435.172528) (xy 344.227099 -435.195551) (xy 344.212838 -435.215122)
			(xy 344.19322 -435.229317) (xy 344.170171 -435.236741) (xy 344.158062 -435.237128) (xy 343.218262 -435.237128)
			(xy 343.206167 -435.236724) (xy 343.18316 -435.229253) (xy 343.163578 -435.215052) (xy 343.14933 -435.195503)
			(xy 343.141804 -435.172514) (xy 343.1413 -435.16042) (xy 343.1413 -434.548026) (xy 343.139752 -434.533534)
			(xy 343.138102 -434.504434) (xy 343.137998 -434.48986) (xy 342.235028 -434.48986) (xy 342.235028 -435.489858)
			(xy 345.137994 -435.489858) (xy 345.138091 -435.475284) (xy 345.139741 -435.446183) (xy 345.141296 -435.431692)
			(xy 345.141296 -434.348128) (xy 345.139748 -434.333636) (xy 345.138098 -434.304536) (xy 345.137994 -434.289962)
			(xy 345.138092 -434.275388) (xy 345.139741 -434.246287) (xy 345.141296 -434.231796) (xy 345.141296 -433.618894)
			(xy 345.141806 -433.606783) (xy 345.14929 -433.583747) (xy 345.163524 -433.564149) (xy 345.183115 -433.549906)
			(xy 345.206148 -433.542412) (xy 345.218258 -433.541932) (xy 346.158058 -433.541932) (xy 346.170178 -433.542396)
			(xy 346.193234 -433.549876) (xy 346.21285 -433.564116) (xy 346.227103 -433.583722) (xy 346.234597 -433.606774)
			(xy 346.23502 -433.618894) (xy 346.23502 -436.160418) (xy 346.234654 -436.172546) (xy 346.227152 -436.195612)
			(xy 346.212888 -436.215231) (xy 346.193258 -436.22948) (xy 346.170186 -436.236964) (xy 346.158058 -436.23738)
			(xy 345.218258 -436.23738) (xy 345.206143 -436.236924) (xy 345.183101 -436.229428) (xy 345.163502 -436.215181)
			(xy 345.149261 -436.195577) (xy 345.141772 -436.172533) (xy 345.141296 -436.160418) (xy 345.141296 -435.548024)
			(xy 345.139748 -435.533532) (xy 345.138098 -435.504432) (xy 345.137994 -435.489858) (xy 342.235028 -435.489858)
			(xy 342.235028 -436.160418) (xy 342.234655 -436.172545) (xy 342.227153 -436.19561) (xy 342.212891 -436.215228)
			(xy 342.193264 -436.229477) (xy 342.170193 -436.236963) (xy 342.158066 -436.23738) (xy 341.218266 -436.23738)
			(xy 341.206151 -436.236918) (xy 341.18311 -436.229423) (xy 341.16351 -436.215178) (xy 341.149269 -436.195576)
			(xy 341.14178 -436.172533) (xy 341.141304 -436.160418) (xy 341.141304 -435.548024) (xy 341.139755 -435.533532)
			(xy 341.138106 -435.504432) (xy 341.138002 -435.489858) (xy 338.235036 -435.489858) (xy 338.235036 -436.160418)
			(xy 338.234655 -436.172544) (xy 338.227154 -436.195608) (xy 338.212894 -436.215225) (xy 338.193269 -436.229474)
			(xy 338.1702 -436.236962) (xy 338.158074 -436.23738) (xy 337.218274 -436.23738) (xy 337.20616 -436.236911)
			(xy 337.183119 -436.229419) (xy 337.163519 -436.215175) (xy 337.149278 -436.195574) (xy 337.141788 -436.172532)
			(xy 337.141312 -436.160418) (xy 337.141312 -435.548024) (xy 337.139763 -435.533532) (xy 337.138114 -435.504432)
			(xy 337.13801 -435.489858) (xy 334.235044 -435.489858) (xy 334.235044 -436.160418) (xy 334.234604 -436.172535)
			(xy 334.227109 -436.195582) (xy 334.21286 -436.215185) (xy 334.19325 -436.229426) (xy 334.1702 -436.236909)
			(xy 334.158082 -436.23738) (xy 333.218282 -436.23738) (xy 333.206168 -436.236904) (xy 333.183127 -436.229414)
			(xy 333.163528 -436.215172) (xy 333.149286 -436.195573) (xy 333.141796 -436.172532) (xy 333.14132 -436.160418)
			(xy 333.14132 -435.548024) (xy 333.139771 -435.533532) (xy 333.138122 -435.504432) (xy 333.138018 -435.489858)
			(xy 329.2348 -435.489858) (xy 329.2348 -436.160418) (xy 329.234309 -436.172505) (xy 329.226852 -436.195499)
			(xy 329.21267 -436.215075) (xy 329.193145 -436.229327) (xy 329.170177 -436.236865) (xy 329.158092 -436.23738)
			(xy 328.218292 -436.23738) (xy 328.206181 -436.23699) (xy 328.18315 -436.229486) (xy 328.163575 -436.215219)
			(xy 328.149381 -436.19559) (xy 328.141964 -436.172531) (xy 328.141584 -436.160418) (xy 328.141584 -435.550056)
			(xy 328.139918 -435.535062) (xy 328.138138 -435.504944) (xy 328.138028 -435.489858) (xy 325.234808 -435.489858)
			(xy 325.234808 -436.160418) (xy 325.234309 -436.172504) (xy 325.226853 -436.195497) (xy 325.212673 -436.215072)
			(xy 325.19315 -436.229324) (xy 325.170184 -436.236864) (xy 325.1581 -436.23738) (xy 324.2183 -436.23738)
			(xy 324.206189 -436.236984) (xy 324.183158 -436.229482) (xy 324.163583 -436.215216) (xy 324.14939 -436.195589)
			(xy 324.141972 -436.17253) (xy 324.141592 -436.160418) (xy 324.141592 -435.550056) (xy 324.139926 -435.535062)
			(xy 324.138146 -435.504944) (xy 324.138036 -435.489858) (xy 321.234816 -435.489858) (xy 321.234816 -436.160418)
			(xy 321.234407 -436.172513) (xy 321.22694 -436.195522) (xy 321.21274 -436.215105) (xy 321.193192 -436.229353)
			(xy 321.170202 -436.236877) (xy 321.158108 -436.23738) (xy 320.218308 -436.23738) (xy 320.206198 -436.236977)
			(xy 320.183167 -436.229477) (xy 320.163592 -436.215213) (xy 320.149398 -436.195587) (xy 320.14198 -436.17253)
			(xy 320.1416 -436.160418) (xy 320.1416 -435.550056) (xy 320.139934 -435.535062) (xy 320.138154 -435.504944)
			(xy 320.138044 -435.489858) (xy 317.234824 -435.489858) (xy 317.234824 -436.160418) (xy 317.234407 -436.172512)
			(xy 317.226941 -436.195519) (xy 317.212743 -436.215102) (xy 317.193197 -436.229351) (xy 317.170209 -436.236876)
			(xy 317.158116 -436.23738) (xy 316.218316 -436.23738) (xy 316.206206 -436.23697) (xy 316.183176 -436.229472)
			(xy 316.163601 -436.21521) (xy 316.149406 -436.195585) (xy 316.141989 -436.172529) (xy 316.141608 -436.160418)
			(xy 316.141608 -435.550056) (xy 316.139942 -435.535062) (xy 316.138162 -435.504944) (xy 316.138052 -435.489858)
			(xy 273.934286 -435.489858) (xy 273.867468 -435.573645) (xy 273.750836 -435.707142) (xy 273.628331 -435.835271)
			(xy 273.500202 -435.957776) (xy 273.366705 -436.074408) (xy 273.22811 -436.184934) (xy 273.084696 -436.289131)
			(xy 272.936752 -436.386788) (xy 272.784575 -436.477709) (xy 272.628472 -436.561712) (xy 272.468758 -436.638626)
			(xy 272.305753 -436.708298) (xy 272.139788 -436.770586) (xy 271.971194 -436.825365) (xy 271.800313 -436.872525)
			(xy 271.627488 -436.911971) (xy 271.453067 -436.943624) (xy 271.277402 -436.967419) (xy 271.100846 -436.98331)
			(xy 270.923755 -436.991263) (xy 270.746485 -436.991263) (xy 270.569394 -436.98331) (xy 270.392838 -436.967419)
			(xy 270.217173 -436.943624) (xy 270.042752 -436.911971) (xy 269.869927 -436.872525) (xy 269.699046 -436.825365)
			(xy 269.530452 -436.770586) (xy 269.364487 -436.708298) (xy 269.201482 -436.638626) (xy 269.041768 -436.561712)
			(xy 268.885665 -436.477709) (xy 268.733488 -436.386788) (xy 268.585544 -436.289131) (xy 268.44213 -436.184934)
			(xy 268.303535 -436.074408) (xy 268.170038 -435.957776) (xy 268.041909 -435.835271) (xy 267.919404 -435.707142)
			(xy 267.802772 -435.573645) (xy 267.692246 -435.43505) (xy 267.588049 -435.291636) (xy 267.490392 -435.143692)
			(xy 267.399471 -434.991515) (xy 267.315468 -434.835412) (xy 267.238554 -434.675698) (xy 267.168882 -434.512693)
			(xy 267.106594 -434.346728) (xy 267.051815 -434.178134) (xy 267.004655 -434.007253) (xy 266.965209 -433.834428)
			(xy 266.933556 -433.660007) (xy 266.909761 -433.484342) (xy 266.89387 -433.307786) (xy 266.885917 -433.130695)
			(xy 231.01554 -433.130695) (xy 231.01554 -435.063392) (xy 231.015024 -435.08834) (xy 231.007214 -435.137622)
			(xy 230.991802 -435.185079) (xy 230.969165 -435.229545) (xy 230.939859 -435.269929) (xy 230.922576 -435.287928)
			(xy 229.133908 -437.076596) (xy 229.115913 -437.093886) (xy 229.075537 -437.12321) (xy 229.031071 -437.145858)
			(xy 228.98361 -437.161272) (xy 228.934323 -437.169073) (xy 228.909372 -437.16956) (xy 207.503268 -437.16956)
			(xy 207.478319 -437.169063) (xy 207.429037 -437.161248) (xy 207.38158 -437.14583) (xy 207.337114 -437.123189)
			(xy 207.296731 -437.09388) (xy 207.278732 -437.076596) (xy 205.949804 -435.747668) (xy 205.932495 -435.72969)
			(xy 205.903173 -435.68931) (xy 205.880529 -435.64484) (xy 205.865119 -435.597375) (xy 205.857324 -435.548084)
			(xy 205.85684 -435.523132) (xy 204.057751 -435.523132) (xy 204.017468 -435.573645) (xy 203.900836 -435.707142)
			(xy 203.778331 -435.835271) (xy 203.650202 -435.957776) (xy 203.516705 -436.074408) (xy 203.37811 -436.184934)
			(xy 203.234696 -436.289131) (xy 203.086752 -436.386788) (xy 202.934575 -436.477709) (xy 202.778472 -436.561712)
			(xy 202.618758 -436.638626) (xy 202.455753 -436.708298) (xy 202.289788 -436.770586) (xy 202.121194 -436.825365)
			(xy 201.950313 -436.872525) (xy 201.777488 -436.911971) (xy 201.603067 -436.943624) (xy 201.427402 -436.967419)
			(xy 201.250846 -436.98331) (xy 201.073755 -436.991263) (xy 200.896485 -436.991263) (xy 200.719394 -436.98331)
			(xy 200.542838 -436.967419) (xy 200.367173 -436.943624) (xy 200.192752 -436.911971) (xy 200.019927 -436.872525)
			(xy 199.849046 -436.825365) (xy 199.680452 -436.770586) (xy 199.514487 -436.708298) (xy 199.351482 -436.638626)
			(xy 199.191768 -436.561712) (xy 199.035665 -436.477709) (xy 198.883488 -436.386788) (xy 198.735544 -436.289131)
			(xy 198.59213 -436.184934) (xy 198.453535 -436.074408) (xy 198.320038 -435.957776) (xy 198.191909 -435.835271)
			(xy 198.069404 -435.707142) (xy 197.952772 -435.573645) (xy 197.842246 -435.43505) (xy 197.738049 -435.291636)
			(xy 197.640392 -435.143692) (xy 197.549471 -434.991515) (xy 197.465468 -434.835412) (xy 197.388554 -434.675698)
			(xy 197.318882 -434.512693) (xy 197.256594 -434.346728) (xy 197.201815 -434.178134) (xy 197.154655 -434.007253)
			(xy 197.115209 -433.834428) (xy 197.083556 -433.660007) (xy 197.059761 -433.484342) (xy 197.04387 -433.307786)
			(xy 197.035917 -433.130695) (xy 155.334716 -433.130695) (xy 155.334716 -435.16042) (xy 155.334253 -435.172495)
			(xy 155.326786 -435.195461) (xy 155.312589 -435.214997) (xy 155.29305 -435.229191) (xy 155.270083 -435.236655)
			(xy 155.258008 -435.237128) (xy 154.318208 -435.237128) (xy 154.306136 -435.236629) (xy 154.283172 -435.229171)
			(xy 154.263637 -435.214983) (xy 154.249441 -435.195453) (xy 154.241975 -435.172492) (xy 154.2415 -435.16042)
			(xy 154.2415 -434.6448) (xy 154.230692 -434.606981) (xy 154.219091 -434.529187) (xy 154.218386 -434.48986)
			(xy 153.33472 -434.48986) (xy 153.33472 -435.489858) (xy 156.218382 -435.489858) (xy 156.218838 -435.457301)
			(xy 156.226789 -435.392673) (xy 156.24258 -435.329502) (xy 156.265973 -435.268734) (xy 156.296618 -435.211281)
			(xy 156.334056 -435.158005) (xy 156.377724 -435.109704) (xy 156.402024 -435.08803) (xy 156.482796 -434.923184)
			(xy 156.487496 -434.912667) (xy 156.490987 -434.889909) (xy 156.487502 -434.86715) (xy 156.482796 -434.856636)
			(xy 156.402024 -434.69179) (xy 156.377745 -434.670096) (xy 156.334091 -434.62179) (xy 156.296664 -434.568513)
			(xy 156.266025 -434.511064) (xy 156.242633 -434.450302) (xy 156.226838 -434.387137) (xy 156.218878 -434.322517)
			(xy 156.218382 -434.289962) (xy 156.219109 -434.250637) (xy 156.230714 -434.172847) (xy 156.241496 -434.135022)
			(xy 156.241496 -433.618894) (xy 156.242002 -433.606809) (xy 156.249455 -433.583815) (xy 156.263633 -433.564239)
			(xy 156.283155 -433.549987) (xy 156.30612 -433.542448) (xy 156.318204 -433.541932) (xy 157.258004 -433.541932)
			(xy 157.270116 -433.542313) (xy 157.293149 -433.549818) (xy 157.312725 -433.564087) (xy 157.326918 -433.583718)
			(xy 157.334333 -433.60678) (xy 157.334712 -433.618894) (xy 157.334712 -436.160418) (xy 157.334307 -436.172513)
			(xy 157.32684 -436.195523) (xy 157.312639 -436.215106) (xy 157.293089 -436.229355) (xy 157.270098 -436.236878)
			(xy 157.258004 -436.23738) (xy 156.318204 -436.23738) (xy 156.306093 -436.23698) (xy 156.283063 -436.229479)
			(xy 156.263488 -436.215214) (xy 156.249294 -436.195588) (xy 156.241876 -436.17253) (xy 156.241496 -436.160418)
			(xy 156.241496 -435.644798) (xy 156.230688 -435.606979) (xy 156.219087 -435.529185) (xy 156.218382 -435.489858)
			(xy 153.33472 -435.489858) (xy 153.33472 -436.160418) (xy 153.334307 -436.172513) (xy 153.326841 -436.195521)
			(xy 153.312642 -436.215104) (xy 153.293094 -436.229352) (xy 153.270105 -436.236877) (xy 153.258012 -436.23738)
			(xy 152.318212 -436.23738) (xy 152.306102 -436.236973) (xy 152.283072 -436.229474) (xy 152.263497 -436.215211)
			(xy 152.249302 -436.195586) (xy 152.241885 -436.17253) (xy 152.241504 -436.160418) (xy 152.241504 -435.644798)
			(xy 152.230696 -435.606979) (xy 152.219095 -435.529185) (xy 152.21839 -435.489858) (xy 149.334728 -435.489858)
			(xy 149.334728 -436.160418) (xy 149.334308 -436.172512) (xy 149.326842 -436.195518) (xy 149.312645 -436.215101)
			(xy 149.293099 -436.22935) (xy 149.270112 -436.236876) (xy 149.25802 -436.23738) (xy 148.31822 -436.23738)
			(xy 148.30611 -436.236966) (xy 148.28308 -436.22947) (xy 148.263505 -436.215208) (xy 148.249311 -436.195585)
			(xy 148.241893 -436.172529) (xy 148.241512 -436.160418) (xy 148.241512 -435.644798) (xy 148.230704 -435.606979)
			(xy 148.219103 -435.529185) (xy 148.218398 -435.489858) (xy 145.334736 -435.489858) (xy 145.334736 -436.160418)
			(xy 145.334308 -436.172511) (xy 145.326843 -436.195516) (xy 145.312647 -436.215098) (xy 145.293104 -436.229347)
			(xy 145.27012 -436.236874) (xy 145.258028 -436.23738) (xy 144.318228 -436.23738) (xy 144.306119 -436.236959)
			(xy 144.283089 -436.229465) (xy 144.263514 -436.215206) (xy 144.249319 -436.195583) (xy 144.241901 -436.172529)
			(xy 144.24152 -436.160418) (xy 144.24152 -435.644798) (xy 144.230712 -435.606979) (xy 144.219111 -435.529185)
			(xy 144.218406 -435.489858) (xy 140.335 -435.489858) (xy 140.335 -436.160418) (xy 140.334504 -436.17253)
			(xy 140.327017 -436.195567) (xy 140.31278 -436.215165) (xy 140.293185 -436.229408) (xy 140.27015 -436.236901)
			(xy 140.258038 -436.23738) (xy 139.318238 -436.23738) (xy 139.306119 -436.236908) (xy 139.283064 -436.229428)
			(xy 139.26345 -436.21519) (xy 139.249197 -436.195586) (xy 139.241701 -436.172537) (xy 139.241276 -436.160418)
			(xy 139.241276 -435.644036) (xy 139.230579 -435.606394) (xy 139.219108 -435.528985) (xy 139.218416 -435.489858)
			(xy 136.335008 -435.489858) (xy 136.335008 -436.160418) (xy 136.334505 -436.172529) (xy 136.327018 -436.195565)
			(xy 136.312782 -436.215163) (xy 136.29319 -436.229405) (xy 136.270157 -436.2369) (xy 136.258046 -436.23738)
			(xy 135.318246 -436.23738) (xy 135.306127 -436.236901) (xy 135.283073 -436.229424) (xy 135.263459 -436.215187)
			(xy 135.249205 -436.195584) (xy 135.241709 -436.172536) (xy 135.241284 -436.160418) (xy 135.241284 -435.644036)
			(xy 135.230587 -435.606394) (xy 135.219116 -435.528985) (xy 135.218424 -435.489858) (xy 132.335016 -435.489858)
			(xy 132.335016 -436.160418) (xy 132.334654 -436.172546) (xy 132.327152 -436.195613) (xy 132.312886 -436.215232)
			(xy 132.293256 -436.229481) (xy 132.270183 -436.236965) (xy 132.258054 -436.23738) (xy 131.318254 -436.23738)
			(xy 131.306139 -436.236928) (xy 131.283097 -436.22943) (xy 131.263498 -436.215182) (xy 131.249257 -436.195578)
			(xy 131.241768 -436.172533) (xy 131.241292 -436.160418) (xy 131.241292 -435.644036) (xy 131.230595 -435.606393)
			(xy 131.219124 -435.528985) (xy 131.218432 -435.489858) (xy 128.335024 -435.489858) (xy 128.335024 -436.160418)
			(xy 128.334655 -436.172545) (xy 128.327153 -436.195611) (xy 128.312889 -436.215229) (xy 128.293261 -436.229478)
			(xy 128.27019 -436.236963) (xy 128.258062 -436.23738) (xy 127.318262 -436.23738) (xy 127.306147 -436.236921)
			(xy 127.283106 -436.229425) (xy 127.263506 -436.21518) (xy 127.249265 -436.195576) (xy 127.241776 -436.172533)
			(xy 127.2413 -436.160418) (xy 127.2413 -435.644036) (xy 127.230603 -435.606393) (xy 127.219132 -435.528985)
			(xy 127.21844 -435.489858) (xy 113.866512 -435.489858) (xy 113.892486 -435.537087) (xy 113.947862 -435.654438)
			(xy 113.995874 -435.77499) (xy 114.036336 -435.89828) (xy 114.069094 -436.023838) (xy 114.094022 -436.151181)
			(xy 114.111025 -436.279823) (xy 114.120038 -436.40927) (xy 114.121027 -436.539027) (xy 114.113986 -436.668596)
			(xy 114.098945 -436.797482) (xy 114.075959 -436.92519) (xy 114.045118 -437.051232) (xy 114.006538 -437.175125)
			(xy 113.960369 -437.296394) (xy 113.906786 -437.414574) (xy 113.845996 -437.529214) (xy 113.77823 -437.639874)
			(xy 113.703749 -437.74613) (xy 113.622838 -437.847575) (xy 113.535806 -437.943821) (xy 113.442988 -438.034499)
			(xy 113.378885 -438.089802) (xy 125.238002 -438.089802) (xy 125.238095 -438.075228) (xy 125.239748 -438.046127)
			(xy 125.241304 -438.031636) (xy 125.241304 -436.948072) (xy 125.239759 -436.93358) (xy 125.238107 -436.90448)
			(xy 125.238002 -436.889906) (xy 125.238095 -436.875332) (xy 125.239748 -436.846231) (xy 125.241304 -436.83174)
			(xy 125.241304 -436.219092) (xy 125.241709 -436.206982) (xy 125.249212 -436.183954) (xy 125.263476 -436.164381)
			(xy 125.2831 -436.150186) (xy 125.306155 -436.142767) (xy 125.318266 -436.142384) (xy 126.258066 -436.142384)
			(xy 126.270158 -436.142837) (xy 126.293165 -436.15029) (xy 126.312749 -436.164478) (xy 126.327 -436.184018)
			(xy 126.334525 -436.207001) (xy 126.335028 -436.219092) (xy 126.335028 -438.760616) (xy 126.334598 -438.772723)
			(xy 126.327097 -438.795746) (xy 126.312838 -438.815316) (xy 126.293222 -438.829511) (xy 126.270174 -438.836937)
			(xy 126.258066 -438.837324) (xy 125.318266 -438.837324) (xy 125.306171 -438.836921) (xy 125.283163 -438.829451)
			(xy 125.263581 -438.815249) (xy 125.249333 -438.7957) (xy 125.241808 -438.77271) (xy 125.241304 -438.760616)
			(xy 125.241304 -438.147968) (xy 125.239759 -438.133476) (xy 125.238107 -438.104376) (xy 125.238002 -438.089802)
			(xy 113.378885 -438.089802) (xy 113.344738 -438.119261) (xy 113.241432 -438.197784) (xy 113.133467 -438.269766)
			(xy 113.021257 -438.334931) (xy 112.90523 -438.39303) (xy 112.785831 -438.443841) (xy 112.663518 -438.487169)
			(xy 112.538759 -438.522847) (xy 112.412032 -438.550739) (xy 112.283822 -438.570739) (xy 112.15462 -438.58277)
			(xy 112.024922 -438.586785) (xy 111.895224 -438.58277) (xy 111.766022 -438.570739) (xy 111.637812 -438.550739)
			(xy 111.511085 -438.522847) (xy 111.386326 -438.487169) (xy 111.264013 -438.443841) (xy 111.144614 -438.39303)
			(xy 111.028587 -438.334931) (xy 110.916377 -438.269766) (xy 110.808412 -438.197784) (xy 110.705106 -438.119261)
			(xy 110.606856 -438.034499) (xy 110.514038 -437.943821) (xy 110.427006 -437.847575) (xy 110.346095 -437.74613)
			(xy 110.271614 -437.639874) (xy 110.203848 -437.529214) (xy 110.143058 -437.414574) (xy 110.089475 -437.296394)
			(xy 110.043306 -437.175125) (xy 110.004726 -437.051232) (xy 109.973885 -436.92519) (xy 109.950899 -436.797482)
			(xy 109.935858 -436.668596) (xy 109.928817 -436.539027) (xy 109.929806 -436.40927) (xy 109.938819 -436.279823)
			(xy 109.955822 -436.151181) (xy 109.98075 -436.023838) (xy 110.013508 -435.89828) (xy 110.05397 -435.77499)
			(xy 110.101982 -435.654438) (xy 110.157358 -435.537087) (xy 110.219888 -435.423387) (xy 110.289331 -435.313772)
			(xy 110.365422 -435.208663) (xy 110.447869 -435.108462) (xy 110.536357 -435.013553) (xy 110.630546 -434.924299)
			(xy 110.679992 -434.88229) (xy 110.691093 -434.872254) (xy 110.707515 -434.847259) (xy 110.71599 -434.818578)
			(xy 110.71579 -434.788672) (xy 110.706933 -434.760107) (xy 110.690178 -434.735334) (xy 110.666963 -434.71648)
			(xy 110.653322 -434.710332) (xy 110.574304 -434.677407) (xy 110.419107 -434.605131) (xy 110.267499 -434.5256)
			(xy 110.119821 -434.438991) (xy 109.976402 -434.345497) (xy 109.837562 -434.245328) (xy 109.703613 -434.138709)
			(xy 109.574854 -434.025876) (xy 109.451573 -433.907083) (xy 109.334045 -433.782595) (xy 109.222533 -433.65269)
			(xy 109.117287 -433.517659) (xy 109.018541 -433.377804) (xy 108.926517 -433.233438) (xy 108.84142 -433.084883)
			(xy 108.763441 -432.932471) (xy 108.692754 -432.776543) (xy 108.629516 -432.617449) (xy 108.57387 -432.455542)
			(xy 108.52594 -432.291187) (xy 108.485833 -432.124749) (xy 108.453638 -431.956601) (xy 108.429428 -431.78712)
			(xy 108.413257 -431.616683) (xy 108.405161 -431.445673) (xy 108.40466 -431.360072) (xy 90.235024 -431.360072)
			(xy 90.235024 -432.560476) (xy 90.234563 -432.572581) (xy 90.227074 -432.595604) (xy 90.212823 -432.615175)
			(xy 90.193212 -432.629371) (xy 90.170168 -432.636797) (xy 90.158062 -432.637184) (xy 89.218262 -432.637184)
			(xy 89.206173 -432.636726) (xy 89.183175 -432.629261) (xy 89.163598 -432.615072) (xy 89.149348 -432.595538)
			(xy 89.141812 -432.572564) (xy 89.1413 -432.560476) (xy 89.1413 -431.948082) (xy 89.139756 -431.93359)
			(xy 89.138104 -431.90449) (xy 89.137998 -431.889916) (xy 86.235032 -431.889916) (xy 86.235032 -432.560476)
			(xy 86.234563 -432.57258) (xy 86.227075 -432.595601) (xy 86.212825 -432.615172) (xy 86.193217 -432.629369)
			(xy 86.170175 -432.636796) (xy 86.15807 -432.637184) (xy 85.21827 -432.637184) (xy 85.206181 -432.636719)
			(xy 85.183184 -432.629257) (xy 85.163606 -432.615069) (xy 85.149356 -432.595537) (xy 85.14182 -432.572563)
			(xy 85.141308 -432.560476) (xy 85.141308 -431.948082) (xy 85.139764 -431.93359) (xy 85.138112 -431.90449)
			(xy 85.138006 -431.889916) (xy 82.23504 -431.889916) (xy 82.23504 -432.560476) (xy 82.234564 -432.57258)
			(xy 82.227076 -432.595599) (xy 82.212828 -432.615169) (xy 82.193222 -432.629366) (xy 82.170183 -432.636795)
			(xy 82.158078 -432.637184) (xy 81.218278 -432.637184) (xy 81.20619 -432.636712) (xy 81.183192 -432.629252)
			(xy 81.163615 -432.615066) (xy 81.149364 -432.595535) (xy 81.141828 -432.572563) (xy 81.141316 -432.560476)
			(xy 81.141316 -431.948082) (xy 81.139772 -431.93359) (xy 81.13812 -431.90449) (xy 81.138014 -431.889916)
			(xy 78.235048 -431.889916) (xy 78.235048 -432.560476) (xy 78.234564 -432.572579) (xy 78.227077 -432.595597)
			(xy 78.212831 -432.615166) (xy 78.193227 -432.629364) (xy 78.17019 -432.636793) (xy 78.158086 -432.637184)
			(xy 77.218286 -432.637184) (xy 77.206198 -432.636705) (xy 77.183201 -432.629248) (xy 77.163623 -432.615063)
			(xy 77.149372 -432.595534) (xy 77.141836 -432.572562) (xy 77.141324 -432.560476) (xy 77.141324 -431.948082)
			(xy 77.13978 -431.93359) (xy 77.138128 -431.90449) (xy 77.138022 -431.889916) (xy 73.234804 -431.889916)
			(xy 73.234804 -432.560476) (xy 73.234367 -432.572558) (xy 73.226905 -432.59554) (xy 73.212706 -432.615091)
			(xy 73.193158 -432.629296) (xy 73.170178 -432.636764) (xy 73.158096 -432.637184) (xy 72.218296 -432.637184)
			(xy 72.206211 -432.636791) (xy 72.183224 -432.629319) (xy 72.163671 -432.615109) (xy 72.149468 -432.595551)
			(xy 72.142005 -432.572562) (xy 72.141588 -432.560476) (xy 72.141588 -431.950114) (xy 72.139918 -431.935121)
			(xy 72.138141 -431.905002) (xy 72.138032 -431.889916) (xy 69.234812 -431.889916) (xy 69.234812 -432.560476)
			(xy 69.234367 -432.572557) (xy 69.226906 -432.595538) (xy 69.212709 -432.615089) (xy 69.193163 -432.629294)
			(xy 69.170185 -432.636762) (xy 69.158104 -432.637184) (xy 68.218304 -432.637184) (xy 68.206219 -432.636784)
			(xy 68.183232 -432.629314) (xy 68.16368 -432.615106) (xy 68.149476 -432.59555) (xy 68.142013 -432.572561)
			(xy 68.141596 -432.560476) (xy 68.141596 -431.950114) (xy 68.139926 -431.935121) (xy 68.138149 -431.905002)
			(xy 68.13804 -431.889916) (xy 65.23482 -431.889916) (xy 65.23482 -432.560476) (xy 65.234367 -432.572556)
			(xy 65.226907 -432.595536) (xy 65.212711 -432.615086) (xy 65.193168 -432.629291) (xy 65.170192 -432.636761)
			(xy 65.158112 -432.637184) (xy 64.218312 -432.637184) (xy 64.206228 -432.636777) (xy 64.183241 -432.629309)
			(xy 64.163689 -432.615103) (xy 64.149485 -432.595548) (xy 64.142022 -432.572561) (xy 64.141604 -432.560476)
			(xy 64.141604 -431.950114) (xy 64.139934 -431.935121) (xy 64.138157 -431.905002) (xy 64.138048 -431.889916)
			(xy 61.234828 -431.889916) (xy 61.234828 -432.560476) (xy 61.234367 -432.572555) (xy 61.226909 -432.595534)
			(xy 61.212714 -432.615083) (xy 61.193173 -432.629288) (xy 61.170199 -432.63676) (xy 61.15812 -432.637184)
			(xy 60.21832 -432.637184) (xy 60.206236 -432.63677) (xy 60.18325 -432.629305) (xy 60.163697 -432.6151)
			(xy 60.149493 -432.595547) (xy 60.14203 -432.57256) (xy 60.141612 -432.560476) (xy 60.141612 -431.950114)
			(xy 60.139942 -431.935121) (xy 60.138165 -431.905002) (xy 60.138056 -431.889916) (xy 7.00913 -431.889916)
			(xy 7.00913 -434.48986) (xy 58.13806 -434.48986) (xy 58.138173 -434.474774) (xy 58.139952 -434.444656)
			(xy 58.141616 -434.429662) (xy 58.141616 -433.350162) (xy 58.139951 -433.335168) (xy 58.13817 -433.30505)
			(xy 58.13806 -433.289964) (xy 58.138173 -433.274878) (xy 58.139952 -433.24476) (xy 58.141616 -433.229766)
			(xy 58.141616 -432.618896) (xy 58.142009 -432.606811) (xy 58.149481 -432.583824) (xy 58.163691 -432.564271)
			(xy 58.183249 -432.550068) (xy 58.206238 -432.542605) (xy 58.218324 -432.542188) (xy 59.158124 -432.542188)
			(xy 59.170199 -432.542644) (xy 59.193167 -432.550113) (xy 59.212703 -432.564311) (xy 59.226897 -432.583851)
			(xy 59.234359 -432.606821) (xy 59.234832 -432.618896) (xy 59.234832 -435.16042) (xy 59.234353 -435.172493)
			(xy 59.226888 -435.195457) (xy 59.212694 -435.214991) (xy 59.19316 -435.229186) (xy 59.170197 -435.236652)
			(xy 59.158124 -435.237128) (xy 58.218324 -435.237128) (xy 58.206245 -435.236667) (xy 58.183266 -435.229209)
			(xy 58.163717 -435.215014) (xy 58.149512 -435.195473) (xy 58.14204 -435.172499) (xy 58.141616 -435.16042)
			(xy 58.141616 -434.550058) (xy 58.13995 -434.535064) (xy 58.13817 -434.504946) (xy 58.13806 -434.48986)
			(xy 7.00913 -434.48986) (xy 7.00913 -435.489858) (xy 60.138056 -435.489858) (xy 60.138169 -435.474772)
			(xy 60.139948 -435.444654) (xy 60.141612 -435.42966) (xy 60.141612 -434.35016) (xy 60.139947 -434.335166)
			(xy 60.138166 -434.305048) (xy 60.138056 -434.289962) (xy 60.138169 -434.274876) (xy 60.139948 -434.244758)
			(xy 60.141612 -434.229764) (xy 60.141612 -433.618894) (xy 60.142102 -433.606807) (xy 60.149557 -433.583811)
			(xy 60.163739 -433.564234) (xy 60.183265 -433.549982) (xy 60.206235 -433.542445) (xy 60.21832 -433.541932)
			(xy 61.15812 -433.541932) (xy 61.170233 -433.5423) (xy 61.193267 -433.549808) (xy 61.212842 -433.564081)
			(xy 61.227035 -433.583715) (xy 61.234449 -433.606779) (xy 61.234828 -433.618894) (xy 61.234828 -434.48986)
			(xy 62.138052 -434.48986) (xy 62.138165 -434.474774) (xy 62.139944 -434.444656) (xy 62.141608 -434.429662)
			(xy 62.141608 -433.350162) (xy 62.139943 -433.335168) (xy 62.138162 -433.30505) (xy 62.138052 -433.289964)
			(xy 62.138165 -433.274878) (xy 62.139944 -433.24476) (xy 62.141608 -433.229766) (xy 62.141608 -432.618896)
			(xy 62.142009 -432.606811) (xy 62.14948 -432.583826) (xy 62.163688 -432.564274) (xy 62.183244 -432.550071)
			(xy 62.206231 -432.542606) (xy 62.218316 -432.542188) (xy 63.158116 -432.542188) (xy 63.170191 -432.542651)
			(xy 63.193158 -432.550117) (xy 63.212694 -432.564314) (xy 63.226888 -432.583853) (xy 63.234351 -432.606821)
			(xy 63.234824 -432.618896) (xy 63.234824 -435.16042) (xy 63.234353 -435.172494) (xy 63.226887 -435.195459)
			(xy 63.212691 -435.214994) (xy 63.193155 -435.229189) (xy 63.17019 -435.236654) (xy 63.158116 -435.237128)
			(xy 62.218316 -435.237128) (xy 62.206244 -435.236622) (xy 62.183281 -435.229167) (xy 62.163745 -435.21498)
			(xy 62.14955 -435.195451) (xy 62.142083 -435.172492) (xy 62.141608 -435.16042) (xy 62.141608 -434.550058)
			(xy 62.139942 -434.535064) (xy 62.138162 -434.504946) (xy 62.138052 -434.48986) (xy 61.234828 -434.48986)
			(xy 61.234828 -435.489858) (xy 64.138048 -435.489858) (xy 64.138161 -435.474772) (xy 64.13994 -435.444654)
			(xy 64.141604 -435.42966) (xy 64.141604 -434.35016) (xy 64.139938 -434.335166) (xy 64.138158 -434.305048)
			(xy 64.138048 -434.289962) (xy 64.138161 -434.274876) (xy 64.13994 -434.244758) (xy 64.141604 -434.229764)
			(xy 64.141604 -433.618894) (xy 64.142102 -433.606808) (xy 64.149556 -433.583813) (xy 64.163736 -433.564236)
			(xy 64.18326 -433.549985) (xy 64.206228 -433.542447) (xy 64.218312 -433.541932) (xy 65.158112 -433.541932)
			(xy 65.170225 -433.542306) (xy 65.193258 -433.549813) (xy 65.212834 -433.564084) (xy 65.227027 -433.583717)
			(xy 65.234441 -433.60678) (xy 65.23482 -433.618894) (xy 65.23482 -434.48986) (xy 66.138044 -434.48986)
			(xy 66.138157 -434.474774) (xy 66.139936 -434.444656) (xy 66.1416 -434.429662) (xy 66.1416 -433.350162)
			(xy 66.139935 -433.335168) (xy 66.138154 -433.30505) (xy 66.138044 -433.289964) (xy 66.138157 -433.274878)
			(xy 66.139936 -433.24476) (xy 66.1416 -433.229766) (xy 66.1416 -432.618896) (xy 66.142009 -432.606812)
			(xy 66.149479 -432.583828) (xy 66.163686 -432.564277) (xy 66.183239 -432.550073) (xy 66.206224 -432.542607)
			(xy 66.218308 -432.542188) (xy 67.158108 -432.542188) (xy 67.170183 -432.542657) (xy 67.193149 -432.550122)
			(xy 67.212686 -432.564317) (xy 67.22688 -432.583854) (xy 67.234343 -432.606821) (xy 67.234816 -432.618896)
			(xy 67.234816 -435.16042) (xy 67.234353 -435.172495) (xy 67.226886 -435.195461) (xy 67.212689 -435.214997)
			(xy 67.19315 -435.229191) (xy 67.170183 -435.236655) (xy 67.158108 -435.237128) (xy 66.218308 -435.237128)
			(xy 66.206236 -435.236629) (xy 66.183272 -435.229171) (xy 66.163737 -435.214983) (xy 66.149541 -435.195453)
			(xy 66.142075 -435.172492) (xy 66.1416 -435.16042) (xy 66.1416 -434.550058) (xy 66.139934 -434.535064)
			(xy 66.138154 -434.504946) (xy 66.138044 -434.48986) (xy 65.23482 -434.48986) (xy 65.23482 -435.489858)
			(xy 68.13804 -435.489858) (xy 68.138153 -435.474772) (xy 68.139932 -435.444654) (xy 68.141596 -435.42966)
			(xy 68.141596 -434.35016) (xy 68.13993 -434.335166) (xy 68.13815 -434.305048) (xy 68.13804 -434.289962)
			(xy 68.138153 -434.274876) (xy 68.139932 -434.244758) (xy 68.141596 -434.229764) (xy 68.141596 -433.618894)
			(xy 68.142102 -433.606809) (xy 68.149555 -433.583815) (xy 68.163733 -433.564239) (xy 68.183255 -433.549987)
			(xy 68.20622 -433.542448) (xy 68.218304 -433.541932) (xy 69.158104 -433.541932) (xy 69.170216 -433.542313)
			(xy 69.193249 -433.549818) (xy 69.212825 -433.564087) (xy 69.227018 -433.583718) (xy 69.234433 -433.60678)
			(xy 69.234812 -433.618894) (xy 69.234812 -434.48986) (xy 70.138036 -434.48986) (xy 70.138151 -434.474775)
			(xy 70.13993 -434.444656) (xy 70.141592 -434.429662) (xy 70.141592 -433.350162) (xy 70.139927 -433.335168)
			(xy 70.138146 -433.30505) (xy 70.138036 -433.289964) (xy 70.138152 -433.274879) (xy 70.13993 -433.24476)
			(xy 70.141592 -433.229766) (xy 70.141592 -432.618896) (xy 70.142061 -432.606821) (xy 70.149524 -432.583854)
			(xy 70.16372 -432.564317) (xy 70.183258 -432.550123) (xy 70.206225 -432.54266) (xy 70.2183 -432.542188)
			(xy 71.1581 -432.542188) (xy 71.170174 -432.542664) (xy 71.193141 -432.550126) (xy 71.212677 -432.56432)
			(xy 71.226872 -432.583856) (xy 71.234335 -432.606822) (xy 71.234808 -432.618896) (xy 71.234808 -435.16042)
			(xy 71.234353 -435.172496) (xy 71.226885 -435.195463) (xy 71.212686 -435.215) (xy 71.193145 -435.229194)
			(xy 71.170176 -435.236656) (xy 71.1581 -435.237128) (xy 70.2183 -435.237128) (xy 70.206227 -435.236636)
			(xy 70.183264 -435.229176) (xy 70.163728 -435.214986) (xy 70.149533 -435.195454) (xy 70.142067 -435.172492)
			(xy 70.141592 -435.16042) (xy 70.141592 -434.550058) (xy 70.139926 -434.535064) (xy 70.138146 -434.504946)
			(xy 70.138036 -434.48986) (xy 69.234812 -434.48986) (xy 69.234812 -435.489858) (xy 72.138032 -435.489858)
			(xy 72.138147 -435.474773) (xy 72.139926 -435.444654) (xy 72.141588 -435.42966) (xy 72.141588 -434.35016)
			(xy 72.139922 -434.335166) (xy 72.138142 -434.305048) (xy 72.138032 -434.289962) (xy 72.138147 -434.274877)
			(xy 72.139926 -434.244758) (xy 72.141588 -434.229764) (xy 72.141588 -433.618894) (xy 72.142003 -433.606799)
			(xy 72.149468 -433.583791) (xy 72.163666 -433.564207) (xy 72.183213 -433.549958) (xy 72.206203 -433.542435)
			(xy 72.218296 -433.541932) (xy 73.158096 -433.541932) (xy 73.170208 -433.54232) (xy 73.193241 -433.549822)
			(xy 73.212817 -433.56409) (xy 73.22701 -433.58372) (xy 73.234425 -433.606781) (xy 73.234804 -433.618894)
			(xy 73.234804 -434.48986) (xy 75.138026 -434.48986) (xy 75.138124 -434.475286) (xy 75.139774 -434.446185)
			(xy 75.141328 -434.431694) (xy 75.141328 -433.34813) (xy 75.13978 -433.333638) (xy 75.13813 -433.304538)
			(xy 75.138026 -433.289964) (xy 75.138124 -433.27539) (xy 75.139774 -433.246289) (xy 75.141328 -433.231798)
			(xy 75.141328 -432.618896) (xy 75.141713 -432.606784) (xy 75.149217 -432.583752) (xy 75.163486 -432.564176)
			(xy 75.183116 -432.549983) (xy 75.206177 -432.542567) (xy 75.21829 -432.542188) (xy 76.15809 -432.542188)
			(xy 76.170184 -432.542617) (xy 76.193192 -432.550077) (xy 76.212776 -432.564271) (xy 76.227025 -432.583816)
			(xy 76.234549 -432.606804) (xy 76.235052 -432.618896) (xy 76.235052 -435.16042) (xy 76.234601 -435.172525)
			(xy 76.227103 -435.195544) (xy 76.212848 -435.215112) (xy 76.193237 -435.229308) (xy 76.170196 -435.236737)
			(xy 76.15809 -435.237128) (xy 75.21829 -435.237128) (xy 75.206197 -435.2367) (xy 75.183191 -435.229237)
			(xy 75.163608 -435.215041) (xy 75.149359 -435.195498) (xy 75.141833 -435.172512) (xy 75.141328 -435.16042)
			(xy 75.141328 -434.548026) (xy 75.13978 -434.533534) (xy 75.13813 -434.504434) (xy 75.138026 -434.48986)
			(xy 73.234804 -434.48986) (xy 73.234804 -435.489858) (xy 77.138022 -435.489858) (xy 77.13812 -435.475284)
			(xy 77.13977 -435.446183) (xy 77.141324 -435.431692) (xy 77.141324 -434.348128) (xy 77.139776 -434.333636)
			(xy 77.138126 -434.304536) (xy 77.138022 -434.289962) (xy 77.13812 -434.275388) (xy 77.13977 -434.246287)
			(xy 77.141324 -434.231796) (xy 77.141324 -433.618894) (xy 77.141807 -433.606781) (xy 77.149294 -433.58374)
			(xy 77.163534 -433.564139) (xy 77.183132 -433.549897) (xy 77.206173 -433.542408) (xy 77.218286 -433.541932)
			(xy 78.158086 -433.541932) (xy 78.170207 -433.542372) (xy 78.193265 -433.54986) (xy 78.21288 -433.564106)
			(xy 78.227131 -433.583717) (xy 78.234625 -433.606773) (xy 78.235048 -433.618894) (xy 78.235048 -434.48986)
			(xy 79.138018 -434.48986) (xy 79.138116 -434.475286) (xy 79.139766 -434.446185) (xy 79.14132 -434.431694)
			(xy 79.14132 -433.34813) (xy 79.139772 -433.333638) (xy 79.138122 -433.304538) (xy 79.138018 -433.289964)
			(xy 79.138116 -433.27539) (xy 79.139766 -433.246289) (xy 79.14132 -433.231798) (xy 79.14132 -432.618896)
			(xy 79.141713 -432.606785) (xy 79.149216 -432.583754) (xy 79.163483 -432.564179) (xy 79.183111 -432.549985)
			(xy 79.206169 -432.542568) (xy 79.218282 -432.542188) (xy 80.158082 -432.542188) (xy 80.170175 -432.542624)
			(xy 80.193183 -432.550081) (xy 80.212768 -432.564274) (xy 80.227017 -432.583818) (xy 80.234541 -432.606804)
			(xy 80.235044 -432.618896) (xy 80.235044 -435.16042) (xy 80.234601 -435.172526) (xy 80.227102 -435.195546)
			(xy 80.212845 -435.215115) (xy 80.193232 -435.22931) (xy 80.170189 -435.236739) (xy 80.158082 -435.237128)
			(xy 79.218282 -435.237128) (xy 79.206188 -435.236708) (xy 79.183182 -435.229242) (xy 79.163599 -435.215045)
			(xy 79.14935 -435.195499) (xy 79.141824 -435.172512) (xy 79.14132 -435.16042) (xy 79.14132 -434.548026)
			(xy 79.139772 -434.533534) (xy 79.138122 -434.504434) (xy 79.138018 -434.48986) (xy 78.235048 -434.48986)
			(xy 78.235048 -435.489858) (xy 81.138014 -435.489858) (xy 81.138111 -435.475284) (xy 81.139761 -435.446183)
			(xy 81.141316 -435.431692) (xy 81.141316 -434.348128) (xy 81.139768 -434.333636) (xy 81.138118 -434.304536)
			(xy 81.138014 -434.289962) (xy 81.138112 -434.275388) (xy 81.139761 -434.246287) (xy 81.141316 -434.231796)
			(xy 81.141316 -433.618894) (xy 81.141807 -433.606781) (xy 81.149293 -433.583742) (xy 81.163531 -433.564142)
			(xy 81.183127 -433.5499) (xy 81.206165 -433.542409) (xy 81.218278 -433.541932) (xy 82.158078 -433.541932)
			(xy 82.170199 -433.542379) (xy 82.193256 -433.549864) (xy 82.212871 -433.564109) (xy 82.227123 -433.583719)
			(xy 82.234617 -433.606773) (xy 82.23504 -433.618894) (xy 82.23504 -434.48986) (xy 83.13801 -434.48986)
			(xy 83.138107 -434.475286) (xy 83.139757 -434.446185) (xy 83.141312 -434.431694) (xy 83.141312 -433.34813)
			(xy 83.139764 -433.333638) (xy 83.138114 -433.304538) (xy 83.13801 -433.289964) (xy 83.138108 -433.27539)
			(xy 83.139757 -433.246289) (xy 83.141312 -433.231798) (xy 83.141312 -432.618896) (xy 83.141713 -432.606786)
			(xy 83.149215 -432.583756) (xy 83.16348 -432.564182) (xy 83.183106 -432.549988) (xy 83.206162 -432.542569)
			(xy 83.218274 -432.542188) (xy 84.158074 -432.542188) (xy 84.170167 -432.54263) (xy 84.193175 -432.550086)
			(xy 84.212759 -432.564277) (xy 84.227009 -432.583819) (xy 84.234533 -432.606804) (xy 84.235036 -432.618896)
			(xy 84.235036 -435.16042) (xy 84.234601 -435.172526) (xy 84.227101 -435.195548) (xy 84.212843 -435.215118)
			(xy 84.193227 -435.229313) (xy 84.170182 -435.23674) (xy 84.158074 -435.237128) (xy 83.218274 -435.237128)
			(xy 83.20618 -435.236714) (xy 83.183173 -435.229247) (xy 83.163591 -435.215047) (xy 83.149342 -435.195501)
			(xy 83.141816 -435.172513) (xy 83.141312 -435.16042) (xy 83.141312 -434.548026) (xy 83.139764 -434.533534)
			(xy 83.138114 -434.504434) (xy 83.13801 -434.48986) (xy 82.23504 -434.48986) (xy 82.23504 -435.489858)
			(xy 85.138006 -435.489858) (xy 85.138103 -435.475284) (xy 85.139753 -435.446183) (xy 85.141308 -435.431692)
			(xy 85.141308 -434.348128) (xy 85.13976 -434.333636) (xy 85.13811 -434.304536) (xy 85.138006 -434.289962)
			(xy 85.138104 -434.275388) (xy 85.139753 -434.246287) (xy 85.141308 -434.231796) (xy 85.141308 -433.618894)
			(xy 85.141806 -433.606782) (xy 85.149292 -433.583744) (xy 85.163528 -433.564145) (xy 85.183122 -433.549903)
			(xy 85.206158 -433.54241) (xy 85.21827 -433.541932) (xy 86.15807 -433.541932) (xy 86.170191 -433.542385)
			(xy 86.193247 -433.549869) (xy 86.212863 -433.564112) (xy 86.227115 -433.58372) (xy 86.234609 -433.606774)
			(xy 86.235032 -433.618894) (xy 86.235032 -434.48986) (xy 87.138002 -434.48986) (xy 87.1381 -434.475286)
			(xy 87.139749 -434.446185) (xy 87.141304 -434.431694) (xy 87.141304 -433.34813) (xy 87.139756 -433.333638)
			(xy 87.138106 -433.304538) (xy 87.138002 -433.289964) (xy 87.1381 -433.27539) (xy 87.139749 -433.246289)
			(xy 87.141304 -433.231798) (xy 87.141304 -432.618896) (xy 87.141713 -432.606787) (xy 87.149214 -432.583758)
			(xy 87.163477 -432.564185) (xy 87.183101 -432.549991) (xy 87.206155 -432.542571) (xy 87.218266 -432.542188)
			(xy 88.158066 -432.542188) (xy 88.170159 -432.542637) (xy 88.193166 -432.55009) (xy 88.212751 -432.56428)
			(xy 88.227001 -432.583821) (xy 88.234525 -432.606805) (xy 88.235028 -432.618896) (xy 88.235028 -435.16042)
			(xy 88.234601 -435.172527) (xy 88.2271 -435.19555) (xy 88.21284 -435.215121) (xy 88.193222 -435.229316)
			(xy 88.170174 -435.236741) (xy 88.158066 -435.237128) (xy 87.218266 -435.237128) (xy 87.206171 -435.236721)
			(xy 87.183164 -435.229251) (xy 87.163582 -435.21505) (xy 87.149334 -435.195502) (xy 87.141808 -435.172513)
			(xy 87.141304 -435.16042) (xy 87.141304 -434.548026) (xy 87.139756 -434.533534) (xy 87.138106 -434.504434)
			(xy 87.138002 -434.48986) (xy 86.235032 -434.48986) (xy 86.235032 -435.489858) (xy 89.137998 -435.489858)
			(xy 89.138095 -435.475284) (xy 89.139745 -435.446183) (xy 89.1413 -435.431692) (xy 89.1413 -434.348128)
			(xy 89.139752 -434.333636) (xy 89.138102 -434.304536) (xy 89.137998 -434.289962) (xy 89.138096 -434.275388)
			(xy 89.139745 -434.246287) (xy 89.1413 -434.231796) (xy 89.1413 -433.618894) (xy 89.141806 -433.606783)
			(xy 89.14929 -433.583746) (xy 89.163525 -433.564148) (xy 89.183117 -433.549905) (xy 89.206151 -433.542411)
			(xy 89.218262 -433.541932) (xy 90.158062 -433.541932) (xy 90.170182 -433.542392) (xy 90.193239 -433.549873)
			(xy 90.212854 -433.564115) (xy 90.227107 -433.583722) (xy 90.234601 -433.606774) (xy 90.235024 -433.618894)
			(xy 90.235024 -436.160418) (xy 90.234655 -436.172545) (xy 90.227153 -436.195611) (xy 90.212889 -436.215229)
			(xy 90.193261 -436.229478) (xy 90.17019 -436.236963) (xy 90.158062 -436.23738) (xy 89.218262 -436.23738)
			(xy 89.206147 -436.236921) (xy 89.183106 -436.229425) (xy 89.163506 -436.21518) (xy 89.149265 -436.195576)
			(xy 89.141776 -436.172533) (xy 89.1413 -436.160418) (xy 89.1413 -435.548024) (xy 89.139751 -435.533532)
			(xy 89.138102 -435.504432) (xy 89.137998 -435.489858) (xy 86.235032 -435.489858) (xy 86.235032 -436.160418)
			(xy 86.234655 -436.172545) (xy 86.227154 -436.195609) (xy 86.212892 -436.215226) (xy 86.193266 -436.229476)
			(xy 86.170197 -436.236962) (xy 86.15807 -436.23738) (xy 85.21827 -436.23738) (xy 85.206156 -436.236914)
			(xy 85.183114 -436.229421) (xy 85.163515 -436.215177) (xy 85.149274 -436.195575) (xy 85.141784 -436.172532)
			(xy 85.141308 -436.160418) (xy 85.141308 -435.548024) (xy 85.139759 -435.533532) (xy 85.13811 -435.504432)
			(xy 85.138006 -435.489858) (xy 82.23504 -435.489858) (xy 82.23504 -436.160418) (xy 82.234655 -436.172544)
			(xy 82.227155 -436.195607) (xy 82.212895 -436.215224) (xy 82.193271 -436.229473) (xy 82.170204 -436.236961)
			(xy 82.158078 -436.23738) (xy 81.218278 -436.23738) (xy 81.206164 -436.236907) (xy 81.183123 -436.229416)
			(xy 81.163523 -436.215174) (xy 81.149282 -436.195573) (xy 81.141792 -436.172532) (xy 81.141316 -436.160418)
			(xy 81.141316 -435.548024) (xy 81.139767 -435.533532) (xy 81.138118 -435.504432) (xy 81.138014 -435.489858)
			(xy 78.235048 -435.489858) (xy 78.235048 -436.160418) (xy 78.234604 -436.172535) (xy 78.22711 -436.195581)
			(xy 78.212861 -436.215184) (xy 78.193252 -436.229424) (xy 78.170203 -436.236909) (xy 78.158086 -436.23738)
			(xy 77.218286 -436.23738) (xy 77.206172 -436.236901) (xy 77.183132 -436.229412) (xy 77.163532 -436.215171)
			(xy 77.14929 -436.195572) (xy 77.1418 -436.172531) (xy 77.141324 -436.160418) (xy 77.141324 -435.548024)
			(xy 77.139775 -435.533532) (xy 77.138126 -435.504432) (xy 77.138022 -435.489858) (xy 73.234804 -435.489858)
			(xy 73.234804 -436.160418) (xy 73.234309 -436.172504) (xy 73.226853 -436.195498) (xy 73.212672 -436.215074)
			(xy 73.193147 -436.229325) (xy 73.17018 -436.236865) (xy 73.158096 -436.23738) (xy 72.218296 -436.23738)
			(xy 72.206185 -436.236987) (xy 72.183154 -436.229484) (xy 72.163579 -436.215217) (xy 72.149385 -436.195589)
			(xy 72.141968 -436.172531) (xy 72.141588 -436.160418) (xy 72.141588 -435.550056) (xy 72.139922 -435.535062)
			(xy 72.138142 -435.504944) (xy 72.138032 -435.489858) (xy 69.234812 -435.489858) (xy 69.234812 -436.160418)
			(xy 69.234407 -436.172513) (xy 69.22694 -436.195523) (xy 69.212739 -436.215106) (xy 69.193189 -436.229355)
			(xy 69.170198 -436.236878) (xy 69.158104 -436.23738) (xy 68.218304 -436.23738) (xy 68.206193 -436.23698)
			(xy 68.183163 -436.229479) (xy 68.163588 -436.215214) (xy 68.149394 -436.195588) (xy 68.141976 -436.17253)
			(xy 68.141596 -436.160418) (xy 68.141596 -435.550056) (xy 68.13993 -435.535062) (xy 68.13815 -435.504944)
			(xy 68.13804 -435.489858) (xy 65.23482 -435.489858) (xy 65.23482 -436.160418) (xy 65.234407 -436.172513)
			(xy 65.226941 -436.195521) (xy 65.212742 -436.215104) (xy 65.193194 -436.229352) (xy 65.170205 -436.236877)
			(xy 65.158112 -436.23738) (xy 64.218312 -436.23738) (xy 64.206202 -436.236973) (xy 64.183172 -436.229474)
			(xy 64.163597 -436.215211) (xy 64.149402 -436.195586) (xy 64.141985 -436.17253) (xy 64.141604 -436.160418)
			(xy 64.141604 -435.550056) (xy 64.139938 -435.535062) (xy 64.138158 -435.504944) (xy 64.138048 -435.489858)
			(xy 61.234828 -435.489858) (xy 61.234828 -436.160418) (xy 61.234408 -436.172512) (xy 61.226942 -436.195518)
			(xy 61.212745 -436.215101) (xy 61.193199 -436.22935) (xy 61.170212 -436.236876) (xy 61.15812 -436.23738)
			(xy 60.21832 -436.23738) (xy 60.20621 -436.236966) (xy 60.18318 -436.22947) (xy 60.163605 -436.215208)
			(xy 60.149411 -436.195585) (xy 60.141993 -436.172529) (xy 60.141612 -436.160418) (xy 60.141612 -435.550056)
			(xy 60.139946 -435.535062) (xy 60.138166 -435.504944) (xy 60.138056 -435.489858) (xy 7.00913 -435.489858)
			(xy 7.00913 -438.089802) (xy 58.118502 -438.089802) (xy 58.119024 -438.057222) (xy 58.126997 -437.992552)
			(xy 58.142813 -437.929341) (xy 58.166234 -437.868536) (xy 58.196909 -437.811048) (xy 58.234378 -437.757739)
			(xy 58.27808 -437.709407) (xy 58.302398 -437.68772) (xy 58.382916 -437.523382) (xy 58.387617 -437.512865)
			(xy 58.391107 -437.490107) (xy 58.387622 -437.467348) (xy 58.382916 -437.456834) (xy 58.30189 -437.291734)
			(xy 58.277614 -437.270052) (xy 58.234018 -437.221717) (xy 58.196645 -437.168424) (xy 58.166053 -437.110969)
			(xy 58.1427 -437.05021) (xy 58.126935 -436.987057) (xy 58.118992 -436.922452) (xy 58.118502 -436.889906)
			(xy 58.119238 -436.850581) (xy 58.130837 -436.772791) (xy 58.141616 -436.734966) (xy 58.141616 -436.219092)
			(xy 58.142006 -436.207006) (xy 58.149479 -436.184019) (xy 58.16369 -436.164467) (xy 58.183248 -436.150264)
			(xy 58.206238 -436.142801) (xy 58.218324 -436.142384) (xy 59.158124 -436.142384) (xy 59.170199 -436.142844)
			(xy 59.193166 -436.150312) (xy 59.212701 -436.16451) (xy 59.226895 -436.184049) (xy 59.234359 -436.207017)
			(xy 59.234832 -436.219092) (xy 59.234832 -438.760616) (xy 59.23435 -438.772689) (xy 59.226886 -438.795653)
			(xy 59.212693 -438.815187) (xy 59.19316 -438.829382) (xy 59.170197 -438.836848) (xy 59.158124 -438.837324)
			(xy 58.218324 -438.837324) (xy 58.206244 -438.836867) (xy 58.183265 -438.829408) (xy 58.163716 -438.815213)
			(xy 58.14951 -438.795671) (xy 58.142039 -438.772696) (xy 58.141616 -438.760616) (xy 58.141616 -438.244742)
			(xy 58.130818 -438.20692) (xy 58.11921 -438.129129) (xy 58.118502 -438.089802) (xy 7.00913 -438.089802)
			(xy 7.00913 -439.0898) (xy 60.118498 -439.0898) (xy 60.11902 -439.05722) (xy 60.126993 -438.99255)
			(xy 60.142809 -438.929339) (xy 60.16623 -438.868534) (xy 60.196905 -438.811046) (xy 60.234374 -438.757737)
			(xy 60.278076 -438.709405) (xy 60.302394 -438.687718) (xy 60.382912 -438.52338) (xy 60.387615 -438.512864)
			(xy 60.391104 -438.490105) (xy 60.387618 -438.467346) (xy 60.382912 -438.456832) (xy 60.301886 -438.291732)
			(xy 60.277608 -438.270052) (xy 60.234012 -438.221716) (xy 60.196639 -438.168423) (xy 60.166048 -438.110967)
			(xy 60.142696 -438.050209) (xy 60.12693 -437.987055) (xy 60.118988 -437.92245) (xy 60.118498 -437.889904)
			(xy 60.119234 -437.850579) (xy 60.130833 -437.772789) (xy 60.141612 -437.734964) (xy 60.141612 -437.21909)
			(xy 60.142099 -437.207003) (xy 60.149555 -437.184007) (xy 60.163737 -437.164429) (xy 60.183265 -437.150178)
			(xy 60.206234 -437.142641) (xy 60.21832 -437.142128) (xy 61.15812 -437.142128) (xy 61.170233 -437.1425)
			(xy 61.193265 -437.150008) (xy 61.212841 -437.16428) (xy 61.227034 -437.183913) (xy 61.234449 -437.206976)
			(xy 61.234828 -437.21909) (xy 61.234828 -438.089802) (xy 62.118494 -438.089802) (xy 62.119018 -438.057222)
			(xy 62.126992 -437.992552) (xy 62.142807 -437.929341) (xy 62.166228 -437.868536) (xy 62.196902 -437.811048)
			(xy 62.234371 -437.757739) (xy 62.278072 -437.709407) (xy 62.30239 -437.68772) (xy 62.382908 -437.523382)
			(xy 62.387609 -437.512865) (xy 62.391099 -437.490107) (xy 62.387614 -437.467348) (xy 62.382908 -437.456834)
			(xy 62.301882 -437.291734) (xy 62.277604 -437.270054) (xy 62.234008 -437.221718) (xy 62.196636 -437.168424)
			(xy 62.166045 -437.110969) (xy 62.142692 -437.050211) (xy 62.126927 -436.987057) (xy 62.118984 -436.922452)
			(xy 62.118494 -436.889906) (xy 62.11923 -436.850581) (xy 62.130829 -436.772791) (xy 62.141608 -436.734966)
			(xy 62.141608 -436.219092) (xy 62.142006 -436.207007) (xy 62.149478 -436.184021) (xy 62.163687 -436.16447)
			(xy 62.183243 -436.150267) (xy 62.206231 -436.142802) (xy 62.218316 -436.142384) (xy 63.158116 -436.142384)
			(xy 63.170191 -436.142851) (xy 63.193157 -436.150317) (xy 63.212693 -436.164513) (xy 63.226887 -436.18405)
			(xy 63.234351 -436.207017) (xy 63.234824 -436.219092) (xy 63.234824 -438.760616) (xy 63.23435 -438.77269)
			(xy 63.226885 -438.795655) (xy 63.21269 -438.81519) (xy 63.193155 -438.829385) (xy 63.17019 -438.83685)
			(xy 63.158116 -438.837324) (xy 62.218316 -438.837324) (xy 62.206244 -438.836822) (xy 62.18328 -438.829366)
			(xy 62.163744 -438.815179) (xy 62.149548 -438.795649) (xy 62.142083 -438.772688) (xy 62.141608 -438.760616)
			(xy 62.141608 -438.244742) (xy 62.13081 -438.20692) (xy 62.119202 -438.129129) (xy 62.118494 -438.089802)
			(xy 61.234828 -438.089802) (xy 61.234828 -439.0898) (xy 64.11849 -439.0898) (xy 64.119014 -439.05722)
			(xy 64.126988 -438.99255) (xy 64.142804 -438.929339) (xy 64.166224 -438.868534) (xy 64.196898 -438.811046)
			(xy 64.234367 -438.757737) (xy 64.278068 -438.709405) (xy 64.302386 -438.687718) (xy 64.382904 -438.52338)
			(xy 64.387607 -438.512864) (xy 64.391096 -438.490105) (xy 64.38761 -438.467346) (xy 64.382904 -438.456832)
			(xy 64.301878 -438.291732) (xy 64.277598 -438.270054) (xy 64.234003 -438.221718) (xy 64.196631 -438.168423)
			(xy 64.16604 -438.110968) (xy 64.142687 -438.050209) (xy 64.126922 -437.987055) (xy 64.11898 -437.92245)
			(xy 64.11849 -437.889904) (xy 64.119226 -437.850579) (xy 64.130825 -437.772789) (xy 64.141604 -437.734964)
			(xy 64.141604 -437.21909) (xy 64.142098 -437.207004) (xy 64.149553 -437.184009) (xy 64.163734 -437.164432)
			(xy 64.18326 -437.150181) (xy 64.206227 -437.142643) (xy 64.218312 -437.142128) (xy 65.158112 -437.142128)
			(xy 65.170224 -437.142506) (xy 65.193257 -437.150012) (xy 65.212832 -437.164283) (xy 65.227025 -437.183914)
			(xy 65.234441 -437.206976) (xy 65.23482 -437.21909) (xy 65.23482 -438.089802) (xy 66.118486 -438.089802)
			(xy 66.119013 -438.057222) (xy 66.126986 -437.992553) (xy 66.142802 -437.929342) (xy 66.166222 -437.868537)
			(xy 66.196896 -437.811049) (xy 66.234364 -437.757739) (xy 66.278065 -437.709408) (xy 66.302382 -437.68772)
			(xy 66.3829 -437.523382) (xy 66.387602 -437.512866) (xy 66.391092 -437.490107) (xy 66.387606 -437.467348)
			(xy 66.3829 -437.456834) (xy 66.301874 -437.291734) (xy 66.277594 -437.270056) (xy 66.233999 -437.221719)
			(xy 66.196627 -437.168425) (xy 66.166036 -437.11097) (xy 66.142684 -437.050211) (xy 66.126919 -436.987057)
			(xy 66.118976 -436.922452) (xy 66.118486 -436.889906) (xy 66.119223 -436.850581) (xy 66.130821 -436.772791)
			(xy 66.1416 -436.734966) (xy 66.1416 -436.219092) (xy 66.142058 -436.207016) (xy 66.149523 -436.184047)
			(xy 66.163721 -436.16451) (xy 66.183262 -436.150316) (xy 66.206232 -436.142855) (xy 66.218308 -436.142384)
			(xy 67.158108 -436.142384) (xy 67.170182 -436.142857) (xy 67.193148 -436.150321) (xy 67.212684 -436.164516)
			(xy 67.226879 -436.184052) (xy 67.234343 -436.207018) (xy 67.234816 -436.219092) (xy 67.234816 -438.760616)
			(xy 67.234349 -438.772691) (xy 67.226883 -438.795657) (xy 67.212687 -438.815193) (xy 67.19315 -438.829387)
			(xy 67.170183 -438.836851) (xy 67.158108 -438.837324) (xy 66.218308 -438.837324) (xy 66.206235 -438.836829)
			(xy 66.183271 -438.829371) (xy 66.163735 -438.815182) (xy 66.14954 -438.79565) (xy 66.142075 -438.772688)
			(xy 66.1416 -438.760616) (xy 66.1416 -438.244742) (xy 66.130801 -438.20692) (xy 66.119194 -438.129129)
			(xy 66.118486 -438.089802) (xy 65.23482 -438.089802) (xy 65.23482 -439.0898) (xy 68.118482 -439.0898)
			(xy 68.119009 -439.05722) (xy 68.126983 -438.992551) (xy 68.142798 -438.92934) (xy 68.166218 -438.868535)
			(xy 68.196892 -438.811047) (xy 68.23436 -438.757738) (xy 68.278061 -438.709406) (xy 68.302378 -438.687718)
			(xy 68.382896 -438.52338) (xy 68.387599 -438.512864) (xy 68.391089 -438.490105) (xy 68.387602 -438.467346)
			(xy 68.382896 -438.456832) (xy 68.30187 -438.291732) (xy 68.277609 -438.270033) (xy 68.234009 -438.221703)
			(xy 68.196632 -438.168413) (xy 68.166038 -438.110961) (xy 68.142683 -438.050205) (xy 68.126915 -437.987053)
			(xy 68.118972 -437.922449) (xy 68.118482 -437.889904) (xy 68.119219 -437.850579) (xy 68.130817 -437.772789)
			(xy 68.141596 -437.734964) (xy 68.141596 -437.21909) (xy 68.142098 -437.207004) (xy 68.149552 -437.184011)
			(xy 68.163731 -437.164435) (xy 68.183255 -437.150183) (xy 68.20622 -437.142644) (xy 68.218304 -437.142128)
			(xy 69.158104 -437.142128) (xy 69.170216 -437.142513) (xy 69.193248 -437.150017) (xy 69.212824 -437.164286)
			(xy 69.227017 -437.183916) (xy 69.234433 -437.206977) (xy 69.234812 -437.21909) (xy 69.234812 -438.089802)
			(xy 70.118478 -438.089802) (xy 70.119008 -438.057223) (xy 70.126981 -437.992553) (xy 70.142796 -437.929342)
			(xy 70.166216 -437.868537) (xy 70.196889 -437.811049) (xy 70.234357 -437.75774) (xy 70.278057 -437.709408)
			(xy 70.302374 -437.68772) (xy 70.382892 -437.523382) (xy 70.387594 -437.512866) (xy 70.391085 -437.490107)
			(xy 70.387598 -437.467348) (xy 70.382892 -437.456834) (xy 70.301866 -437.291734) (xy 70.277605 -437.270035)
			(xy 70.234005 -437.221705) (xy 70.196629 -437.168415) (xy 70.166034 -437.110963) (xy 70.142679 -437.050207)
			(xy 70.126912 -436.987055) (xy 70.118968 -436.922451) (xy 70.118478 -436.889906) (xy 70.119215 -436.850581)
			(xy 70.130814 -436.772792) (xy 70.141592 -436.734966) (xy 70.141592 -436.219092) (xy 70.142058 -436.207017)
			(xy 70.149522 -436.18405) (xy 70.163718 -436.164513) (xy 70.183257 -436.150319) (xy 70.206225 -436.142856)
			(xy 70.2183 -436.142384) (xy 71.1581 -436.142384) (xy 71.170174 -436.142864) (xy 71.19314 -436.150326)
			(xy 71.212676 -436.164518) (xy 71.226871 -436.184053) (xy 71.234335 -436.207018) (xy 71.234808 -436.219092)
			(xy 71.234808 -438.760616) (xy 71.234349 -438.772691) (xy 71.226882 -438.795659) (xy 71.212684 -438.815196)
			(xy 71.193145 -438.82939) (xy 71.170175 -438.836852) (xy 71.1581 -438.837324) (xy 70.2183 -438.837324)
			(xy 70.206227 -438.836836) (xy 70.183263 -438.829375) (xy 70.163727 -438.815184) (xy 70.149532 -438.795652)
			(xy 70.142067 -438.772689) (xy 70.141592 -438.760616) (xy 70.141592 -438.244742) (xy 70.130793 -438.20692)
			(xy 70.119186 -438.129129) (xy 70.118478 -438.089802) (xy 69.234812 -438.089802) (xy 69.234812 -439.0898)
			(xy 72.118474 -439.0898) (xy 72.119004 -439.057221) (xy 72.126977 -438.992551) (xy 72.142792 -438.92934)
			(xy 72.166212 -438.868535) (xy 72.196885 -438.811048) (xy 72.234353 -438.757738) (xy 72.278053 -438.709406)
			(xy 72.30237 -438.687718) (xy 72.382888 -438.52338) (xy 72.387592 -438.512864) (xy 72.391082 -438.490105)
			(xy 72.387595 -438.467346) (xy 72.382888 -438.456832) (xy 72.301862 -438.291732) (xy 72.277599 -438.270035)
			(xy 72.234 -438.221704) (xy 72.196624 -438.168414) (xy 72.166029 -438.110962) (xy 72.142674 -438.050206)
			(xy 72.126907 -437.987053) (xy 72.118964 -437.922449) (xy 72.118474 -437.889904) (xy 72.119211 -437.850579)
			(xy 72.130809 -437.772789) (xy 72.141588 -437.734964) (xy 72.141588 -437.21909) (xy 72.142 -437.206995)
			(xy 72.149465 -437.183986) (xy 72.163664 -437.164402) (xy 72.183212 -437.150154) (xy 72.206202 -437.142631)
			(xy 72.218296 -437.142128) (xy 73.158096 -437.142128) (xy 73.170207 -437.14252) (xy 73.193239 -437.150022)
			(xy 73.212815 -437.164288) (xy 73.227009 -437.183917) (xy 73.234425 -437.206977) (xy 73.234804 -437.21909)
			(xy 73.234804 -438.089802) (xy 75.118468 -438.089802) (xy 75.119001 -438.057223) (xy 75.126974 -437.992553)
			(xy 75.142789 -437.929343) (xy 75.166208 -437.868538) (xy 75.196881 -437.81105) (xy 75.234348 -437.75774)
			(xy 75.278047 -437.709408) (xy 75.302364 -437.68772) (xy 75.382882 -437.523382) (xy 75.387585 -437.512866)
			(xy 75.391076 -437.490107) (xy 75.387589 -437.467348) (xy 75.382882 -437.456834) (xy 75.301856 -437.291734)
			(xy 75.277593 -437.270038) (xy 75.233994 -437.221706) (xy 75.196618 -437.168416) (xy 75.166024 -437.110964)
			(xy 75.142669 -437.050208) (xy 75.126902 -436.987055) (xy 75.118958 -436.922451) (xy 75.118468 -436.889906)
			(xy 75.119168 -436.85078) (xy 75.130642 -436.773373) (xy 75.141328 -436.735728) (xy 75.141328 -436.219092)
			(xy 75.14171 -436.20698) (xy 75.149215 -436.183948) (xy 75.163484 -436.164372) (xy 75.183115 -436.150179)
			(xy 75.206176 -436.142763) (xy 75.21829 -436.142384) (xy 76.15809 -436.142384) (xy 76.170183 -436.142817)
			(xy 76.193191 -436.150276) (xy 76.212775 -436.16447) (xy 76.227024 -436.184014) (xy 76.234549 -436.207)
			(xy 76.235052 -436.219092) (xy 76.235052 -438.760616) (xy 76.234598 -438.772721) (xy 76.227101 -438.795739)
			(xy 76.212847 -438.815308) (xy 76.193237 -438.829504) (xy 76.170196 -438.836933) (xy 76.15809 -438.837324)
			(xy 75.21829 -438.837324) (xy 75.206196 -438.8369) (xy 75.183189 -438.829436) (xy 75.163607 -438.81524)
			(xy 75.149358 -438.795695) (xy 75.141832 -438.772708) (xy 75.141328 -438.760616) (xy 75.141328 -438.24398)
			(xy 75.130641 -438.206335) (xy 75.119164 -438.128928) (xy 75.118468 -438.089802) (xy 73.234804 -438.089802)
			(xy 73.234804 -439.0898) (xy 77.118464 -439.0898) (xy 77.118963 -439.057219) (xy 77.126938 -438.992548)
			(xy 77.142756 -438.929335) (xy 77.16618 -438.868529) (xy 77.196859 -438.811041) (xy 77.234333 -438.757733)
			(xy 77.27804 -438.709404) (xy 77.30236 -438.687718) (xy 77.382878 -438.52338) (xy 77.387582 -438.512864)
			(xy 77.391073 -438.490105) (xy 77.387585 -438.467346) (xy 77.382878 -438.456832) (xy 77.301852 -438.291732)
			(xy 77.277587 -438.270037) (xy 77.233988 -438.221706) (xy 77.196612 -438.168415) (xy 77.166019 -438.110963)
			(xy 77.142664 -438.050206) (xy 77.126897 -437.987054) (xy 77.118954 -437.922449) (xy 77.118464 -437.889904)
			(xy 77.119164 -437.850778) (xy 77.130638 -437.773371) (xy 77.141324 -437.735726) (xy 77.141324 -437.21909)
			(xy 77.141803 -437.206976) (xy 77.149291 -437.183935) (xy 77.163532 -437.164335) (xy 77.183132 -437.150093)
			(xy 77.206172 -437.142604) (xy 77.218286 -437.142128) (xy 78.158086 -437.142128) (xy 78.170207 -437.142572)
			(xy 78.193264 -437.150059) (xy 78.212878 -437.164305) (xy 78.22713 -437.183915) (xy 78.234624 -437.206969)
			(xy 78.235048 -437.21909) (xy 78.235048 -438.089802) (xy 79.11846 -438.089802) (xy 79.118962 -438.057221)
			(xy 79.126937 -437.99255) (xy 79.142754 -437.929337) (xy 79.166178 -437.868532) (xy 79.196856 -437.811044)
			(xy 79.234329 -437.757736) (xy 79.278036 -437.709406) (xy 79.302356 -437.68772) (xy 79.382874 -437.523382)
			(xy 79.387577 -437.512866) (xy 79.391068 -437.490107) (xy 79.387581 -437.467348) (xy 79.382874 -437.456834)
			(xy 79.301848 -437.291734) (xy 79.277583 -437.270039) (xy 79.233984 -437.221708) (xy 79.196609 -437.168417)
			(xy 79.166015 -437.110964) (xy 79.14266 -437.050208) (xy 79.126894 -436.987056) (xy 79.11895 -436.922451)
			(xy 79.11846 -436.889906) (xy 79.11916 -436.85078) (xy 79.130635 -436.773373) (xy 79.14132 -436.735728)
			(xy 79.14132 -436.219092) (xy 79.14171 -436.206981) (xy 79.149214 -436.18395) (xy 79.163481 -436.164375)
			(xy 79.18311 -436.150181) (xy 79.206169 -436.142764) (xy 79.218282 -436.142384) (xy 80.158082 -436.142384)
			(xy 80.170175 -436.142824) (xy 80.193182 -436.150281) (xy 80.212766 -436.164473) (xy 80.227016 -436.184015)
			(xy 80.234541 -436.207) (xy 80.235044 -436.219092) (xy 80.235044 -438.760616) (xy 80.234598 -438.772721)
			(xy 80.227099 -438.795742) (xy 80.212844 -438.815311) (xy 80.193232 -438.829506) (xy 80.170189 -438.836935)
			(xy 80.158082 -438.837324) (xy 79.218282 -438.837324) (xy 79.206188 -438.836907) (xy 79.183181 -438.829441)
			(xy 79.163598 -438.815243) (xy 79.149349 -438.795697) (xy 79.141824 -438.772709) (xy 79.14132 -438.760616)
			(xy 79.14132 -438.24398) (xy 79.130633 -438.206335) (xy 79.119156 -438.128928) (xy 79.11846 -438.089802)
			(xy 78.235048 -438.089802) (xy 78.235048 -439.0898) (xy 81.118456 -439.0898) (xy 81.118958 -439.057219)
			(xy 81.126933 -438.992548) (xy 81.142751 -438.929335) (xy 81.166174 -438.86853) (xy 81.196852 -438.811042)
			(xy 81.234326 -438.757734) (xy 81.278032 -438.709404) (xy 81.302352 -438.687718) (xy 81.38287 -438.52338)
			(xy 81.387575 -438.512864) (xy 81.391066 -438.490105) (xy 81.387578 -438.467346) (xy 81.38287 -438.456832)
			(xy 81.301844 -438.291732) (xy 81.277577 -438.270039) (xy 81.233979 -438.221707) (xy 81.196604 -438.168416)
			(xy 81.16601 -438.110963) (xy 81.142656 -438.050206) (xy 81.126889 -437.987054) (xy 81.118946 -437.922449)
			(xy 81.118456 -437.889904) (xy 81.119156 -437.850778) (xy 81.130631 -437.773371) (xy 81.141316 -437.735726)
			(xy 81.141316 -437.21909) (xy 81.141803 -437.206977) (xy 81.14929 -437.183937) (xy 81.163529 -437.164338)
			(xy 81.183127 -437.150096) (xy 81.206165 -437.142605) (xy 81.218278 -437.142128) (xy 82.158078 -437.142128)
			(xy 82.170199 -437.142579) (xy 82.193255 -437.150064) (xy 82.21287 -437.164308) (xy 82.227122 -437.183916)
			(xy 82.234616 -437.20697) (xy 82.23504 -437.21909) (xy 82.23504 -438.089802) (xy 83.118452 -438.089802)
			(xy 83.118957 -438.057222) (xy 83.126931 -437.99255) (xy 83.142749 -437.929338) (xy 83.166172 -437.868532)
			(xy 83.19685 -437.811044) (xy 83.234322 -437.757736) (xy 83.278028 -437.709406) (xy 83.302348 -437.68772)
			(xy 83.382866 -437.523382) (xy 83.387564 -437.512865) (xy 83.391052 -437.490107) (xy 83.387569 -437.467349)
			(xy 83.382866 -437.456834) (xy 83.30184 -437.291734) (xy 83.277574 -437.270041) (xy 83.233975 -437.221709)
			(xy 83.1966 -437.168418) (xy 83.166007 -437.110965) (xy 83.142652 -437.050208) (xy 83.126885 -436.987056)
			(xy 83.118942 -436.922451) (xy 83.118452 -436.889906) (xy 83.119153 -436.85078) (xy 83.130627 -436.773373)
			(xy 83.141312 -436.735728) (xy 83.141312 -436.219092) (xy 83.14171 -436.206981) (xy 83.149213 -436.183952)
			(xy 83.163479 -436.164378) (xy 83.183105 -436.150184) (xy 83.206162 -436.142765) (xy 83.218274 -436.142384)
			(xy 84.158074 -436.142384) (xy 84.170167 -436.14283) (xy 84.193174 -436.150285) (xy 84.212758 -436.164476)
			(xy 84.227008 -436.184017) (xy 84.234533 -436.207001) (xy 84.235036 -436.219092) (xy 84.235036 -438.760616)
			(xy 84.234598 -438.772722) (xy 84.227098 -438.795744) (xy 84.212841 -438.815313) (xy 84.193227 -438.829509)
			(xy 84.170181 -438.836936) (xy 84.158074 -438.837324) (xy 83.218274 -438.837324) (xy 83.206179 -438.836914)
			(xy 83.183172 -438.829446) (xy 83.163589 -438.815246) (xy 83.149341 -438.795698) (xy 83.141816 -438.772709)
			(xy 83.141312 -438.760616) (xy 83.141312 -438.24398) (xy 83.130625 -438.206335) (xy 83.119148 -438.128928)
			(xy 83.118452 -438.089802) (xy 82.23504 -438.089802) (xy 82.23504 -439.0898) (xy 85.118448 -439.0898)
			(xy 85.118953 -439.05722) (xy 85.126928 -438.992548) (xy 85.142745 -438.929336) (xy 85.166168 -438.86853)
			(xy 85.196846 -438.811042) (xy 85.234319 -438.757734) (xy 85.278025 -438.709404) (xy 85.302344 -438.687718)
			(xy 85.382862 -438.52338) (xy 85.387562 -438.512863) (xy 85.391049 -438.490105) (xy 85.387565 -438.467347)
			(xy 85.382862 -438.456832) (xy 85.301836 -438.291732) (xy 85.277568 -438.270041) (xy 85.23397 -438.221708)
			(xy 85.196595 -438.168417) (xy 85.166002 -438.110964) (xy 85.142647 -438.050207) (xy 85.126881 -437.987054)
			(xy 85.118938 -437.922449) (xy 85.118448 -437.889904) (xy 85.119148 -437.850778) (xy 85.130623 -437.773371)
			(xy 85.141308 -437.735726) (xy 85.141308 -437.21909) (xy 85.141803 -437.206978) (xy 85.149289 -437.18394)
			(xy 85.163526 -437.164341) (xy 85.183122 -437.150098) (xy 85.206158 -437.142606) (xy 85.21827 -437.142128)
			(xy 86.15807 -437.142128) (xy 86.17019 -437.142585) (xy 86.193246 -437.150068) (xy 86.212861 -437.16431)
			(xy 86.227114 -437.183918) (xy 86.234608 -437.20697) (xy 86.235032 -437.21909) (xy 86.235032 -438.089802)
			(xy 87.118444 -438.089802) (xy 87.118952 -438.057222) (xy 87.126926 -437.99255) (xy 87.142743 -437.929338)
			(xy 87.166166 -437.868533) (xy 87.196843 -437.811045) (xy 87.234315 -437.757736) (xy 87.278021 -437.709407)
			(xy 87.30234 -437.68772) (xy 87.382858 -437.523382) (xy 87.387557 -437.512865) (xy 87.391044 -437.490107)
			(xy 87.387561 -437.467349) (xy 87.382858 -437.456834) (xy 87.301832 -437.291734) (xy 87.277564 -437.270043)
			(xy 87.233966 -437.22171) (xy 87.196591 -437.168419) (xy 87.165998 -437.110966) (xy 87.142644 -437.050209)
			(xy 87.126877 -436.987056) (xy 87.118934 -436.922451) (xy 87.118444 -436.889906) (xy 87.119145 -436.85078)
			(xy 87.130619 -436.773373) (xy 87.141304 -436.735728) (xy 87.141304 -436.219092) (xy 87.141709 -436.206982)
			(xy 87.149212 -436.183954) (xy 87.163476 -436.164381) (xy 87.1831 -436.150186) (xy 87.206155 -436.142767)
			(xy 87.218266 -436.142384) (xy 88.158066 -436.142384) (xy 88.170158 -436.142837) (xy 88.193165 -436.15029)
			(xy 88.212749 -436.164478) (xy 88.227 -436.184018) (xy 88.234525 -436.207001) (xy 88.235028 -436.219092)
			(xy 88.235028 -438.760616) (xy 88.234598 -438.772723) (xy 88.227097 -438.795746) (xy 88.212838 -438.815316)
			(xy 88.193222 -438.829511) (xy 88.170174 -438.836937) (xy 88.158066 -438.837324) (xy 87.218266 -438.837324)
			(xy 87.206171 -438.836921) (xy 87.183163 -438.829451) (xy 87.163581 -438.815249) (xy 87.149333 -438.7957)
			(xy 87.141808 -438.77271) (xy 87.141304 -438.760616) (xy 87.141304 -438.24398) (xy 87.130617 -438.206335)
			(xy 87.11914 -438.128928) (xy 87.118444 -438.089802) (xy 86.235032 -438.089802) (xy 86.235032 -439.0898)
			(xy 89.11844 -439.0898) (xy 89.118948 -439.05722) (xy 89.126922 -438.992549) (xy 89.142739 -438.929336)
			(xy 89.166162 -438.868531) (xy 89.196839 -438.811043) (xy 89.234312 -438.757735) (xy 89.278017 -438.709405)
			(xy 89.302336 -438.687718) (xy 89.382854 -438.52338) (xy 89.387555 -438.512864) (xy 89.391042 -438.490105)
			(xy 89.387558 -438.467347) (xy 89.382854 -438.456832) (xy 89.301828 -438.291732) (xy 89.277558 -438.270043)
			(xy 89.23396 -438.22171) (xy 89.196586 -438.168418) (xy 89.165993 -438.110964) (xy 89.142639 -438.050207)
			(xy 89.126873 -437.987054) (xy 89.11893 -437.92245) (xy 89.11844 -437.889904) (xy 89.119141 -437.850778)
			(xy 89.130615 -437.773371) (xy 89.1413 -437.735726) (xy 89.1413 -437.21909) (xy 89.141803 -437.206979)
			(xy 89.149288 -437.183942) (xy 89.163524 -437.164343) (xy 89.183117 -437.150101) (xy 89.206151 -437.142607)
			(xy 89.218262 -437.142128) (xy 90.158062 -437.142128) (xy 90.170182 -437.142592) (xy 90.193238 -437.150073)
			(xy 90.212853 -437.164313) (xy 90.227105 -437.183919) (xy 90.2346 -437.20697) (xy 90.235024 -437.21909)
			(xy 90.235024 -439.0898) (xy 127.237998 -439.0898) (xy 127.23809 -439.075226) (xy 127.239744 -439.046125)
			(xy 127.2413 -439.031634) (xy 127.2413 -437.94807) (xy 127.239755 -437.933578) (xy 127.238103 -437.904478)
			(xy 127.237998 -437.889904) (xy 127.238091 -437.87533) (xy 127.239744 -437.846229) (xy 127.2413 -437.831738)
			(xy 127.2413 -437.21909) (xy 127.241803 -437.206979) (xy 127.249288 -437.183942) (xy 127.263524 -437.164343)
			(xy 127.283117 -437.150101) (xy 127.306151 -437.142607) (xy 127.318262 -437.142128) (xy 128.258062 -437.142128)
			(xy 128.270182 -437.142592) (xy 128.293238 -437.150073) (xy 128.312853 -437.164313) (xy 128.327105 -437.183919)
			(xy 128.3346 -437.20697) (xy 128.335024 -437.21909) (xy 128.335024 -438.089802) (xy 129.237994 -438.089802)
			(xy 129.238087 -438.075228) (xy 129.23974 -438.046127) (xy 129.241296 -438.031636) (xy 129.241296 -436.948072)
			(xy 129.239752 -436.93358) (xy 129.238099 -436.90448) (xy 129.237994 -436.889906) (xy 129.238087 -436.875332)
			(xy 129.23974 -436.846231) (xy 129.241296 -436.83174) (xy 129.241296 -436.219092) (xy 129.241709 -436.206983)
			(xy 129.24921 -436.183956) (xy 129.263473 -436.164384) (xy 129.283095 -436.150189) (xy 129.306148 -436.142768)
			(xy 129.318258 -436.142384) (xy 130.258058 -436.142384) (xy 130.27015 -436.142844) (xy 130.293156 -436.150294)
			(xy 130.312741 -436.164481) (xy 130.326991 -436.184019) (xy 130.334516 -436.207002) (xy 130.33502 -436.219092)
			(xy 130.33502 -438.760616) (xy 130.334598 -438.772724) (xy 130.327096 -438.795748) (xy 130.312836 -438.815319)
			(xy 130.293217 -438.829514) (xy 130.270167 -438.836938) (xy 130.258058 -438.837324) (xy 129.318258 -438.837324)
			(xy 129.306163 -438.836928) (xy 129.283155 -438.829455) (xy 129.263572 -438.815252) (xy 129.249324 -438.795701)
			(xy 129.2418 -438.77271) (xy 129.241296 -438.760616) (xy 129.241296 -438.147968) (xy 129.239751 -438.133476)
			(xy 129.238099 -438.104376) (xy 129.237994 -438.089802) (xy 128.335024 -438.089802) (xy 128.335024 -439.0898)
			(xy 131.23799 -439.0898) (xy 131.238082 -439.075226) (xy 131.239736 -439.046125) (xy 131.241292 -439.031634)
			(xy 131.241292 -437.94807) (xy 131.239748 -437.933578) (xy 131.238095 -437.904478) (xy 131.23799 -437.889904)
			(xy 131.238083 -437.87533) (xy 131.239736 -437.846229) (xy 131.241292 -437.831738) (xy 131.241292 -437.21909)
			(xy 131.241803 -437.20698) (xy 131.249287 -437.183944) (xy 131.263521 -437.164346) (xy 131.283112 -437.150104)
			(xy 131.306144 -437.142608) (xy 131.318254 -437.142128) (xy 132.258054 -437.142128) (xy 132.270173 -437.142599)
			(xy 132.293229 -437.150077) (xy 132.312844 -437.164316) (xy 132.327097 -437.183921) (xy 132.334592 -437.206971)
			(xy 132.335016 -437.21909) (xy 132.335016 -438.089802) (xy 133.237986 -438.089802) (xy 133.238079 -438.075228)
			(xy 133.239732 -438.046127) (xy 133.241288 -438.031636) (xy 133.241288 -436.948072) (xy 133.239744 -436.93358)
			(xy 133.238091 -436.90448) (xy 133.237986 -436.889906) (xy 133.238079 -436.875332) (xy 133.239732 -436.846231)
			(xy 133.241288 -436.83174) (xy 133.241288 -436.219092) (xy 133.241709 -436.206984) (xy 133.249209 -436.183958)
			(xy 133.26347 -436.164386) (xy 133.28309 -436.150192) (xy 133.306141 -436.142769) (xy 133.31825 -436.142384)
			(xy 134.25805 -436.142384) (xy 134.270141 -436.142851) (xy 134.293148 -436.150299) (xy 134.312732 -436.164484)
			(xy 134.326983 -436.184021) (xy 134.334508 -436.207002) (xy 134.335012 -436.219092) (xy 134.335012 -438.760616)
			(xy 134.334598 -438.772725) (xy 134.327095 -438.79575) (xy 134.312833 -438.815322) (xy 134.293212 -438.829517)
			(xy 134.27016 -438.836939) (xy 134.25805 -438.837324) (xy 133.31825 -438.837324) (xy 133.306159 -438.836849)
			(xy 133.283154 -438.829402) (xy 133.26357 -438.815219) (xy 133.249319 -438.795684) (xy 133.241793 -438.772705)
			(xy 133.241288 -438.760616) (xy 133.241288 -438.147968) (xy 133.239743 -438.133476) (xy 133.238091 -438.104376)
			(xy 133.237986 -438.089802) (xy 132.335016 -438.089802) (xy 132.335016 -439.0898) (xy 135.237982 -439.0898)
			(xy 135.238075 -439.075226) (xy 135.239728 -439.046125) (xy 135.241284 -439.031634) (xy 135.241284 -437.94807)
			(xy 135.23974 -437.933578) (xy 135.238087 -437.904478) (xy 135.237982 -437.889904) (xy 135.238075 -437.87533)
			(xy 135.239728 -437.846229) (xy 135.241284 -437.831738) (xy 135.241284 -437.21909) (xy 135.241652 -437.206962)
			(xy 135.249153 -437.183895) (xy 135.263416 -437.164276) (xy 135.283045 -437.150027) (xy 135.306118 -437.142544)
			(xy 135.318246 -437.142128) (xy 136.258046 -437.142128) (xy 136.270162 -437.142572) (xy 136.293205 -437.150071)
			(xy 136.312805 -437.164321) (xy 136.327045 -437.183927) (xy 136.334533 -437.206974) (xy 136.335008 -437.21909)
			(xy 136.335008 -438.089802) (xy 137.237978 -438.089802) (xy 137.238071 -438.075228) (xy 137.239724 -438.046127)
			(xy 137.24128 -438.031636) (xy 137.24128 -436.948072) (xy 137.239736 -436.93358) (xy 137.238083 -436.90448)
			(xy 137.237978 -436.889906) (xy 137.238071 -436.875332) (xy 137.239724 -436.846231) (xy 137.24128 -436.83174)
			(xy 137.24128 -436.219092) (xy 137.241709 -436.206985) (xy 137.249208 -436.183961) (xy 137.263467 -436.164389)
			(xy 137.283085 -436.150194) (xy 137.306133 -436.14277) (xy 137.318242 -436.142384) (xy 138.258042 -436.142384)
			(xy 138.270138 -436.142772) (xy 138.293148 -436.150246) (xy 138.312731 -436.164451) (xy 138.326978 -436.184004)
			(xy 138.334501 -436.206997) (xy 138.335004 -436.219092) (xy 138.335004 -438.760616) (xy 138.334597 -438.772725)
			(xy 138.327094 -438.795752) (xy 138.31283 -438.815325) (xy 138.293207 -438.829519) (xy 138.270153 -438.83694)
			(xy 138.258042 -438.837324) (xy 137.318242 -438.837324) (xy 137.306151 -438.836856) (xy 137.283146 -438.829407)
			(xy 137.263562 -438.815222) (xy 137.249311 -438.795686) (xy 137.241785 -438.772705) (xy 137.24128 -438.760616)
			(xy 137.24128 -438.147968) (xy 137.239735 -438.133476) (xy 137.238083 -438.104376) (xy 137.237978 -438.089802)
			(xy 136.335008 -438.089802) (xy 136.335008 -439.0898) (xy 139.237974 -439.0898) (xy 139.238067 -439.075226)
			(xy 139.23972 -439.046125) (xy 139.241276 -439.031634) (xy 139.241276 -437.94807) (xy 139.239732 -437.933578)
			(xy 139.238079 -437.904478) (xy 139.237974 -437.889904) (xy 139.238067 -437.87533) (xy 139.23972 -437.846229)
			(xy 139.241276 -437.831738) (xy 139.241276 -437.21909) (xy 139.241652 -437.206963) (xy 139.249152 -437.183897)
			(xy 139.263413 -437.164279) (xy 139.28304 -437.15003) (xy 139.306111 -437.142545) (xy 139.318238 -437.142128)
			(xy 140.258038 -437.142128) (xy 140.270154 -437.142579) (xy 140.293196 -437.150076) (xy 140.312797 -437.164323)
			(xy 140.327037 -437.183929) (xy 140.334525 -437.206974) (xy 140.335 -437.21909) (xy 140.335 -438.089802)
			(xy 142.237968 -438.089802) (xy 142.238085 -438.074717) (xy 142.239861 -438.044598) (xy 142.241524 -438.029604)
			(xy 142.241524 -436.950104) (xy 142.239854 -436.935111) (xy 142.238076 -436.904992) (xy 142.237968 -436.889906)
			(xy 142.238076 -436.87482) (xy 142.239858 -436.844702) (xy 142.241524 -436.829708) (xy 142.241524 -436.219092)
			(xy 142.241906 -436.207006) (xy 142.24938 -436.184017) (xy 142.263593 -436.164464) (xy 142.283153 -436.150262)
			(xy 142.306145 -436.1428) (xy 142.318232 -436.142384) (xy 143.258032 -436.142384) (xy 143.270107 -436.142837)
			(xy 143.293074 -436.150307) (xy 143.31261 -436.164507) (xy 143.326804 -436.184047) (xy 143.334267 -436.207016)
			(xy 143.33474 -436.219092) (xy 143.33474 -438.760616) (xy 143.33425 -438.772688) (xy 143.326787 -438.79565)
			(xy 143.312596 -438.815184) (xy 143.293065 -438.829379) (xy 143.270104 -438.836847) (xy 143.258032 -438.837324)
			(xy 142.318232 -438.837324) (xy 142.306153 -438.83686) (xy 142.283174 -438.829403) (xy 142.263624 -438.81521)
			(xy 142.249418 -438.795669) (xy 142.241947 -438.772695) (xy 142.241524 -438.760616) (xy 142.241524 -438.15)
			(xy 142.239853 -438.135007) (xy 142.238076 -438.104888) (xy 142.237968 -438.089802) (xy 140.335 -438.089802)
			(xy 140.335 -439.0898) (xy 144.237964 -439.0898) (xy 144.23808 -439.074715) (xy 144.239857 -439.044596)
			(xy 144.24152 -439.029602) (xy 144.24152 -437.950102) (xy 144.239849 -437.935109) (xy 144.238072 -437.90499)
			(xy 144.237964 -437.889904) (xy 144.238081 -437.874819) (xy 144.239857 -437.8447) (xy 144.24152 -437.829706)
			(xy 144.24152 -437.21909) (xy 144.241999 -437.207002) (xy 144.249456 -437.184004) (xy 144.26364 -437.164426)
			(xy 144.28317 -437.150176) (xy 144.306142 -437.14264) (xy 144.318228 -437.142128) (xy 145.258028 -437.142128)
			(xy 145.270141 -437.142493) (xy 145.293174 -437.150003) (xy 145.312749 -437.164277) (xy 145.326942 -437.183911)
			(xy 145.334357 -437.206975) (xy 145.334736 -437.21909) (xy 145.334736 -438.089802) (xy 146.23796 -438.089802)
			(xy 146.238077 -438.074717) (xy 146.239853 -438.044598) (xy 146.241516 -438.029604) (xy 146.241516 -436.950104)
			(xy 146.239846 -436.935111) (xy 146.238068 -436.904992) (xy 146.23796 -436.889906) (xy 146.238068 -436.87482)
			(xy 146.23985 -436.844702) (xy 146.241516 -436.829708) (xy 146.241516 -436.219092) (xy 146.241906 -436.207006)
			(xy 146.249379 -436.184019) (xy 146.26359 -436.164467) (xy 146.283148 -436.150264) (xy 146.306138 -436.142801)
			(xy 146.318224 -436.142384) (xy 147.258024 -436.142384) (xy 147.270099 -436.142844) (xy 147.293066 -436.150312)
			(xy 147.312601 -436.16451) (xy 147.326795 -436.184049) (xy 147.334259 -436.207017) (xy 147.334732 -436.219092)
			(xy 147.334732 -438.760616) (xy 147.33425 -438.772689) (xy 147.326786 -438.795653) (xy 147.312593 -438.815187)
			(xy 147.29306 -438.829382) (xy 147.270097 -438.836848) (xy 147.258024 -438.837324) (xy 146.318224 -438.837324)
			(xy 146.306144 -438.836867) (xy 146.283165 -438.829408) (xy 146.263616 -438.815213) (xy 146.24941 -438.795671)
			(xy 146.241939 -438.772696) (xy 146.241516 -438.760616) (xy 146.241516 -438.15) (xy 146.239845 -438.135007)
			(xy 146.238068 -438.104888) (xy 146.23796 -438.089802) (xy 145.334736 -438.089802) (xy 145.334736 -439.0898)
			(xy 148.237956 -439.0898) (xy 148.238073 -439.074715) (xy 148.239849 -439.044596) (xy 148.241512 -439.029602)
			(xy 148.241512 -437.950102) (xy 148.239841 -437.935109) (xy 148.238064 -437.90499) (xy 148.237956 -437.889904)
			(xy 148.238073 -437.874819) (xy 148.239849 -437.8447) (xy 148.241512 -437.829706) (xy 148.241512 -437.21909)
			(xy 148.241999 -437.207003) (xy 148.249455 -437.184007) (xy 148.263637 -437.164429) (xy 148.283165 -437.150178)
			(xy 148.306134 -437.142641) (xy 148.31822 -437.142128) (xy 149.25802 -437.142128) (xy 149.270133 -437.1425)
			(xy 149.293165 -437.150008) (xy 149.312741 -437.16428) (xy 149.326934 -437.183913) (xy 149.334349 -437.206976)
			(xy 149.334728 -437.21909) (xy 149.334728 -438.089802) (xy 150.237952 -438.089802) (xy 150.238069 -438.074717)
			(xy 150.239845 -438.044598) (xy 150.241508 -438.029604) (xy 150.241508 -436.950104) (xy 150.239838 -436.935111)
			(xy 150.23806 -436.904992) (xy 150.237952 -436.889906) (xy 150.23806 -436.87482) (xy 150.239842 -436.844702)
			(xy 150.241508 -436.829708) (xy 150.241508 -436.219092) (xy 150.241906 -436.207007) (xy 150.249378 -436.184021)
			(xy 150.263587 -436.16447) (xy 150.283143 -436.150267) (xy 150.306131 -436.142802) (xy 150.318216 -436.142384)
			(xy 151.258016 -436.142384) (xy 151.270091 -436.142851) (xy 151.293057 -436.150317) (xy 151.312593 -436.164513)
			(xy 151.326787 -436.18405) (xy 151.334251 -436.207017) (xy 151.334724 -436.219092) (xy 151.334724 -438.760616)
			(xy 151.33425 -438.77269) (xy 151.326785 -438.795655) (xy 151.31259 -438.81519) (xy 151.293055 -438.829385)
			(xy 151.27009 -438.83685) (xy 151.258016 -438.837324) (xy 150.318216 -438.837324) (xy 150.306144 -438.836822)
			(xy 150.28318 -438.829366) (xy 150.263644 -438.815179) (xy 150.249448 -438.795649) (xy 150.241983 -438.772688)
			(xy 150.241508 -438.760616) (xy 150.241508 -438.15) (xy 150.239837 -438.135007) (xy 150.23806 -438.104888)
			(xy 150.237952 -438.089802) (xy 149.334728 -438.089802) (xy 149.334728 -439.0898) (xy 152.237948 -439.0898)
			(xy 152.238065 -439.074715) (xy 152.239841 -439.044596) (xy 152.241504 -439.029602) (xy 152.241504 -437.950102)
			(xy 152.239833 -437.935109) (xy 152.238056 -437.90499) (xy 152.237948 -437.889904) (xy 152.238065 -437.874819)
			(xy 152.239841 -437.8447) (xy 152.241504 -437.829706) (xy 152.241504 -437.21909) (xy 152.241998 -437.207004)
			(xy 152.249453 -437.184009) (xy 152.263634 -437.164432) (xy 152.28316 -437.150181) (xy 152.306127 -437.142643)
			(xy 152.318212 -437.142128) (xy 153.258012 -437.142128) (xy 153.270124 -437.142506) (xy 153.293157 -437.150012)
			(xy 153.312732 -437.164283) (xy 153.326925 -437.183914) (xy 153.334341 -437.206976) (xy 153.33472 -437.21909)
			(xy 153.33472 -438.089802) (xy 154.237944 -438.089802) (xy 154.238061 -438.074717) (xy 154.239837 -438.044598)
			(xy 154.2415 -438.029604) (xy 154.2415 -436.950104) (xy 154.23983 -436.935111) (xy 154.238052 -436.904992)
			(xy 154.237944 -436.889906) (xy 154.238052 -436.87482) (xy 154.239834 -436.844702) (xy 154.2415 -436.829708)
			(xy 154.2415 -436.219092) (xy 154.241958 -436.207016) (xy 154.249423 -436.184047) (xy 154.263621 -436.16451)
			(xy 154.283162 -436.150316) (xy 154.306132 -436.142855) (xy 154.318208 -436.142384) (xy 155.258008 -436.142384)
			(xy 155.270082 -436.142857) (xy 155.293048 -436.150321) (xy 155.312584 -436.164516) (xy 155.326779 -436.184052)
			(xy 155.334243 -436.207018) (xy 155.334716 -436.219092) (xy 155.334716 -438.760616) (xy 155.334249 -438.772691)
			(xy 155.326783 -438.795657) (xy 155.312587 -438.815193) (xy 155.29305 -438.829387) (xy 155.270083 -438.836851)
			(xy 155.258008 -438.837324) (xy 154.318208 -438.837324) (xy 154.306135 -438.836829) (xy 154.283171 -438.829371)
			(xy 154.263635 -438.815182) (xy 154.24944 -438.79565) (xy 154.241975 -438.772688) (xy 154.2415 -438.760616)
			(xy 154.2415 -438.15) (xy 154.239829 -438.135007) (xy 154.238052 -438.104888) (xy 154.237944 -438.089802)
			(xy 153.33472 -438.089802) (xy 153.33472 -439.0898) (xy 156.23794 -439.0898) (xy 156.238057 -439.074715)
			(xy 156.239833 -439.044596) (xy 156.241496 -439.029602) (xy 156.241496 -437.950102) (xy 156.239825 -437.935109)
			(xy 156.238048 -437.90499) (xy 156.23794 -437.889904) (xy 156.238057 -437.874819) (xy 156.239833 -437.8447)
			(xy 156.241496 -437.829706) (xy 156.241496 -437.21909) (xy 156.241998 -437.207004) (xy 156.249452 -437.184011)
			(xy 156.263631 -437.164435) (xy 156.283155 -437.150183) (xy 156.30612 -437.142644) (xy 156.318204 -437.142128)
			(xy 157.258004 -437.142128) (xy 157.270116 -437.142513) (xy 157.293148 -437.150017) (xy 157.312724 -437.164286)
			(xy 157.326917 -437.183916) (xy 157.334333 -437.206977) (xy 157.334712 -437.21909) (xy 157.334712 -438.089802)
			(xy 314.118498 -438.089802) (xy 314.119021 -438.057222) (xy 314.126995 -437.992552) (xy 314.14281 -437.929341)
			(xy 314.166231 -437.868536) (xy 314.196905 -437.811048) (xy 314.234374 -437.757739) (xy 314.278076 -437.709407)
			(xy 314.302394 -437.68772) (xy 314.382912 -437.523382) (xy 314.387613 -437.512866) (xy 314.391103 -437.490107)
			(xy 314.387618 -437.467348) (xy 314.382912 -437.456834) (xy 314.301886 -437.291734) (xy 314.277609 -437.270053)
			(xy 314.234013 -437.221717) (xy 314.19664 -437.168424) (xy 314.166049 -437.110969) (xy 314.142696 -437.050211)
			(xy 314.126931 -436.987057) (xy 314.118988 -436.922452) (xy 314.118498 -436.889906) (xy 314.119234 -436.850581)
			(xy 314.130833 -436.772791) (xy 314.141612 -436.734966) (xy 314.141612 -436.219092) (xy 314.142006 -436.207007)
			(xy 314.149478 -436.18402) (xy 314.163688 -436.164469) (xy 314.183246 -436.150265) (xy 314.206235 -436.142802)
			(xy 314.21832 -436.142384) (xy 315.15812 -436.142384) (xy 315.170195 -436.142847) (xy 315.193161 -436.150314)
			(xy 315.212697 -436.164511) (xy 315.226891 -436.18405) (xy 315.234355 -436.207017) (xy 315.234828 -436.219092)
			(xy 315.234828 -438.760616) (xy 315.23435 -438.772689) (xy 315.226885 -438.795654) (xy 315.212691 -438.815189)
			(xy 315.193157 -438.829383) (xy 315.170193 -438.836849) (xy 315.15812 -438.837324) (xy 314.21832 -438.837324)
			(xy 314.20624 -438.83687) (xy 314.183261 -438.82941) (xy 314.163711 -438.815214) (xy 314.149506 -438.795672)
			(xy 314.142035 -438.772696) (xy 314.141612 -438.760616) (xy 314.141612 -438.244742) (xy 314.130814 -438.20692)
			(xy 314.119206 -438.129129) (xy 314.118498 -438.089802) (xy 157.334712 -438.089802) (xy 157.334712 -439.0898)
			(xy 316.118494 -439.0898) (xy 316.119017 -439.05722) (xy 316.126991 -438.99255) (xy 316.142806 -438.929339)
			(xy 316.166227 -438.868534) (xy 316.196902 -438.811046) (xy 316.234371 -438.757737) (xy 316.278072 -438.709405)
			(xy 316.30239 -438.687718) (xy 316.382908 -438.52338) (xy 316.387611 -438.512864) (xy 316.3911 -438.490105)
			(xy 316.387614 -438.467346) (xy 316.382908 -438.456832) (xy 316.301882 -438.291732) (xy 316.277603 -438.270053)
			(xy 316.234007 -438.221717) (xy 316.196635 -438.168423) (xy 316.166044 -438.110968) (xy 316.142691 -438.050209)
			(xy 316.126926 -437.987055) (xy 316.118984 -437.92245) (xy 316.118494 -437.889904) (xy 316.11923 -437.850579)
			(xy 316.130829 -437.772789) (xy 316.141608 -437.734964) (xy 316.141608 -437.21909) (xy 316.142098 -437.207003)
			(xy 316.149554 -437.184008) (xy 316.163736 -437.164431) (xy 316.183262 -437.150179) (xy 316.206231 -437.142642)
			(xy 316.218316 -437.142128) (xy 317.158116 -437.142128) (xy 317.170229 -437.142503) (xy 317.193261 -437.15001)
			(xy 317.212836 -437.164281) (xy 317.227029 -437.183914) (xy 317.234445 -437.206976) (xy 317.234824 -437.21909)
			(xy 317.234824 -438.089802) (xy 318.11849 -438.089802) (xy 318.119016 -438.057222) (xy 318.126989 -437.992553)
			(xy 318.142804 -437.929341) (xy 318.166225 -437.868536) (xy 318.196899 -437.811048) (xy 318.234367 -437.757739)
			(xy 318.278069 -437.709407) (xy 318.302386 -437.68772) (xy 318.382904 -437.523382) (xy 318.387605 -437.512865)
			(xy 318.391095 -437.490107) (xy 318.38761 -437.467348) (xy 318.382904 -437.456834) (xy 318.301878 -437.291734)
			(xy 318.277599 -437.270055) (xy 318.234004 -437.221719) (xy 318.196631 -437.168425) (xy 318.16604 -437.110969)
			(xy 318.142688 -437.050211) (xy 318.126923 -436.987057) (xy 318.11898 -436.922452) (xy 318.11849 -436.889906)
			(xy 318.119227 -436.850581) (xy 318.130825 -436.772791) (xy 318.141604 -436.734966) (xy 318.141604 -436.219092)
			(xy 318.142006 -436.207008) (xy 318.149477 -436.184023) (xy 318.163686 -436.164471) (xy 318.183241 -436.150268)
			(xy 318.206228 -436.142803) (xy 318.218312 -436.142384) (xy 319.158112 -436.142384) (xy 319.170186 -436.142854)
			(xy 319.193153 -436.150319) (xy 319.212689 -436.164514) (xy 319.226883 -436.184051) (xy 319.234347 -436.207018)
			(xy 319.23482 -436.219092) (xy 319.23482 -438.760616) (xy 319.234349 -438.77269) (xy 319.226884 -438.795656)
			(xy 319.212689 -438.815191) (xy 319.193152 -438.829386) (xy 319.170186 -438.83685) (xy 319.158112 -438.837324)
			(xy 318.218312 -438.837324) (xy 318.20624 -438.836826) (xy 318.183276 -438.829369) (xy 318.16374 -438.81518)
			(xy 318.149544 -438.79565) (xy 318.142079 -438.772688) (xy 318.141604 -438.760616) (xy 318.141604 -438.244742)
			(xy 318.130805 -438.20692) (xy 318.119198 -438.129129) (xy 318.11849 -438.089802) (xy 317.234824 -438.089802)
			(xy 317.234824 -439.0898) (xy 320.118486 -439.0898) (xy 320.119012 -439.05722) (xy 320.126985 -438.992551)
			(xy 320.142801 -438.92934) (xy 320.166221 -438.868535) (xy 320.196895 -438.811047) (xy 320.234363 -438.757737)
			(xy 320.278065 -438.709406) (xy 320.302382 -438.687718) (xy 320.3829 -438.52338) (xy 320.387603 -438.512864)
			(xy 320.391093 -438.490105) (xy 320.387606 -438.467346) (xy 320.3829 -438.456832) (xy 320.301874 -438.291732)
			(xy 320.277593 -438.270055) (xy 320.233998 -438.221718) (xy 320.196626 -438.168424) (xy 320.166035 -438.110968)
			(xy 320.142683 -438.050209) (xy 320.126918 -437.987055) (xy 320.118976 -437.92245) (xy 320.118486 -437.889904)
			(xy 320.119222 -437.850579) (xy 320.130821 -437.772789) (xy 320.1416 -437.734964) (xy 320.1416 -437.21909)
			(xy 320.142098 -437.207004) (xy 320.149553 -437.18401) (xy 320.163733 -437.164434) (xy 320.183257 -437.150182)
			(xy 320.206224 -437.142643) (xy 320.218308 -437.142128) (xy 321.158108 -437.142128) (xy 321.17022 -437.14251)
			(xy 321.193252 -437.150015) (xy 321.212828 -437.164284) (xy 321.227021 -437.183915) (xy 321.234437 -437.206976)
			(xy 321.234816 -437.21909) (xy 321.234816 -438.089802) (xy 322.118482 -438.089802) (xy 322.11901 -438.057222)
			(xy 322.126984 -437.992553) (xy 322.142799 -437.929342) (xy 322.166219 -437.868537) (xy 322.196892 -437.811049)
			(xy 322.23436 -437.75774) (xy 322.278061 -437.709408) (xy 322.302378 -437.68772) (xy 322.382896 -437.523382)
			(xy 322.387598 -437.512866) (xy 322.391088 -437.490107) (xy 322.387602 -437.467348) (xy 322.382896 -437.456834)
			(xy 322.30187 -437.291734) (xy 322.27761 -437.270034) (xy 322.23401 -437.221704) (xy 322.196633 -437.168415)
			(xy 322.166039 -437.110963) (xy 322.142683 -437.050207) (xy 322.126916 -436.987055) (xy 322.118972 -436.922451)
			(xy 322.118482 -436.889906) (xy 322.119219 -436.850581) (xy 322.130817 -436.772791) (xy 322.141596 -436.734966)
			(xy 322.141596 -436.219092) (xy 322.142058 -436.207017) (xy 322.149523 -436.184049) (xy 322.16372 -436.164511)
			(xy 322.183259 -436.150317) (xy 322.206229 -436.142856) (xy 322.218304 -436.142384) (xy 323.158104 -436.142384)
			(xy 323.170178 -436.142861) (xy 323.193144 -436.150323) (xy 323.21268 -436.164517) (xy 323.226875 -436.184053)
			(xy 323.234339 -436.207018) (xy 323.234812 -436.219092) (xy 323.234812 -438.760616) (xy 323.234349 -438.772691)
			(xy 323.226883 -438.795658) (xy 323.212686 -438.815194) (xy 323.193147 -438.829388) (xy 323.170179 -438.836851)
			(xy 323.158104 -438.837324) (xy 322.218304 -438.837324) (xy 322.206231 -438.836833) (xy 322.183267 -438.829373)
			(xy 322.163731 -438.815183) (xy 322.149536 -438.795651) (xy 322.142071 -438.772689) (xy 322.141596 -438.760616)
			(xy 322.141596 -438.244742) (xy 322.130797 -438.20692) (xy 322.11919 -438.129129) (xy 322.118482 -438.089802)
			(xy 321.234816 -438.089802) (xy 321.234816 -439.0898) (xy 324.118478 -439.0898) (xy 324.119006 -439.05722)
			(xy 324.12698 -438.992551) (xy 324.142795 -438.92934) (xy 324.166215 -438.868535) (xy 324.196889 -438.811047)
			(xy 324.234356 -438.757738) (xy 324.278057 -438.709406) (xy 324.302374 -438.687718) (xy 324.382892 -438.52338)
			(xy 324.387595 -438.512864) (xy 324.391085 -438.490105) (xy 324.387599 -438.467346) (xy 324.382892 -438.456832)
			(xy 324.301866 -438.291732) (xy 324.277604 -438.270034) (xy 324.234004 -438.221704) (xy 324.196628 -438.168414)
			(xy 324.166034 -438.110962) (xy 324.142678 -438.050205) (xy 324.126911 -437.987053) (xy 324.118968 -437.922449)
			(xy 324.118478 -437.889904) (xy 324.119215 -437.850579) (xy 324.130813 -437.772789) (xy 324.141592 -437.734964)
			(xy 324.141592 -437.21909) (xy 324.142098 -437.207005) (xy 324.149552 -437.184012) (xy 324.16373 -437.164436)
			(xy 324.183252 -437.150184) (xy 324.206217 -437.142644) (xy 324.2183 -437.142128) (xy 325.1581 -437.142128)
			(xy 325.170212 -437.142516) (xy 325.193244 -437.150019) (xy 325.212819 -437.164287) (xy 325.227013 -437.183916)
			(xy 325.234429 -437.206977) (xy 325.234808 -437.21909) (xy 325.234808 -438.089802) (xy 326.118474 -438.089802)
			(xy 326.119005 -438.057223) (xy 326.126978 -437.992553) (xy 326.142793 -437.929342) (xy 326.166213 -437.868538)
			(xy 326.196886 -437.81105) (xy 326.234353 -437.75774) (xy 326.278053 -437.709408) (xy 326.30237 -437.68772)
			(xy 326.382888 -437.523382) (xy 326.38759 -437.512866) (xy 326.391081 -437.490107) (xy 326.387595 -437.467348)
			(xy 326.382888 -437.456834) (xy 326.301862 -437.291734) (xy 326.2776 -437.270036) (xy 326.234001 -437.221705)
			(xy 326.196624 -437.168416) (xy 326.16603 -437.110963) (xy 326.142675 -437.050207) (xy 326.126908 -436.987055)
			(xy 326.118964 -436.922451) (xy 326.118474 -436.889906) (xy 326.119211 -436.850581) (xy 326.13081 -436.772792)
			(xy 326.141588 -436.734966) (xy 326.141588 -436.219092) (xy 326.142057 -436.207017) (xy 326.149522 -436.184051)
			(xy 326.163717 -436.164514) (xy 326.183254 -436.15032) (xy 326.206221 -436.142857) (xy 326.218296 -436.142384)
			(xy 327.158096 -436.142384) (xy 327.17017 -436.142868) (xy 327.193135 -436.150328) (xy 327.212672 -436.16452)
			(xy 327.226867 -436.184054) (xy 327.234331 -436.207019) (xy 327.234804 -436.219092) (xy 327.234804 -438.760616)
			(xy 327.234349 -438.772692) (xy 327.226882 -438.79566) (xy 327.212683 -438.815197) (xy 327.193142 -438.829391)
			(xy 327.170172 -438.836852) (xy 327.158096 -438.837324) (xy 326.218296 -438.837324) (xy 326.206223 -438.836839)
			(xy 326.183258 -438.829378) (xy 326.163723 -438.815186) (xy 326.149528 -438.795652) (xy 326.142063 -438.772689)
			(xy 326.141588 -438.760616) (xy 326.141588 -438.244742) (xy 326.130789 -438.20692) (xy 326.119182 -438.129129)
			(xy 326.118474 -438.089802) (xy 325.234808 -438.089802) (xy 325.234808 -439.0898) (xy 328.11847 -439.0898)
			(xy 328.119001 -439.057221) (xy 328.126975 -438.992551) (xy 328.142789 -438.929341) (xy 328.166209 -438.868536)
			(xy 328.196882 -438.811048) (xy 328.234349 -438.757738) (xy 328.278049 -438.709406) (xy 328.302366 -438.687718)
			(xy 328.382884 -438.52338) (xy 328.387588 -438.512864) (xy 328.391078 -438.490105) (xy 328.387591 -438.467346)
			(xy 328.382884 -438.456832) (xy 328.301858 -438.291732) (xy 328.277594 -438.270036) (xy 328.233995 -438.221705)
			(xy 328.196619 -438.168415) (xy 328.166025 -438.110962) (xy 328.14267 -438.050206) (xy 328.126903 -437.987054)
			(xy 328.11896 -437.922449) (xy 328.11847 -437.889904) (xy 328.119207 -437.850579) (xy 328.130806 -437.77279)
			(xy 328.141584 -437.734964) (xy 328.141584 -437.21909) (xy 328.142 -437.206996) (xy 328.149465 -437.183987)
			(xy 328.163663 -437.164404) (xy 328.18321 -437.150155) (xy 328.206199 -437.142631) (xy 328.218292 -437.142128)
			(xy 329.158092 -437.142128) (xy 329.170203 -437.142523) (xy 329.193235 -437.150024) (xy 329.212811 -437.16429)
			(xy 329.227005 -437.183918) (xy 329.234421 -437.206977) (xy 329.2348 -437.21909) (xy 329.2348 -438.089802)
			(xy 331.118464 -438.089802) (xy 331.118965 -438.057221) (xy 331.126939 -437.99255) (xy 331.142757 -437.929337)
			(xy 331.166181 -437.868531) (xy 331.196859 -437.811043) (xy 331.234333 -437.757735) (xy 331.27804 -437.709406)
			(xy 331.30236 -437.68772) (xy 331.382878 -437.523382) (xy 331.387581 -437.512866) (xy 331.391072 -437.490107)
			(xy 331.387585 -437.467348) (xy 331.382878 -437.456834) (xy 331.301852 -437.291734) (xy 331.277588 -437.270038)
			(xy 331.233989 -437.221707) (xy 331.196613 -437.168417) (xy 331.166019 -437.110964) (xy 331.142664 -437.050208)
			(xy 331.126898 -436.987056) (xy 331.118954 -436.922451) (xy 331.118464 -436.889906) (xy 331.119164 -436.85078)
			(xy 331.130639 -436.773373) (xy 331.141324 -436.735728) (xy 331.141324 -436.219092) (xy 331.14171 -436.20698)
			(xy 331.149214 -436.183949) (xy 331.163483 -436.164374) (xy 331.183112 -436.15018) (xy 331.206173 -436.142764)
			(xy 331.218286 -436.142384) (xy 332.158086 -436.142384) (xy 332.170179 -436.14282) (xy 332.193187 -436.150278)
			(xy 332.212771 -436.164471) (xy 332.22702 -436.184014) (xy 332.234545 -436.207) (xy 332.235048 -436.219092)
			(xy 332.235048 -438.760616) (xy 332.234598 -438.772721) (xy 332.2271 -438.795741) (xy 332.212845 -438.815309)
			(xy 332.193234 -438.829505) (xy 332.170192 -438.836934) (xy 332.158086 -438.837324) (xy 331.218286 -438.837324)
			(xy 331.206192 -438.836904) (xy 331.183185 -438.829439) (xy 331.163602 -438.815242) (xy 331.149353 -438.795696)
			(xy 331.141828 -438.772709) (xy 331.141324 -438.760616) (xy 331.141324 -438.24398) (xy 331.130637 -438.206335)
			(xy 331.11916 -438.128928) (xy 331.118464 -438.089802) (xy 329.2348 -438.089802) (xy 329.2348 -439.0898)
			(xy 333.11846 -439.0898) (xy 333.118961 -439.057219) (xy 333.126936 -438.992548) (xy 333.142753 -438.929335)
			(xy 333.166177 -438.868529) (xy 333.196856 -438.811042) (xy 333.234329 -438.757734) (xy 333.278036 -438.709404)
			(xy 333.302356 -438.687718) (xy 333.382874 -438.52338) (xy 333.387578 -438.512864) (xy 333.391069 -438.490105)
			(xy 333.387582 -438.467346) (xy 333.382874 -438.456832) (xy 333.301848 -438.291732) (xy 333.277582 -438.270038)
			(xy 333.233984 -438.221706) (xy 333.196608 -438.168416) (xy 333.166014 -438.110963) (xy 333.14266 -438.050206)
			(xy 333.126893 -437.987054) (xy 333.11895 -437.922449) (xy 333.11846 -437.889904) (xy 333.11916 -437.850778)
			(xy 333.130634 -437.773371) (xy 333.14132 -437.735726) (xy 333.14132 -437.21909) (xy 333.141803 -437.206977)
			(xy 333.149291 -437.183936) (xy 333.163531 -437.164336) (xy 333.183129 -437.150095) (xy 333.206169 -437.142604)
			(xy 333.218282 -437.142128) (xy 334.158082 -437.142128) (xy 334.170203 -437.142575) (xy 334.193259 -437.150061)
			(xy 334.212874 -437.164306) (xy 334.227126 -437.183916) (xy 334.23462 -437.206969) (xy 334.235044 -437.21909)
			(xy 334.235044 -438.089802) (xy 335.118456 -438.089802) (xy 335.11896 -438.057221) (xy 335.126934 -437.99255)
			(xy 335.142751 -437.929338) (xy 335.166175 -437.868532) (xy 335.196853 -437.811044) (xy 335.234326 -437.757736)
			(xy 335.278032 -437.709406) (xy 335.302352 -437.68772) (xy 335.38287 -437.523382) (xy 335.387573 -437.512866)
			(xy 335.391065 -437.490107) (xy 335.387578 -437.467348) (xy 335.38287 -437.456834) (xy 335.301844 -437.291734)
			(xy 335.277578 -437.27004) (xy 335.23398 -437.221708) (xy 335.196604 -437.168418) (xy 335.166011 -437.110965)
			(xy 335.142656 -437.050208) (xy 335.12689 -436.987056) (xy 335.118946 -436.922451) (xy 335.118456 -436.889906)
			(xy 335.119156 -436.85078) (xy 335.130631 -436.773373) (xy 335.141316 -436.735728) (xy 335.141316 -436.219092)
			(xy 335.14171 -436.206981) (xy 335.149213 -436.183951) (xy 335.16348 -436.164376) (xy 335.183107 -436.150183)
			(xy 335.206166 -436.142765) (xy 335.218278 -436.142384) (xy 336.158078 -436.142384) (xy 336.170171 -436.142827)
			(xy 336.193178 -436.150283) (xy 336.212762 -436.164474) (xy 336.227012 -436.184016) (xy 336.234537 -436.207001)
			(xy 336.23504 -436.219092) (xy 336.23504 -438.760616) (xy 336.234598 -438.772722) (xy 336.227099 -438.795743)
			(xy 336.212843 -438.815312) (xy 336.193229 -438.829508) (xy 336.170185 -438.836935) (xy 336.158078 -438.837324)
			(xy 335.218278 -438.837324) (xy 335.206184 -438.836911) (xy 335.183176 -438.829444) (xy 335.163594 -438.815245)
			(xy 335.149345 -438.795698) (xy 335.14182 -438.772709) (xy 335.141316 -438.760616) (xy 335.141316 -438.24398)
			(xy 335.130629 -438.206335) (xy 335.119152 -438.128928) (xy 335.118456 -438.089802) (xy 334.235044 -438.089802)
			(xy 334.235044 -439.0898) (xy 337.118452 -439.0898) (xy 337.118956 -439.057219) (xy 337.12693 -438.992548)
			(xy 337.142748 -438.929336) (xy 337.166171 -438.86853) (xy 337.196849 -438.811042) (xy 337.234322 -438.757734)
			(xy 337.278028 -438.709404) (xy 337.302348 -438.687718) (xy 337.382866 -438.52338) (xy 337.387566 -438.512863)
			(xy 337.391052 -438.490105) (xy 337.387569 -438.467347) (xy 337.382866 -438.456832) (xy 337.30184 -438.291732)
			(xy 337.277573 -438.27004) (xy 337.233974 -438.221708) (xy 337.196599 -438.168417) (xy 337.166006 -438.110963)
			(xy 337.142652 -438.050207) (xy 337.126885 -437.987054) (xy 337.118942 -437.922449) (xy 337.118452 -437.889904)
			(xy 337.119152 -437.850778) (xy 337.130627 -437.773371) (xy 337.141312 -437.735726) (xy 337.141312 -437.21909)
			(xy 337.141803 -437.206978) (xy 337.14929 -437.183938) (xy 337.163528 -437.164339) (xy 337.183124 -437.150097)
			(xy 337.206162 -437.142606) (xy 337.218274 -437.142128) (xy 338.158074 -437.142128) (xy 338.170194 -437.142582)
			(xy 338.193251 -437.150066) (xy 338.212865 -437.164309) (xy 338.227118 -437.183917) (xy 338.234612 -437.20697)
			(xy 338.235036 -437.21909) (xy 338.235036 -438.089802) (xy 339.118448 -438.089802) (xy 339.118954 -438.057222)
			(xy 339.126929 -437.99255) (xy 339.142746 -437.929338) (xy 339.166169 -437.868532) (xy 339.196846 -437.811045)
			(xy 339.234319 -437.757736) (xy 339.278025 -437.709406) (xy 339.302344 -437.68772) (xy 339.382862 -437.523382)
			(xy 339.387561 -437.512865) (xy 339.391048 -437.490107) (xy 339.387565 -437.467349) (xy 339.382862 -437.456834)
			(xy 339.301836 -437.291734) (xy 339.277569 -437.270042) (xy 339.233971 -437.22171) (xy 339.196596 -437.168419)
			(xy 339.166002 -437.110965) (xy 339.142648 -437.050208) (xy 339.126881 -436.987056) (xy 339.118938 -436.922451)
			(xy 339.118448 -436.889906) (xy 339.119149 -436.85078) (xy 339.130623 -436.773373) (xy 339.141308 -436.735728)
			(xy 339.141308 -436.219092) (xy 339.141709 -436.206982) (xy 339.149212 -436.183953) (xy 339.163477 -436.164379)
			(xy 339.183102 -436.150185) (xy 339.206158 -436.142766) (xy 339.21827 -436.142384) (xy 340.15807 -436.142384)
			(xy 340.170162 -436.142834) (xy 340.193169 -436.150288) (xy 340.212754 -436.164477) (xy 340.227004 -436.184017)
			(xy 340.234529 -436.207001) (xy 340.235032 -436.219092) (xy 340.235032 -438.760616) (xy 340.234598 -438.772723)
			(xy 340.227098 -438.795745) (xy 340.21284 -438.815315) (xy 340.193224 -438.82951) (xy 340.170178 -438.836936)
			(xy 340.15807 -438.837324) (xy 339.21827 -438.837324) (xy 339.206175 -438.836918) (xy 339.183168 -438.829448)
			(xy 339.163585 -438.815247) (xy 339.149337 -438.795699) (xy 339.141812 -438.77271) (xy 339.141308 -438.760616)
			(xy 339.141308 -438.24398) (xy 339.130621 -438.206335) (xy 339.119144 -438.128928) (xy 339.118448 -438.089802)
			(xy 338.235036 -438.089802) (xy 338.235036 -439.0898) (xy 341.118444 -439.0898) (xy 341.11895 -439.05722)
			(xy 341.126925 -438.992548) (xy 341.142742 -438.929336) (xy 341.166165 -438.868531) (xy 341.196843 -438.811043)
			(xy 341.234315 -438.757734) (xy 341.278021 -438.709405) (xy 341.30234 -438.687718) (xy 341.382858 -438.52338)
			(xy 341.387558 -438.512863) (xy 341.391045 -438.490105) (xy 341.387562 -438.467347) (xy 341.382858 -438.456832)
			(xy 341.301832 -438.291732) (xy 341.277563 -438.270042) (xy 341.233965 -438.221709) (xy 341.19659 -438.168418)
			(xy 341.165997 -438.110964) (xy 341.142643 -438.050207) (xy 341.126877 -437.987054) (xy 341.118934 -437.92245)
			(xy 341.118444 -437.889904) (xy 341.119145 -437.850778) (xy 341.130619 -437.773371) (xy 341.141304 -437.735726)
			(xy 341.141304 -437.21909) (xy 341.141803 -437.206978) (xy 341.149289 -437.183941) (xy 341.163525 -437.164342)
			(xy 341.183119 -437.1501) (xy 341.206154 -437.142607) (xy 341.218266 -437.142128) (xy 342.158066 -437.142128)
			(xy 342.170186 -437.142589) (xy 342.193242 -437.15007) (xy 342.212857 -437.164312) (xy 342.22711 -437.183918)
			(xy 342.234604 -437.20697) (xy 342.235028 -437.21909) (xy 342.235028 -438.089802) (xy 343.11844 -438.089802)
			(xy 343.118949 -438.057222) (xy 343.126923 -437.992551) (xy 343.14274 -437.929339) (xy 343.166163 -437.868533)
			(xy 343.19684 -437.811045) (xy 343.234312 -437.757737) (xy 343.278017 -437.709407) (xy 343.302336 -437.68772)
			(xy 343.382854 -437.523382) (xy 343.387553 -437.512865) (xy 343.391041 -437.490107) (xy 343.387557 -437.467349)
			(xy 343.382854 -437.456834) (xy 343.301828 -437.291734) (xy 343.277559 -437.270044) (xy 343.233961 -437.221711)
			(xy 343.196587 -437.168419) (xy 343.165994 -437.110966) (xy 343.14264 -437.050209) (xy 343.126873 -436.987056)
			(xy 343.11893 -436.922451) (xy 343.11844 -436.889906) (xy 343.119141 -436.85078) (xy 343.130615 -436.773373)
			(xy 343.1413 -436.735728) (xy 343.1413 -436.219092) (xy 343.141709 -436.206983) (xy 343.149211 -436.183955)
			(xy 343.163474 -436.164382) (xy 343.183097 -436.150188) (xy 343.206151 -436.142767) (xy 343.218262 -436.142384)
			(xy 344.158062 -436.142384) (xy 344.170154 -436.142841) (xy 344.193161 -436.150292) (xy 344.212745 -436.16448)
			(xy 344.226995 -436.184019) (xy 344.234521 -436.207002) (xy 344.235024 -436.219092) (xy 344.235024 -438.760616)
			(xy 344.234598 -438.772723) (xy 344.227097 -438.795747) (xy 344.212837 -438.815318) (xy 344.193219 -438.829513)
			(xy 344.170171 -438.836937) (xy 344.158062 -438.837324) (xy 343.218262 -438.837324) (xy 343.206167 -438.836924)
			(xy 343.183159 -438.829453) (xy 343.163577 -438.81525) (xy 343.149329 -438.795701) (xy 343.141804 -438.77271)
			(xy 343.1413 -438.760616) (xy 343.1413 -438.24398) (xy 343.130613 -438.206335) (xy 343.119136 -438.128928)
			(xy 343.11844 -438.089802) (xy 342.235028 -438.089802) (xy 342.235028 -439.0898) (xy 345.118436 -439.0898)
			(xy 345.118945 -439.05722) (xy 345.126919 -438.992549) (xy 345.142736 -438.929337) (xy 345.166159 -438.868531)
			(xy 345.196836 -438.811043) (xy 345.234308 -438.757735) (xy 345.278013 -438.709405) (xy 345.302332 -438.687718)
			(xy 345.38285 -438.52338) (xy 345.387551 -438.512864) (xy 345.391038 -438.490105) (xy 345.387554 -438.467347)
			(xy 345.38285 -438.456832) (xy 345.301824 -438.291732) (xy 345.277553 -438.270044) (xy 345.233956 -438.22171)
			(xy 345.196582 -438.168418) (xy 345.165989 -438.110965) (xy 345.142635 -438.050207) (xy 345.126869 -437.987054)
			(xy 345.118926 -437.92245) (xy 345.118436 -437.889904) (xy 345.119137 -437.850778) (xy 345.130611 -437.773371)
			(xy 345.141296 -437.735726) (xy 345.141296 -437.21909) (xy 345.141803 -437.206979) (xy 345.149288 -437.183943)
			(xy 345.163522 -437.164345) (xy 345.183114 -437.150102) (xy 345.206147 -437.142608) (xy 345.218258 -437.142128)
			(xy 346.158058 -437.142128) (xy 346.170178 -437.142595) (xy 346.193233 -437.150075) (xy 346.212848 -437.164315)
			(xy 346.227101 -437.18392) (xy 346.234596 -437.206971) (xy 346.23502 -437.21909) (xy 346.23502 -439.0898)
			(xy 383.237994 -439.0898) (xy 383.238086 -439.075226) (xy 383.23974 -439.046125) (xy 383.241296 -439.031634)
			(xy 383.241296 -437.94807) (xy 383.239752 -437.933578) (xy 383.238099 -437.904478) (xy 383.237994 -437.889904)
			(xy 383.238087 -437.87533) (xy 383.23974 -437.846229) (xy 383.241296 -437.831738) (xy 383.241296 -437.21909)
			(xy 383.241803 -437.206979) (xy 383.249288 -437.183943) (xy 383.263522 -437.164345) (xy 383.283114 -437.150102)
			(xy 383.306147 -437.142608) (xy 383.318258 -437.142128) (xy 384.258058 -437.142128) (xy 384.270178 -437.142595)
			(xy 384.293233 -437.150075) (xy 384.312848 -437.164315) (xy 384.327101 -437.18392) (xy 384.334596 -437.206971)
			(xy 384.33502 -437.21909) (xy 384.33502 -438.089802) (xy 385.23799 -438.089802) (xy 385.238083 -438.075228)
			(xy 385.239736 -438.046127) (xy 385.241292 -438.031636) (xy 385.241292 -436.948072) (xy 385.239748 -436.93358)
			(xy 385.238095 -436.90448) (xy 385.23799 -436.889906) (xy 385.238083 -436.875332) (xy 385.239736 -436.846231)
			(xy 385.241292 -436.83174) (xy 385.241292 -436.219092) (xy 385.241709 -436.206983) (xy 385.24921 -436.183957)
			(xy 385.263472 -436.164385) (xy 385.283092 -436.15019) (xy 385.306144 -436.142768) (xy 385.318254 -436.142384)
			(xy 386.258054 -436.142384) (xy 386.270146 -436.142847) (xy 386.293152 -436.150297) (xy 386.312737 -436.164483)
			(xy 386.326987 -436.18402) (xy 386.334512 -436.207002) (xy 386.335016 -436.219092) (xy 386.335016 -438.760616)
			(xy 386.334598 -438.772724) (xy 386.327096 -438.795749) (xy 386.312834 -438.815321) (xy 386.293214 -438.829515)
			(xy 386.270163 -438.836939) (xy 386.258054 -438.837324) (xy 385.318254 -438.837324) (xy 385.306158 -438.836931)
			(xy 385.28315 -438.829457) (xy 385.263568 -438.815253) (xy 385.24932 -438.795702) (xy 385.241796 -438.77271)
			(xy 385.241292 -438.760616) (xy 385.241292 -438.147968) (xy 385.239747 -438.133476) (xy 385.238095 -438.104376)
			(xy 385.23799 -438.089802) (xy 384.33502 -438.089802) (xy 384.33502 -439.0898) (xy 387.237986 -439.0898)
			(xy 387.238078 -439.075226) (xy 387.239732 -439.046125) (xy 387.241288 -439.031634) (xy 387.241288 -437.94807)
			(xy 387.239744 -437.933578) (xy 387.238091 -437.904478) (xy 387.237986 -437.889904) (xy 387.238079 -437.87533)
			(xy 387.239732 -437.846229) (xy 387.241288 -437.831738) (xy 387.241288 -437.21909) (xy 387.241803 -437.20698)
			(xy 387.249287 -437.183945) (xy 387.263519 -437.164348) (xy 387.283109 -437.150105) (xy 387.30614 -437.142609)
			(xy 387.31825 -437.142128) (xy 388.25805 -437.142128) (xy 388.270166 -437.142569) (xy 388.293209 -437.150069)
			(xy 388.312809 -437.164319) (xy 388.32705 -437.183927) (xy 388.334537 -437.206974) (xy 388.335012 -437.21909)
			(xy 388.335012 -438.089802) (xy 389.237982 -438.089802) (xy 389.238075 -438.075228) (xy 389.239728 -438.046127)
			(xy 389.241284 -438.031636) (xy 389.241284 -436.948072) (xy 389.23974 -436.93358) (xy 389.238087 -436.90448)
			(xy 389.237982 -436.889906) (xy 389.238075 -436.875332) (xy 389.239728 -436.846231) (xy 389.241284 -436.83174)
			(xy 389.241284 -436.219092) (xy 389.241709 -436.206984) (xy 389.249209 -436.183959) (xy 389.263469 -436.164388)
			(xy 389.283087 -436.150193) (xy 389.306137 -436.142769) (xy 389.318246 -436.142384) (xy 390.258046 -436.142384)
			(xy 390.270142 -436.142769) (xy 390.293152 -436.150244) (xy 390.312735 -436.16445) (xy 390.326982 -436.184003)
			(xy 390.334505 -436.206997) (xy 390.335008 -436.219092) (xy 390.335008 -438.760616) (xy 390.334598 -438.772725)
			(xy 390.327095 -438.795751) (xy 390.312831 -438.815324) (xy 390.293209 -438.829518) (xy 390.270156 -438.83694)
			(xy 390.258046 -438.837324) (xy 389.318246 -438.837324) (xy 389.306155 -438.836853) (xy 389.28315 -438.829404)
			(xy 389.263566 -438.81522) (xy 389.249315 -438.795685) (xy 389.241789 -438.772705) (xy 389.241284 -438.760616)
			(xy 389.241284 -438.147968) (xy 389.239739 -438.133476) (xy 389.238087 -438.104376) (xy 389.237982 -438.089802)
			(xy 388.335012 -438.089802) (xy 388.335012 -439.0898) (xy 391.237978 -439.0898) (xy 391.238071 -439.075226)
			(xy 391.239724 -439.046125) (xy 391.24128 -439.031634) (xy 391.24128 -437.94807) (xy 391.239736 -437.933578)
			(xy 391.238083 -437.904478) (xy 391.237978 -437.889904) (xy 391.238071 -437.87533) (xy 391.239724 -437.846229)
			(xy 391.24128 -437.831738) (xy 391.24128 -437.21909) (xy 391.241652 -437.206963) (xy 391.249152 -437.183896)
			(xy 391.263415 -437.164278) (xy 391.283043 -437.150029) (xy 391.306114 -437.142544) (xy 391.318242 -437.142128)
			(xy 392.258042 -437.142128) (xy 392.270158 -437.142576) (xy 392.293201 -437.150073) (xy 392.312801 -437.164322)
			(xy 392.327041 -437.183928) (xy 392.334529 -437.206974) (xy 392.335004 -437.21909) (xy 392.335004 -438.089802)
			(xy 393.237974 -438.089802) (xy 393.238067 -438.075228) (xy 393.23972 -438.046127) (xy 393.241276 -438.031636)
			(xy 393.241276 -436.948072) (xy 393.239732 -436.93358) (xy 393.238079 -436.90448) (xy 393.237974 -436.889906)
			(xy 393.238067 -436.875332) (xy 393.23972 -436.846231) (xy 393.241276 -436.83174) (xy 393.241276 -436.219092)
			(xy 393.241709 -436.206985) (xy 393.249208 -436.183962) (xy 393.263466 -436.164391) (xy 393.283082 -436.150195)
			(xy 393.30613 -436.142771) (xy 393.318238 -436.142384) (xy 394.258038 -436.142384) (xy 394.270134 -436.142776)
			(xy 394.293143 -436.150248) (xy 394.312726 -436.164453) (xy 394.326974 -436.184004) (xy 394.334497 -436.206997)
			(xy 394.335 -436.219092) (xy 394.335 -438.760616) (xy 394.334597 -438.772726) (xy 394.327094 -438.795754)
			(xy 394.312828 -438.815326) (xy 394.293204 -438.82952) (xy 394.270149 -438.836941) (xy 394.258038 -438.837324)
			(xy 393.318238 -438.837324) (xy 393.306147 -438.83686) (xy 393.283141 -438.829409) (xy 393.263558 -438.815223)
			(xy 393.249307 -438.795686) (xy 393.241781 -438.772706) (xy 393.241276 -438.760616) (xy 393.241276 -438.147968)
			(xy 393.239731 -438.133476) (xy 393.238079 -438.104376) (xy 393.237974 -438.089802) (xy 392.335004 -438.089802)
			(xy 392.335004 -439.0898) (xy 395.23797 -439.0898) (xy 395.238063 -439.075226) (xy 395.239716 -439.046125)
			(xy 395.241272 -439.031634) (xy 395.241272 -437.94807) (xy 395.239728 -437.933578) (xy 395.238075 -437.904478)
			(xy 395.23797 -437.889904) (xy 395.238063 -437.87533) (xy 395.239716 -437.846229) (xy 395.241272 -437.831738)
			(xy 395.241272 -437.21909) (xy 395.241652 -437.206963) (xy 395.249151 -437.183898) (xy 395.263412 -437.164281)
			(xy 395.283038 -437.150031) (xy 395.306107 -437.142545) (xy 395.318234 -437.142128) (xy 396.258034 -437.142128)
			(xy 396.270149 -437.142583) (xy 396.293192 -437.150078) (xy 396.312792 -437.164325) (xy 396.327033 -437.18393)
			(xy 396.334521 -437.206975) (xy 396.334996 -437.21909) (xy 396.334996 -438.089802) (xy 398.237964 -438.089802)
			(xy 398.238081 -438.074717) (xy 398.239857 -438.044598) (xy 398.24152 -438.029604) (xy 398.24152 -436.950104)
			(xy 398.23985 -436.935111) (xy 398.238072 -436.904992) (xy 398.237964 -436.889906) (xy 398.238072 -436.87482)
			(xy 398.239854 -436.844702) (xy 398.24152 -436.829708) (xy 398.24152 -436.219092) (xy 398.241906 -436.207006)
			(xy 398.249379 -436.184018) (xy 398.263591 -436.164466) (xy 398.283151 -436.150263) (xy 398.306142 -436.1428)
			(xy 398.318228 -436.142384) (xy 399.258028 -436.142384) (xy 399.270103 -436.14284) (xy 399.29307 -436.150309)
			(xy 399.312606 -436.164508) (xy 399.3268 -436.184048) (xy 399.334263 -436.207017) (xy 399.334736 -436.219092)
			(xy 399.334736 -438.760616) (xy 399.33425 -438.772689) (xy 399.326786 -438.795651) (xy 399.312594 -438.815186)
			(xy 399.293062 -438.829381) (xy 399.270101 -438.836848) (xy 399.258028 -438.837324) (xy 398.318228 -438.837324)
			(xy 398.306148 -438.836864) (xy 398.283169 -438.829406) (xy 398.26362 -438.815211) (xy 398.249414 -438.79567)
			(xy 398.241943 -438.772695) (xy 398.24152 -438.760616) (xy 398.24152 -438.15) (xy 398.239849 -438.135007)
			(xy 398.238072 -438.104888) (xy 398.237964 -438.089802) (xy 396.334996 -438.089802) (xy 396.334996 -439.0898)
			(xy 400.23796 -439.0898) (xy 400.238077 -439.074715) (xy 400.239853 -439.044596) (xy 400.241516 -439.029602)
			(xy 400.241516 -437.950102) (xy 400.239845 -437.935109) (xy 400.238068 -437.90499) (xy 400.23796 -437.889904)
			(xy 400.238077 -437.874819) (xy 400.239853 -437.8447) (xy 400.241516 -437.829706) (xy 400.241516 -437.21909)
			(xy 400.241999 -437.207002) (xy 400.249455 -437.184006) (xy 400.263639 -437.164428) (xy 400.283167 -437.150177)
			(xy 400.306138 -437.142641) (xy 400.318224 -437.142128) (xy 401.258024 -437.142128) (xy 401.270137 -437.142496)
			(xy 401.29317 -437.150006) (xy 401.312745 -437.164279) (xy 401.326938 -437.183912) (xy 401.334353 -437.206975)
			(xy 401.334732 -437.21909) (xy 401.334732 -438.089802) (xy 402.237956 -438.089802) (xy 402.238073 -438.074717)
			(xy 402.239849 -438.044598) (xy 402.241512 -438.029604) (xy 402.241512 -436.950104) (xy 402.239842 -436.935111)
			(xy 402.238064 -436.904992) (xy 402.237956 -436.889906) (xy 402.238064 -436.87482) (xy 402.239846 -436.844702)
			(xy 402.241512 -436.829708) (xy 402.241512 -436.219092) (xy 402.241906 -436.207007) (xy 402.249378 -436.18402)
			(xy 402.263588 -436.164469) (xy 402.283146 -436.150265) (xy 402.306135 -436.142802) (xy 402.31822 -436.142384)
			(xy 403.25802 -436.142384) (xy 403.270095 -436.142847) (xy 403.293061 -436.150314) (xy 403.312597 -436.164511)
			(xy 403.326791 -436.18405) (xy 403.334255 -436.207017) (xy 403.334728 -436.219092) (xy 403.334728 -438.760616)
			(xy 403.33425 -438.772689) (xy 403.326785 -438.795654) (xy 403.312591 -438.815189) (xy 403.293057 -438.829383)
			(xy 403.270093 -438.836849) (xy 403.25802 -438.837324) (xy 402.31822 -438.837324) (xy 402.30614 -438.83687)
			(xy 402.283161 -438.82941) (xy 402.263611 -438.815214) (xy 402.249406 -438.795672) (xy 402.241935 -438.772696)
			(xy 402.241512 -438.760616) (xy 402.241512 -438.15) (xy 402.239841 -438.135007) (xy 402.238064 -438.104888)
			(xy 402.237956 -438.089802) (xy 401.334732 -438.089802) (xy 401.334732 -439.0898) (xy 404.237952 -439.0898)
			(xy 404.238069 -439.074715) (xy 404.239845 -439.044596) (xy 404.241508 -439.029602) (xy 404.241508 -437.950102)
			(xy 404.239837 -437.935109) (xy 404.23806 -437.90499) (xy 404.237952 -437.889904) (xy 404.238069 -437.874819)
			(xy 404.239845 -437.8447) (xy 404.241508 -437.829706) (xy 404.241508 -437.21909) (xy 404.241998 -437.207003)
			(xy 404.249454 -437.184008) (xy 404.263636 -437.164431) (xy 404.283162 -437.150179) (xy 404.306131 -437.142642)
			(xy 404.318216 -437.142128) (xy 405.258016 -437.142128) (xy 405.270129 -437.142503) (xy 405.293161 -437.15001)
			(xy 405.312736 -437.164281) (xy 405.326929 -437.183914) (xy 405.334345 -437.206976) (xy 405.334724 -437.21909)
			(xy 405.334724 -438.089802) (xy 406.237948 -438.089802) (xy 406.238065 -438.074717) (xy 406.239841 -438.044598)
			(xy 406.241504 -438.029604) (xy 406.241504 -436.950104) (xy 406.239834 -436.935111) (xy 406.238056 -436.904992)
			(xy 406.237948 -436.889906) (xy 406.238056 -436.87482) (xy 406.239838 -436.844702) (xy 406.241504 -436.829708)
			(xy 406.241504 -436.219092) (xy 406.241906 -436.207008) (xy 406.249377 -436.184023) (xy 406.263586 -436.164471)
			(xy 406.283141 -436.150268) (xy 406.306128 -436.142803) (xy 406.318212 -436.142384) (xy 407.258012 -436.142384)
			(xy 407.270086 -436.142854) (xy 407.293053 -436.150319) (xy 407.312589 -436.164514) (xy 407.326783 -436.184051)
			(xy 407.334247 -436.207018) (xy 407.33472 -436.219092) (xy 407.33472 -438.760616) (xy 407.334249 -438.77269)
			(xy 407.326784 -438.795656) (xy 407.312589 -438.815191) (xy 407.293052 -438.829386) (xy 407.270086 -438.83685)
			(xy 407.258012 -438.837324) (xy 406.318212 -438.837324) (xy 406.30614 -438.836826) (xy 406.283176 -438.829369)
			(xy 406.26364 -438.81518) (xy 406.249444 -438.79565) (xy 406.241979 -438.772688) (xy 406.241504 -438.760616)
			(xy 406.241504 -438.15) (xy 406.239833 -438.135007) (xy 406.238056 -438.104888) (xy 406.237948 -438.089802)
			(xy 405.334724 -438.089802) (xy 405.334724 -439.0898) (xy 408.237944 -439.0898) (xy 408.238061 -439.074715)
			(xy 408.239837 -439.044596) (xy 408.2415 -439.029602) (xy 408.2415 -437.950102) (xy 408.239829 -437.935109)
			(xy 408.238052 -437.90499) (xy 408.237944 -437.889904) (xy 408.238061 -437.874819) (xy 408.239837 -437.8447)
			(xy 408.2415 -437.829706) (xy 408.2415 -437.21909) (xy 408.241998 -437.207004) (xy 408.249453 -437.18401)
			(xy 408.263633 -437.164434) (xy 408.283157 -437.150182) (xy 408.306124 -437.142643) (xy 408.318208 -437.142128)
			(xy 409.258008 -437.142128) (xy 409.27012 -437.14251) (xy 409.293152 -437.150015) (xy 409.312728 -437.164284)
			(xy 409.326921 -437.183915) (xy 409.334337 -437.206976) (xy 409.334716 -437.21909) (xy 409.334716 -438.089802)
			(xy 410.23794 -438.089802) (xy 410.238057 -438.074717) (xy 410.239833 -438.044598) (xy 410.241496 -438.029604)
			(xy 410.241496 -436.950104) (xy 410.239826 -436.935111) (xy 410.238048 -436.904992) (xy 410.23794 -436.889906)
			(xy 410.23805 -436.87482) (xy 410.239832 -436.844702) (xy 410.241496 -436.829708) (xy 410.241496 -436.219092)
			(xy 410.241958 -436.207017) (xy 410.249423 -436.184049) (xy 410.26362 -436.164511) (xy 410.283159 -436.150317)
			(xy 410.306129 -436.142856) (xy 410.318204 -436.142384) (xy 411.258004 -436.142384) (xy 411.270078 -436.142861)
			(xy 411.293044 -436.150323) (xy 411.31258 -436.164517) (xy 411.326775 -436.184053) (xy 411.334239 -436.207018)
			(xy 411.334712 -436.219092) (xy 411.334712 -438.760616) (xy 411.334249 -438.772691) (xy 411.326783 -438.795658)
			(xy 411.312586 -438.815194) (xy 411.293047 -438.829388) (xy 411.270079 -438.836851) (xy 411.258004 -438.837324)
			(xy 410.318204 -438.837324) (xy 410.306131 -438.836833) (xy 410.283167 -438.829373) (xy 410.263631 -438.815183)
			(xy 410.249436 -438.795651) (xy 410.241971 -438.772689) (xy 410.241496 -438.760616) (xy 410.241496 -438.15)
			(xy 410.239825 -438.135007) (xy 410.238048 -438.104888) (xy 410.23794 -438.089802) (xy 409.334716 -438.089802)
			(xy 409.334716 -439.0898) (xy 412.237936 -439.0898) (xy 412.238053 -439.074715) (xy 412.239829 -439.044596)
			(xy 412.241492 -439.029602) (xy 412.241492 -437.950102) (xy 412.239821 -437.935109) (xy 412.238044 -437.90499)
			(xy 412.237936 -437.889904) (xy 412.238053 -437.874819) (xy 412.239829 -437.8447) (xy 412.241492 -437.829706)
			(xy 412.241492 -437.21909) (xy 412.241998 -437.207005) (xy 412.249452 -437.184012) (xy 412.26363 -437.164436)
			(xy 412.283152 -437.150184) (xy 412.306117 -437.142644) (xy 412.3182 -437.142128) (xy 413.258 -437.142128)
			(xy 413.270112 -437.142516) (xy 413.293144 -437.150019) (xy 413.312719 -437.164287) (xy 413.326913 -437.183916)
			(xy 413.334329 -437.206977) (xy 413.334708 -437.21909) (xy 413.334708 -439.760614) (xy 413.334206 -439.7727)
			(xy 413.326751 -439.795693) (xy 413.312572 -439.815268) (xy 413.293049 -439.82952) (xy 413.270084 -439.83706)
			(xy 413.258 -439.837576) (xy 412.3182 -439.837576) (xy 412.306089 -439.837184) (xy 412.283057 -439.829681)
			(xy 412.263482 -439.815414) (xy 412.249288 -439.795786) (xy 412.241872 -439.772727) (xy 412.241492 -439.760614)
			(xy 412.241492 -439.149998) (xy 412.239821 -439.135005) (xy 412.238044 -439.104886) (xy 412.237936 -439.0898)
			(xy 409.334716 -439.0898) (xy 409.334716 -439.760614) (xy 409.334304 -439.772709) (xy 409.326838 -439.795717)
			(xy 409.312639 -439.815301) (xy 409.293091 -439.829549) (xy 409.270101 -439.837073) (xy 409.258008 -439.837576)
			(xy 408.318208 -439.837576) (xy 408.306097 -439.837177) (xy 408.283066 -439.829677) (xy 408.263491 -439.815412)
			(xy 408.249296 -439.795785) (xy 408.24188 -439.772726) (xy 408.2415 -439.760614) (xy 408.2415 -439.149998)
			(xy 408.239829 -439.135005) (xy 408.238052 -439.104886) (xy 408.237944 -439.0898) (xy 405.334724 -439.0898)
			(xy 405.334724 -439.760614) (xy 405.334304 -439.772708) (xy 405.326839 -439.795715) (xy 405.312642 -439.815298)
			(xy 405.293096 -439.829547) (xy 405.270109 -439.837072) (xy 405.258016 -439.837576) (xy 404.318216 -439.837576)
			(xy 404.306106 -439.83717) (xy 404.283075 -439.829672) (xy 404.263499 -439.815408) (xy 404.249305 -439.795783)
			(xy 404.241888 -439.772726) (xy 404.241508 -439.760614) (xy 404.241508 -439.149998) (xy 404.239837 -439.135005)
			(xy 404.23806 -439.104886) (xy 404.237952 -439.0898) (xy 401.334732 -439.0898) (xy 401.334732 -439.760614)
			(xy 401.334304 -439.772707) (xy 401.32684 -439.795713) (xy 401.312645 -439.815295) (xy 401.293101 -439.829544)
			(xy 401.270116 -439.837071) (xy 401.258024 -439.837576) (xy 400.318224 -439.837576) (xy 400.306114 -439.837163)
			(xy 400.283083 -439.829667) (xy 400.263508 -439.815406) (xy 400.249313 -439.795781) (xy 400.241896 -439.772725)
			(xy 400.241516 -439.760614) (xy 400.241516 -439.149998) (xy 400.239845 -439.135005) (xy 400.238068 -439.104886)
			(xy 400.23796 -439.0898) (xy 396.334996 -439.0898) (xy 396.334996 -439.760614) (xy 396.334501 -439.772726)
			(xy 396.327014 -439.795764) (xy 396.312777 -439.815363) (xy 396.293182 -439.829605) (xy 396.270146 -439.837098)
			(xy 396.258034 -439.837576) (xy 395.318234 -439.837576) (xy 395.306114 -439.837111) (xy 395.283059 -439.82963)
			(xy 395.263445 -439.81539) (xy 395.249192 -439.795784) (xy 395.241696 -439.772733) (xy 395.241272 -439.760614)
			(xy 395.241272 -439.147966) (xy 395.239727 -439.133474) (xy 395.238075 -439.104374) (xy 395.23797 -439.0898)
			(xy 392.335004 -439.0898) (xy 392.335004 -439.760614) (xy 392.334501 -439.772725) (xy 392.327015 -439.795762)
			(xy 392.31278 -439.81536) (xy 392.293187 -439.829602) (xy 392.270153 -439.837097) (xy 392.258042 -439.837576)
			(xy 391.318242 -439.837576) (xy 391.306123 -439.837105) (xy 391.283068 -439.829626) (xy 391.263453 -439.815387)
			(xy 391.2492 -439.795783) (xy 391.241704 -439.772733) (xy 391.24128 -439.760614) (xy 391.24128 -439.147966)
			(xy 391.239735 -439.133474) (xy 391.238083 -439.104374) (xy 391.237978 -439.0898) (xy 388.335012 -439.0898)
			(xy 388.335012 -439.760614) (xy 388.334501 -439.772724) (xy 388.327016 -439.79576) (xy 388.312782 -439.815357)
			(xy 388.293192 -439.8296) (xy 388.27016 -439.837096) (xy 388.25805 -439.837576) (xy 387.31825 -439.837576)
			(xy 387.306134 -439.837131) (xy 387.283092 -439.829632) (xy 387.263492 -439.815382) (xy 387.249252 -439.795776)
			(xy 387.241763 -439.77273) (xy 387.241288 -439.760614) (xy 387.241288 -439.147966) (xy 387.239743 -439.133474)
			(xy 387.238091 -439.104374) (xy 387.237986 -439.0898) (xy 384.33502 -439.0898) (xy 384.33502 -439.760614)
			(xy 384.334651 -439.772742) (xy 384.32715 -439.795808) (xy 384.312886 -439.815426) (xy 384.293258 -439.829675)
			(xy 384.270186 -439.83716) (xy 384.258058 -439.837576) (xy 383.318258 -439.837576) (xy 383.306143 -439.837124)
			(xy 383.2831 -439.829627) (xy 383.263501 -439.815379) (xy 383.24926 -439.795774) (xy 383.241771 -439.77273)
			(xy 383.241296 -439.760614) (xy 383.241296 -439.147966) (xy 383.239751 -439.133474) (xy 383.238099 -439.104374)
			(xy 383.237994 -439.0898) (xy 346.23502 -439.0898) (xy 346.23502 -439.760614) (xy 346.234651 -439.772742)
			(xy 346.22715 -439.795808) (xy 346.212886 -439.815426) (xy 346.193258 -439.829675) (xy 346.170186 -439.83716)
			(xy 346.158058 -439.837576) (xy 345.218258 -439.837576) (xy 345.206143 -439.837124) (xy 345.1831 -439.829627)
			(xy 345.163501 -439.815379) (xy 345.14926 -439.795774) (xy 345.141771 -439.77273) (xy 345.141296 -439.760614)
			(xy 345.141296 -439.243978) (xy 345.130608 -439.206333) (xy 345.119131 -439.128926) (xy 345.118436 -439.0898)
			(xy 342.235028 -439.0898) (xy 342.235028 -439.760614) (xy 342.234651 -439.772741) (xy 342.227151 -439.795806)
			(xy 342.212889 -439.815424) (xy 342.193263 -439.829673) (xy 342.170193 -439.837159) (xy 342.158066 -439.837576)
			(xy 341.218266 -439.837576) (xy 341.206151 -439.837118) (xy 341.183109 -439.829623) (xy 341.163509 -439.815377)
			(xy 341.149268 -439.795773) (xy 341.141779 -439.772729) (xy 341.141304 -439.760614) (xy 341.141304 -439.243978)
			(xy 341.130616 -439.206333) (xy 341.119139 -439.128926) (xy 341.118444 -439.0898) (xy 338.235036 -439.0898)
			(xy 338.235036 -439.760614) (xy 338.234651 -439.77274) (xy 338.227152 -439.795804) (xy 338.212892 -439.815421)
			(xy 338.193268 -439.82967) (xy 338.1702 -439.837158) (xy 338.158074 -439.837576) (xy 337.218274 -439.837576)
			(xy 337.206159 -439.837111) (xy 337.183118 -439.829618) (xy 337.163518 -439.815374) (xy 337.149276 -439.795772)
			(xy 337.141787 -439.772729) (xy 337.141312 -439.760614) (xy 337.141312 -439.243978) (xy 337.130625 -439.206333)
			(xy 337.119147 -439.128926) (xy 337.118452 -439.0898) (xy 334.235044 -439.0898) (xy 334.235044 -439.760614)
			(xy 334.234651 -439.772739) (xy 334.227153 -439.795802) (xy 334.212895 -439.815418) (xy 334.193273 -439.829668)
			(xy 334.170207 -439.837157) (xy 334.158082 -439.837576) (xy 333.218282 -439.837576) (xy 333.206168 -439.837104)
			(xy 333.183126 -439.829614) (xy 333.163526 -439.815371) (xy 333.149285 -439.79577) (xy 333.141795 -439.772728)
			(xy 333.14132 -439.760614) (xy 333.14132 -439.243978) (xy 333.130633 -439.206333) (xy 333.119156 -439.128926)
			(xy 333.11846 -439.0898) (xy 329.2348 -439.0898) (xy 329.2348 -439.760614) (xy 329.234306 -439.7727)
			(xy 329.22685 -439.795695) (xy 329.212669 -439.815271) (xy 329.193144 -439.829523) (xy 329.170177 -439.837061)
			(xy 329.158092 -439.837576) (xy 328.218292 -439.837576) (xy 328.20618 -439.83719) (xy 328.183149 -439.829686)
			(xy 328.163574 -439.815417) (xy 328.14938 -439.795788) (xy 328.141964 -439.772727) (xy 328.141584 -439.760614)
			(xy 328.141584 -439.24474) (xy 328.130784 -439.206919) (xy 328.119178 -439.129127) (xy 328.11847 -439.0898)
			(xy 325.234808 -439.0898) (xy 325.234808 -439.760614) (xy 325.234306 -439.7727) (xy 325.226851 -439.795693)
			(xy 325.212672 -439.815268) (xy 325.193149 -439.82952) (xy 325.170184 -439.83706) (xy 325.1581 -439.837576)
			(xy 324.2183 -439.837576) (xy 324.206189 -439.837184) (xy 324.183157 -439.829681) (xy 324.163582 -439.815414)
			(xy 324.149388 -439.795786) (xy 324.141972 -439.772727) (xy 324.141592 -439.760614) (xy 324.141592 -439.24474)
			(xy 324.130793 -439.206919) (xy 324.119186 -439.129127) (xy 324.118478 -439.0898) (xy 321.234816 -439.0898)
			(xy 321.234816 -439.760614) (xy 321.234404 -439.772709) (xy 321.226938 -439.795717) (xy 321.212739 -439.815301)
			(xy 321.193191 -439.829549) (xy 321.170201 -439.837073) (xy 321.158108 -439.837576) (xy 320.218308 -439.837576)
			(xy 320.206197 -439.837177) (xy 320.183166 -439.829677) (xy 320.163591 -439.815412) (xy 320.149396 -439.795785)
			(xy 320.14198 -439.772726) (xy 320.1416 -439.760614) (xy 320.1416 -439.24474) (xy 320.130801 -439.206918)
			(xy 320.119194 -439.129127) (xy 320.118486 -439.0898) (xy 317.234824 -439.0898) (xy 317.234824 -439.760614)
			(xy 317.234404 -439.772708) (xy 317.226939 -439.795715) (xy 317.212742 -439.815298) (xy 317.193196 -439.829547)
			(xy 317.170209 -439.837072) (xy 317.158116 -439.837576) (xy 316.218316 -439.837576) (xy 316.206206 -439.83717)
			(xy 316.183175 -439.829672) (xy 316.163599 -439.815408) (xy 316.149405 -439.795783) (xy 316.141988 -439.772726)
			(xy 316.141608 -439.760614) (xy 316.141608 -439.24474) (xy 316.130809 -439.206918) (xy 316.119202 -439.129127)
			(xy 316.118494 -439.0898) (xy 157.334712 -439.0898) (xy 157.334712 -439.760614) (xy 157.334304 -439.772709)
			(xy 157.326838 -439.795718) (xy 157.312637 -439.815302) (xy 157.293089 -439.829551) (xy 157.270098 -439.837074)
			(xy 157.258004 -439.837576) (xy 156.318204 -439.837576) (xy 156.306093 -439.83718) (xy 156.283062 -439.829679)
			(xy 156.263486 -439.815413) (xy 156.249292 -439.795785) (xy 156.241876 -439.772727) (xy 156.241496 -439.760614)
			(xy 156.241496 -439.149998) (xy 156.239825 -439.135005) (xy 156.238048 -439.104886) (xy 156.23794 -439.0898)
			(xy 153.33472 -439.0898) (xy 153.33472 -439.760614) (xy 153.334304 -439.772708) (xy 153.326839 -439.795716)
			(xy 153.31264 -439.815299) (xy 153.293094 -439.829548) (xy 153.270105 -439.837073) (xy 153.258012 -439.837576)
			(xy 152.318212 -439.837576) (xy 152.306101 -439.837173) (xy 152.28307 -439.829674) (xy 152.263495 -439.81541)
			(xy 152.249301 -439.795784) (xy 152.241884 -439.772726) (xy 152.241504 -439.760614) (xy 152.241504 -439.149998)
			(xy 152.239833 -439.135005) (xy 152.238056 -439.104886) (xy 152.237948 -439.0898) (xy 149.334728 -439.0898)
			(xy 149.334728 -439.760614) (xy 149.334304 -439.772708) (xy 149.32684 -439.795714) (xy 149.312643 -439.815297)
			(xy 149.293099 -439.829546) (xy 149.270112 -439.837072) (xy 149.25802 -439.837576) (xy 148.31822 -439.837576)
			(xy 148.30611 -439.837166) (xy 148.283079 -439.829669) (xy 148.263504 -439.815407) (xy 148.249309 -439.795782)
			(xy 148.241892 -439.772726) (xy 148.241512 -439.760614) (xy 148.241512 -439.149998) (xy 148.239841 -439.135005)
			(xy 148.238064 -439.104886) (xy 148.237956 -439.0898) (xy 145.334736 -439.0898) (xy 145.334736 -439.760614)
			(xy 145.334304 -439.772707) (xy 145.326841 -439.795712) (xy 145.312646 -439.815294) (xy 145.293104 -439.829543)
			(xy 145.270119 -439.83707) (xy 145.258028 -439.837576) (xy 144.318228 -439.837576) (xy 144.306118 -439.837159)
			(xy 144.283088 -439.829665) (xy 144.263512 -439.815404) (xy 144.249317 -439.795781) (xy 144.2419 -439.772725)
			(xy 144.24152 -439.760614) (xy 144.24152 -439.149998) (xy 144.239849 -439.135005) (xy 144.238072 -439.104886)
			(xy 144.237964 -439.0898) (xy 140.335 -439.0898) (xy 140.335 -439.760614) (xy 140.334501 -439.772726)
			(xy 140.327015 -439.795763) (xy 140.312778 -439.815361) (xy 140.293184 -439.829604) (xy 140.270149 -439.837097)
			(xy 140.258038 -439.837576) (xy 139.318238 -439.837576) (xy 139.306119 -439.837108) (xy 139.283063 -439.829628)
			(xy 139.263449 -439.815388) (xy 139.249196 -439.795783) (xy 139.2417 -439.772733) (xy 139.241276 -439.760614)
			(xy 139.241276 -439.147966) (xy 139.239731 -439.133474) (xy 139.238079 -439.104374) (xy 139.237974 -439.0898)
			(xy 136.335008 -439.0898) (xy 136.335008 -439.760614) (xy 136.334501 -439.772725) (xy 136.327016 -439.795761)
			(xy 136.312781 -439.815358) (xy 136.293189 -439.829601) (xy 136.270157 -439.837096) (xy 136.258046 -439.837576)
			(xy 135.318246 -439.837576) (xy 135.306127 -439.837101) (xy 135.283072 -439.829623) (xy 135.263457 -439.815385)
			(xy 135.249204 -439.795782) (xy 135.241708 -439.772733) (xy 135.241284 -439.760614) (xy 135.241284 -439.147966)
			(xy 135.239739 -439.133474) (xy 135.238087 -439.104374) (xy 135.237982 -439.0898) (xy 132.335016 -439.0898)
			(xy 132.335016 -439.760614) (xy 132.334651 -439.772742) (xy 132.327149 -439.795809) (xy 132.312885 -439.815428)
			(xy 132.293255 -439.829677) (xy 132.270182 -439.83716) (xy 132.258054 -439.837576) (xy 131.318254 -439.837576)
			(xy 131.306138 -439.837128) (xy 131.283096 -439.82963) (xy 131.263496 -439.815381) (xy 131.249256 -439.795775)
			(xy 131.241767 -439.77273) (xy 131.241292 -439.760614) (xy 131.241292 -439.147966) (xy 131.239747 -439.133474)
			(xy 131.238095 -439.104374) (xy 131.23799 -439.0898) (xy 128.335024 -439.0898) (xy 128.335024 -439.760614)
			(xy 128.334651 -439.772741) (xy 128.32715 -439.795807) (xy 128.312888 -439.815425) (xy 128.29326 -439.829674)
			(xy 128.27019 -439.837159) (xy 128.258062 -439.837576) (xy 127.318262 -439.837576) (xy 127.306147 -439.837121)
			(xy 127.283105 -439.829625) (xy 127.263505 -439.815378) (xy 127.249264 -439.795774) (xy 127.241775 -439.772729)
			(xy 127.2413 -439.760614) (xy 127.2413 -439.147966) (xy 127.239755 -439.133474) (xy 127.238103 -439.104374)
			(xy 127.237998 -439.0898) (xy 90.235024 -439.0898) (xy 90.235024 -439.760614) (xy 90.234651 -439.772741)
			(xy 90.22715 -439.795807) (xy 90.212888 -439.815425) (xy 90.19326 -439.829674) (xy 90.17019 -439.837159)
			(xy 90.158062 -439.837576) (xy 89.218262 -439.837576) (xy 89.206147 -439.837121) (xy 89.183105 -439.829625)
			(xy 89.163505 -439.815378) (xy 89.149264 -439.795774) (xy 89.141775 -439.772729) (xy 89.1413 -439.760614)
			(xy 89.1413 -439.243978) (xy 89.130612 -439.206333) (xy 89.119135 -439.128926) (xy 89.11844 -439.0898)
			(xy 86.235032 -439.0898) (xy 86.235032 -439.760614) (xy 86.234651 -439.77274) (xy 86.227152 -439.795805)
			(xy 86.212891 -439.815422) (xy 86.193265 -439.829672) (xy 86.170197 -439.837158) (xy 86.15807 -439.837576)
			(xy 85.21827 -439.837576) (xy 85.206155 -439.837114) (xy 85.183113 -439.82962) (xy 85.163513 -439.815375)
			(xy 85.149272 -439.795772) (xy 85.141783 -439.772729) (xy 85.141308 -439.760614) (xy 85.141308 -439.243978)
			(xy 85.130621 -439.206333) (xy 85.119143 -439.128926) (xy 85.118448 -439.0898) (xy 82.23504 -439.0898)
			(xy 82.23504 -439.760614) (xy 82.234651 -439.77274) (xy 82.227153 -439.795803) (xy 82.212894 -439.815419)
			(xy 82.19327 -439.829669) (xy 82.170204 -439.837157) (xy 82.158078 -439.837576) (xy 81.218278 -439.837576)
			(xy 81.206164 -439.837107) (xy 81.183122 -439.829616) (xy 81.163522 -439.815372) (xy 81.149281 -439.795771)
			(xy 81.141791 -439.772728) (xy 81.141316 -439.760614) (xy 81.141316 -439.243978) (xy 81.130629 -439.206333)
			(xy 81.119152 -439.128926) (xy 81.118456 -439.0898) (xy 78.235048 -439.0898) (xy 78.235048 -439.760614)
			(xy 78.2346 -439.772731) (xy 78.227107 -439.795777) (xy 78.21286 -439.81538) (xy 78.193252 -439.82962)
			(xy 78.170203 -439.837105) (xy 78.158086 -439.837576) (xy 77.218286 -439.837576) (xy 77.206172 -439.837101)
			(xy 77.183131 -439.829611) (xy 77.16353 -439.81537) (xy 77.149289 -439.795769) (xy 77.141799 -439.772728)
			(xy 77.141324 -439.760614) (xy 77.141324 -439.243978) (xy 77.130637 -439.206333) (xy 77.11916 -439.128926)
			(xy 77.118464 -439.0898) (xy 73.234804 -439.0898) (xy 73.234804 -439.760614) (xy 73.234306 -439.7727)
			(xy 73.22685 -439.795694) (xy 73.21267 -439.81527) (xy 73.193146 -439.829521) (xy 73.17018 -439.837061)
			(xy 73.158096 -439.837576) (xy 72.218296 -439.837576) (xy 72.206185 -439.837187) (xy 72.183153 -439.829683)
			(xy 72.163578 -439.815416) (xy 72.149384 -439.795787) (xy 72.141968 -439.772727) (xy 72.141588 -439.760614)
			(xy 72.141588 -439.24474) (xy 72.130789 -439.206919) (xy 72.119182 -439.129127) (xy 72.118474 -439.0898)
			(xy 69.234812 -439.0898) (xy 69.234812 -439.760614) (xy 69.234404 -439.772709) (xy 69.226938 -439.795718)
			(xy 69.212737 -439.815302) (xy 69.193189 -439.829551) (xy 69.170198 -439.837074) (xy 69.158104 -439.837576)
			(xy 68.218304 -439.837576) (xy 68.206193 -439.83718) (xy 68.183162 -439.829679) (xy 68.163586 -439.815413)
			(xy 68.149392 -439.795785) (xy 68.141976 -439.772727) (xy 68.141596 -439.760614) (xy 68.141596 -439.24474)
			(xy 68.130797 -439.206918) (xy 68.11919 -439.129127) (xy 68.118482 -439.0898) (xy 65.23482 -439.0898)
			(xy 65.23482 -439.760614) (xy 65.234404 -439.772708) (xy 65.226939 -439.795716) (xy 65.21274 -439.815299)
			(xy 65.193194 -439.829548) (xy 65.170205 -439.837073) (xy 65.158112 -439.837576) (xy 64.218312 -439.837576)
			(xy 64.206201 -439.837173) (xy 64.18317 -439.829674) (xy 64.163595 -439.81541) (xy 64.149401 -439.795784)
			(xy 64.141984 -439.772726) (xy 64.141604 -439.760614) (xy 64.141604 -439.24474) (xy 64.130805 -439.206918)
			(xy 64.119198 -439.129127) (xy 64.11849 -439.0898) (xy 61.234828 -439.0898) (xy 61.234828 -439.760614)
			(xy 61.234404 -439.772708) (xy 61.22694 -439.795714) (xy 61.212743 -439.815297) (xy 61.193199 -439.829546)
			(xy 61.170212 -439.837072) (xy 61.15812 -439.837576) (xy 60.21832 -439.837576) (xy 60.20621 -439.837166)
			(xy 60.183179 -439.829669) (xy 60.163604 -439.815407) (xy 60.149409 -439.795782) (xy 60.141992 -439.772726)
			(xy 60.141612 -439.760614) (xy 60.141612 -439.24474) (xy 60.130813 -439.206918) (xy 60.119206 -439.129127)
			(xy 60.118498 -439.0898) (xy 7.00913 -439.0898) (xy 7.00913 -439.989976) (xy 7.009638 -440.045746)
			(xy 7.017973 -440.156973) (xy 7.034597 -440.267266) (xy 7.059417 -440.376009) (xy 7.092293 -440.482593)
			(xy 7.133043 -440.586422) (xy 7.181438 -440.686915) (xy 7.237207 -440.783511) (xy 7.300039 -440.87567)
			(xy 7.369583 -440.962874) (xy 7.445449 -441.044639) (xy 7.527212 -441.120505) (xy 7.614417 -441.190048)
			(xy 7.706575 -441.252881) (xy 7.803171 -441.30865) (xy 7.903664 -441.357045) (xy 8.007493 -441.397795)
			(xy 8.114077 -441.430672) (xy 8.22282 -441.455492) (xy 8.333113 -441.472116) (xy 8.44434 -441.480451)
			(xy 8.50011 -441.480956) (xy 194.495928 -441.480956)
		)
		(stroke
			(width 0)
			(type solid)
		)
		(fill yes)
		(layer "In14.Cu")
		(net "GND")
	)
	(gr_line
		(start 206.17434 -435.523132)
		(end 207.503268 -436.85206)
		(stroke
			(width 0.635)
			(type default)
		)
		(layer "In14.Cu")
	)
	(gr_line
		(start 206.17434 -415.567368)
		(end 206.17434 -435.523132)
		(stroke
			(width 0.635)
			(type default)
		)
		(layer "In14.Cu")
	)
	(gr_line
		(start 207.213708 -414.528)
		(end 206.17434 -415.567368)
		(stroke
			(width 0.635)
			(type default)
		)
		(layer "In14.Cu")
	)
	(gr_line
		(start 207.503268 -436.85206)
		(end 228.909372 -436.85206)
		(stroke
			(width 0.635)
			(type default)
		)
		(layer "In14.Cu")
	)
	(gr_line
		(start 228.909372 -436.85206)
		(end 230.69804 -435.063392)
		(stroke
			(width 0.635)
			(type default)
		)
		(layer "In14.Cu")
	)
	(gr_line
		(start 230.69804 -435.063392)
		(end 230.69804 -423.4688)
		(stroke
			(width 0.635)
			(type default)
		)
		(layer "In14.Cu")
	)
	(gr_line
		(start 230.69804 -423.4688)
		(end 233.20756 -420.95928)
		(stroke
			(width 0.635)
			(type default)
		)
		(layer "In14.Cu")
	)
	(gr_line
		(start 232.938828 -414.528)
		(end 207.213708 -414.528)
		(stroke
			(width 0.635)
			(type default)
		)
		(layer "In14.Cu")
	)
	(gr_line
		(start 233.20756 -420.95928)
		(end 270.49476 -420.95928)
		(stroke
			(width 0.635)
			(type default)
		)
		(layer "In14.Cu")
	)
	(gr_line
		(start 239.67694 -402.10994)
		(end 239.86236 -402.29536)
		(stroke
			(width 0.508)
			(type default)
		)
		(layer "In14.Cu")
	)
	(gr_line
		(start 239.67694 -397.53286)
		(end 239.67694 -402.10994)
		(stroke
			(width 0.508)
			(type default)
		)
		(layer "In14.Cu")
	)
	(gr_line
		(start 239.713008 -407.75382)
		(end 232.938828 -414.528)
		(stroke
			(width 0.635)
			(type default)
		)
		(layer "In14.Cu")
	)
	(gr_line
		(start 239.81918 -401.97786)
		(end 239.81918 -397.5608)
		(stroke
			(width 0.2)
			(type default)
		)
		(layer "In14.Cu")
	)
	(gr_line
		(start 239.81918 -397.5608)
		(end 240.07826 -397.30172)
		(stroke
			(width 0.2)
			(type default)
		)
		(layer "In14.Cu")
	)
	(gr_line
		(start 239.86236 -402.29536)
		(end 275.44522 -402.29536)
		(stroke
			(width 0.508)
			(type default)
		)
		(layer "In14.Cu")
	)
	(gr_line
		(start 239.96904 -402.12772)
		(end 239.81918 -401.97786)
		(stroke
			(width 0.2)
			(type default)
		)
		(layer "In14.Cu")
	)
	(gr_line
		(start 240.06556 -397.14424)
		(end 239.67694 -397.53286)
		(stroke
			(width 0.508)
			(type default)
		)
		(layer "In14.Cu")
	)
	(gr_line
		(start 240.07826 -397.30172)
		(end 280.16454 -397.30172)
		(stroke
			(width 0.2)
			(type default)
		)
		(layer "In14.Cu")
	)
	(gr_line
		(start 270.49476 -420.95928)
		(end 275.680932 -415.773108)
		(stroke
			(width 0.635)
			(type default)
		)
		(layer "In14.Cu")
	)
	(gr_line
		(start 275.44522 -402.29536)
		(end 280.32202 -402.29536)
		(stroke
			(width 0.508)
			(type default)
		)
		(layer "In14.Cu")
	)
	(gr_line
		(start 275.680932 -415.773108)
		(end 275.680932 -415.7599)
		(stroke
			(width 0.635)
			(type default)
		)
		(layer "In14.Cu")
	)
	(gr_line
		(start 275.680932 -415.7599)
		(end 279.927812 -415.7599)
		(stroke
			(width 0.635)
			(type default)
		)
		(layer "In14.Cu")
	)
	(gr_line
		(start 279.927812 -415.7599)
		(end 280.51506 -415.172652)
		(stroke
			(width 0.635)
			(type default)
		)
		(layer "In14.Cu")
	)
	(gr_line
		(start 280.100532 -407.75382)
		(end 239.713008 -407.75382)
		(stroke
			(width 0.635)
			(type default)
		)
		(layer "In14.Cu")
	)
	(gr_line
		(start 280.16454 -397.30172)
		(end 280.34742 -397.4846)
		(stroke
			(width 0.2)
			(type default)
		)
		(layer "In14.Cu")
	)
	(gr_line
		(start 280.17978 -402.12772)
		(end 239.96904 -402.12772)
		(stroke
			(width 0.2)
			(type default)
		)
		(layer "In14.Cu")
	)
	(gr_line
		(start 280.24074 -397.14424)
		(end 240.06556 -397.14424)
		(stroke
			(width 0.508)
			(type default)
		)
		(layer "In14.Cu")
	)
	(gr_line
		(start 280.32202 -402.29536)
		(end 280.50998 -402.1074)
		(stroke
			(width 0.508)
			(type default)
		)
		(layer "In14.Cu")
	)
	(gr_line
		(start 280.34742 -401.96008)
		(end 280.17978 -402.12772)
		(stroke
			(width 0.2)
			(type default)
		)
		(layer "In14.Cu")
	)
	(gr_line
		(start 280.34742 -397.4846)
		(end 280.34742 -401.96008)
		(stroke
			(width 0.2)
			(type default)
		)
		(layer "In14.Cu")
	)
	(gr_line
		(start 280.50998 -402.1074)
		(end 280.50998 -397.41348)
		(stroke
			(width 0.508)
			(type default)
		)
		(layer "In14.Cu")
	)
	(gr_line
		(start 280.50998 -397.41348)
		(end 280.24074 -397.14424)
		(stroke
			(width 0.508)
			(type default)
		)
		(layer "In14.Cu")
	)
	(gr_line
		(start 280.51506 -415.172652)
		(end 280.51506 -408.168348)
		(stroke
			(width 0.635)
			(type default)
		)
		(layer "In14.Cu")
	)
	(gr_line
		(start 280.51506 -408.168348)
		(end 280.100532 -407.75382)
		(stroke
			(width 0.635)
			(type default)
		)
		(layer "In14.Cu")
	)
	(gr_poly
		(pts
			(xy 326.70242 -32.253428) (xy 326.70242 -31.360872) (xy 323.918326 -28.576778) (xy 321.00901 -31.486348)
			(xy 321.00901 -31.812484) (xy 323.807074 -34.610548) (xy 324.3453 -34.610548)
		)
		(stroke
			(width 0)
			(type solid)
		)
		(fill yes)
		(layer "In15.Cu")
		(net "GND")
	)
	(gr_poly
		(pts
			(xy 29.542486 -166.656004) (xy 29.542486 -162.998404) (xy 29.491686 -162.947604) (xy 25.834086 -162.947604)
			(xy 25.783286 -162.998404) (xy 25.783286 -166.656004) (xy 25.834086 -166.706804) (xy 29.491686 -166.706804)
		)
		(stroke
			(width 0)
			(type solid)
		)
		(fill yes)
		(layer "In15.Cu")
		(net "GND")
	)
	(gr_poly
		(pts
			(xy 30.154118 -335.06537) (xy 30.154118 -330.49591) (xy 29.138118 -329.47991) (xy 18.368518 -329.47991)
			(xy 17.18564 -330.662788) (xy 17.18564 -336.111088) (xy 17.407382 -336.33283) (xy 28.886658 -336.33283)
		)
		(stroke
			(width 0)
			(type solid)
		)
		(fill yes)
		(layer "In15.Cu")
		(net "P12V_S3_AUX_CPU1_NVDIMM")
	)
	(gr_poly
		(pts
			(xy 33.94075 -131.462272) (xy 33.94075 -127.804672) (xy 33.88995 -127.753872) (xy 30.23235 -127.753872)
			(xy 30.18155 -127.804672) (xy 30.18155 -131.462272) (xy 30.23235 -131.513072) (xy 33.88995 -131.513072)
		)
		(stroke
			(width 0)
			(type solid)
		)
		(fill yes)
		(layer "In15.Cu")
		(net "GND")
	)
	(gr_poly
		(pts
			(xy 217.33256 -26.947368) (xy 217.33256 -25.212548) (xy 216.7382 -24.618188) (xy 213.22538 -24.618188)
			(xy 213.03488 -24.808688) (xy 213.03488 -27.396948) (xy 213.26856 -27.630628) (xy 216.6493 -27.630628)
		)
		(stroke
			(width 0)
			(type solid)
		)
		(fill yes)
		(layer "In15.Cu")
		(net "GND")
	)
	(gr_poly
		(pts
			(xy 249.511312 -89.374472) (xy 249.511312 -86.478872) (xy 249.333512 -86.301072) (xy 245.904512 -86.301072)
			(xy 245.752112 -86.453472) (xy 245.752112 -89.653872) (xy 245.929912 -89.831672) (xy 249.054112 -89.831672)
		)
		(stroke
			(width 0)
			(type solid)
		)
		(fill yes)
		(layer "In15.Cu")
		(net "GND")
	)
	(gr_poly
		(pts
			(xy 337.936586 -70.187058) (xy 337.936586 -67.25412) (xy 337.568032 -66.885566) (xy 333.806038 -66.885566)
			(xy 333.422244 -67.26936) (xy 333.422244 -70.586092) (xy 333.54518 -70.709028) (xy 337.414616 -70.709028)
		)
		(stroke
			(width 0)
			(type solid)
		)
		(fill yes)
		(layer "In15.Cu")
		(net "GND")
	)
	(gr_poly
		(pts
			(xy 427.559216 -138.21791) (xy 427.559216 -134.61111) (xy 427.508416 -134.56031) (xy 423.901616 -134.56031)
			(xy 423.850816 -134.61111) (xy 423.850816 -138.21791) (xy 423.901616 -138.26871) (xy 427.508416 -138.26871)
		)
		(stroke
			(width 0)
			(type solid)
		)
		(fill yes)
		(layer "In15.Cu")
		(net "GND")
	)
	(gr_poly
		(pts
			(xy 230.38054 -434.93182) (xy 230.38054 -427.00194) (xy 230.0732 -426.6946) (xy 230.0732 -421.7162)
			(xy 231.15524 -420.63416) (xy 270.3576 -420.63416) (xy 275.70684 -415.28492) (xy 279.95372 -415.28492)
			(xy 280.19756 -415.04108) (xy 280.19756 -408.29992) (xy 279.96896 -408.07132) (xy 239.84458 -408.07132)
			(xy 233.0704 -414.8455) (xy 207.34528 -414.8455) (xy 206.49184 -415.69894) (xy 206.49184 -435.39156)
			(xy 207.63484 -436.53456) (xy 228.7778 -436.53456)
		)
		(stroke
			(width 0)
			(type solid)
		)
		(fill yes)
		(layer "In15.Cu")
		(net "P12V_PSU")
	)
	(gr_poly
		(pts
			(xy 42.0624 -369.484148) (xy 42.0624 -361.660948) (xy 41.1988 -360.797348) (xy 36.7792 -360.797348)
			(xy 33.9852 -358.003348) (xy 33.9852 -338.775548) (xy 32.7152 -337.505548)
			(arc
				(start 30.816804 -337.505548)
				(mid 30.547818 -337.616521)
				(end 30.278832 -337.505548)
			)
			(xy 17.907 -337.505548) (xy 17.5006 -337.911948) (xy 17.5006 -341.747348) (xy 22.1742 -346.420948)
			(xy 22.1742 -369.585748) (xy 22.606 -370.017548) (xy 41.529 -370.017548)
		)
		(stroke
			(width 0)
			(type solid)
		)
		(fill yes)
		(layer "In15.Cu")
		(net "P12V_AUX")
	)
	(gr_poly
		(pts
			(arc
				(start 50.738786 -187.797948)
				(mid 50.464974 -187.797948)
				(end 50.738786 -187.797948)
			)
		)
		(stroke
			(width 0)
			(type solid)
		)
		(fill yes)
		(layer "In15.Cu")
		(net "GND")
	)
	(gr_poly
		(pts
			(arc
				(start 50.865786 -186.146948)
				(mid 50.591974 -186.146948)
				(end 50.865786 -186.146948)
			)
		)
		(stroke
			(width 0)
			(type solid)
		)
		(fill yes)
		(layer "In15.Cu")
		(net "GND")
	)
	(gr_poly
		(pts
			(arc
				(start 52.643786 -185.892948)
				(mid 52.369974 -185.892948)
				(end 52.643786 -185.892948)
			)
		)
		(stroke
			(width 0)
			(type solid)
		)
		(fill yes)
		(layer "In15.Cu")
		(net "GND")
	)
	(gr_poly
		(pts
			(arc
				(start 53.786786 -188.051948)
				(mid 53.512974 -188.051948)
				(end 53.786786 -188.051948)
			)
		)
		(stroke
			(width 0)
			(type solid)
		)
		(fill yes)
		(layer "In15.Cu")
		(net "GND")
	)
	(gr_poly
		(pts
			(arc
				(start 133.957314 -129.878074)
				(mid 133.683502 -129.878074)
				(end 133.957314 -129.878074)
			)
		)
		(stroke
			(width 0)
			(type solid)
		)
		(fill yes)
		(layer "In15.Cu")
		(net "GND")
	)
	(gr_poly
		(pts
			(arc
				(start 133.957568 -131.271518)
				(mid 133.683756 -131.271518)
				(end 133.957568 -131.271518)
			)
		)
		(stroke
			(width 0)
			(type solid)
		)
		(fill yes)
		(layer "In15.Cu")
		(net "GND")
	)
	(gr_poly
		(pts
			(arc
				(start 134.005574 -128.48082)
				(mid 133.731762 -128.48082)
				(end 134.005574 -128.48082)
			)
		)
		(stroke
			(width 0)
			(type solid)
		)
		(fill yes)
		(layer "In15.Cu")
		(net "GND")
	)
	(gr_poly
		(pts
			(arc
				(start 145.348706 -140.2588)
				(mid 145.074894 -140.2588)
				(end 145.348706 -140.2588)
			)
		)
		(stroke
			(width 0)
			(type solid)
		)
		(fill yes)
		(layer "In15.Cu")
		(net "GND")
	)
	(gr_poly
		(pts
			(arc
				(start 150.930356 -135.814308)
				(mid 150.656544 -135.814308)
				(end 150.930356 -135.814308)
			)
		)
		(stroke
			(width 0)
			(type solid)
		)
		(fill yes)
		(layer "In15.Cu")
		(net "GND")
	)
	(gr_poly
		(pts
			(arc
				(start 156.092906 -139.9032)
				(mid 155.819094 -139.9032)
				(end 156.092906 -139.9032)
			)
		)
		(stroke
			(width 0)
			(type solid)
		)
		(fill yes)
		(layer "In15.Cu")
		(net "GND")
	)
	(gr_poly
		(pts
			(arc
				(start 156.11475 -136.556496)
				(mid 155.840938 -136.556496)
				(end 156.11475 -136.556496)
			)
		)
		(stroke
			(width 0)
			(type solid)
		)
		(fill yes)
		(layer "In15.Cu")
		(net "GND")
	)
	(gr_poly
		(pts
			(arc
				(start 177.581306 -134.7978)
				(mid 177.307494 -134.7978)
				(end 177.581306 -134.7978)
			)
		)
		(stroke
			(width 0)
			(type solid)
		)
		(fill yes)
		(layer "In15.Cu")
		(net "GND")
	)
	(gr_poly
		(pts
			(arc
				(start 183.707786 -132.425948)
				(mid 183.433974 -132.425948)
				(end 183.707786 -132.425948)
			)
		)
		(stroke
			(width 0)
			(type solid)
		)
		(fill yes)
		(layer "In15.Cu")
		(net "GND")
	)
	(gr_poly
		(pts
			(arc
				(start 185.574686 -128.577848)
				(mid 185.300874 -128.577848)
				(end 185.574686 -128.577848)
			)
		)
		(stroke
			(width 0)
			(type solid)
		)
		(fill yes)
		(layer "In15.Cu")
		(net "GND")
	)
	(gr_poly
		(pts
			(arc
				(start 189.272926 -128.658366)
				(mid 188.999114 -128.658366)
				(end 189.272926 -128.658366)
			)
		)
		(stroke
			(width 0)
			(type solid)
		)
		(fill yes)
		(layer "In15.Cu")
		(net "GND")
	)
	(gr_poly
		(pts
			(arc
				(start 196.280786 -134.711948)
				(mid 196.006974 -134.711948)
				(end 196.280786 -134.711948)
			)
		)
		(stroke
			(width 0)
			(type solid)
		)
		(fill yes)
		(layer "In15.Cu")
		(net "GND")
	)
	(gr_poly
		(pts
			(arc
				(start 214.464646 -115.143788)
				(mid 214.190834 -115.143788)
				(end 214.464646 -115.143788)
			)
		)
		(stroke
			(width 0)
			(type solid)
		)
		(fill yes)
		(layer "In15.Cu")
		(net "GND")
	)
	(gr_poly
		(pts
			(arc
				(start 215.485726 -112.748568)
				(mid 215.211914 -112.748568)
				(end 215.485726 -112.748568)
			)
		)
		(stroke
			(width 0)
			(type solid)
		)
		(fill yes)
		(layer "In15.Cu")
		(net "GND")
	)
	(gr_poly
		(pts
			(arc
				(start 184.984644 -90.515948)
				(mid 184.697116 -90.515948)
				(end 184.984644 -90.515948)
			)
		)
		(stroke
			(width 0)
			(type solid)
		)
		(fill yes)
		(layer "In15.Cu")
		(net "GND")
	)
	(gr_poly
		(pts
			(arc
				(start 96.97212 -364.139988)
				(mid 96.60636 -364.139988)
				(end 96.97212 -364.139988)
			)
		)
		(stroke
			(width 0)
			(type solid)
		)
		(fill yes)
		(layer "In15.Cu")
		(net "GND")
	)
	(gr_poly
		(pts
			(arc
				(start 150.250652 -39.515288)
				(mid 150.54834 -39.354795)
				(end 150.846028 -39.515288)
			)
			(xy 151.5364 -39.515288) (xy 151.70658 -39.345108) (xy 151.70658 -35.753548) (xy 151.43226 -35.479228)
			(xy 149.09292 -35.479228) (xy 148.80082 -35.771328) (xy 148.80082 -38.727888)
			(arc
				(start 148.84527 -38.772338)
				(mid 148.914265 -38.875457)
				(end 148.938488 -38.997128)
			)
			(xy 148.938488 -39.335456) (xy 149.11832 -39.515288)
		)
		(stroke
			(width 0)
			(type solid)
		)
		(fill yes)
		(layer "In15.Cu")
		(net "GND")
	)
	(gr_poly
		(pts
			(arc
				(start 300.7233 -187.731908)
				(mid 300.35754 -187.731908)
				(end 300.7233 -187.731908)
			)
		)
		(stroke
			(width 0)
			(type solid)
		)
		(fill yes)
		(layer "In15.Cu")
		(net "GND")
	)
	(gr_poly
		(pts
			(arc
				(start 306.2224 -191.524128)
				(mid 305.85664 -191.524128)
				(end 306.2224 -191.524128)
			)
		)
		(stroke
			(width 0)
			(type solid)
		)
		(fill yes)
		(layer "In15.Cu")
		(net "GND")
	)
	(gr_poly
		(pts
			(arc
				(start 346.90304 -363.510068)
				(mid 346.53728 -363.510068)
				(end 346.90304 -363.510068)
			)
		)
		(stroke
			(width 0)
			(type solid)
		)
		(fill yes)
		(layer "In15.Cu")
		(net "GND")
	)
	(gr_poly
		(pts
			(arc
				(start 348.66072 -364.787688)
				(mid 348.29496 -364.787688)
				(end 348.66072 -364.787688)
			)
		)
		(stroke
			(width 0)
			(type solid)
		)
		(fill yes)
		(layer "In15.Cu")
		(net "GND")
	)
	(gr_poly
		(pts
			(arc
				(start 432.55946 -140.396468)
				(mid 432.1937 -140.396468)
				(end 432.55946 -140.396468)
			)
		)
		(stroke
			(width 0)
			(type solid)
		)
		(fill yes)
		(layer "In15.Cu")
		(net "GND")
	)
	(gr_poly
		(pts
			(arc
				(start 434.64988 -136.693148)
				(mid 434.28412 -136.693148)
				(end 434.64988 -136.693148)
			)
		)
		(stroke
			(width 0)
			(type solid)
		)
		(fill yes)
		(layer "In15.Cu")
		(net "GND")
	)
	(gr_poly
		(pts
			(xy 245.0465 -251.770388) (xy 245.0465 -247.239028) (xy 244.62232 -246.814848) (xy 240.538 -246.814848)
			(xy 240.22812 -247.124728) (xy 240.22812 -249.273568) (xy 240.806222 -249.273568) (xy 240.810293 -249.217946)
			(xy 240.822419 -249.163509) (xy 240.842342 -249.111418) (xy 240.869638 -249.062783) (xy 240.903724 -249.01864)
			(xy 240.943873 -248.979931) (xy 240.989231 -248.94748) (xy 241.038831 -248.921979) (xy 241.091615 -248.903972)
			(xy 241.146458 -248.893842) (xy 241.202192 -248.891805) (xy 241.257629 -248.897905) (xy 241.311586 -248.912011)
			(xy 241.362915 -248.933823) (xy 241.410521 -248.962877) (xy 241.453389 -248.998552) (xy 241.490606 -249.040089)
			(xy 241.521379 -249.086602) (xy 241.545051 -249.137099) (xy 241.561119 -249.190506) (xy 241.569239 -249.245682)
			(xy 241.569748 -249.273568) (xy 241.569239 -249.301454) (xy 241.561119 -249.35663) (xy 241.545051 -249.410037)
			(xy 241.521379 -249.460534) (xy 241.490606 -249.507047) (xy 241.453389 -249.548584) (xy 241.410521 -249.584259)
			(xy 241.362915 -249.613313) (xy 241.311586 -249.635125) (xy 241.257629 -249.649231) (xy 241.202192 -249.655331)
			(xy 241.146458 -249.653294) (xy 241.091615 -249.643164) (xy 241.038831 -249.625157) (xy 240.989231 -249.599656)
			(xy 240.943873 -249.567205) (xy 240.903724 -249.528496) (xy 240.869638 -249.484353) (xy 240.842342 -249.435718)
			(xy 240.822419 -249.383627) (xy 240.810293 -249.32919) (xy 240.806222 -249.273568) (xy 240.22812 -249.273568)
			(xy 240.22812 -251.955808) (xy 240.45164 -252.179328) (xy 244.63756 -252.179328)
		)
		(stroke
			(width 0)
			(type solid)
		)
		(fill yes)
		(layer "In15.Cu")
		(net "GND")
	)
	(gr_poly
		(pts
			(xy 431.359564 -183.74868)
			(arc
				(start 431.334672 -183.713628)
				(mid 431.285035 -183.615102)
				(end 431.26787 -183.50611)
			)
			(arc
				(start 431.26787 -183.50611)
				(mid 431.372172 -183.254304)
				(end 431.623978 -183.150002)
			)
			(arc
				(start 431.623978 -183.150002)
				(mid 431.753034 -183.174309)
				(end 431.864516 -183.243728)
			)
			(xy 432.039776 -183.068468) (xy 432.039776 -182.996586)
			(arc
				(start 432.009042 -182.989728)
				(mid 431.801591 -182.866847)
				(end 431.71999 -182.63997)
			)
			(arc
				(start 431.71999 -182.63997)
				(mid 431.798668 -182.416798)
				(end 431.999898 -182.292244)
			)
			(xy 432.039776 -182.283354)
			(arc
				(start 432.039776 -180.795422)
				(mid 432.000605 -180.715265)
				(end 431.913284 -180.69687)
			)
			(arc
				(start 431.598832 -181.011576)
				(mid 431.495682 -181.080405)
				(end 431.374042 -181.10454)
			)
			(xy 425.699174 -181.10454) (xy 425.478448 -181.32552) (xy 425.478448 -184.085992) (xy 431.022506 -184.085992)
		)
		(stroke
			(width 0)
			(type solid)
		)
		(fill yes)
		(layer "In15.Cu")
		(net "GND")
	)
	(gr_poly
		(pts
			(xy 10.35558 -100.975668)
			(arc
				(start 10.35558 -100.736908)
				(mid 10.269496 -100.495608)
				(end 10.35558 -100.254308)
			)
			(arc
				(start 10.35558 -100.03917)
				(mid 10.302076 -99.949675)
				(end 10.197846 -99.954334)
			)
			(arc
				(start 10.197846 -99.954334)
				(mid 10.09724 -100.001603)
				(end 9.98728 -100.017834)
			)
			(arc
				(start 9.98728 -100.017834)
				(mid 9.605772 -99.636326)
				(end 9.98728 -99.254818)
			)
			(arc
				(start 9.98728 -99.254818)
				(mid 10.097231 -99.271082)
				(end 10.197846 -99.318318)
			)
			(arc
				(start 10.197846 -99.318318)
				(mid 10.302135 -99.323088)
				(end 10.35558 -99.233482)
			)
			(xy 10.35558 -98.755962)
			(arc
				(start 10.315702 -98.747072)
				(mid 10.017245 -98.374708)
				(end 10.315702 -98.002344)
			)
			(xy 10.35558 -97.993454) (xy 10.35558 -97.711768) (xy 9.72566 -97.081848) (xy 6.02742 -97.081848)
			(xy 5.44576 -97.663508) (xy 5.44576 -100.912168) (xy 5.91312 -101.379528) (xy 9.95172 -101.379528)
		)
		(stroke
			(width 0)
			(type solid)
		)
		(fill yes)
		(layer "In15.Cu")
		(net "GND")
	)
	(gr_poly
		(pts
			(arc
				(start 467.7029 -169.388536)
				(mid 467.728891 -169.402542)
				(end 467.758272 -169.399712)
			)
			(xy 467.772496 -169.393616) (xy 467.789514 -169.36847)
			(arc
				(start 467.789514 -82.82813)
				(mid 467.980666 -81.867526)
				(end 468.524844 -81.053178)
			)
			(arc
				(start 470.853262 -78.72476)
				(mid 471.176045 -78.241587)
				(end 471.28938 -77.671676)
			)
			(arc
				(start 471.28938 -26.830528)
				(mid 471.282263 -26.804596)
				(end 471.262964 -26.785824)
			)
			(xy 471.17254 -26.736294) (xy 471.145108 -26.73731)
			(arc
				(start 471.13317 -26.744676)
				(mid 470.972569 -26.843078)
				(end 470.808558 -26.935684)
			)
			(arc
				(start 470.808558 -26.935684)
				(mid 470.789062 -26.95436)
				(end 470.781888 -26.980388)
			)
			(arc
				(start 470.781888 -77.67193)
				(mid 470.707224 -78.04756)
				(end 470.494614 -78.366112)
			)
			(arc
				(start 468.166196 -80.69453)
				(mid 467.512084 -81.673433)
				(end 467.282276 -82.82813)
			)
			(xy 467.282276 -115.104926) (xy 467.284816 -115.116356)
			(arc
				(start 467.287864 -115.121944)
				(mid 467.319142 -115.206449)
				(end 467.329774 -115.295934)
			)
			(arc
				(start 467.329774 -115.295934)
				(mid 467.31919 -115.38543)
				(end 467.287864 -115.469924)
			)
			(xy 467.284816 -115.475512) (xy 467.282276 -115.486942)
			(arc
				(start 467.282276 -168.94683)
				(mid 467.28606 -168.966324)
				(end 467.297008 -168.982898)
			)
		)
		(stroke
			(width 0)
			(type solid)
		)
		(fill yes)
		(layer "In15.Cu")
		(net "GND")
	)
	(gr_poly
		(pts
			(xy 72.02678 -179.886864) (xy 72.02678 -174.495968) (xy 70.66915 -173.138338) (xy 68.55587 -173.138338)
			(xy 66.480182 -171.06265) (xy 61.143134 -171.06265) (xy 61.110114 -171.09567) (xy 61.061854 -171.09567)
			(xy 60.661804 -171.49572) (xy 60.661804 -177.947504) (xy 67.755004 -177.947504) (xy 67.755004 -177.862808)
			(xy 67.763055 -177.778494) (xy 67.779084 -177.695328) (xy 67.802945 -177.614061) (xy 67.834424 -177.535431)
			(xy 67.873235 -177.46015) (xy 67.919025 -177.388898) (xy 67.971381 -177.322322) (xy 68.029829 -177.261024)
			(xy 68.093839 -177.205559) (xy 68.162831 -177.15643) (xy 68.236181 -177.114081) (xy 68.313224 -177.078897)
			(xy 68.393263 -177.051195) (xy 68.475572 -177.031227) (xy 68.559407 -177.019174) (xy 68.644008 -177.015144)
			(xy 68.728609 -177.019174) (xy 68.812444 -177.031227) (xy 68.894753 -177.051195) (xy 68.974792 -177.078897)
			(xy 69.051835 -177.114081) (xy 69.125185 -177.15643) (xy 69.194177 -177.205559) (xy 69.258187 -177.261024)
			(xy 69.316635 -177.322322) (xy 69.368991 -177.388898) (xy 69.414781 -177.46015) (xy 69.453592 -177.535431)
			(xy 69.485071 -177.614061) (xy 69.508932 -177.695328) (xy 69.524961 -177.778494) (xy 69.533012 -177.862808)
			(xy 69.533516 -177.905156) (xy 69.728593 -177.905156) (xy 69.732615 -177.819436) (xy 69.744646 -177.734468)
			(xy 69.764582 -177.651001) (xy 69.792245 -177.569767) (xy 69.827394 -177.491481) (xy 69.86972 -177.41683)
			(xy 69.918849 -177.346471) (xy 69.974352 -177.281021) (xy 70.035739 -177.221057) (xy 70.102472 -177.167104)
			(xy 70.173964 -177.119637) (xy 70.249586 -177.079073) (xy 70.328675 -177.045769) (xy 70.410535 -177.020017)
			(xy 70.494446 -177.002044) (xy 70.579672 -176.992008) (xy 70.665464 -176.989996) (xy 70.751066 -176.996027)
			(xy 70.835728 -177.010047) (xy 70.918705 -177.031933) (xy 70.999268 -177.061494) (xy 71.076708 -177.098468)
			(xy 71.150347 -177.142532) (xy 71.219535 -177.193298) (xy 71.283666 -177.250319) (xy 71.342175 -177.313095)
			(xy 71.394548 -177.381075) (xy 71.440326 -177.45366) (xy 71.479106 -177.530212) (xy 71.510547 -177.61006)
			(xy 71.534373 -177.692501) (xy 71.550374 -177.776811) (xy 71.558409 -177.862249) (xy 71.558912 -177.905156)
			(xy 71.558409 -177.948063) (xy 71.550374 -178.033501) (xy 71.534373 -178.117811) (xy 71.510547 -178.200252)
			(xy 71.479106 -178.2801) (xy 71.440326 -178.356652) (xy 71.394548 -178.429237) (xy 71.342175 -178.497217)
			(xy 71.283666 -178.559993) (xy 71.219535 -178.617014) (xy 71.150347 -178.66778) (xy 71.076708 -178.711844)
			(xy 70.999268 -178.748818) (xy 70.918705 -178.778379) (xy 70.835728 -178.800265) (xy 70.751066 -178.814285)
			(xy 70.665464 -178.820316) (xy 70.579672 -178.818304) (xy 70.494446 -178.808268) (xy 70.410535 -178.790295)
			(xy 70.328675 -178.764543) (xy 70.249586 -178.731239) (xy 70.173964 -178.690675) (xy 70.102472 -178.643208)
			(xy 70.035739 -178.589255) (xy 69.974352 -178.529291) (xy 69.918849 -178.463841) (xy 69.86972 -178.393482)
			(xy 69.827394 -178.318831) (xy 69.792245 -178.240545) (xy 69.764582 -178.159311) (xy 69.744646 -178.075844)
			(xy 69.732615 -177.990876) (xy 69.728593 -177.905156) (xy 69.533516 -177.905156) (xy 69.533012 -177.947504)
			(xy 69.524961 -178.031818) (xy 69.508932 -178.114984) (xy 69.485071 -178.196251) (xy 69.453592 -178.274881)
			(xy 69.414781 -178.350162) (xy 69.368991 -178.421414) (xy 69.316635 -178.48799) (xy 69.258187 -178.549288)
			(xy 69.194177 -178.604753) (xy 69.125185 -178.653882) (xy 69.051835 -178.696231) (xy 68.974792 -178.731415)
			(xy 68.894753 -178.759117) (xy 68.812444 -178.779085) (xy 68.728609 -178.791138) (xy 68.644008 -178.795169)
			(xy 68.559407 -178.791138) (xy 68.475572 -178.779085) (xy 68.393263 -178.759117) (xy 68.313224 -178.731415)
			(xy 68.236181 -178.696231) (xy 68.162831 -178.653882) (xy 68.093839 -178.604753) (xy 68.029829 -178.549288)
			(xy 67.971381 -178.48799) (xy 67.919025 -178.421414) (xy 67.873235 -178.350162) (xy 67.834424 -178.274881)
			(xy 67.802945 -178.196251) (xy 67.779084 -178.114984) (xy 67.763055 -178.031818) (xy 67.755004 -177.947504)
			(xy 60.661804 -177.947504) (xy 60.661804 -180.67401) (xy 61.148468 -181.160674) (xy 70.75297 -181.160674)
		)
		(stroke
			(width 0)
			(type solid)
		)
		(fill yes)
		(layer "In15.Cu")
		(net "PVCCFA_EHV_CPU1")
	)
	(gr_poly
		(pts
			(xy 409.22956 -156.088588) (xy 409.22956 -148.760688) (xy 408.62758 -148.158708) (xy 400.4818 -148.158708)
			(xy 399.31594 -149.324568) (xy 399.31594 -150.339552) (xy 399.642589 -150.339552) (xy 399.646611 -150.253832)
			(xy 399.658642 -150.168864) (xy 399.678578 -150.085397) (xy 399.706241 -150.004163) (xy 399.74139 -149.925877)
			(xy 399.783716 -149.851226) (xy 399.832845 -149.780867) (xy 399.888348 -149.715417) (xy 399.949735 -149.655453)
			(xy 400.016468 -149.6015) (xy 400.08796 -149.554033) (xy 400.163582 -149.513469) (xy 400.242671 -149.480165)
			(xy 400.324531 -149.454413) (xy 400.408442 -149.43644) (xy 400.493668 -149.426404) (xy 400.57946 -149.424392)
			(xy 400.665062 -149.430423) (xy 400.749724 -149.444443) (xy 400.832701 -149.466329) (xy 400.913264 -149.49589)
			(xy 400.990704 -149.532864) (xy 401.064343 -149.576928) (xy 401.133531 -149.627694) (xy 401.197662 -149.684715)
			(xy 401.256171 -149.747491) (xy 401.308544 -149.815471) (xy 401.354322 -149.888056) (xy 401.393102 -149.964608)
			(xy 401.424543 -150.044456) (xy 401.448369 -150.126897) (xy 401.46437 -150.211207) (xy 401.472405 -150.296645)
			(xy 401.472908 -150.339552) (xy 401.472405 -150.382459) (xy 401.46437 -150.467897) (xy 401.448369 -150.552207)
			(xy 401.424543 -150.634648) (xy 401.393102 -150.714496) (xy 401.354322 -150.791048) (xy 401.308544 -150.863633)
			(xy 401.256171 -150.931613) (xy 401.197662 -150.994389) (xy 401.133531 -151.05141) (xy 401.064343 -151.102176)
			(xy 400.990704 -151.14624) (xy 400.913264 -151.183214) (xy 400.832701 -151.212775) (xy 400.749724 -151.234661)
			(xy 400.665062 -151.248681) (xy 400.57946 -151.254712) (xy 400.493668 -151.2527) (xy 400.408442 -151.242664)
			(xy 400.324531 -151.224691) (xy 400.242671 -151.198939) (xy 400.163582 -151.165635) (xy 400.08796 -151.125071)
			(xy 400.016468 -151.077604) (xy 399.949735 -151.023651) (xy 399.888348 -150.963687) (xy 399.832845 -150.898237)
			(xy 399.783716 -150.827878) (xy 399.74139 -150.753227) (xy 399.706241 -150.674941) (xy 399.678578 -150.593707)
			(xy 399.658642 -150.51024) (xy 399.646611 -150.425272) (xy 399.642589 -150.339552) (xy 399.31594 -150.339552)
			(xy 399.31594 -152.381896) (xy 399.668996 -152.381896) (xy 399.668996 -152.2972) (xy 399.677047 -152.212886)
			(xy 399.693076 -152.12972) (xy 399.716937 -152.048453) (xy 399.748416 -151.969823) (xy 399.787227 -151.894542)
			(xy 399.833017 -151.82329) (xy 399.885373 -151.756714) (xy 399.943821 -151.695416) (xy 400.007831 -151.639951)
			(xy 400.076823 -151.590822) (xy 400.150173 -151.548473) (xy 400.227216 -151.513289) (xy 400.307255 -151.485587)
			(xy 400.389564 -151.465619) (xy 400.473399 -151.453566) (xy 400.558 -151.449536) (xy 400.642601 -151.453566)
			(xy 400.726436 -151.465619) (xy 400.808745 -151.485587) (xy 400.888784 -151.513289) (xy 400.965827 -151.548473)
			(xy 401.039177 -151.590822) (xy 401.108169 -151.639951) (xy 401.172179 -151.695416) (xy 401.230627 -151.756714)
			(xy 401.282983 -151.82329) (xy 401.328773 -151.894542) (xy 401.367584 -151.969823) (xy 401.399063 -152.048453)
			(xy 401.422924 -152.12972) (xy 401.438953 -152.212886) (xy 401.447004 -152.2972) (xy 401.447508 -152.339548)
			(xy 401.447004 -152.381896) (xy 401.438953 -152.46621) (xy 401.422924 -152.549376) (xy 401.399063 -152.630643)
			(xy 401.367584 -152.709273) (xy 401.328773 -152.784554) (xy 401.282983 -152.855806) (xy 401.230627 -152.922382)
			(xy 401.172179 -152.98368) (xy 401.108169 -153.039145) (xy 401.039177 -153.088274) (xy 400.965827 -153.130623)
			(xy 400.888784 -153.165807) (xy 400.808745 -153.193509) (xy 400.726436 -153.213477) (xy 400.642601 -153.22553)
			(xy 400.558 -153.229561) (xy 400.473399 -153.22553) (xy 400.389564 -153.213477) (xy 400.307255 -153.193509)
			(xy 400.227216 -153.165807) (xy 400.150173 -153.130623) (xy 400.076823 -153.088274) (xy 400.007831 -153.039145)
			(xy 399.943821 -152.98368) (xy 399.885373 -152.922382) (xy 399.833017 -152.855806) (xy 399.787227 -152.784554)
			(xy 399.748416 -152.709273) (xy 399.716937 -152.630643) (xy 399.693076 -152.549376) (xy 399.677047 -152.46621)
			(xy 399.668996 -152.381896) (xy 399.31594 -152.381896) (xy 399.31594 -156.131768) (xy 399.515838 -156.331666)
			(xy 399.526776 -156.341811) (xy 399.553089 -156.355838) (xy 399.582331 -156.361675) (xy 399.612012 -156.358822)
			(xy 399.639608 -156.347525) (xy 399.662768 -156.328743) (xy 399.679521 -156.304076) (xy 399.684494 -156.29001)
			(xy 399.697296 -156.250582) (xy 399.729071 -156.174009) (xy 399.76764 -156.100624) (xy 399.812689 -156.031028)
			(xy 399.863847 -155.965791) (xy 399.920696 -155.905449) (xy 399.98277 -155.850495) (xy 400.049559 -155.801381)
			(xy 400.120516 -155.758509) (xy 400.19506 -155.722229) (xy 400.27258 -155.692841) (xy 400.35244 -155.670583)
			(xy 400.433985 -155.65564) (xy 400.516548 -155.648133) (xy 400.558 -155.647644) (xy 400.601441 -155.648157)
			(xy 400.687931 -155.656394) (xy 400.773251 -155.672794) (xy 400.856631 -155.697208) (xy 400.937322 -155.729418)
			(xy 401.014595 -155.769133) (xy 401.087755 -155.815995) (xy 401.156142 -155.869581) (xy 401.219141 -155.92941)
			(xy 401.276185 -155.994943) (xy 401.326758 -156.065588) (xy 401.370406 -156.14071) (xy 401.406735 -156.219631)
			(xy 401.435418 -156.301641) (xy 401.456197 -156.386001) (xy 401.468885 -156.471952) (xy 401.471638 -156.515308)
			(xy 401.474178 -156.563568) (xy 408.75458 -156.563568)
		)
		(stroke
			(width 0)
			(type solid)
		)
		(fill yes)
		(layer "In15.Cu")
		(net "PVCCFA_EHV_CPU0")
	)
	(gr_poly
		(pts
			(xy 197.77329 -114.205258) (xy 197.791272 -114.187899) (xy 197.831682 -114.158487) (xy 197.8762 -114.135767)
			(xy 197.923727 -114.120301) (xy 197.97309 -114.11247) (xy 197.99808 -114.11204) (xy 198.406512 -114.11204)
			(xy 198.406512 -113.551208) (xy 198.406058 -113.53703) (xy 198.398276 -113.509763) (xy 198.383284 -113.485695)
			(xy 198.362242 -113.466689) (xy 198.336778 -113.454214) (xy 198.308863 -113.449236) (xy 198.280657 -113.45214)
			(xy 198.26732 -113.456974) (xy 198.244624 -113.465664) (xy 198.197587 -113.477883) (xy 198.149379 -113.484041)
			(xy 198.12508 -113.484406) (xy 198.09783 -113.483919) (xy 198.043885 -113.47616) (xy 197.991592 -113.460803)
			(xy 197.942018 -113.438161) (xy 197.89617 -113.408694) (xy 197.854983 -113.373003) (xy 197.819294 -113.331814)
			(xy 197.789829 -113.285964) (xy 197.76719 -113.236389) (xy 197.751836 -113.184096) (xy 197.74408 -113.13015)
			(xy 197.74408 -113.07565) (xy 197.751836 -113.021704) (xy 197.76719 -112.969411) (xy 197.789829 -112.919836)
			(xy 197.819294 -112.873986) (xy 197.854983 -112.832797) (xy 197.89617 -112.797106) (xy 197.942018 -112.767639)
			(xy 197.991592 -112.744997) (xy 198.043885 -112.72964) (xy 198.09783 -112.721881) (xy 198.12508 -112.72139)
			(xy 198.153458 -112.72191) (xy 198.209586 -112.730317) (xy 198.26385 -112.746949) (xy 198.289672 -112.758728)
			(xy 198.303113 -112.7646) (xy 198.332072 -112.769183) (xy 198.361141 -112.765354) (xy 198.387926 -112.75343)
			(xy 198.410222 -112.73439) (xy 198.426195 -112.709804) (xy 198.43453 -112.681694) (xy 198.43496 -112.667034)
			(xy 198.43496 -112.560862) (xy 198.434485 -112.5462) (xy 198.426171 -112.518081) (xy 198.41021 -112.493484)
			(xy 198.387918 -112.474434) (xy 198.361132 -112.462504) (xy 198.332061 -112.458675) (xy 198.3031 -112.463265)
			(xy 198.289672 -112.469168) (xy 198.263848 -112.480944) (xy 198.209585 -112.497581) (xy 198.153458 -112.505999)
			(xy 198.12508 -112.506506) (xy 198.09783 -112.506019) (xy 198.043885 -112.49826) (xy 197.991592 -112.482903)
			(xy 197.942018 -112.460261) (xy 197.89617 -112.430794) (xy 197.854983 -112.395103) (xy 197.819294 -112.353914)
			(xy 197.789829 -112.308064) (xy 197.76719 -112.258489) (xy 197.751836 -112.206196) (xy 197.74408 -112.15225)
			(xy 197.74408 -112.09775) (xy 197.751836 -112.043804) (xy 197.76719 -111.991511) (xy 197.789829 -111.941936)
			(xy 197.819294 -111.896086) (xy 197.854983 -111.854897) (xy 197.89617 -111.819206) (xy 197.942018 -111.789739)
			(xy 197.991592 -111.767097) (xy 198.043885 -111.75174) (xy 198.09783 -111.743981) (xy 198.12508 -111.74349)
			(xy 198.153458 -111.74401) (xy 198.209586 -111.752417) (xy 198.26385 -111.769049) (xy 198.289672 -111.780828)
			(xy 198.303113 -111.7867) (xy 198.332072 -111.791283) (xy 198.361141 -111.787454) (xy 198.387926 -111.77553)
			(xy 198.410222 -111.75649) (xy 198.426195 -111.731904) (xy 198.43453 -111.703794) (xy 198.43496 -111.689134)
			(xy 198.43496 -111.369348) (xy 197.98792 -110.922308) (xy 193.381376 -110.922308) (xy 193.367067 -110.922795)
			(xy 193.339573 -110.930735) (xy 193.315358 -110.945985) (xy 193.296319 -110.967351) (xy 193.283949 -110.993157)
			(xy 193.279219 -111.021381) (xy 193.282497 -111.04981) (xy 193.293529 -111.076216) (xy 193.302128 -111.087662)
			(xy 193.316963 -111.106715) (xy 193.341899 -111.148068) (xy 193.361012 -111.192414) (xy 193.373951 -111.238937)
			(xy 193.380479 -111.286783) (xy 193.380868 -111.310928) (xy 193.38035 -111.338136) (xy 193.372067 -111.391917)
			(xy 193.355696 -111.443812) (xy 193.331621 -111.492611) (xy 193.3004 -111.537179) (xy 193.262762 -111.576478)
			(xy 193.219583 -111.609593) (xy 193.195956 -111.623094) (xy 193.16954 -111.637572) (xy 193.16954 -112.048544)
			(xy 193.213228 -112.05464) (xy 193.240149 -112.058967) (xy 193.292471 -112.074307) (xy 193.342077 -112.09694)
			(xy 193.387955 -112.126404) (xy 193.429171 -112.1621) (xy 193.464887 -112.203299) (xy 193.494373 -112.249164)
			(xy 193.517029 -112.298758) (xy 193.532395 -112.351073) (xy 193.540156 -112.405043) (xy 193.540155 -112.459568)
			(xy 193.532392 -112.513537) (xy 193.517025 -112.565852) (xy 193.494367 -112.615446) (xy 193.46488 -112.661309)
			(xy 193.429164 -112.702508) (xy 193.387946 -112.738202) (xy 193.342067 -112.767665) (xy 193.292461 -112.790297)
			(xy 193.240138 -112.805636) (xy 193.213228 -112.810036) (xy 193.16954 -112.816132) (xy 193.16954 -113.514632)
			(xy 196.46341 -113.514632) (xy 196.467481 -113.45901) (xy 196.479607 -113.404573) (xy 196.49953 -113.352482)
			(xy 196.526826 -113.303847) (xy 196.560912 -113.259704) (xy 196.601061 -113.220995) (xy 196.646419 -113.188544)
			(xy 196.696019 -113.163043) (xy 196.748803 -113.145036) (xy 196.803646 -113.134906) (xy 196.85938 -113.132869)
			(xy 196.914817 -113.138969) (xy 196.968774 -113.153075) (xy 197.020103 -113.174887) (xy 197.067709 -113.203941)
			(xy 197.110577 -113.239616) (xy 197.147794 -113.281153) (xy 197.178567 -113.327666) (xy 197.202239 -113.378163)
			(xy 197.218307 -113.43157) (xy 197.226427 -113.486746) (xy 197.226936 -113.514632) (xy 197.226427 -113.542518)
			(xy 197.218307 -113.597694) (xy 197.202239 -113.651101) (xy 197.178567 -113.701598) (xy 197.147794 -113.748111)
			(xy 197.110577 -113.789648) (xy 197.067709 -113.825323) (xy 197.020103 -113.854377) (xy 196.968774 -113.876189)
			(xy 196.914817 -113.890295) (xy 196.85938 -113.896395) (xy 196.803646 -113.894358) (xy 196.748803 -113.884228)
			(xy 196.696019 -113.866221) (xy 196.646419 -113.84072) (xy 196.601061 -113.808269) (xy 196.560912 -113.76956)
			(xy 196.526826 -113.725417) (xy 196.49953 -113.676782) (xy 196.479607 -113.624691) (xy 196.467481 -113.570254)
			(xy 196.46341 -113.514632) (xy 193.16954 -113.514632) (xy 193.16954 -114.27714) (xy 197.701408 -114.27714)
		)
		(stroke
			(width 0)
			(type solid)
		)
		(fill yes)
		(layer "In15.Cu")
		(net "GND")
	)
	(gr_poly
		(pts
			(xy 180.18633 -131.518406) (xy 180.199834 -131.517984) (xy 180.225897 -131.5109) (xy 180.249194 -131.497235)
			(xy 180.268097 -131.477945) (xy 180.281285 -131.454375) (xy 180.287838 -131.428174) (xy 180.287297 -131.401171)
			(xy 180.283866 -131.388104) (xy 180.276601 -131.361776) (xy 180.268818 -131.307716) (xy 180.268372 -131.280408)
			(xy 180.268858 -131.253157) (xy 180.276614 -131.199209) (xy 180.291969 -131.146914) (xy 180.314611 -131.097337)
			(xy 180.344077 -131.051487) (xy 180.379768 -131.010296) (xy 180.420959 -130.974605) (xy 180.466809 -130.945139)
			(xy 180.516386 -130.922497) (xy 180.568681 -130.907142) (xy 180.622629 -130.899386) (xy 180.677131 -130.899386)
			(xy 180.731079 -130.907142) (xy 180.783374 -130.922497) (xy 180.832951 -130.945139) (xy 180.878801 -130.974605)
			(xy 180.919992 -131.010296) (xy 180.955683 -131.051487) (xy 180.985149 -131.097337) (xy 181.007791 -131.146914)
			(xy 181.023146 -131.199209) (xy 181.030902 -131.253157) (xy 181.031388 -131.280408) (xy 181.030894 -131.307713)
			(xy 181.023114 -131.361766) (xy 181.015894 -131.388104) (xy 181.012481 -131.401177) (xy 181.011914 -131.428179)
			(xy 181.018453 -131.454384) (xy 181.031638 -131.477955) (xy 181.050547 -131.497241) (xy 181.073854 -131.510888)
			(xy 181.099925 -131.517942) (xy 181.11343 -131.518406) (xy 183.74741 -131.518406) (xy 184.110884 -131.154932)
			(xy 184.110884 -129.625344) (xy 184.110372 -129.610894) (xy 184.102267 -129.583153) (xy 184.08672 -129.55879)
			(xy 184.064975 -129.539753) (xy 184.03877 -129.527564) (xy 184.0102 -129.523198) (xy 183.981551 -129.527004)
			(xy 183.955113 -129.538677) (xy 183.943752 -129.54762) (xy 183.923021 -129.564505) (xy 183.877732 -129.592923)
			(xy 183.828924 -129.614751) (xy 183.77755 -129.629563) (xy 183.724613 -129.637068) (xy 183.69788 -129.637536)
			(xy 183.670628 -129.637049) (xy 183.616678 -129.629289) (xy 183.564382 -129.613931) (xy 183.514804 -129.591287)
			(xy 183.468952 -129.561818) (xy 183.427762 -129.526124) (xy 183.39207 -129.484932) (xy 183.362603 -129.439079)
			(xy 183.339962 -129.389499) (xy 183.324606 -129.337202) (xy 183.31685 -129.283252) (xy 183.31685 -129.228748)
			(xy 183.324606 -129.174798) (xy 183.339962 -129.122501) (xy 183.362603 -129.072921) (xy 183.39207 -129.027068)
			(xy 183.427762 -128.985876) (xy 183.468952 -128.950182) (xy 183.514804 -128.920713) (xy 183.564382 -128.898069)
			(xy 183.616678 -128.882711) (xy 183.670628 -128.874951) (xy 183.69788 -128.87452) (xy 183.725007 -128.874995)
			(xy 183.778714 -128.882677) (xy 183.830792 -128.897889) (xy 183.88019 -128.920324) (xy 183.925913 -128.949529)
			(xy 183.967038 -128.984916) (xy 184.002735 -129.025772) (xy 184.01792 -129.048256) (xy 184.026616 -129.060593)
			(xy 184.049751 -129.079954) (xy 184.077529 -129.091722) (xy 184.107532 -129.094875) (xy 184.137149 -129.089136)
			(xy 184.163803 -129.075007) (xy 184.174892 -129.064766) (xy 184.95899 -128.280668) (xy 185.183272 -128.280668)
			(xy 185.20465 -128.263019) (xy 185.251439 -128.233292) (xy 185.301953 -128.210459) (xy 185.355182 -128.194978)
			(xy 185.410063 -128.187158) (xy 185.43778 -128.186688) (xy 185.475372 -128.188466) (xy 185.499248 -128.190752)
			(xy 185.599832 -128.090168) (xy 185.599832 -126.74346) (xy 183.872886 -125.016514) (xy 178.812698 -125.016514)
			(xy 177.808382 -126.02083) (xy 177.808382 -129.250948) (xy 178.743862 -129.250948) (xy 178.747933 -129.195326)
			(xy 178.760059 -129.140889) (xy 178.779982 -129.088798) (xy 178.807278 -129.040163) (xy 178.841364 -128.99602)
			(xy 178.881513 -128.957311) (xy 178.926871 -128.92486) (xy 178.976471 -128.899359) (xy 179.029255 -128.881352)
			(xy 179.084098 -128.871222) (xy 179.139832 -128.869185) (xy 179.195269 -128.875285) (xy 179.249226 -128.889391)
			(xy 179.300555 -128.911203) (xy 179.348161 -128.940257) (xy 179.391029 -128.975932) (xy 179.428246 -129.017469)
			(xy 179.459019 -129.063982) (xy 179.482691 -129.114479) (xy 179.498759 -129.167886) (xy 179.506879 -129.223062)
			(xy 179.507388 -129.250948) (xy 179.507295 -129.256028) (xy 180.267862 -129.256028) (xy 180.271933 -129.200406)
			(xy 180.284059 -129.145969) (xy 180.303982 -129.093878) (xy 180.331278 -129.045243) (xy 180.365364 -129.0011)
			(xy 180.405513 -128.962391) (xy 180.450871 -128.92994) (xy 180.500471 -128.904439) (xy 180.553255 -128.886432)
			(xy 180.608098 -128.876302) (xy 180.663832 -128.874265) (xy 180.719269 -128.880365) (xy 180.773226 -128.894471)
			(xy 180.824555 -128.916283) (xy 180.872161 -128.945337) (xy 180.915029 -128.981012) (xy 180.952246 -129.022549)
			(xy 180.983019 -129.069062) (xy 181.006691 -129.119559) (xy 181.022759 -129.172966) (xy 181.030879 -129.228142)
			(xy 181.031388 -129.256028) (xy 181.791862 -129.256028) (xy 181.795933 -129.200406) (xy 181.808059 -129.145969)
			(xy 181.827982 -129.093878) (xy 181.855278 -129.045243) (xy 181.889364 -129.0011) (xy 181.929513 -128.962391)
			(xy 181.974871 -128.92994) (xy 182.024471 -128.904439) (xy 182.077255 -128.886432) (xy 182.132098 -128.876302)
			(xy 182.187832 -128.874265) (xy 182.243269 -128.880365) (xy 182.297226 -128.894471) (xy 182.348555 -128.916283)
			(xy 182.396161 -128.945337) (xy 182.439029 -128.981012) (xy 182.476246 -129.022549) (xy 182.507019 -129.069062)
			(xy 182.530691 -129.119559) (xy 182.546759 -129.172966) (xy 182.554879 -129.228142) (xy 182.555388 -129.256028)
			(xy 182.554879 -129.283914) (xy 182.546759 -129.33909) (xy 182.530691 -129.392497) (xy 182.507019 -129.442994)
			(xy 182.476246 -129.489507) (xy 182.439029 -129.531044) (xy 182.396161 -129.566719) (xy 182.348555 -129.595773)
			(xy 182.297226 -129.617585) (xy 182.243269 -129.631691) (xy 182.187832 -129.637791) (xy 182.132098 -129.635754)
			(xy 182.077255 -129.625624) (xy 182.024471 -129.607617) (xy 181.974871 -129.582116) (xy 181.929513 -129.549665)
			(xy 181.889364 -129.510956) (xy 181.855278 -129.466813) (xy 181.827982 -129.418178) (xy 181.808059 -129.366087)
			(xy 181.795933 -129.31165) (xy 181.791862 -129.256028) (xy 181.031388 -129.256028) (xy 181.030879 -129.283914)
			(xy 181.022759 -129.33909) (xy 181.006691 -129.392497) (xy 180.983019 -129.442994) (xy 180.952246 -129.489507)
			(xy 180.915029 -129.531044) (xy 180.872161 -129.566719) (xy 180.824555 -129.595773) (xy 180.773226 -129.617585)
			(xy 180.719269 -129.631691) (xy 180.663832 -129.637791) (xy 180.608098 -129.635754) (xy 180.553255 -129.625624)
			(xy 180.500471 -129.607617) (xy 180.450871 -129.582116) (xy 180.405513 -129.549665) (xy 180.365364 -129.510956)
			(xy 180.331278 -129.466813) (xy 180.303982 -129.418178) (xy 180.284059 -129.366087) (xy 180.271933 -129.31165)
			(xy 180.267862 -129.256028) (xy 179.507295 -129.256028) (xy 179.506879 -129.278834) (xy 179.498759 -129.33401)
			(xy 179.482691 -129.387417) (xy 179.459019 -129.437914) (xy 179.428246 -129.484427) (xy 179.391029 -129.525964)
			(xy 179.348161 -129.561639) (xy 179.300555 -129.590693) (xy 179.249226 -129.612505) (xy 179.195269 -129.626611)
			(xy 179.139832 -129.632711) (xy 179.084098 -129.630674) (xy 179.029255 -129.620544) (xy 178.976471 -129.602537)
			(xy 178.926871 -129.577036) (xy 178.881513 -129.544585) (xy 178.841364 -129.505876) (xy 178.807278 -129.461733)
			(xy 178.779982 -129.413098) (xy 178.760059 -129.361007) (xy 178.747933 -129.30657) (xy 178.743862 -129.250948)
			(xy 177.808382 -129.250948) (xy 177.808382 -130.367024) (xy 178.607974 -131.166616) (xy 178.618389 -131.176368)
			(xy 178.64334 -131.190184) (xy 178.671141 -131.196553) (xy 178.699618 -131.194978) (xy 178.726546 -131.185582)
			(xy 178.749821 -131.169099) (xy 178.767624 -131.146817) (xy 178.773582 -131.13385) (xy 178.784822 -131.108123)
			(xy 178.813748 -131.060008) (xy 178.849416 -131.016653) (xy 178.891055 -130.978996) (xy 178.937764 -130.94785)
			(xy 178.988535 -130.923889) (xy 179.042271 -130.907631) (xy 179.097809 -130.899426) (xy 179.12588 -130.8989)
			(xy 179.153134 -130.899362) (xy 179.207086 -130.907117) (xy 179.259386 -130.922471) (xy 179.308968 -130.945113)
			(xy 179.354823 -130.97458) (xy 179.396018 -131.010274) (xy 179.431713 -131.051467) (xy 179.461182 -131.097321)
			(xy 179.483825 -131.146903) (xy 179.499181 -131.199202) (xy 179.506937 -131.253154) (xy 179.507388 -131.280408)
			(xy 179.506894 -131.307713) (xy 179.499114 -131.361766) (xy 179.491894 -131.388104) (xy 179.488481 -131.401177)
			(xy 179.487914 -131.428179) (xy 179.494453 -131.454384) (xy 179.507638 -131.477955) (xy 179.526547 -131.497241)
			(xy 179.549854 -131.510888) (xy 179.575925 -131.517942) (xy 179.58943 -131.518406)
		)
		(stroke
			(width 0)
			(type solid)
		)
		(fill yes)
		(layer "In15.Cu")
		(net "P3V3_AUX")
	)
	(gr_poly
		(pts
			(xy 409.455366 -165.563042) (xy 409.464968 -165.552825) (xy 409.478672 -165.528374) (xy 409.485218 -165.501121)
			(xy 409.484116 -165.473114) (xy 409.475447 -165.44646) (xy 409.459864 -165.423162) (xy 409.449524 -165.41369)
			(xy 409.428885 -165.395489) (xy 409.392543 -165.354167) (xy 409.362521 -165.30805) (xy 409.339443 -165.258094)
			(xy 409.323787 -165.20534) (xy 409.315879 -165.150882) (xy 409.315412 -165.123368) (xy 409.315907 -165.095699)
			(xy 409.323905 -165.040942) (xy 409.339729 -164.987914) (xy 409.363046 -164.937729) (xy 409.393368 -164.891437)
			(xy 409.430058 -164.850011) (xy 409.472348 -164.81432) (xy 409.51935 -164.785111) (xy 409.54452 -164.77361)
			(xy 409.575 -164.760402) (xy 409.575 -159.458914) (xy 409.54452 -159.445706) (xy 409.519352 -159.434201)
			(xy 409.472347 -159.404997) (xy 409.430056 -159.369309) (xy 409.393365 -159.327883) (xy 409.363045 -159.281591)
			(xy 409.339732 -159.231404) (xy 409.323915 -159.178375) (xy 409.315927 -159.123617) (xy 409.315412 -159.095948)
			(xy 409.315929 -159.067208) (xy 409.324546 -159.010376) (xy 409.341591 -158.955481) (xy 409.366679 -158.903765)
			(xy 409.399242 -158.856397) (xy 409.418536 -158.83509) (xy 409.428618 -158.823557) (xy 409.441978 -158.796007)
			(xy 409.446577 -158.765735) (xy 409.441999 -158.73546) (xy 409.428658 -158.707901) (xy 409.418536 -158.696406)
			(xy 409.399262 -158.67508) (xy 409.36669 -158.62772) (xy 409.341591 -158.576008) (xy 409.324533 -158.521117)
			(xy 409.315903 -158.464288) (xy 409.315412 -158.435548) (xy 409.315908 -158.40788) (xy 409.323909 -158.353125)
			(xy 409.339734 -158.300099) (xy 409.363053 -158.249916) (xy 409.393376 -158.203627) (xy 409.430067 -158.162203)
			(xy 409.472356 -158.126513) (xy 409.519357 -158.097307) (xy 409.54452 -158.08579) (xy 409.575 -158.072582)
			(xy 409.575 -157.599888) (xy 408.97048 -156.995368) (xy 401.363942 -156.995368) (xy 401.343218 -157.032919)
			(xy 401.295757 -157.104366) (xy 401.241816 -157.171056) (xy 401.181868 -157.232404) (xy 401.11644 -157.28787)
			(xy 401.046107 -157.336966) (xy 400.971487 -157.379263) (xy 400.893234 -157.414388) (xy 400.812036 -157.442032)
			(xy 400.728608 -157.461953) (xy 400.64368 -157.473977) (xy 400.558 -157.477996) (xy 400.47232 -157.473977)
			(xy 400.387392 -157.461953) (xy 400.303964 -157.442032) (xy 400.222766 -157.414388) (xy 400.144513 -157.379263)
			(xy 400.069893 -157.336966) (xy 399.99956 -157.28787) (xy 399.934132 -157.232404) (xy 399.874184 -157.171056)
			(xy 399.820243 -157.104366) (xy 399.772782 -157.032919) (xy 399.752058 -156.995368) (xy 398.36852 -156.995368)
			(xy 397.80718 -157.556708) (xy 397.80718 -158.604896) (xy 399.668996 -158.604896) (xy 399.668996 -158.5202)
			(xy 399.677047 -158.435886) (xy 399.693076 -158.35272) (xy 399.716937 -158.271453) (xy 399.748416 -158.192823)
			(xy 399.787227 -158.117542) (xy 399.833017 -158.04629) (xy 399.885373 -157.979714) (xy 399.943821 -157.918416)
			(xy 400.007831 -157.862951) (xy 400.076823 -157.813822) (xy 400.150173 -157.771473) (xy 400.227216 -157.736289)
			(xy 400.307255 -157.708587) (xy 400.389564 -157.688619) (xy 400.473399 -157.676566) (xy 400.558 -157.672536)
			(xy 400.642601 -157.676566) (xy 400.726436 -157.688619) (xy 400.808745 -157.708587) (xy 400.888784 -157.736289)
			(xy 400.965827 -157.771473) (xy 401.039177 -157.813822) (xy 401.108169 -157.862951) (xy 401.172179 -157.918416)
			(xy 401.230627 -157.979714) (xy 401.282983 -158.04629) (xy 401.328773 -158.117542) (xy 401.367584 -158.192823)
			(xy 401.399063 -158.271453) (xy 401.422924 -158.35272) (xy 401.438953 -158.435886) (xy 401.447004 -158.5202)
			(xy 401.447508 -158.562548) (xy 401.447004 -158.604896) (xy 401.438953 -158.68921) (xy 401.422924 -158.772376)
			(xy 401.399063 -158.853643) (xy 401.367584 -158.932273) (xy 401.328773 -159.007554) (xy 401.282983 -159.078806)
			(xy 401.230627 -159.145382) (xy 401.172179 -159.20668) (xy 401.108169 -159.262145) (xy 401.039177 -159.311274)
			(xy 400.965827 -159.353623) (xy 400.888784 -159.388807) (xy 400.808745 -159.416509) (xy 400.726436 -159.436477)
			(xy 400.642601 -159.44853) (xy 400.558 -159.452561) (xy 400.473399 -159.44853) (xy 400.389564 -159.436477)
			(xy 400.307255 -159.416509) (xy 400.227216 -159.388807) (xy 400.150173 -159.353623) (xy 400.076823 -159.311274)
			(xy 400.007831 -159.262145) (xy 399.943821 -159.20668) (xy 399.885373 -159.145382) (xy 399.833017 -159.078806)
			(xy 399.787227 -159.007554) (xy 399.748416 -158.932273) (xy 399.716937 -158.853643) (xy 399.693076 -158.772376)
			(xy 399.677047 -158.68921) (xy 399.668996 -158.604896) (xy 397.80718 -158.604896) (xy 397.80718 -162.785552)
			(xy 399.642589 -162.785552) (xy 399.646611 -162.699832) (xy 399.658642 -162.614864) (xy 399.678578 -162.531397)
			(xy 399.706241 -162.450163) (xy 399.74139 -162.371877) (xy 399.783716 -162.297226) (xy 399.832845 -162.226867)
			(xy 399.888348 -162.161417) (xy 399.949735 -162.101453) (xy 400.016468 -162.0475) (xy 400.08796 -162.000033)
			(xy 400.163582 -161.959469) (xy 400.242671 -161.926165) (xy 400.324531 -161.900413) (xy 400.408442 -161.88244)
			(xy 400.493668 -161.872404) (xy 400.57946 -161.870392) (xy 400.665062 -161.876423) (xy 400.749724 -161.890443)
			(xy 400.832701 -161.912329) (xy 400.913264 -161.94189) (xy 400.990704 -161.978864) (xy 401.064343 -162.022928)
			(xy 401.133531 -162.073694) (xy 401.197662 -162.130715) (xy 401.256171 -162.193491) (xy 401.308544 -162.261471)
			(xy 401.354322 -162.334056) (xy 401.393102 -162.410608) (xy 401.424543 -162.490456) (xy 401.448369 -162.572897)
			(xy 401.46437 -162.657207) (xy 401.472405 -162.742645) (xy 401.472908 -162.785552) (xy 401.472405 -162.828459)
			(xy 401.46437 -162.913897) (xy 401.448369 -162.998207) (xy 401.424543 -163.080648) (xy 401.393102 -163.160496)
			(xy 401.354322 -163.237048) (xy 401.308544 -163.309633) (xy 401.256171 -163.377613) (xy 401.197662 -163.440389)
			(xy 401.133531 -163.49741) (xy 401.064343 -163.548176) (xy 400.990704 -163.59224) (xy 400.913264 -163.629214)
			(xy 400.832701 -163.658775) (xy 400.749724 -163.680661) (xy 400.665062 -163.694681) (xy 400.57946 -163.700712)
			(xy 400.493668 -163.6987) (xy 400.408442 -163.688664) (xy 400.324531 -163.670691) (xy 400.242671 -163.644939)
			(xy 400.163582 -163.611635) (xy 400.08796 -163.571071) (xy 400.016468 -163.523604) (xy 399.949735 -163.469651)
			(xy 399.888348 -163.409687) (xy 399.832845 -163.344237) (xy 399.783716 -163.273878) (xy 399.74139 -163.199227)
			(xy 399.706241 -163.120941) (xy 399.678578 -163.039707) (xy 399.658642 -162.95624) (xy 399.646611 -162.871272)
			(xy 399.642589 -162.785552) (xy 397.80718 -162.785552) (xy 397.80718 -164.827896) (xy 399.668996 -164.827896)
			(xy 399.668996 -164.7432) (xy 399.677047 -164.658886) (xy 399.693076 -164.57572) (xy 399.716937 -164.494453)
			(xy 399.748416 -164.415823) (xy 399.787227 -164.340542) (xy 399.833017 -164.26929) (xy 399.885373 -164.202714)
			(xy 399.943821 -164.141416) (xy 400.007831 -164.085951) (xy 400.076823 -164.036822) (xy 400.150173 -163.994473)
			(xy 400.227216 -163.959289) (xy 400.307255 -163.931587) (xy 400.389564 -163.911619) (xy 400.473399 -163.899566)
			(xy 400.558 -163.895536) (xy 400.642601 -163.899566) (xy 400.726436 -163.911619) (xy 400.808745 -163.931587)
			(xy 400.888784 -163.959289) (xy 400.965827 -163.994473) (xy 401.039177 -164.036822) (xy 401.108169 -164.085951)
			(xy 401.172179 -164.141416) (xy 401.230627 -164.202714) (xy 401.282983 -164.26929) (xy 401.328773 -164.340542)
			(xy 401.367584 -164.415823) (xy 401.399063 -164.494453) (xy 401.422924 -164.57572) (xy 401.438953 -164.658886)
			(xy 401.447004 -164.7432) (xy 401.447508 -164.785548) (xy 401.447004 -164.827896) (xy 401.438953 -164.91221)
			(xy 401.422924 -164.995376) (xy 401.399063 -165.076643) (xy 401.367584 -165.155273) (xy 401.328773 -165.230554)
			(xy 401.282983 -165.301806) (xy 401.230627 -165.368382) (xy 401.172179 -165.42968) (xy 401.108169 -165.485145)
			(xy 401.039177 -165.534274) (xy 400.965827 -165.576623) (xy 400.888784 -165.611807) (xy 400.808745 -165.639509)
			(xy 400.726436 -165.659477) (xy 400.642601 -165.67153) (xy 400.558 -165.675561) (xy 400.473399 -165.67153)
			(xy 400.389564 -165.659477) (xy 400.307255 -165.639509) (xy 400.227216 -165.611807) (xy 400.150173 -165.576623)
			(xy 400.076823 -165.534274) (xy 400.007831 -165.485145) (xy 399.943821 -165.42968) (xy 399.885373 -165.368382)
			(xy 399.833017 -165.301806) (xy 399.787227 -165.230554) (xy 399.748416 -165.155273) (xy 399.716937 -165.076643)
			(xy 399.693076 -164.995376) (xy 399.677047 -164.91221) (xy 399.668996 -164.827896) (xy 397.80718 -164.827896)
			(xy 397.80718 -164.965888) (xy 398.972532 -166.13124) (xy 408.28849 -166.13124) (xy 408.331924 -166.174928)
			(xy 408.84348 -166.174928)
		)
		(stroke
			(width 0)
			(type solid)
		)
		(fill yes)
		(layer "In15.Cu")
		(net "PVCCD_HV_CPU0")
	)
	(gr_poly
		(pts
			(xy 252.01118 -51.541426) (xy 252.01118 -48.386746) (xy 251.103892 -47.479458) (xy 251.088906 -47.476664)
			(xy 251.061533 -47.470659) (xy 251.008796 -47.451702) (xy 250.959399 -47.425237) (xy 250.914404 -47.391832)
			(xy 250.874777 -47.352207) (xy 250.841371 -47.307213) (xy 250.814903 -47.257817) (xy 250.795944 -47.205081)
			(xy 250.789948 -47.177706) (xy 250.787154 -47.16272) (xy 249.779282 -46.154848) (xy 249.769532 -46.145654)
			(xy 249.746323 -46.132273) (xy 249.720431 -46.125393) (xy 249.693641 -46.12549) (xy 249.6678 -46.132555)
			(xy 249.644687 -46.146103) (xy 249.625898 -46.165199) (xy 249.619008 -46.176692) (xy 249.604371 -46.201478)
			(xy 249.568808 -46.246738) (xy 249.526849 -46.286142) (xy 249.479447 -46.318796) (xy 249.427678 -46.343959)
			(xy 249.372717 -46.36106) (xy 249.31581 -46.369711) (xy 249.28703 -46.37024) (xy 249.259777 -46.369756)
			(xy 249.205824 -46.362003) (xy 249.153524 -46.346651) (xy 249.103941 -46.324012) (xy 249.058084 -46.294547)
			(xy 249.016888 -46.258856) (xy 248.98119 -46.217666) (xy 248.951718 -46.171814) (xy 248.92907 -46.122235)
			(xy 248.91371 -46.069937) (xy 248.905948 -46.015985) (xy 248.905522 -45.988732) (xy 248.906006 -45.961143)
			(xy 248.913943 -45.906538) (xy 248.929656 -45.853644) (xy 248.952818 -45.803562) (xy 248.967498 -45.780198)
			(xy 248.974573 -45.76851) (xy 248.982859 -45.742487) (xy 248.98395 -45.715199) (xy 248.977769 -45.688597)
			(xy 248.964757 -45.664586) (xy 248.945846 -45.644882) (xy 248.922388 -45.630897) (xy 248.896063 -45.623629)
			(xy 248.882408 -45.623226) (xy 244.2591 -45.623226) (xy 243.907056 -45.271182) (xy 243.88826 -45.269658)
			(xy 243.854556 -45.266609) (xy 243.788148 -45.253575) (xy 243.723743 -45.232794) (xy 243.66224 -45.204557)
			(xy 243.6045 -45.169259) (xy 243.551329 -45.127392) (xy 243.527072 -45.103796) (xy 242.49761 -44.074588)
			(xy 240.567464 -44.074588) (xy 240.564506 -44.100722) (xy 240.551882 -44.151779) (xy 240.531885 -44.200423)
			(xy 240.50495 -44.245596) (xy 240.471663 -44.286316) (xy 240.432747 -44.321696) (xy 240.389051 -44.350966)
			(xy 240.341525 -44.373491) (xy 240.291202 -44.388779) (xy 240.239177 -44.396498) (xy 240.21288 -44.396914)
			(xy 240.186305 -44.396421) (xy 240.133744 -44.388523) (xy 240.08294 -44.372905) (xy 240.03502 -44.349913)
			(xy 239.991047 -44.320058) (xy 239.951996 -44.284003) (xy 239.935004 -44.263564) (xy 239.929005 -44.256683)
			(xy 239.913331 -44.247348) (xy 239.89538 -44.244099) (xy 239.877429 -44.247348) (xy 239.861755 -44.256683)
			(xy 239.855756 -44.263564) (xy 239.838749 -44.283992) (xy 239.799709 -44.320063) (xy 239.755741 -44.34993)
			(xy 239.707823 -44.372931) (xy 239.657019 -44.388555) (xy 239.604456 -44.396455) (xy 239.551304 -44.396455)
			(xy 239.498741 -44.388555) (xy 239.447937 -44.372931) (xy 239.400019 -44.34993) (xy 239.356051 -44.320063)
			(xy 239.317011 -44.283992) (xy 239.300004 -44.263564) (xy 239.294005 -44.256683) (xy 239.278331 -44.247348)
			(xy 239.26038 -44.244099) (xy 239.242429 -44.247348) (xy 239.226755 -44.256683) (xy 239.220756 -44.263564)
			(xy 239.203749 -44.28399) (xy 239.164709 -44.320056) (xy 239.120741 -44.349917) (xy 239.072822 -44.372908)
			(xy 239.022016 -44.38852) (xy 238.969455 -44.396404) (xy 238.94288 -44.396914) (xy 238.915397 -44.39641)
			(xy 238.861082 -44.387971) (xy 238.808711 -44.371283) (xy 238.759527 -44.346742) (xy 238.714702 -44.314931)
			(xy 238.675299 -44.276606) (xy 238.6584 -44.254928) (xy 238.652419 -44.24759) (xy 238.636354 -44.237599)
			(xy 238.61776 -44.234111) (xy 238.599166 -44.237599) (xy 238.583101 -44.24759) (xy 238.57712 -44.254928)
			(xy 238.560184 -44.276573) (xy 238.520776 -44.314878) (xy 238.475953 -44.346677) (xy 238.426779 -44.371216)
			(xy 238.37442 -44.387914) (xy 238.320118 -44.396374) (xy 238.29264 -44.396914) (xy 238.267814 -44.396479)
			(xy 238.218645 -44.389574) (xy 238.170912 -44.375904) (xy 238.125541 -44.355736) (xy 238.083411 -44.329461)
			(xy 238.04534 -44.297588) (xy 238.012066 -44.260736) (xy 237.997746 -44.24045) (xy 237.991922 -44.232664)
			(xy 237.975803 -44.221818) (xy 237.956809 -44.217734) (xy 237.937656 -44.220995) (xy 237.921084 -44.231135)
			(xy 237.914942 -44.238672) (xy 237.898016 -44.260462) (xy 237.858574 -44.299042) (xy 237.813657 -44.331082)
			(xy 237.764338 -44.355815) (xy 237.711796 -44.37265) (xy 237.657286 -44.381185) (xy 237.6297 -44.381674)
			(xy 237.600527 -44.38109) (xy 237.542961 -44.371583) (xy 237.487713 -44.352824) (xy 237.436261 -44.325313)
			(xy 237.389978 -44.289786) (xy 237.369604 -44.268898) (xy 237.362346 -44.26179) (xy 237.343821 -44.253493)
			(xy 237.323528 -44.253019) (xy 237.304636 -44.260443) (xy 237.290095 -44.274605) (xy 237.282174 -44.293294)
			(xy 237.28172 -44.303442) (xy 237.28172 -46.458886) (xy 237.391702 -46.568868) (xy 237.402366 -46.578825)
			(xy 237.428001 -46.592732) (xy 237.456521 -46.598829) (xy 237.485602 -46.596619) (xy 237.512873 -46.586283)
			(xy 237.536113 -46.568662) (xy 237.545118 -46.557184) (xy 237.56324 -46.53366) (xy 237.605543 -46.491992)
			(xy 237.65379 -46.45738) (xy 237.706818 -46.430663) (xy 237.763346 -46.412484) (xy 237.822007 -46.403283)
			(xy 237.851696 -46.402752) (xy 237.878948 -46.403237) (xy 237.932899 -46.410993) (xy 237.985196 -46.426348)
			(xy 238.034777 -46.448988) (xy 238.08063 -46.478454) (xy 238.121824 -46.514145) (xy 238.15752 -46.555334)
			(xy 238.186991 -46.601185) (xy 238.209637 -46.650762) (xy 238.224997 -46.703058) (xy 238.232759 -46.757008)
			(xy 238.233204 -46.78426) (xy 238.485678 -46.78426) (xy 238.489749 -46.728638) (xy 238.501875 -46.674201)
			(xy 238.521798 -46.62211) (xy 238.549094 -46.573475) (xy 238.58318 -46.529332) (xy 238.623329 -46.490623)
			(xy 238.668687 -46.458172) (xy 238.718287 -46.432671) (xy 238.771071 -46.414664) (xy 238.825914 -46.404534)
			(xy 238.881648 -46.402497) (xy 238.937085 -46.408597) (xy 238.991042 -46.422703) (xy 239.042371 -46.444515)
			(xy 239.089977 -46.473569) (xy 239.132845 -46.509244) (xy 239.170062 -46.550781) (xy 239.200835 -46.597294)
			(xy 239.224507 -46.647791) (xy 239.240575 -46.701198) (xy 239.248695 -46.756374) (xy 239.249204 -46.78426)
			(xy 239.248695 -46.812146) (xy 239.240575 -46.867322) (xy 239.224507 -46.920729) (xy 239.202512 -46.967648)
			(xy 240.694462 -46.967648) (xy 240.698533 -46.912026) (xy 240.710659 -46.857589) (xy 240.730582 -46.805498)
			(xy 240.757878 -46.756863) (xy 240.791964 -46.71272) (xy 240.832113 -46.674011) (xy 240.877471 -46.64156)
			(xy 240.927071 -46.616059) (xy 240.979855 -46.598052) (xy 241.034698 -46.587922) (xy 241.090432 -46.585885)
			(xy 241.145869 -46.591985) (xy 241.199826 -46.606091) (xy 241.251155 -46.627903) (xy 241.298761 -46.656957)
			(xy 241.341629 -46.692632) (xy 241.378846 -46.734169) (xy 241.409619 -46.780682) (xy 241.433291 -46.831179)
			(xy 241.449359 -46.884586) (xy 241.457479 -46.939762) (xy 241.457988 -46.967648) (xy 241.457479 -46.995534)
			(xy 241.449359 -47.05071) (xy 241.433291 -47.104117) (xy 241.409619 -47.154614) (xy 241.378846 -47.201127)
			(xy 241.341629 -47.242664) (xy 241.298761 -47.278339) (xy 241.251155 -47.307393) (xy 241.199826 -47.329205)
			(xy 241.145869 -47.343311) (xy 241.090432 -47.349411) (xy 241.034698 -47.347374) (xy 240.979855 -47.337244)
			(xy 240.927071 -47.319237) (xy 240.877471 -47.293736) (xy 240.832113 -47.261285) (xy 240.791964 -47.222576)
			(xy 240.757878 -47.178433) (xy 240.730582 -47.129798) (xy 240.710659 -47.077707) (xy 240.698533 -47.02327)
			(xy 240.694462 -46.967648) (xy 239.202512 -46.967648) (xy 239.200835 -46.971226) (xy 239.170062 -47.017739)
			(xy 239.132845 -47.059276) (xy 239.089977 -47.094951) (xy 239.042371 -47.124005) (xy 238.991042 -47.145817)
			(xy 238.937085 -47.159923) (xy 238.881648 -47.166023) (xy 238.825914 -47.163986) (xy 238.771071 -47.153856)
			(xy 238.718287 -47.135849) (xy 238.668687 -47.110348) (xy 238.623329 -47.077897) (xy 238.58318 -47.039188)
			(xy 238.549094 -46.995045) (xy 238.521798 -46.94641) (xy 238.501875 -46.894319) (xy 238.489749 -46.839882)
			(xy 238.485678 -46.78426) (xy 238.233204 -46.78426) (xy 238.232642 -46.813949) (xy 238.223449 -46.87261)
			(xy 238.205278 -46.929139) (xy 238.178569 -46.98217) (xy 238.143967 -47.030422) (xy 238.102306 -47.072731)
			(xy 238.078772 -47.090838) (xy 238.067301 -47.099863) (xy 238.049648 -47.123091) (xy 238.039288 -47.150365)
			(xy 238.037067 -47.179455) (xy 238.043166 -47.207985) (xy 238.057089 -47.233624) (xy 238.067088 -47.244254)
			(xy 238.37646 -47.553626) (xy 240.88344 -47.553626) (xy 241.75212 -48.422306) (xy 241.75212 -50.380646)
			(xy 243.3955 -52.024026) (xy 251.52858 -52.024026)
		)
		(stroke
			(width 0)
			(type solid)
		)
		(fill yes)
		(layer "In15.Cu")
		(net "P12V_E1S_0")
	)
	(gr_poly
		(pts
			(xy 70.037706 -172.687488) (xy 70.051862 -172.687036) (xy 70.079091 -172.67928) (xy 70.103139 -172.664338)
			(xy 70.122154 -172.643363) (xy 70.134671 -172.617969) (xy 70.139727 -172.590112) (xy 70.136932 -172.561939)
			(xy 70.126501 -172.535619) (xy 70.109237 -172.51318) (xy 70.098158 -172.504354) (xy 70.064249 -172.478525)
			(xy 70.000873 -172.421512) (xy 69.943073 -172.358852) (xy 69.891349 -172.29109) (xy 69.84615 -172.218813)
			(xy 69.807868 -172.142645) (xy 69.776833 -172.063248) (xy 69.753316 -171.98131) (xy 69.737519 -171.89754)
			(xy 69.72958 -171.812663) (xy 69.729096 -171.77004) (xy 69.729584 -171.727764) (xy 69.737386 -171.643572)
			(xy 69.752922 -171.560459) (xy 69.776061 -171.479135) (xy 69.806605 -171.400292) (xy 69.844293 -171.324604)
			(xy 69.888804 -171.252716) (xy 69.939758 -171.185242) (xy 69.996721 -171.122757) (xy 70.059206 -171.065794)
			(xy 70.12668 -171.01484) (xy 70.198568 -170.970329) (xy 70.274256 -170.932641) (xy 70.353099 -170.902097)
			(xy 70.434423 -170.878958) (xy 70.517536 -170.863422) (xy 70.601728 -170.85562) (xy 70.68628 -170.85562)
			(xy 70.770472 -170.863422) (xy 70.853585 -170.878958) (xy 70.934909 -170.902097) (xy 71.013752 -170.932641)
			(xy 71.08944 -170.970329) (xy 71.161328 -171.01484) (xy 71.228802 -171.065794) (xy 71.291287 -171.122757)
			(xy 71.34825 -171.185242) (xy 71.399204 -171.252716) (xy 71.443715 -171.324604) (xy 71.481403 -171.400292)
			(xy 71.511947 -171.479135) (xy 71.535086 -171.560459) (xy 71.550622 -171.643572) (xy 71.558424 -171.727764)
			(xy 71.558912 -171.77004) (xy 71.558425 -171.812664) (xy 71.550501 -171.897544) (xy 71.534715 -171.981318)
			(xy 71.511204 -172.063261) (xy 71.480172 -172.142661) (xy 71.441889 -172.21883) (xy 71.396686 -172.291107)
			(xy 71.344956 -172.358867) (xy 71.287147 -172.42152) (xy 71.22376 -172.478524) (xy 71.18985 -172.504354)
			(xy 71.17877 -172.513158) (xy 71.161557 -172.535608) (xy 71.151167 -172.561919) (xy 71.148395 -172.590072)
			(xy 71.153456 -172.617904) (xy 71.165961 -172.643279) (xy 71.184949 -172.664249) (xy 71.208963 -172.679202)
			(xy 71.236158 -172.686992) (xy 71.250302 -172.687488) (xy 73.30186 -172.687488) (xy 75.946 -170.043348)
			(xy 75.946 -168.906444) (xy 75.95108 -168.884346) (xy 75.95108 -163.167568) (xy 75.08494 -162.301428)
			(xy 75.050396 -162.32378) (xy 75.027134 -162.338272) (xy 74.977336 -162.36116) (xy 74.924776 -162.376688)
			(xy 74.870535 -162.384535) (xy 74.843132 -162.384994) (xy 74.815878 -162.384533) (xy 74.761924 -162.376779)
			(xy 74.709623 -162.361426) (xy 74.66004 -162.338785) (xy 74.614184 -162.309318) (xy 74.572989 -162.273624)
			(xy 74.537293 -162.23243) (xy 74.507823 -162.186576) (xy 74.48518 -162.136993) (xy 74.469824 -162.084693)
			(xy 74.462068 -162.03074) (xy 74.461624 -162.003486) (xy 74.462064 -161.977486) (xy 74.469122 -161.925968)
			(xy 74.483105 -161.875884) (xy 74.503755 -161.828161) (xy 74.53069 -161.783681) (xy 74.546714 -161.763202)
			(xy 73.61936 -160.835848) (xy 72.08774 -160.835848) (xy 70.91934 -162.004248) (xy 69.09054 -162.004248)
			(xy 68.119752 -161.03346) (xy 63.270638 -161.03346) (xy 63.123572 -161.180526) (xy 63.123572 -164.634926)
			(xy 69.007995 -164.634926) (xy 69.012017 -164.549206) (xy 69.024048 -164.464238) (xy 69.043984 -164.380771)
			(xy 69.071647 -164.299537) (xy 69.106796 -164.221251) (xy 69.149122 -164.1466) (xy 69.198251 -164.076241)
			(xy 69.253754 -164.010791) (xy 69.315141 -163.950827) (xy 69.381874 -163.896874) (xy 69.453366 -163.849407)
			(xy 69.528988 -163.808843) (xy 69.608077 -163.775539) (xy 69.689937 -163.749787) (xy 69.773848 -163.731814)
			(xy 69.859074 -163.721778) (xy 69.944866 -163.719766) (xy 70.030468 -163.725797) (xy 70.11513 -163.739817)
			(xy 70.198107 -163.761703) (xy 70.27867 -163.791264) (xy 70.35611 -163.828238) (xy 70.429749 -163.872302)
			(xy 70.498937 -163.923068) (xy 70.563068 -163.980089) (xy 70.621577 -164.042865) (xy 70.67395 -164.110845)
			(xy 70.719728 -164.18343) (xy 70.758508 -164.259982) (xy 70.789949 -164.33983) (xy 70.813775 -164.422271)
			(xy 70.829776 -164.506581) (xy 70.837811 -164.592019) (xy 70.838314 -164.634926) (xy 70.837811 -164.677833)
			(xy 70.829776 -164.763271) (xy 70.813775 -164.847581) (xy 70.789949 -164.930022) (xy 70.758508 -165.00987)
			(xy 70.719728 -165.086422) (xy 70.67395 -165.159007) (xy 70.621577 -165.226987) (xy 70.563068 -165.289763)
			(xy 70.498937 -165.346784) (xy 70.429749 -165.39755) (xy 70.35611 -165.441614) (xy 70.27867 -165.478588)
			(xy 70.198107 -165.508149) (xy 70.11513 -165.530035) (xy 70.030468 -165.544055) (xy 69.944866 -165.550086)
			(xy 69.859074 -165.548074) (xy 69.773848 -165.538038) (xy 69.689937 -165.520065) (xy 69.608077 -165.494313)
			(xy 69.528988 -165.461009) (xy 69.453366 -165.420445) (xy 69.381874 -165.372978) (xy 69.315141 -165.319025)
			(xy 69.253754 -165.259061) (xy 69.198251 -165.193611) (xy 69.149122 -165.123252) (xy 69.106796 -165.048601)
			(xy 69.071647 -164.970315) (xy 69.043984 -164.889081) (xy 69.024048 -164.805614) (xy 69.012017 -164.720646)
			(xy 69.007995 -164.634926) (xy 63.123572 -164.634926) (xy 63.123572 -166.67727) (xy 69.034402 -166.67727)
			(xy 69.034402 -166.592574) (xy 69.042453 -166.50826) (xy 69.058482 -166.425094) (xy 69.082343 -166.343827)
			(xy 69.113822 -166.265197) (xy 69.152633 -166.189916) (xy 69.198423 -166.118664) (xy 69.250779 -166.052088)
			(xy 69.309227 -165.99079) (xy 69.373237 -165.935325) (xy 69.442229 -165.886196) (xy 69.515579 -165.843847)
			(xy 69.592622 -165.808663) (xy 69.672661 -165.780961) (xy 69.75497 -165.760993) (xy 69.838805 -165.74894)
			(xy 69.923406 -165.74491) (xy 70.008007 -165.74894) (xy 70.091842 -165.760993) (xy 70.174151 -165.780961)
			(xy 70.25419 -165.808663) (xy 70.331233 -165.843847) (xy 70.404583 -165.886196) (xy 70.473575 -165.935325)
			(xy 70.537585 -165.99079) (xy 70.596033 -166.052088) (xy 70.648389 -166.118664) (xy 70.694179 -166.189916)
			(xy 70.73299 -166.265197) (xy 70.764469 -166.343827) (xy 70.78833 -166.425094) (xy 70.804359 -166.50826)
			(xy 70.81241 -166.592574) (xy 70.812914 -166.634922) (xy 70.81241 -166.67727) (xy 70.804359 -166.761584)
			(xy 70.78833 -166.84475) (xy 70.764469 -166.926017) (xy 70.73299 -167.004647) (xy 70.694179 -167.079928)
			(xy 70.648389 -167.15118) (xy 70.596033 -167.217756) (xy 70.537585 -167.279054) (xy 70.473575 -167.334519)
			(xy 70.404583 -167.383648) (xy 70.331233 -167.425997) (xy 70.25419 -167.461181) (xy 70.174151 -167.488883)
			(xy 70.091842 -167.508851) (xy 70.008007 -167.520904) (xy 69.923406 -167.524935) (xy 69.838805 -167.520904)
			(xy 69.75497 -167.508851) (xy 69.672661 -167.488883) (xy 69.592622 -167.461181) (xy 69.515579 -167.425997)
			(xy 69.442229 -167.383648) (xy 69.373237 -167.334519) (xy 69.309227 -167.279054) (xy 69.250779 -167.217756)
			(xy 69.198423 -167.15118) (xy 69.152633 -167.079928) (xy 69.113822 -167.004647) (xy 69.082343 -166.926017)
			(xy 69.058482 -166.84475) (xy 69.042453 -166.761584) (xy 69.034402 -166.67727) (xy 63.123572 -166.67727)
			(xy 63.123572 -169.185844) (xy 63.284608 -169.34688) (xy 64.9986 -169.34688) (xy 66.460116 -170.808396)
			(xy 66.585592 -170.808396) (xy 67.58178 -171.804584) (xy 67.592572 -171.814613) (xy 67.618515 -171.82855)
			(xy 67.647354 -171.83451) (xy 67.676695 -171.831998) (xy 67.704102 -171.821223) (xy 67.727298 -171.80308)
			(xy 67.744357 -171.779075) (xy 67.753863 -171.751203) (xy 67.755008 -171.736512) (xy 67.757132 -171.693939)
			(xy 67.76851 -171.609455) (xy 67.787915 -171.526447) (xy 67.81517 -171.445675) (xy 67.850025 -171.36788)
			(xy 67.89216 -171.293775) (xy 67.941188 -171.224039) (xy 67.996661 -171.159311) (xy 68.05807 -171.100185)
			(xy 68.124852 -171.047203) (xy 68.196395 -171.00085) (xy 68.272042 -170.961552) (xy 68.351102 -170.929668)
			(xy 68.432848 -170.905492) (xy 68.516531 -170.889243) (xy 68.601385 -170.881073) (xy 68.644008 -170.880532)
			(xy 68.68511 -170.880993) (xy 68.766964 -170.888578) (xy 68.847769 -170.903684) (xy 68.926835 -170.926182)
			(xy 69.003488 -170.955879) (xy 69.077073 -170.992522) (xy 69.146964 -171.035799) (xy 69.212564 -171.08534)
			(xy 69.273312 -171.140722) (xy 69.328691 -171.201473) (xy 69.378228 -171.267076) (xy 69.421501 -171.336969)
			(xy 69.45814 -171.410556) (xy 69.487833 -171.487211) (xy 69.510327 -171.566278) (xy 69.525428 -171.647084)
			(xy 69.53301 -171.728938) (xy 69.533516 -171.77004) (xy 69.53301 -171.813061) (xy 69.524698 -171.898701)
			(xy 69.508156 -171.983138) (xy 69.483538 -172.065583) (xy 69.451074 -172.145266) (xy 69.411068 -172.221441)
			(xy 69.363894 -172.293399) (xy 69.309992 -172.360464) (xy 69.249866 -172.422012) (xy 69.184078 -172.477467)
			(xy 69.14896 -172.502322) (xy 69.13744 -172.510875) (xy 69.119309 -172.533095) (xy 69.108071 -172.55948)
			(xy 69.104615 -172.587949) (xy 69.109211 -172.616257) (xy 69.121499 -172.64217) (xy 69.140507 -172.663644)
			(xy 69.164738 -172.678985) (xy 69.192279 -172.686982) (xy 69.206618 -172.687488)
		)
		(stroke
			(width 0)
			(type solid)
		)
		(fill yes)
		(layer "In15.Cu")
		(net "PVCCD_HV_CPU1")
	)
	(gr_poly
		(pts
			(xy 0.654812 -17.86255)
			(arc
				(start 0.66675 -17.85493)
				(mid 0.827347 -17.756522)
				(end 0.991362 -17.663922)
			)
			(xy 1.017524 -17.61998)
			(arc
				(start 1.017524 -13.780008)
				(mid 1.305283 -13.085295)
				(end 1.999996 -12.797536)
			)
			(arc
				(start 11.102594 -12.797536)
				(mid 13.236139 -11.913635)
				(end 14.11986 -9.780016)
			)
			(xy 14.11986 -3.945382)
			(arc
				(start 14.10081 -3.90779)
				(mid 13.825764 -3.583504)
				(end 13.726922 -3.16992)
			)
			(arc
				(start 13.726922 -3.16992)
				(mid 13.825371 -2.757062)
				(end 14.09954 -2.433066)
			)
			(xy 14.11986 -2.392934) (xy 14.11986 -1.016) (xy 80.684116 -1.016) (xy 80.684116 -2.39141)
			(arc
				(start 80.704944 -2.43205)
				(mid 81.07796 -3.169158)
				(end 80.704944 -3.906266)
			)
			(xy 80.684116 -3.946906)
			(arc
				(start 80.684116 -9.780016)
				(mid 81.568091 -11.91374)
				(end 83.70189 -12.797536)
			)
			(arc
				(start 124.102622 -12.797536)
				(mid 126.236167 -11.913635)
				(end 127.119888 -9.780016)
			)
			(arc
				(start 127.119888 -9.223756)
				(mid 127.113727 -9.202804)
				(end 127.099314 -9.186418)
			)
			(arc
				(start 127.099314 -9.186418)
				(mid 126.839825 -8.890054)
				(end 126.728982 -8.512048)
			)
			(xy 126.700534 -8.46963) (xy 126.687326 -8.463026)
			(arc
				(start 126.66345 -8.457184)
				(mid 126.627619 -8.471973)
				(end 126.61265 -8.50773)
			)
			(arc
				(start 126.61265 -9.780016)
				(mid 125.877331 -11.555233)
				(end 124.102114 -12.290552)
			)
			(arc
				(start 83.70189 -12.290552)
				(mid 81.926673 -11.555233)
				(end 81.191354 -9.780016)
			)
			(xy 81.191354 -1.28524) (xy 81.19364 -1.28524)
			(arc
				(start 81.19364 -0.999998)
				(mid 81.049612 -0.652282)
				(end 80.701896 -0.508254)
			)
			(arc
				(start 14.10208 -0.508254)
				(mid 13.754364 -0.652282)
				(end 13.610336 -0.999998)
			)
			(xy 13.610336 -1.28524) (xy 13.612622 -1.28524)
			(arc
				(start 13.612622 -9.780016)
				(mid 12.877303 -11.555233)
				(end 11.102086 -12.290552)
			)
			(arc
				(start 1.999996 -12.290552)
				(mid 0.946792 -12.726804)
				(end 0.51054 -13.780008)
			)
			(arc
				(start 0.51054 -17.769332)
				(mid 0.517626 -17.795211)
				(end 0.536956 -17.813782)
			)
			(xy 0.62738 -17.863566)
		)
		(stroke
			(width 0)
			(type solid)
		)
		(fill yes)
		(layer "In15.Cu")
		(net "GND")
	)
	(gr_poly
		(pts
			(xy 15.4432 -321.706748) (xy 15.4432 -319.573148) (xy 15.0876 -319.217548) (xy 11.197082 -319.217548)
			(xy 11.193018 -319.21831) (xy 11.178766 -319.220469) (xy 11.150028 -319.222754) (xy 11.135614 -319.222882)
			(xy 11.1212 -319.22276) (xy 11.092462 -319.220473) (xy 11.07821 -319.21831) (xy 11.074146 -319.217548)
			(xy 9.714992 -319.217548) (xy 9.701203 -319.217995) (xy 9.674629 -319.225364) (xy 9.651002 -319.239586)
			(xy 9.632053 -319.259621) (xy 9.619168 -319.284002) (xy 9.61329 -319.310946) (xy 9.613646 -319.324736)
			(xy 9.614154 -319.344548) (xy 9.613656 -319.371197) (xy 9.605713 -319.423901) (xy 9.590003 -319.474831)
			(xy 9.566877 -319.522852) (xy 9.536853 -319.566889) (xy 9.500601 -319.60596) (xy 9.45893 -319.639191)
			(xy 9.412772 -319.66584) (xy 9.363158 -319.685312) (xy 9.311196 -319.697172) (xy 9.258046 -319.701156)
			(xy 9.204896 -319.697172) (xy 9.152934 -319.685312) (xy 9.10332 -319.66584) (xy 9.057162 -319.639191)
			(xy 9.015491 -319.60596) (xy 8.979239 -319.566889) (xy 8.949215 -319.522852) (xy 8.926089 -319.474831)
			(xy 8.910379 -319.423901) (xy 8.902436 -319.371197) (xy 8.901938 -319.344548) (xy 8.902446 -319.324736)
			(xy 8.902741 -319.310952) (xy 8.896832 -319.284034) (xy 8.883944 -319.259674) (xy 8.865015 -319.239645)
			(xy 8.841421 -319.225404) (xy 8.814879 -319.217986) (xy 8.8011 -319.217548) (xy 7.097014 -319.217548)
			(xy 7.09295 -319.21831) (xy 7.0739 -319.22085) (xy 7.05612 -319.222628) (xy 6.7818 -319.496948) (xy 6.7818 -319.743307)
			(xy 10.780004 -319.743307) (xy 10.780004 -319.690009) (xy 10.787947 -319.637305) (xy 10.803657 -319.586375)
			(xy 10.826783 -319.538354) (xy 10.856807 -319.494317) (xy 10.893059 -319.455246) (xy 10.93473 -319.422015)
			(xy 10.980888 -319.395366) (xy 11.030502 -319.375894) (xy 11.082464 -319.364034) (xy 11.135614 -319.360051)
			(xy 11.188764 -319.364034) (xy 11.240726 -319.375894) (xy 11.29034 -319.395366) (xy 11.336498 -319.422015)
			(xy 11.378169 -319.455246) (xy 11.414421 -319.494317) (xy 11.444445 -319.538354) (xy 11.467571 -319.586375)
			(xy 11.483281 -319.637305) (xy 11.491224 -319.690009) (xy 11.491722 -319.716658) (xy 11.491224 -319.743307)
			(xy 11.483281 -319.796011) (xy 11.467571 -319.846941) (xy 11.444445 -319.894962) (xy 11.414421 -319.938999)
			(xy 11.378169 -319.97807) (xy 11.336498 -320.011301) (xy 11.29034 -320.03795) (xy 11.240726 -320.057422)
			(xy 11.188764 -320.069282) (xy 11.135614 -320.073266) (xy 11.082464 -320.069282) (xy 11.030502 -320.057422)
			(xy 10.980888 -320.03795) (xy 10.93473 -320.011301) (xy 10.893059 -319.97807) (xy 10.856807 -319.938999)
			(xy 10.826783 -319.894962) (xy 10.803657 -319.846941) (xy 10.787947 -319.796011) (xy 10.780004 -319.743307)
			(xy 6.7818 -319.743307) (xy 6.7818 -320.13525) (xy 6.782265 -320.149131) (xy 6.789739 -320.175867)
			(xy 6.804147 -320.199597) (xy 6.82442 -320.218561) (xy 6.849057 -320.231356) (xy 6.876232 -320.237032)
			(xy 6.90393 -320.235168) (xy 6.917182 -320.231008) (xy 6.945856 -320.221549) (xy 7.005359 -320.211329)
			(xy 7.035546 -320.210688) (xy 7.062198 -320.211161) (xy 7.114906 -320.219105) (xy 7.165841 -320.234816)
			(xy 7.213866 -320.257943) (xy 7.257907 -320.287969) (xy 7.296981 -320.324225) (xy 7.330216 -320.365899)
			(xy 7.356867 -320.41206) (xy 7.376341 -320.461679) (xy 7.388203 -320.513646) (xy 7.392186 -320.5668)
			(xy 7.390189 -320.593445) (xy 10.780004 -320.593445) (xy 10.780004 -320.540147) (xy 10.787947 -320.487443)
			(xy 10.803657 -320.436513) (xy 10.826783 -320.388492) (xy 10.856807 -320.344455) (xy 10.893059 -320.305384)
			(xy 10.93473 -320.272153) (xy 10.980888 -320.245504) (xy 11.030502 -320.226032) (xy 11.082464 -320.214172)
			(xy 11.135614 -320.210189) (xy 11.188764 -320.214172) (xy 11.240726 -320.226032) (xy 11.29034 -320.245504)
			(xy 11.336498 -320.272153) (xy 11.378169 -320.305384) (xy 11.414421 -320.344455) (xy 11.444445 -320.388492)
			(xy 11.467571 -320.436513) (xy 11.483281 -320.487443) (xy 11.491224 -320.540147) (xy 11.491722 -320.566796)
			(xy 11.491224 -320.593445) (xy 14.223736 -320.593445) (xy 14.223736 -320.540147) (xy 14.231679 -320.487443)
			(xy 14.247389 -320.436513) (xy 14.270515 -320.388492) (xy 14.300539 -320.344455) (xy 14.336791 -320.305384)
			(xy 14.378462 -320.272153) (xy 14.42462 -320.245504) (xy 14.474234 -320.226032) (xy 14.526196 -320.214172)
			(xy 14.579346 -320.210189) (xy 14.632496 -320.214172) (xy 14.684458 -320.226032) (xy 14.734072 -320.245504)
			(xy 14.78023 -320.272153) (xy 14.821901 -320.305384) (xy 14.858153 -320.344455) (xy 14.888177 -320.388492)
			(xy 14.911303 -320.436513) (xy 14.927013 -320.487443) (xy 14.934956 -320.540147) (xy 14.935454 -320.566796)
			(xy 14.934956 -320.593445) (xy 14.927013 -320.646149) (xy 14.911303 -320.697079) (xy 14.888177 -320.7451)
			(xy 14.858153 -320.789137) (xy 14.821901 -320.828208) (xy 14.78023 -320.861439) (xy 14.734072 -320.888088)
			(xy 14.684458 -320.90756) (xy 14.632496 -320.91942) (xy 14.579346 -320.923404) (xy 14.526196 -320.91942)
			(xy 14.474234 -320.90756) (xy 14.42462 -320.888088) (xy 14.378462 -320.861439) (xy 14.336791 -320.828208)
			(xy 14.300539 -320.789137) (xy 14.270515 -320.7451) (xy 14.247389 -320.697079) (xy 14.231679 -320.646149)
			(xy 14.223736 -320.593445) (xy 11.491224 -320.593445) (xy 11.483281 -320.646149) (xy 11.467571 -320.697079)
			(xy 11.444445 -320.7451) (xy 11.414421 -320.789137) (xy 11.378169 -320.828208) (xy 11.336498 -320.861439)
			(xy 11.29034 -320.888088) (xy 11.240726 -320.90756) (xy 11.188764 -320.91942) (xy 11.135614 -320.923404)
			(xy 11.082464 -320.91942) (xy 11.030502 -320.90756) (xy 10.980888 -320.888088) (xy 10.93473 -320.861439)
			(xy 10.893059 -320.828208) (xy 10.856807 -320.789137) (xy 10.826783 -320.7451) (xy 10.803657 -320.697079)
			(xy 10.787947 -320.646149) (xy 10.780004 -320.593445) (xy 7.390189 -320.593445) (xy 7.388203 -320.619954)
			(xy 7.376341 -320.671921) (xy 7.356867 -320.72154) (xy 7.330216 -320.767701) (xy 7.296981 -320.809375)
			(xy 7.257907 -320.845631) (xy 7.213866 -320.875657) (xy 7.165841 -320.898784) (xy 7.114906 -320.914495)
			(xy 7.062198 -320.922439) (xy 7.035546 -320.922904) (xy 7.00536 -320.922249) (xy 6.945856 -320.912041)
			(xy 6.917182 -320.902584) (xy 6.903938 -320.898413) (xy 6.876246 -320.896577) (xy 6.849082 -320.902268)
			(xy 6.824455 -320.915066) (xy 6.804186 -320.934024) (xy 6.789773 -320.957742) (xy 6.782281 -320.984465)
			(xy 6.7818 -320.998342) (xy 6.7818 -321.064128) (xy 6.782259 -321.07484) (xy 6.790955 -321.094417)
			(xy 6.806869 -321.108757) (xy 6.827244 -321.115374) (xy 6.848547 -321.113119) (xy 6.858 -321.10807)
			(xy 6.885196 -321.093167) (xy 6.943473 -321.071983) (xy 7.004542 -321.061231) (xy 7.035546 -321.060572)
			(xy 7.063527 -321.061124) (xy 7.1188 -321.069885) (xy 7.172022 -321.087183) (xy 7.221884 -321.112594)
			(xy 7.267157 -321.14549) (xy 7.306727 -321.185063) (xy 7.33962 -321.230339) (xy 7.365027 -321.280202)
			(xy 7.382321 -321.333425) (xy 7.391078 -321.388699) (xy 7.391654 -321.41668) (xy 7.391181 -321.442595)
			(xy 7.391073 -321.443329) (xy 10.780004 -321.443329) (xy 10.780004 -321.390031) (xy 10.787947 -321.337327)
			(xy 10.803657 -321.286397) (xy 10.826783 -321.238376) (xy 10.856807 -321.194339) (xy 10.893059 -321.155268)
			(xy 10.93473 -321.122037) (xy 10.980888 -321.095388) (xy 11.030502 -321.075916) (xy 11.082464 -321.064056)
			(xy 11.135614 -321.060073) (xy 11.188764 -321.064056) (xy 11.240726 -321.075916) (xy 11.29034 -321.095388)
			(xy 11.336498 -321.122037) (xy 11.378169 -321.155268) (xy 11.414421 -321.194339) (xy 11.444445 -321.238376)
			(xy 11.467571 -321.286397) (xy 11.483281 -321.337327) (xy 11.491224 -321.390031) (xy 11.491722 -321.41668)
			(xy 11.491224 -321.443329) (xy 14.223736 -321.443329) (xy 14.223736 -321.390031) (xy 14.231679 -321.337327)
			(xy 14.247389 -321.286397) (xy 14.270515 -321.238376) (xy 14.300539 -321.194339) (xy 14.336791 -321.155268)
			(xy 14.378462 -321.122037) (xy 14.42462 -321.095388) (xy 14.474234 -321.075916) (xy 14.526196 -321.064056)
			(xy 14.579346 -321.060073) (xy 14.632496 -321.064056) (xy 14.684458 -321.075916) (xy 14.734072 -321.095388)
			(xy 14.78023 -321.122037) (xy 14.821901 -321.155268) (xy 14.858153 -321.194339) (xy 14.888177 -321.238376)
			(xy 14.911303 -321.286397) (xy 14.927013 -321.337327) (xy 14.934956 -321.390031) (xy 14.935454 -321.41668)
			(xy 14.934956 -321.443329) (xy 14.927013 -321.496033) (xy 14.911303 -321.546963) (xy 14.888177 -321.594984)
			(xy 14.858153 -321.639021) (xy 14.821901 -321.678092) (xy 14.78023 -321.711323) (xy 14.734072 -321.737972)
			(xy 14.684458 -321.757444) (xy 14.632496 -321.769304) (xy 14.579346 -321.773288) (xy 14.526196 -321.769304)
			(xy 14.474234 -321.757444) (xy 14.42462 -321.737972) (xy 14.378462 -321.711323) (xy 14.336791 -321.678092)
			(xy 14.300539 -321.639021) (xy 14.270515 -321.594984) (xy 14.247389 -321.546963) (xy 14.231679 -321.496033)
			(xy 14.223736 -321.443329) (xy 11.491224 -321.443329) (xy 11.483281 -321.496033) (xy 11.467571 -321.546963)
			(xy 11.444445 -321.594984) (xy 11.414421 -321.639021) (xy 11.378169 -321.678092) (xy 11.336498 -321.711323)
			(xy 11.29034 -321.737972) (xy 11.240726 -321.757444) (xy 11.188764 -321.769304) (xy 11.135614 -321.773288)
			(xy 11.082464 -321.769304) (xy 11.030502 -321.757444) (xy 10.980888 -321.737972) (xy 10.93473 -321.711323)
			(xy 10.893059 -321.678092) (xy 10.856807 -321.639021) (xy 10.826783 -321.594984) (xy 10.803657 -321.546963)
			(xy 10.787947 -321.496033) (xy 10.780004 -321.443329) (xy 7.391073 -321.443329) (xy 7.383655 -321.493876)
			(xy 7.368772 -321.543524) (xy 7.346849 -321.59049) (xy 7.318348 -321.633781) (xy 7.283871 -321.672481)
			(xy 7.244147 -321.705774) (xy 7.200016 -321.732956) (xy 7.15241 -321.753452) (xy 7.127494 -321.760596)
			(xy 7.112865 -321.765007) (xy 7.086978 -321.781212) (xy 7.06704 -321.804348) (xy 7.054835 -321.832344)
			(xy 7.051453 -321.862697) (xy 7.057199 -321.892693) (xy 7.071556 -321.919649) (xy 7.082028 -321.930776)
			(xy 7.1374 -321.986148) (xy 15.1638 -321.986148)
		)
		(stroke
			(width 0)
			(type solid)
		)
		(fill yes)
		(layer "In15.Cu")
		(net "P3V3_AUX")
	)
	(gr_poly
		(pts
			(xy 444.62954 -25.799288) (xy 444.62954 -11.420348) (xy 442.90996 -9.700768) (xy 437.37276 -9.700768)
			(xy 435.00802 -12.065508) (xy 435.00802 -14.544548) (xy 438.941462 -14.544548) (xy 438.945533 -14.488926)
			(xy 438.957659 -14.434489) (xy 438.977582 -14.382398) (xy 439.004878 -14.333763) (xy 439.038964 -14.28962)
			(xy 439.079113 -14.250911) (xy 439.124471 -14.21846) (xy 439.174071 -14.192959) (xy 439.226855 -14.174952)
			(xy 439.281698 -14.164822) (xy 439.337432 -14.162785) (xy 439.392869 -14.168885) (xy 439.446826 -14.182991)
			(xy 439.498155 -14.204803) (xy 439.545761 -14.233857) (xy 439.588629 -14.269532) (xy 439.625846 -14.311069)
			(xy 439.656619 -14.357582) (xy 439.680291 -14.408079) (xy 439.696359 -14.461486) (xy 439.704479 -14.516662)
			(xy 439.704988 -14.544548) (xy 439.704479 -14.572434) (xy 439.696359 -14.62761) (xy 439.680291 -14.681017)
			(xy 439.656619 -14.731514) (xy 439.625846 -14.778027) (xy 439.588629 -14.819564) (xy 439.545761 -14.855239)
			(xy 439.498155 -14.884293) (xy 439.446826 -14.906105) (xy 439.392869 -14.920211) (xy 439.337432 -14.926311)
			(xy 439.281698 -14.924274) (xy 439.226855 -14.914144) (xy 439.174071 -14.896137) (xy 439.124471 -14.870636)
			(xy 439.079113 -14.838185) (xy 439.038964 -14.799476) (xy 439.004878 -14.755333) (xy 438.977582 -14.706698)
			(xy 438.957659 -14.654607) (xy 438.945533 -14.60017) (xy 438.941462 -14.544548) (xy 435.00802 -14.544548)
			(xy 435.00802 -15.687548) (xy 438.916062 -15.687548) (xy 438.920133 -15.631926) (xy 438.932259 -15.577489)
			(xy 438.952182 -15.525398) (xy 438.979478 -15.476763) (xy 439.013564 -15.43262) (xy 439.053713 -15.393911)
			(xy 439.099071 -15.36146) (xy 439.148671 -15.335959) (xy 439.201455 -15.317952) (xy 439.256298 -15.307822)
			(xy 439.312032 -15.305785) (xy 439.367469 -15.311885) (xy 439.421426 -15.325991) (xy 439.472755 -15.347803)
			(xy 439.520361 -15.376857) (xy 439.563229 -15.412532) (xy 439.600446 -15.454069) (xy 439.631219 -15.500582)
			(xy 439.654891 -15.551079) (xy 439.670959 -15.604486) (xy 439.679079 -15.659662) (xy 439.679588 -15.687548)
			(xy 439.679079 -15.715434) (xy 439.670959 -15.77061) (xy 439.654891 -15.824017) (xy 439.631219 -15.874514)
			(xy 439.600446 -15.921027) (xy 439.563229 -15.962564) (xy 439.520361 -15.998239) (xy 439.472755 -16.027293)
			(xy 439.421426 -16.049105) (xy 439.367469 -16.063211) (xy 439.312032 -16.069311) (xy 439.256298 -16.067274)
			(xy 439.201455 -16.057144) (xy 439.148671 -16.039137) (xy 439.099071 -16.013636) (xy 439.053713 -15.981185)
			(xy 439.013564 -15.942476) (xy 438.979478 -15.898333) (xy 438.952182 -15.849698) (xy 438.932259 -15.797607)
			(xy 438.920133 -15.74317) (xy 438.916062 -15.687548) (xy 435.00802 -15.687548) (xy 435.00802 -17.287748)
			(xy 435.704232 -17.287748) (xy 435.708303 -17.232126) (xy 435.720429 -17.177689) (xy 435.740352 -17.125598)
			(xy 435.767648 -17.076963) (xy 435.801734 -17.03282) (xy 435.841883 -16.994111) (xy 435.887241 -16.96166)
			(xy 435.936841 -16.936159) (xy 435.989625 -16.918152) (xy 436.044468 -16.908022) (xy 436.100202 -16.905985)
			(xy 436.155639 -16.912085) (xy 436.209596 -16.926191) (xy 436.260925 -16.948003) (xy 436.308531 -16.977057)
			(xy 436.351399 -17.012732) (xy 436.388616 -17.054269) (xy 436.419389 -17.100782) (xy 436.443061 -17.151279)
			(xy 436.459129 -17.204686) (xy 436.467249 -17.259862) (xy 436.467758 -17.287748) (xy 436.725312 -17.287748)
			(xy 436.729383 -17.232126) (xy 436.741509 -17.177689) (xy 436.761432 -17.125598) (xy 436.788728 -17.076963)
			(xy 436.822814 -17.03282) (xy 436.862963 -16.994111) (xy 436.908321 -16.96166) (xy 436.957921 -16.936159)
			(xy 437.010705 -16.918152) (xy 437.065548 -16.908022) (xy 437.121282 -16.905985) (xy 437.176719 -16.912085)
			(xy 437.230676 -16.926191) (xy 437.282005 -16.948003) (xy 437.329611 -16.977057) (xy 437.372479 -17.012732)
			(xy 437.409696 -17.054269) (xy 437.440469 -17.100782) (xy 437.464141 -17.151279) (xy 437.480209 -17.204686)
			(xy 437.488329 -17.259862) (xy 437.488374 -17.262348) (xy 437.849262 -17.262348) (xy 437.853333 -17.206726)
			(xy 437.865459 -17.152289) (xy 437.885382 -17.100198) (xy 437.912678 -17.051563) (xy 437.946764 -17.00742)
			(xy 437.986913 -16.968711) (xy 438.032271 -16.93626) (xy 438.081871 -16.910759) (xy 438.134655 -16.892752)
			(xy 438.189498 -16.882622) (xy 438.245232 -16.880585) (xy 438.300669 -16.886685) (xy 438.354626 -16.900791)
			(xy 438.405955 -16.922603) (xy 438.453561 -16.951657) (xy 438.496429 -16.987332) (xy 438.533646 -17.028869)
			(xy 438.564419 -17.075382) (xy 438.588091 -17.125879) (xy 438.604159 -17.179286) (xy 438.612279 -17.234462)
			(xy 438.612788 -17.262348) (xy 438.612279 -17.290234) (xy 438.604159 -17.34541) (xy 438.588091 -17.398817)
			(xy 438.564419 -17.449314) (xy 438.533646 -17.495827) (xy 438.496429 -17.537364) (xy 438.453561 -17.573039)
			(xy 438.405955 -17.602093) (xy 438.354626 -17.623905) (xy 438.300669 -17.638011) (xy 438.245232 -17.644111)
			(xy 438.189498 -17.642074) (xy 438.134655 -17.631944) (xy 438.081871 -17.613937) (xy 438.032271 -17.588436)
			(xy 437.986913 -17.555985) (xy 437.946764 -17.517276) (xy 437.912678 -17.473133) (xy 437.885382 -17.424498)
			(xy 437.865459 -17.372407) (xy 437.853333 -17.31797) (xy 437.849262 -17.262348) (xy 437.488374 -17.262348)
			(xy 437.488838 -17.287748) (xy 437.488329 -17.315634) (xy 437.480209 -17.37081) (xy 437.464141 -17.424217)
			(xy 437.440469 -17.474714) (xy 437.409696 -17.521227) (xy 437.372479 -17.562764) (xy 437.329611 -17.598439)
			(xy 437.282005 -17.627493) (xy 437.230676 -17.649305) (xy 437.176719 -17.663411) (xy 437.121282 -17.669511)
			(xy 437.065548 -17.667474) (xy 437.010705 -17.657344) (xy 436.957921 -17.639337) (xy 436.908321 -17.613836)
			(xy 436.862963 -17.581385) (xy 436.822814 -17.542676) (xy 436.788728 -17.498533) (xy 436.761432 -17.449898)
			(xy 436.741509 -17.397807) (xy 436.729383 -17.34337) (xy 436.725312 -17.287748) (xy 436.467758 -17.287748)
			(xy 436.467249 -17.315634) (xy 436.459129 -17.37081) (xy 436.443061 -17.424217) (xy 436.419389 -17.474714)
			(xy 436.388616 -17.521227) (xy 436.351399 -17.562764) (xy 436.308531 -17.598439) (xy 436.260925 -17.627493)
			(xy 436.209596 -17.649305) (xy 436.155639 -17.663411) (xy 436.100202 -17.669511) (xy 436.044468 -17.667474)
			(xy 435.989625 -17.657344) (xy 435.936841 -17.639337) (xy 435.887241 -17.613836) (xy 435.841883 -17.581385)
			(xy 435.801734 -17.542676) (xy 435.767648 -17.498533) (xy 435.740352 -17.449898) (xy 435.720429 -17.397807)
			(xy 435.708303 -17.34337) (xy 435.704232 -17.287748) (xy 435.00802 -17.287748) (xy 435.00802 -19.395948)
			(xy 439.246262 -19.395948) (xy 439.250333 -19.340326) (xy 439.262459 -19.285889) (xy 439.282382 -19.233798)
			(xy 439.309678 -19.185163) (xy 439.343764 -19.14102) (xy 439.383913 -19.102311) (xy 439.429271 -19.06986)
			(xy 439.478871 -19.044359) (xy 439.531655 -19.026352) (xy 439.586498 -19.016222) (xy 439.642232 -19.014185)
			(xy 439.697669 -19.020285) (xy 439.751626 -19.034391) (xy 439.802955 -19.056203) (xy 439.850561 -19.085257)
			(xy 439.893429 -19.120932) (xy 439.930646 -19.162469) (xy 439.961419 -19.208982) (xy 439.985091 -19.259479)
			(xy 440.001159 -19.312886) (xy 440.009279 -19.368062) (xy 440.009788 -19.395948) (xy 440.009279 -19.423834)
			(xy 440.001159 -19.47901) (xy 439.985091 -19.532417) (xy 439.961419 -19.582914) (xy 439.930646 -19.629427)
			(xy 439.893429 -19.670964) (xy 439.850561 -19.706639) (xy 439.802955 -19.735693) (xy 439.751626 -19.757505)
			(xy 439.697669 -19.771611) (xy 439.642232 -19.777711) (xy 439.586498 -19.775674) (xy 439.531655 -19.765544)
			(xy 439.478871 -19.747537) (xy 439.429271 -19.722036) (xy 439.383913 -19.689585) (xy 439.343764 -19.650876)
			(xy 439.309678 -19.606733) (xy 439.282382 -19.558098) (xy 439.262459 -19.506007) (xy 439.250333 -19.45157)
			(xy 439.246262 -19.395948) (xy 435.00802 -19.395948) (xy 435.00802 -23.689818) (xy 437.315354 -23.689818)
			(xy 437.319425 -23.634196) (xy 437.331551 -23.579759) (xy 437.351474 -23.527668) (xy 437.37877 -23.479033)
			(xy 437.412856 -23.43489) (xy 437.453005 -23.396181) (xy 437.498363 -23.36373) (xy 437.547963 -23.338229)
			(xy 437.600747 -23.320222) (xy 437.65559 -23.310092) (xy 437.711324 -23.308055) (xy 437.766761 -23.314155)
			(xy 437.820718 -23.328261) (xy 437.872047 -23.350073) (xy 437.919653 -23.379127) (xy 437.962521 -23.414802)
			(xy 437.999738 -23.456339) (xy 438.030511 -23.502852) (xy 438.054183 -23.553349) (xy 438.070251 -23.606756)
			(xy 438.078371 -23.661932) (xy 438.07888 -23.689818) (xy 438.078371 -23.717704) (xy 438.070251 -23.77288)
			(xy 438.054183 -23.826287) (xy 438.030511 -23.876784) (xy 437.999738 -23.923297) (xy 437.962521 -23.964834)
			(xy 437.919653 -24.000509) (xy 437.872047 -24.029563) (xy 437.820718 -24.051375) (xy 437.766761 -24.065481)
			(xy 437.711324 -24.071581) (xy 437.65559 -24.069544) (xy 437.600747 -24.059414) (xy 437.547963 -24.041407)
			(xy 437.498363 -24.015906) (xy 437.453005 -23.983455) (xy 437.412856 -23.944746) (xy 437.37877 -23.900603)
			(xy 437.351474 -23.851968) (xy 437.331551 -23.799877) (xy 437.319425 -23.74544) (xy 437.315354 -23.689818)
			(xy 435.00802 -23.689818) (xy 435.00802 -25.823418) (xy 437.264554 -25.823418) (xy 437.268625 -25.767796)
			(xy 437.280751 -25.713359) (xy 437.300674 -25.661268) (xy 437.32797 -25.612633) (xy 437.362056 -25.56849)
			(xy 437.402205 -25.529781) (xy 437.447563 -25.49733) (xy 437.497163 -25.471829) (xy 437.549947 -25.453822)
			(xy 437.60479 -25.443692) (xy 437.660524 -25.441655) (xy 437.715961 -25.447755) (xy 437.769918 -25.461861)
			(xy 437.821247 -25.483673) (xy 437.868853 -25.512727) (xy 437.911721 -25.548402) (xy 437.948938 -25.589939)
			(xy 437.979711 -25.636452) (xy 438.003383 -25.686949) (xy 438.019451 -25.740356) (xy 438.027571 -25.795532)
			(xy 438.02808 -25.823418) (xy 438.027571 -25.851304) (xy 438.020461 -25.899618) (xy 438.255154 -25.899618)
			(xy 438.259225 -25.843996) (xy 438.271351 -25.789559) (xy 438.291274 -25.737468) (xy 438.31857 -25.688833)
			(xy 438.352656 -25.64469) (xy 438.392805 -25.605981) (xy 438.438163 -25.57353) (xy 438.487763 -25.548029)
			(xy 438.540547 -25.530022) (xy 438.59539 -25.519892) (xy 438.651124 -25.517855) (xy 438.706561 -25.523955)
			(xy 438.760518 -25.538061) (xy 438.811847 -25.559873) (xy 438.859453 -25.588927) (xy 438.902321 -25.624602)
			(xy 438.939538 -25.666139) (xy 438.970311 -25.712652) (xy 438.993983 -25.763149) (xy 439.010051 -25.816556)
			(xy 439.018171 -25.871732) (xy 439.01868 -25.899618) (xy 439.018171 -25.927504) (xy 439.010051 -25.98268)
			(xy 438.993983 -26.036087) (xy 438.970311 -26.086584) (xy 438.939538 -26.133097) (xy 438.902321 -26.174634)
			(xy 438.859453 -26.210309) (xy 438.811847 -26.239363) (xy 438.760518 -26.261175) (xy 438.706561 -26.275281)
			(xy 438.651124 -26.281381) (xy 438.59539 -26.279344) (xy 438.540547 -26.269214) (xy 438.487763 -26.251207)
			(xy 438.438163 -26.225706) (xy 438.392805 -26.193255) (xy 438.352656 -26.154546) (xy 438.31857 -26.110403)
			(xy 438.291274 -26.061768) (xy 438.271351 -26.009677) (xy 438.259225 -25.95524) (xy 438.255154 -25.899618)
			(xy 438.020461 -25.899618) (xy 438.019451 -25.90648) (xy 438.003383 -25.959887) (xy 437.979711 -26.010384)
			(xy 437.948938 -26.056897) (xy 437.911721 -26.098434) (xy 437.868853 -26.134109) (xy 437.821247 -26.163163)
			(xy 437.769918 -26.184975) (xy 437.715961 -26.199081) (xy 437.660524 -26.205181) (xy 437.60479 -26.203144)
			(xy 437.549947 -26.193014) (xy 437.497163 -26.175007) (xy 437.447563 -26.149506) (xy 437.402205 -26.117055)
			(xy 437.362056 -26.078346) (xy 437.32797 -26.034203) (xy 437.300674 -25.985568) (xy 437.280751 -25.933477)
			(xy 437.268625 -25.87904) (xy 437.264554 -25.823418) (xy 435.00802 -25.823418) (xy 435.00802 -26.228548)
			(xy 435.3306 -26.551128) (xy 443.8777 -26.551128)
		)
		(stroke
			(width 0)
			(type solid)
		)
		(fill yes)
		(layer "In15.Cu")
		(net "P12V_OCP_SFF")
	)
	(gr_poly
		(pts
			(arc
				(start 256.800096 -36.291012)
				(mid 258.932727 -35.407647)
				(end 259.816092 -33.275016)
			)
			(xy 259.817616 -32.293306) (xy 259.817616 -32.275018)
			(arc
				(start 259.817616 -13.780008)
				(mid 260.105375 -13.085295)
				(end 260.800088 -12.797536)
			)
			(arc
				(start 385.601972 -12.797536)
				(mid 387.735681 -11.913725)
				(end 388.619492 -9.780016)
			)
			(xy 388.619492 -3.928364)
			(arc
				(start 388.614158 -3.917442)
				(mid 388.329377 -3.590886)
				(end 388.226808 -3.16992)
			)
			(arc
				(start 388.226808 -3.16992)
				(mid 388.275543 -2.875216)
				(end 388.416546 -2.611882)
			)
			(arc
				(start 388.416546 -2.611882)
				(mid 388.501545 -2.513276)
				(end 388.59968 -2.427732)
			)
			(xy 388.619492 -2.388108) (xy 388.619492 -1.016) (xy 455.184256 -1.016) (xy 455.184256 -2.375154)
			(arc
				(start 455.205338 -2.416048)
				(mid 455.573689 -3.012402)
				(end 455.41184 -3.69443)
			)
			(arc
				(start 455.41184 -3.69443)
				(mid 455.315091 -3.810755)
				(end 455.200512 -3.909568)
			)
			(xy 455.184256 -3.941318)
			(arc
				(start 455.184256 -9.780016)
				(mid 456.068231 -11.91374)
				(end 458.20203 -12.797536)
			)
			(arc
				(start 469.799924 -12.797536)
				(mid 470.494637 -13.085295)
				(end 470.782396 -13.780008)
			)
			(xy 470.782396 -17.620234)
			(arc
				(start 470.808558 -17.664176)
				(mid 470.972568 -17.756784)
				(end 471.13317 -17.855184)
			)
			(arc
				(start 471.13317 -17.855184)
				(mid 471.158695 -17.863037)
				(end 471.184732 -17.856962)
			)
			(arc
				(start 471.262964 -17.814036)
				(mid 471.282207 -17.795414)
				(end 471.28938 -17.769586)
			)
			(arc
				(start 471.28938 -13.780008)
				(mid 470.853128 -12.726804)
				(end 469.799924 -12.290552)
			)
			(arc
				(start 458.20203 -12.290552)
				(mid 456.426813 -11.555233)
				(end 455.691494 -9.780016)
			)
			(xy 455.691494 -1.30556) (xy 455.69378 -1.30556)
			(arc
				(start 455.69378 -0.999998)
				(mid 455.549752 -0.652282)
				(end 455.202036 -0.508254)
			)
			(arc
				(start 388.601966 -0.508254)
				(mid 388.25425 -0.652282)
				(end 388.110222 -0.999998)
			)
			(xy 388.110222 -1.30556) (xy 388.112508 -1.30556)
			(arc
				(start 388.112508 -9.780016)
				(mid 387.377189 -11.555233)
				(end 385.601972 -12.290552)
			)
			(arc
				(start 260.800088 -12.290552)
				(mid 259.746884 -12.726804)
				(end 259.310632 -13.780008)
			)
			(arc
				(start 259.310632 -32.275018)
				(mid 259.308727 -32.775015)
				(end 259.308092 -33.275016)
			)
			(arc
				(start 259.308092 -33.275016)
				(mid 258.573517 -35.048437)
				(end 256.800096 -35.783012)
			)
			(arc
				(start 225.300032 -35.783012)
				(mid 223.526611 -35.048437)
				(end 222.792036 -33.275016)
			)
			(arc
				(start 222.792036 -33.275016)
				(mid 222.790131 -32.775019)
				(end 222.789496 -32.275018)
			)
			(arc
				(start 222.789496 -13.780008)
				(mid 222.353244 -12.726804)
				(end 221.30004 -12.290552)
			)
			(arc
				(start 196.701918 -12.290552)
				(mid 194.926701 -11.555233)
				(end 194.191382 -9.780016)
			)
			(xy 194.191382 -6.53796) (xy 194.193668 -6.53796)
			(arc
				(start 194.193668 -6.279896)
				(mid 194.04964 -5.93218)
				(end 193.701924 -5.788152)
			)
			(arc
				(start 127.102108 -5.788152)
				(mid 126.754392 -5.93218)
				(end 126.610364 -6.279896)
			)
			(xy 126.610364 -6.53796) (xy 126.61265 -6.53796)
			(arc
				(start 126.61265 -7.744206)
				(mid 126.627618 -7.779963)
				(end 126.66345 -7.794752)
			)
			(arc
				(start 126.687326 -7.78891)
				(mid 126.774244 -7.75555)
				(end 126.86665 -7.744206)
			)
			(arc
				(start 126.86665 -7.744206)
				(mid 126.931475 -7.749794)
				(end 126.994412 -7.766304)
			)
			(arc
				(start 126.994412 -7.766304)
				(mid 127.020815 -7.768359)
				(end 127.044704 -7.756906)
			)
			(arc
				(start 127.044704 -7.756906)
				(mid 127.071589 -7.734537)
				(end 127.099314 -7.713218)
			)
			(xy 127.119888 -7.672832) (xy 127.119888 -6.295898) (xy 193.684144 -6.295898) (xy 193.684144 -7.673086)
			(arc
				(start 193.704718 -7.713472)
				(mid 194.076604 -8.449818)
				(end 193.704718 -9.186164)
			)
			(xy 193.684144 -9.22655)
			(arc
				(start 193.684144 -9.780016)
				(mid 193.7102 -10.175217)
				(end 193.787776 -10.563606)
			)
			(arc
				(start 193.787776 -10.563606)
				(mid 193.792722 -10.573651)
				(end 193.799714 -10.582402)
			)
			(arc
				(start 193.98107 -10.763758)
				(mid 194.050065 -10.866877)
				(end 194.074288 -10.988548)
			)
			(arc
				(start 194.074288 -11.25093)
				(mid 194.075534 -11.261862)
				(end 194.079114 -11.272266)
			)
			(arc
				(start 194.079114 -11.272266)
				(mid 195.184898 -12.388463)
				(end 196.701918 -12.797536)
			)
			(arc
				(start 221.30004 -12.797536)
				(mid 221.994753 -13.085295)
				(end 222.282512 -13.780008)
			)
			(xy 222.282512 -32.275018)
			(arc
				(start 222.284036 -33.275016)
				(mid 223.167401 -35.407647)
				(end 225.300032 -36.291012)
			)
		)
		(stroke
			(width 0)
			(type solid)
		)
		(fill yes)
		(layer "In15.Cu")
		(net "GND")
	)
	(gr_poly
		(pts
			(xy 237.90148 -128.438148) (xy 237.90148 -125.186948) (xy 236.78388 -124.069348) (xy 232.13568 -124.069348)
			(xy 231.67848 -123.612148) (xy 229.84968 -123.612148) (xy 229.59568 -123.866148) (xy 229.59568 -126.071122)
			(xy 229.77424 -126.071122) (xy 229.778311 -126.0155) (xy 229.790437 -125.961063) (xy 229.81036 -125.908972)
			(xy 229.837656 -125.860337) (xy 229.871742 -125.816194) (xy 229.911891 -125.777485) (xy 229.957249 -125.745034)
			(xy 230.006849 -125.719533) (xy 230.059633 -125.701526) (xy 230.114476 -125.691396) (xy 230.17021 -125.689359)
			(xy 230.225647 -125.695459) (xy 230.279604 -125.709565) (xy 230.330933 -125.731377) (xy 230.378539 -125.760431)
			(xy 230.421407 -125.796106) (xy 230.458624 -125.837643) (xy 230.489397 -125.884156) (xy 230.513069 -125.934653)
			(xy 230.529137 -125.98806) (xy 230.537257 -126.043236) (xy 230.537706 -126.06782) (xy 230.76282 -126.06782)
			(xy 230.766796 -126.013494) (xy 230.778639 -125.960325) (xy 230.798098 -125.909448) (xy 230.824758 -125.861946)
			(xy 230.858049 -125.818832) (xy 230.897263 -125.781025) (xy 230.941565 -125.74933) (xy 230.990008 -125.724424)
			(xy 231.041562 -125.706836) (xy 231.095128 -125.696942) (xy 231.149563 -125.694952) (xy 231.203708 -125.70091)
			(xy 231.256408 -125.714688) (xy 231.306541 -125.735992) (xy 231.353037 -125.764368) (xy 231.365762 -125.774958)
			(xy 232.819194 -125.774958) (xy 232.819618 -125.74834) (xy 232.827199 -125.695647) (xy 232.842203 -125.644569)
			(xy 232.864322 -125.596146) (xy 232.893107 -125.551364) (xy 232.927972 -125.511134) (xy 232.968207 -125.476275)
			(xy 233.012994 -125.447496) (xy 233.06142 -125.425384) (xy 233.1125 -125.410388) (xy 233.165194 -125.402814)
			(xy 233.191812 -125.40234) (xy 233.21767 -125.402773) (xy 233.268891 -125.409922) (xy 233.318632 -125.424081)
			(xy 233.365939 -125.444978) (xy 233.388154 -125.45822) (xy 233.399713 -125.464871) (xy 233.425246 -125.472536)
			(xy 233.451893 -125.473334) (xy 233.477839 -125.46721) (xy 233.501317 -125.454581) (xy 233.520728 -125.436308)
			(xy 233.528108 -125.4252) (xy 233.541892 -125.403575) (xy 233.574354 -125.363876) (xy 233.611831 -125.328871)
			(xy 233.632502 -125.313694) (xy 233.644522 -125.304505) (xy 233.66297 -125.280542) (xy 233.673593 -125.252227)
			(xy 233.67546 -125.222043) (xy 233.668406 -125.192635) (xy 233.661204 -125.179328) (xy 233.648923 -125.157711)
			(xy 233.629542 -125.111929) (xy 233.616424 -125.063975) (xy 233.609804 -125.014702) (xy 233.609388 -124.989844)
			(xy 233.609909 -124.961959) (xy 233.618221 -124.906812) (xy 233.634659 -124.85352) (xy 233.658857 -124.803274)
			(xy 233.690273 -124.757195) (xy 233.728206 -124.716313) (xy 233.771808 -124.681541) (xy 233.820106 -124.653656)
			(xy 233.872021 -124.633281) (xy 233.926392 -124.620871) (xy 233.982006 -124.616704) (xy 234.03762 -124.620871)
			(xy 234.091991 -124.633281) (xy 234.143906 -124.653656) (xy 234.192204 -124.681541) (xy 234.235806 -124.716313)
			(xy 234.273739 -124.757195) (xy 234.305155 -124.803274) (xy 234.329353 -124.85352) (xy 234.345791 -124.906812)
			(xy 234.354103 -124.961959) (xy 234.354624 -124.989844) (xy 234.354568 -124.9926) (xy 234.481072 -124.9926)
			(xy 234.48524 -124.936984) (xy 234.497651 -124.882611) (xy 234.518029 -124.830695) (xy 234.545916 -124.782396)
			(xy 234.580691 -124.738794) (xy 234.621577 -124.700862) (xy 234.66766 -124.669448) (xy 234.717911 -124.645253)
			(xy 234.771206 -124.628819) (xy 234.826356 -124.620512) (xy 234.854242 -124.62002) (xy 234.8821 -124.620522)
			(xy 234.937194 -124.628835) (xy 234.990436 -124.645255) (xy 235.040642 -124.669416) (xy 235.086693 -124.70078)
			(xy 235.10748 -124.719334) (xy 235.119034 -124.72914) (xy 235.146335 -124.742243) (xy 235.176276 -124.746787)
			(xy 235.206236 -124.742374) (xy 235.233595 -124.729391) (xy 235.245148 -124.719588) (xy 235.265889 -124.70125)
			(xy 235.311776 -124.670275) (xy 235.36174 -124.646429) (xy 235.414681 -124.630234) (xy 235.469435 -124.622048)
			(xy 235.497116 -124.621544) (xy 235.524457 -124.622005) (xy 235.578553 -124.629988) (xy 235.6309 -124.645794)
			(xy 235.680374 -124.669084) (xy 235.725911 -124.699357) (xy 235.746544 -124.717302) (xy 235.757995 -124.726927)
			(xy 235.785039 -124.739674) (xy 235.814616 -124.744048) (xy 235.844193 -124.739674) (xy 235.871237 -124.726927)
			(xy 235.882688 -124.717302) (xy 235.90334 -124.699383) (xy 235.948879 -124.669122) (xy 235.99835 -124.645837)
			(xy 236.05069 -124.630027) (xy 236.104778 -124.622029) (xy 236.132116 -124.621544) (xy 236.158731 -124.622042)
			(xy 236.211419 -124.629619) (xy 236.262492 -124.644616) (xy 236.310912 -124.666729) (xy 236.355692 -124.695506)
			(xy 236.395921 -124.730364) (xy 236.43078 -124.770591) (xy 236.459561 -124.815369) (xy 236.481676 -124.863787)
			(xy 236.496677 -124.91486) (xy 236.504257 -124.967547) (xy 236.504734 -124.994162) (xy 236.504268 -125.020648)
			(xy 236.496778 -125.073087) (xy 236.481929 -125.123935) (xy 236.460021 -125.172164) (xy 236.431497 -125.2168)
			(xy 236.396934 -125.256941) (xy 236.357028 -125.291777) (xy 236.335062 -125.306582) (xy 236.323151 -125.314906)
			(xy 236.304186 -125.336903) (xy 236.292193 -125.363355) (xy 236.288145 -125.392115) (xy 236.292371 -125.42085)
			(xy 236.304528 -125.447227) (xy 236.313726 -125.458474) (xy 236.327344 -125.474659) (xy 236.351272 -125.509542)
			(xy 236.361478 -125.52807) (xy 236.368757 -125.540498) (xy 236.388882 -125.561078) (xy 236.413956 -125.575214)
			(xy 236.441982 -125.58178) (xy 236.470725 -125.580254) (xy 236.497898 -125.570756) (xy 236.521334 -125.554044)
			(xy 236.530642 -125.543056) (xy 236.548432 -125.521445) (xy 236.589367 -125.483268) (xy 236.63555 -125.451641)
			(xy 236.685942 -125.427274) (xy 236.739411 -125.410716) (xy 236.794755 -125.402338) (xy 236.822742 -125.401832)
			(xy 236.850629 -125.402256) (xy 236.905778 -125.410574) (xy 236.959072 -125.427018) (xy 237.00932 -125.451222)
			(xy 237.055399 -125.482643) (xy 237.096282 -125.520581) (xy 237.131053 -125.564188) (xy 237.158938 -125.61249)
			(xy 237.179313 -125.664408) (xy 237.191723 -125.718783) (xy 237.195891 -125.7744) (xy 237.191723 -125.830017)
			(xy 237.179313 -125.884392) (xy 237.158938 -125.93631) (xy 237.131053 -125.984612) (xy 237.096282 -126.028219)
			(xy 237.055399 -126.066157) (xy 237.00932 -126.097578) (xy 236.959072 -126.121782) (xy 236.905778 -126.138226)
			(xy 236.850629 -126.146544) (xy 236.822742 -126.147068) (xy 236.79436 -126.146556) (xy 236.738249 -126.137965)
			(xy 236.684093 -126.120959) (xy 236.633143 -126.095933) (xy 236.58658 -126.063466) (xy 236.545483 -126.02431)
			(xy 236.510803 -125.979372) (xy 236.496606 -125.95479) (xy 236.489153 -125.942473) (xy 236.468779 -125.922161)
			(xy 236.443553 -125.908329) (xy 236.415472 -125.902073) (xy 236.386759 -125.903887) (xy 236.359689 -125.913629)
			(xy 236.336405 -125.930527) (xy 236.327188 -125.941582) (xy 236.308995 -125.96421) (xy 236.266952 -126.00425)
			(xy 236.219329 -126.037461) (xy 236.167227 -126.063077) (xy 236.111846 -126.080507) (xy 236.054465 -126.08935)
			(xy 236.025436 -126.089918) (xy 235.998184 -126.089411) (xy 235.944236 -126.081659) (xy 235.891939 -126.066308)
			(xy 235.84236 -126.043671) (xy 235.796507 -126.014208) (xy 235.755314 -125.978518) (xy 235.71962 -125.93733)
			(xy 235.690151 -125.891481) (xy 235.667508 -125.841904) (xy 235.65215 -125.789609) (xy 235.644392 -125.735661)
			(xy 235.643928 -125.70841) (xy 235.644449 -125.680755) (xy 235.652442 -125.626026) (xy 235.668247 -125.573022)
			(xy 235.691534 -125.522853) (xy 235.721816 -125.476569) (xy 235.758458 -125.435138) (xy 235.800695 -125.399428)
			(xy 235.847641 -125.370184) (xy 235.872782 -125.358652) (xy 235.882006 -125.354185) (xy 235.896077 -125.3393)
			(xy 235.903205 -125.320098) (xy 235.902255 -125.299637) (xy 235.893378 -125.281178) (xy 235.88599 -125.27407)
			(xy 235.882688 -125.271022) (xy 235.871237 -125.261397) (xy 235.844193 -125.24865) (xy 235.814616 -125.244276)
			(xy 235.785039 -125.24865) (xy 235.757995 -125.261397) (xy 235.746544 -125.271022) (xy 235.725921 -125.288977)
			(xy 235.680374 -125.319231) (xy 235.630896 -125.342509) (xy 235.578549 -125.358312) (xy 235.524456 -125.3663)
			(xy 235.497116 -125.36678) (xy 235.469259 -125.366243) (xy 235.414167 -125.357938) (xy 235.360925 -125.341527)
			(xy 235.310719 -125.317373) (xy 235.264666 -125.286017) (xy 235.243878 -125.267466) (xy 235.232356 -125.257619)
			(xy 235.205043 -125.244521) (xy 235.175093 -125.239984) (xy 235.145126 -125.244408) (xy 235.117764 -125.257403)
			(xy 235.10621 -125.267212) (xy 235.085485 -125.28557) (xy 235.039594 -125.316542) (xy 234.989626 -125.340385)
			(xy 234.936681 -125.356574) (xy 234.881924 -125.364755) (xy 234.854242 -125.365256) (xy 234.826356 -125.364688)
			(xy 234.771206 -125.356381) (xy 234.717911 -125.339947) (xy 234.66766 -125.315752) (xy 234.621577 -125.284338)
			(xy 234.580691 -125.246406) (xy 234.545916 -125.202804) (xy 234.518028 -125.154505) (xy 234.497651 -125.102589)
			(xy 234.48524 -125.048216) (xy 234.481072 -124.9926) (xy 234.354568 -124.9926) (xy 234.354035 -125.018843)
			(xy 234.345057 -125.076141) (xy 234.327309 -125.131356) (xy 234.301219 -125.183154) (xy 234.267418 -125.230284)
			(xy 234.226723 -125.271607) (xy 234.203748 -125.28931) (xy 234.191892 -125.298762) (xy 234.173866 -125.32312)
			(xy 234.163798 -125.351701) (xy 234.162577 -125.381978) (xy 234.170312 -125.411277) (xy 234.17784 -125.424438)
			(xy 234.191337 -125.447117) (xy 234.21261 -125.495415) (xy 234.22702 -125.546184) (xy 234.234292 -125.598456)
			(xy 234.234736 -125.624844) (xy 234.234263 -125.652095) (xy 234.226501 -125.706042) (xy 234.211142 -125.758335)
			(xy 234.188498 -125.807911) (xy 234.15903 -125.853759) (xy 234.123337 -125.894948) (xy 234.082147 -125.930639)
			(xy 234.036297 -125.960106) (xy 233.98672 -125.982748) (xy 233.934426 -125.998105) (xy 233.880479 -126.005864)
			(xy 233.853228 -126.006352) (xy 233.825864 -126.005933) (xy 233.771693 -125.998143) (xy 233.719196 -125.982676)
			(xy 233.669455 -125.95985) (xy 233.646218 -125.945392) (xy 233.634776 -125.938482) (xy 233.609349 -125.930273)
			(xy 233.582662 -125.928951) (xy 233.556548 -125.934604) (xy 233.532798 -125.946846) (xy 233.513043 -125.964837)
			(xy 233.505502 -125.975872) (xy 233.499831 -125.984616) (xy 233.487631 -126.001517) (xy 233.481118 -126.009654)
			(xy 233.472049 -126.021585) (xy 233.460754 -126.049333) (xy 233.457984 -126.079164) (xy 233.463978 -126.108517)
			(xy 233.478221 -126.134874) (xy 233.488484 -126.145798) (xy 233.508933 -126.166906) (xy 233.543587 -126.21437)
			(xy 233.570371 -126.26668) (xy 233.588622 -126.322542) (xy 233.597889 -126.380574) (xy 233.598466 -126.409958)
			(xy 233.598036 -126.43604) (xy 233.590777 -126.487696) (xy 233.576382 -126.537834) (xy 233.555132 -126.585473)
			(xy 233.527443 -126.629681) (xy 233.493857 -126.669593) (xy 233.45503 -126.704428) (xy 233.43362 -126.71933)
			(xy 233.42211 -126.727719) (xy 233.403783 -126.749498) (xy 233.392181 -126.775491) (xy 233.388207 -126.803676)
			(xy 233.39131 -126.825756) (xy 236.410256 -126.825756) (xy 236.414232 -126.77143) (xy 236.426075 -126.718261)
			(xy 236.445534 -126.667384) (xy 236.472194 -126.619882) (xy 236.505485 -126.576768) (xy 236.544699 -126.538961)
			(xy 236.589001 -126.507266) (xy 236.637444 -126.48236) (xy 236.688998 -126.464772) (xy 236.742564 -126.454878)
			(xy 236.796999 -126.452888) (xy 236.851144 -126.458846) (xy 236.903844 -126.472624) (xy 236.953977 -126.493928)
			(xy 237.000473 -126.522304) (xy 237.042343 -126.557148) (xy 237.078692 -126.597717) (xy 237.108748 -126.643146)
			(xy 237.131869 -126.692467) (xy 237.147562 -126.744629) (xy 237.155493 -126.79852) (xy 237.15599 -126.825756)
			(xy 237.155493 -126.852992) (xy 237.147562 -126.906883) (xy 237.131869 -126.959045) (xy 237.108748 -127.008366)
			(xy 237.078692 -127.053795) (xy 237.042343 -127.094364) (xy 237.000473 -127.129208) (xy 236.953977 -127.157584)
			(xy 236.903844 -127.178888) (xy 236.851144 -127.192666) (xy 236.796999 -127.198624) (xy 236.742564 -127.196634)
			(xy 236.688998 -127.18674) (xy 236.637444 -127.169152) (xy 236.589001 -127.144246) (xy 236.544699 -127.112551)
			(xy 236.505485 -127.074744) (xy 236.472194 -127.03163) (xy 236.445534 -126.984128) (xy 236.426075 -126.933251)
			(xy 236.414232 -126.880082) (xy 236.410256 -126.825756) (xy 233.39131 -126.825756) (xy 233.392168 -126.831864)
			(xy 233.403758 -126.857862) (xy 233.422075 -126.87965) (xy 233.43362 -126.887986) (xy 233.455035 -126.902877)
			(xy 233.493844 -126.937728) (xy 233.527417 -126.977648) (xy 233.555098 -127.021858) (xy 233.576348 -127.069494)
			(xy 233.590751 -127.119627) (xy 233.598027 -127.171278) (xy 233.598466 -127.197358) (xy 233.597892 -127.226622)
			(xy 233.588741 -127.284429) (xy 233.570673 -127.340098) (xy 233.544131 -127.392261) (xy 233.509767 -127.439638)
			(xy 233.4895 -127.460756) (xy 233.479047 -127.472001) (xy 233.46474 -127.499144) (xy 233.459131 -127.529311)
			(xy 233.462728 -127.559783) (xy 233.475205 -127.587815) (xy 233.484928 -127.599694) (xy 233.490516 -127.606044)
			(xy 233.500228 -127.616868) (xy 233.524455 -127.632931) (xy 233.552231 -127.641503) (xy 233.581298 -127.641888)
			(xy 233.609291 -127.634054) (xy 233.633935 -127.618637) (xy 233.643932 -127.608076) (xy 233.662118 -127.588351)
			(xy 233.703068 -127.553688) (xy 233.748468 -127.525101) (xy 233.797425 -127.503154) (xy 233.848972 -127.488278)
			(xy 233.902095 -127.480768) (xy 233.92892 -127.480314) (xy 233.956174 -127.480736) (xy 234.010128 -127.488497)
			(xy 234.062428 -127.503856) (xy 234.11201 -127.526503) (xy 234.157864 -127.555975) (xy 234.199057 -127.591673)
			(xy 234.23475 -127.63287) (xy 234.264217 -127.678727) (xy 234.286858 -127.728311) (xy 234.302212 -127.780613)
			(xy 234.309967 -127.834568) (xy 234.310428 -127.861822) (xy 234.309866 -127.891442) (xy 234.300707 -127.949969)
			(xy 234.282611 -128.006377) (xy 234.256014 -128.059311) (xy 234.221555 -128.107497) (xy 234.201208 -128.12903)
			(xy 234.19205 -128.138934) (xy 234.17894 -128.162504) (xy 234.172448 -128.188681) (xy 234.173023 -128.215645)
			(xy 234.180627 -128.241522) (xy 234.194729 -128.264511) (xy 234.204256 -128.274064) (xy 234.220004 -128.289812)
			(xy 234.229867 -128.299533) (xy 234.253617 -128.313754) (xy 234.28031 -128.321084) (xy 234.307992 -128.320989)
			(xy 234.334634 -128.313473) (xy 234.358285 -128.299088) (xy 234.368086 -128.289304) (xy 234.385755 -128.270895)
			(xy 234.425299 -128.238646) (xy 234.468879 -128.212101) (xy 234.515675 -128.191758) (xy 234.564812 -128.177998)
			(xy 234.615368 -128.17108) (xy 234.640882 -128.170686) (xy 234.667829 -128.171185) (xy 234.72116 -128.178953)
			(xy 234.772818 -128.194316) (xy 234.821727 -128.216954) (xy 234.866869 -128.246394) (xy 234.907304 -128.282025)
			(xy 234.925108 -128.302258) (xy 234.935014 -128.313206) (xy 234.959716 -128.329357) (xy 234.988008 -128.337759)
			(xy 235.01752 -128.337711) (xy 235.045784 -128.329217) (xy 235.070433 -128.312986) (xy 235.080302 -128.302004)
			(xy 235.098091 -128.281535) (xy 235.138605 -128.245486) (xy 235.183917 -128.215691) (xy 235.233069 -128.19278)
			(xy 235.285024 -128.177237) (xy 235.338683 -128.169389) (xy 235.365798 -128.168908) (xy 235.395364 -128.169482)
			(xy 235.453751 -128.178839) (xy 235.509926 -128.197304) (xy 235.562478 -128.224412) (xy 235.610088 -128.259482)
			(xy 235.631228 -128.28016) (xy 235.640878 -128.289411) (xy 235.663938 -128.302923) (xy 235.689713 -128.309989)
			(xy 235.716439 -128.310128) (xy 235.742286 -128.303328) (xy 235.765484 -128.290056) (xy 235.775246 -128.280922)
			(xy 235.802932 -128.256284) (xy 235.814212 -128.246494) (xy 235.830926 -128.221753) (xy 235.839794 -128.193243)
			(xy 235.840064 -128.163386) (xy 235.831711 -128.13472) (xy 235.824014 -128.121918) (xy 235.809294 -128.09853)
			(xy 235.786036 -128.048402) (xy 235.770254 -127.995443) (xy 235.762277 -127.94076) (xy 235.761784 -127.91313)
			(xy 235.762283 -127.885878) (xy 235.770036 -127.831929) (xy 235.785388 -127.779632) (xy 235.808026 -127.730053)
			(xy 235.83749 -127.6842) (xy 235.87318 -127.643007) (xy 235.914369 -127.607313) (xy 235.960219 -127.577844)
			(xy 236.009797 -127.555201) (xy 236.062092 -127.539844) (xy 236.11604 -127.532086) (xy 236.143292 -127.531622)
			(xy 236.170123 -127.53208) (xy 236.223258 -127.539587) (xy 236.274819 -127.554456) (xy 236.323793 -127.576393)
			(xy 236.346746 -127.590296) (xy 236.35821 -127.597055) (xy 236.383605 -127.604981) (xy 236.410186 -127.606062)
			(xy 236.436141 -127.600225) (xy 236.4597 -127.587867) (xy 236.479256 -127.569831) (xy 236.4867 -127.5588)
			(xy 236.501471 -127.536463) (xy 236.53634 -127.49582) (xy 236.576666 -127.460587) (xy 236.62162 -127.431488)
			(xy 236.670276 -127.409123) (xy 236.721632 -127.393953) (xy 236.774631 -127.386289) (xy 236.801406 -127.385826)
			(xy 236.829294 -127.386259) (xy 236.884446 -127.394573) (xy 236.937744 -127.411014) (xy 236.987996 -127.435215)
			(xy 237.034079 -127.466635) (xy 237.074966 -127.504572) (xy 237.109741 -127.54818) (xy 237.137628 -127.596483)
			(xy 237.158005 -127.648403) (xy 237.170416 -127.70278) (xy 237.174585 -127.7584) (xy 237.170416 -127.81402)
			(xy 237.158005 -127.868397) (xy 237.137628 -127.920317) (xy 237.109741 -127.96862) (xy 237.074966 -128.012228)
			(xy 237.034079 -128.050165) (xy 236.987996 -128.081585) (xy 236.937744 -128.105786) (xy 236.884446 -128.122227)
			(xy 236.829294 -128.130541) (xy 236.801406 -128.131062) (xy 236.776064 -128.130626) (xy 236.725848 -128.123746)
			(xy 236.677031 -128.110113) (xy 236.630517 -128.089979) (xy 236.60862 -128.077214) (xy 236.59698 -128.070747)
			(xy 236.571424 -128.063321) (xy 236.544817 -128.062763) (xy 236.518972 -128.06911) (xy 236.495649 -128.081929)
			(xy 236.47644 -128.100348) (xy 236.469174 -128.111504) (xy 236.456843 -128.131077) (xy 236.428167 -128.167379)
			(xy 236.395301 -128.199937) (xy 236.377226 -128.214374) (xy 236.365695 -128.223923) (xy 236.348383 -128.248337)
			(xy 236.338888 -128.276719) (xy 236.338023 -128.306635) (xy 236.345862 -128.335519) (xy 236.35335 -128.348486)
			(xy 236.36679 -128.370765) (xy 236.387977 -128.418288) (xy 236.402329 -128.468302) (xy 236.409566 -128.519828)
			(xy 236.409992 -128.545844) (xy 236.409584 -128.572462) (xy 236.402002 -128.625157) (xy 236.386998 -128.676236)
			(xy 236.364877 -128.72466) (xy 236.33609 -128.769443) (xy 236.301224 -128.809673) (xy 236.260987 -128.844532)
			(xy 236.216198 -128.873311) (xy 236.16777 -128.895422) (xy 236.116688 -128.910417) (xy 236.063993 -128.917989)
			(xy 236.037374 -128.918462) (xy 236.007809 -128.917886) (xy 235.949423 -128.908525) (xy 235.893248 -128.89006)
			(xy 235.840696 -128.862954) (xy 235.793085 -128.827886) (xy 235.771944 -128.80721) (xy 235.762317 -128.797933)
			(xy 235.73925 -128.784428) (xy 235.713469 -128.777367) (xy 235.68674 -128.777234) (xy 235.66089 -128.784037)
			(xy 235.63769 -128.797313) (xy 235.627926 -128.806448) (xy 235.606849 -128.826498) (xy 235.559632 -128.860474)
			(xy 235.507712 -128.886704) (xy 235.452347 -128.904553) (xy 235.394883 -128.913586) (xy 235.365798 -128.914144)
			(xy 235.338851 -128.913648) (xy 235.28552 -128.905878) (xy 235.233863 -128.890514) (xy 235.184954 -128.867876)
			(xy 235.139812 -128.838435) (xy 235.099377 -128.802804) (xy 235.081572 -128.782572) (xy 235.071682 -128.77161)
			(xy 235.046973 -128.755472) (xy 235.018679 -128.747078) (xy 234.989167 -128.747129) (xy 234.960903 -128.755623)
			(xy 234.93625 -128.771847) (xy 234.926378 -128.782826) (xy 234.908553 -128.803263) (xy 234.868046 -128.839313)
			(xy 234.822742 -128.869111) (xy 234.773596 -128.892027) (xy 234.721648 -128.907578) (xy 234.667995 -128.915435)
			(xy 234.640882 -128.915922) (xy 234.615613 -128.915536) (xy 234.565538 -128.908713) (xy 234.516845 -128.895182)
			(xy 234.47043 -128.875191) (xy 234.427144 -128.849108) (xy 234.387782 -128.81741) (xy 234.370118 -128.799336)
			(xy 234.360237 -128.789633) (xy 234.336494 -128.775404) (xy 234.309804 -128.768067) (xy 234.282124 -128.768159)
			(xy 234.255483 -128.775673) (xy 234.231835 -128.790059) (xy 234.222036 -128.799844) (xy 234.204366 -128.818252)
			(xy 234.16482 -128.850499) (xy 234.121241 -128.877043) (xy 234.074445 -128.897386) (xy 234.025309 -128.911146)
			(xy 233.974754 -128.918067) (xy 233.94924 -128.918462) (xy 233.922627 -128.917906) (xy 233.869941 -128.910337)
			(xy 233.818869 -128.895347) (xy 233.770451 -128.873241) (xy 233.72567 -128.84447) (xy 233.685441 -128.809619)
			(xy 233.65058 -128.769397) (xy 233.621799 -128.724623) (xy 233.599682 -128.676209) (xy 233.584681 -128.625141)
			(xy 233.5771 -128.572457) (xy 233.576622 -128.545844) (xy 233.577166 -128.517605) (xy 233.585671 -128.461772)
			(xy 233.602509 -128.407863) (xy 233.627293 -128.357115) (xy 233.659454 -128.310689) (xy 233.678476 -128.289812)
			(xy 233.687416 -128.279693) (xy 233.700176 -128.25591) (xy 233.706252 -128.229613) (xy 233.705218 -128.202643)
			(xy 233.697147 -128.176888) (xy 233.682605 -128.154152) (xy 233.672888 -128.144778) (xy 233.662225 -128.134915)
			(xy 233.642262 -128.113811) (xy 233.63301 -128.102614) (xy 233.623403 -128.091717) (xy 233.59944 -128.075321)
			(xy 233.571834 -128.066326) (xy 233.542812 -128.065458) (xy 233.514718 -128.072788) (xy 233.489818 -128.087723)
			(xy 233.479594 -128.098042) (xy 233.461865 -128.116655) (xy 233.422197 -128.149343) (xy 233.378414 -128.176273)
			(xy 233.331347 -128.196933) (xy 233.281888 -128.210931) (xy 233.230975 -128.218002) (xy 233.205274 -128.218438)
			(xy 233.178658 -128.217968) (xy 233.125968 -128.210389) (xy 233.074893 -128.195389) (xy 233.026473 -128.173274)
			(xy 232.981692 -128.144494) (xy 232.941462 -128.109634) (xy 232.906603 -128.069403) (xy 232.877823 -128.024622)
			(xy 232.855709 -127.976201) (xy 232.84071 -127.925126) (xy 232.833132 -127.872436) (xy 232.832656 -127.84582)
			(xy 232.83321 -127.816555) (xy 232.842365 -127.758747) (xy 232.860438 -127.703077) (xy 232.886984 -127.650914)
			(xy 232.921353 -127.603539) (xy 232.941622 -127.582422) (xy 232.952095 -127.571195) (xy 232.966398 -127.544045)
			(xy 232.972001 -127.513874) (xy 232.968399 -127.483398) (xy 232.955918 -127.455364) (xy 232.946194 -127.443484)
			(xy 232.928748 -127.422998) (xy 232.899361 -127.377924) (xy 232.876768 -127.329089) (xy 232.861442 -127.27751)
			(xy 232.853701 -127.224262) (xy 232.85323 -127.197358) (xy 232.853674 -127.171277) (xy 232.86093 -127.119621)
			(xy 232.875323 -127.069484) (xy 232.896571 -127.021845) (xy 232.924258 -126.977637) (xy 232.957842 -126.937724)
			(xy 232.996667 -126.902888) (xy 233.018076 -126.887986) (xy 233.029668 -126.879702) (xy 233.047999 -126.8579)
			(xy 233.059597 -126.831884) (xy 233.063561 -126.803676) (xy 233.059584 -126.775471) (xy 233.047974 -126.74946)
			(xy 233.029633 -126.727666) (xy 233.018076 -126.71933) (xy 232.996667 -126.70443) (xy 232.957858 -126.66958)
			(xy 232.924285 -126.629661) (xy 232.896603 -126.585453) (xy 232.875352 -126.537819) (xy 232.860948 -126.487688)
			(xy 232.85367 -126.436038) (xy 232.85323 -126.409958) (xy 232.853698 -126.384558) (xy 232.860634 -126.334232)
			(xy 232.874332 -126.285312) (xy 232.894538 -126.238702) (xy 232.92088 -126.195264) (xy 232.936542 -126.175262)
			(xy 232.945587 -126.163316) (xy 232.956877 -126.135573) (xy 232.959647 -126.105749) (xy 232.953661 -126.076401)
			(xy 232.939431 -126.050045) (xy 232.929176 -126.039118) (xy 232.908745 -126.017993) (xy 232.874087 -125.970535)
			(xy 232.847299 -125.91823) (xy 232.829043 -125.862371) (xy 232.819773 -125.804341) (xy 232.819194 -125.774958)
			(xy 231.365762 -125.774958) (xy 231.394907 -125.799212) (xy 231.431256 -125.839781) (xy 231.461312 -125.88521)
			(xy 231.484433 -125.934531) (xy 231.500126 -125.986693) (xy 231.508057 -126.040584) (xy 231.508554 -126.06782)
			(xy 231.508057 -126.095056) (xy 231.500126 -126.148947) (xy 231.484433 -126.201109) (xy 231.461312 -126.25043)
			(xy 231.431256 -126.295859) (xy 231.394907 -126.336428) (xy 231.353037 -126.371272) (xy 231.306541 -126.399648)
			(xy 231.256408 -126.420952) (xy 231.203708 -126.43473) (xy 231.149563 -126.440688) (xy 231.095128 -126.438698)
			(xy 231.041562 -126.428804) (xy 230.990008 -126.411216) (xy 230.941565 -126.38631) (xy 230.897263 -126.354615)
			(xy 230.858049 -126.316808) (xy 230.824758 -126.273694) (xy 230.798098 -126.226192) (xy 230.778639 -126.175315)
			(xy 230.766796 -126.122146) (xy 230.76282 -126.06782) (xy 230.537706 -126.06782) (xy 230.537766 -126.071122)
			(xy 230.537257 -126.099008) (xy 230.529137 -126.154184) (xy 230.513069 -126.207591) (xy 230.489397 -126.258088)
			(xy 230.458624 -126.304601) (xy 230.421407 -126.346138) (xy 230.378539 -126.381813) (xy 230.330933 -126.410867)
			(xy 230.279604 -126.432679) (xy 230.225647 -126.446785) (xy 230.17021 -126.452885) (xy 230.114476 -126.450848)
			(xy 230.059633 -126.440718) (xy 230.006849 -126.422711) (xy 229.957249 -126.39721) (xy 229.911891 -126.364759)
			(xy 229.871742 -126.32605) (xy 229.837656 -126.281907) (xy 229.81036 -126.233272) (xy 229.790437 -126.181181)
			(xy 229.778311 -126.126744) (xy 229.77424 -126.071122) (xy 229.59568 -126.071122) (xy 229.59568 -126.660148)
			(xy 232.38968 -129.454148) (xy 236.88548 -129.454148)
		)
		(stroke
			(width 0)
			(type solid)
		)
		(fill yes)
		(layer "In15.Cu")
		(net "P3V3_DB2000_VDD")
	)
	(gr_poly
		(pts
			(arc
				(start 194.443604 -441.479432)
				(mid 194.479525 -441.464553)
				(end 194.494404 -441.428632)
			)
			(arc
				(start 194.494404 -441.17006)
				(mid 194.790421 -440.455411)
				(end 195.50507 -440.159394)
			)
			(arc
				(start 276.314916 -440.159394)
				(mid 277.029565 -440.455411)
				(end 277.325582 -441.17006)
			)
			(arc
				(start 277.325582 -441.428632)
				(mid 277.340461 -441.464553)
				(end 277.376382 -441.479432)
			)
			(arc
				(start 463.300064 -441.479432)
				(mid 464.353268 -441.04318)
				(end 464.78952 -439.989976)
			)
			(arc
				(start 464.78952 -409.528264)
				(mid 464.980687 -408.567674)
				(end 465.52485 -407.753312)
			)
			(arc
				(start 467.353396 -405.924766)
				(mid 467.676179 -405.441593)
				(end 467.789514 -404.871682)
			)
			(arc
				(start 467.789514 -324.19163)
				(mid 467.780912 -324.163346)
				(end 467.758018 -324.14464)
			)
			(xy 467.743794 -324.138544) (xy 467.713822 -324.14464)
			(arc
				(start 467.297262 -324.561454)
				(mid 467.286151 -324.577988)
				(end 467.282276 -324.597522)
			)
			(arc
				(start 467.282276 -358.935274)
				(mid 467.28295 -358.943778)
				(end 467.28507 -358.952038)
			)
			(arc
				(start 467.28507 -358.952038)
				(mid 467.514132 -359.845086)
				(end 467.59114 -360.76382)
			)
			(arc
				(start 467.59114 -360.76382)
				(mid 467.514124 -361.682553)
				(end 467.28507 -362.575602)
			)
			(arc
				(start 467.28507 -362.575602)
				(mid 467.282984 -362.583868)
				(end 467.282276 -362.592366)
			)
			(arc
				(start 467.282276 -404.871936)
				(mid 467.207495 -405.247595)
				(end 466.994748 -405.566118)
			)
			(arc
				(start 465.166202 -407.394664)
				(mid 464.5119 -408.373524)
				(end 464.282028 -409.528264)
			)
			(arc
				(start 464.282028 -439.989976)
				(mid 463.994417 -440.684329)
				(end 463.300064 -440.97194)
			)
			(xy 410.917898 -440.97194)
			(arc
				(start 410.910024 -440.974734)
				(mid 410.831038 -440.993945)
				(end 410.750004 -441.000388)
			)
			(arc
				(start 410.750004 -441.000388)
				(mid 410.668968 -440.993957)
				(end 410.589984 -440.974734)
			)
			(xy 410.58211 -440.97194) (xy 406.917906 -440.97194)
			(arc
				(start 406.910032 -440.974734)
				(mid 406.831046 -440.993945)
				(end 406.750012 -441.000388)
			)
			(arc
				(start 406.750012 -441.000388)
				(mid 406.668976 -440.993957)
				(end 406.589992 -440.974734)
			)
			(xy 406.582118 -440.97194) (xy 402.917914 -440.97194)
			(arc
				(start 402.91004 -440.974734)
				(mid 402.831054 -440.993945)
				(end 402.75002 -441.000388)
			)
			(arc
				(start 402.75002 -441.000388)
				(mid 402.668984 -440.993957)
				(end 402.59 -440.974734)
			)
			(xy 402.582126 -440.97194) (xy 398.917922 -440.97194)
			(arc
				(start 398.910048 -440.974734)
				(mid 398.831062 -440.993945)
				(end 398.750028 -441.000388)
			)
			(arc
				(start 398.750028 -441.000388)
				(mid 398.668992 -440.993957)
				(end 398.590008 -440.974734)
			)
			(xy 398.582134 -440.97194) (xy 393.917932 -440.97194)
			(arc
				(start 393.910058 -440.974734)
				(mid 393.831072 -440.993945)
				(end 393.750038 -441.000388)
			)
			(arc
				(start 393.750038 -441.000388)
				(mid 393.669002 -440.993957)
				(end 393.590018 -440.974734)
			)
			(xy 393.582144 -440.97194) (xy 389.91794 -440.97194)
			(arc
				(start 389.910066 -440.974734)
				(mid 389.83108 -440.993945)
				(end 389.750046 -441.000388)
			)
			(arc
				(start 389.750046 -441.000388)
				(mid 389.66901 -440.993957)
				(end 389.590026 -440.974734)
			)
			(xy 389.582152 -440.97194) (xy 385.917948 -440.97194)
			(arc
				(start 385.910074 -440.974734)
				(mid 385.831088 -440.993945)
				(end 385.750054 -441.000388)
			)
			(arc
				(start 385.750054 -441.000388)
				(mid 385.669018 -440.993957)
				(end 385.590034 -440.974734)
			)
			(xy 385.58216 -440.97194) (xy 381.917956 -440.97194)
			(arc
				(start 381.910082 -440.974734)
				(mid 381.831096 -440.993945)
				(end 381.750062 -441.000388)
			)
			(arc
				(start 381.750062 -441.000388)
				(mid 381.669026 -440.993957)
				(end 381.590042 -440.974734)
			)
			(xy 381.582168 -440.97194) (xy 343.817956 -440.97194)
			(arc
				(start 343.810082 -440.974734)
				(mid 343.731096 -440.993945)
				(end 343.650062 -441.000388)
			)
			(arc
				(start 343.650062 -441.000388)
				(mid 343.569026 -440.993957)
				(end 343.490042 -440.974734)
			)
			(xy 343.482168 -440.97194) (xy 339.817964 -440.97194)
			(arc
				(start 339.81009 -440.974734)
				(mid 339.731104 -440.993945)
				(end 339.65007 -441.000388)
			)
			(arc
				(start 339.65007 -441.000388)
				(mid 339.569034 -440.993957)
				(end 339.49005 -440.974734)
			)
			(xy 339.482176 -440.97194) (xy 335.817972 -440.97194)
			(arc
				(start 335.810098 -440.974734)
				(mid 335.731112 -440.993945)
				(end 335.650078 -441.000388)
			)
			(arc
				(start 335.650078 -441.000388)
				(mid 335.569042 -440.993957)
				(end 335.490058 -440.974734)
			)
			(xy 335.482184 -440.97194) (xy 331.81798 -440.97194)
			(arc
				(start 331.810106 -440.974734)
				(mid 331.73112 -440.993945)
				(end 331.650086 -441.000388)
			)
			(arc
				(start 331.650086 -441.000388)
				(mid 331.56905 -440.993957)
				(end 331.490066 -440.974734)
			)
			(xy 331.482192 -440.97194) (xy 326.81799 -440.97194)
			(arc
				(start 326.810116 -440.974734)
				(mid 326.73113 -440.993945)
				(end 326.650096 -441.000388)
			)
			(arc
				(start 326.650096 -441.000388)
				(mid 326.56906 -440.993957)
				(end 326.490076 -440.974734)
			)
			(xy 326.482202 -440.97194) (xy 322.817998 -440.97194)
			(arc
				(start 322.810124 -440.974734)
				(mid 322.731138 -440.993945)
				(end 322.650104 -441.000388)
			)
			(arc
				(start 322.650104 -441.000388)
				(mid 322.569068 -440.993957)
				(end 322.490084 -440.974734)
			)
			(xy 322.48221 -440.97194) (xy 318.818006 -440.97194)
			(arc
				(start 318.810132 -440.974734)
				(mid 318.731146 -440.993945)
				(end 318.650112 -441.000388)
			)
			(arc
				(start 318.650112 -441.000388)
				(mid 318.569076 -440.993957)
				(end 318.490092 -440.974734)
			)
			(xy 318.482218 -440.97194) (xy 314.818014 -440.97194)
			(arc
				(start 314.81014 -440.974734)
				(mid 314.731154 -440.993945)
				(end 314.65012 -441.000388)
			)
			(arc
				(start 314.65012 -441.000388)
				(mid 314.569084 -440.993957)
				(end 314.4901 -440.974734)
			)
			(xy 314.482226 -440.97194)
			(arc
				(start 277.82012 -440.97194)
				(mid 277.31587 -440.028787)
				(end 276.314916 -439.652156)
			)
			(arc
				(start 195.50507 -439.652156)
				(mid 194.504157 -440.028834)
				(end 193.999866 -440.97194)
			)
			(xy 154.917902 -440.97194)
			(arc
				(start 154.910028 -440.974734)
				(mid 154.831042 -440.993945)
				(end 154.750008 -441.000388)
			)
			(arc
				(start 154.750008 -441.000388)
				(mid 154.668972 -440.993957)
				(end 154.589988 -440.974734)
			)
			(xy 154.582114 -440.97194) (xy 150.91791 -440.97194)
			(arc
				(start 150.910036 -440.974734)
				(mid 150.83105 -440.993945)
				(end 150.750016 -441.000388)
			)
			(arc
				(start 150.750016 -441.000388)
				(mid 150.66898 -440.993957)
				(end 150.589996 -440.974734)
			)
			(xy 150.582122 -440.97194) (xy 146.917918 -440.97194)
			(arc
				(start 146.910044 -440.974734)
				(mid 146.831058 -440.993945)
				(end 146.750024 -441.000388)
			)
			(arc
				(start 146.750024 -441.000388)
				(mid 146.668988 -440.993957)
				(end 146.590004 -440.974734)
			)
			(xy 146.58213 -440.97194) (xy 142.917926 -440.97194)
			(arc
				(start 142.910052 -440.974734)
				(mid 142.831066 -440.993945)
				(end 142.750032 -441.000388)
			)
			(arc
				(start 142.750032 -441.000388)
				(mid 142.668996 -440.993957)
				(end 142.590012 -440.974734)
			)
			(xy 142.582138 -440.97194) (xy 137.917936 -440.97194)
			(arc
				(start 137.910062 -440.974734)
				(mid 137.831076 -440.993945)
				(end 137.750042 -441.000388)
			)
			(arc
				(start 137.750042 -441.000388)
				(mid 137.669006 -440.993957)
				(end 137.590022 -440.974734)
			)
			(xy 137.582148 -440.97194) (xy 133.917944 -440.97194)
			(arc
				(start 133.91007 -440.974734)
				(mid 133.831084 -440.993945)
				(end 133.75005 -441.000388)
			)
			(arc
				(start 133.75005 -441.000388)
				(mid 133.669014 -440.993957)
				(end 133.59003 -440.974734)
			)
			(xy 133.582156 -440.97194) (xy 129.917952 -440.97194)
			(arc
				(start 129.910078 -440.974734)
				(mid 129.831092 -440.993945)
				(end 129.750058 -441.000388)
			)
			(arc
				(start 129.750058 -441.000388)
				(mid 129.669022 -440.993957)
				(end 129.590038 -440.974734)
			)
			(xy 129.582164 -440.97194) (xy 125.91796 -440.97194)
			(arc
				(start 125.910086 -440.974734)
				(mid 125.8311 -440.993945)
				(end 125.750066 -441.000388)
			)
			(arc
				(start 125.750066 -441.000388)
				(mid 125.66903 -440.993957)
				(end 125.590046 -440.974734)
			)
			(xy 125.582172 -440.97194) (xy 87.81796 -440.97194)
			(arc
				(start 87.810086 -440.974734)
				(mid 87.7311 -440.993945)
				(end 87.650066 -441.000388)
			)
			(arc
				(start 87.650066 -441.000388)
				(mid 87.56903 -440.993957)
				(end 87.490046 -440.974734)
			)
			(xy 87.482172 -440.97194) (xy 83.817968 -440.97194)
			(arc
				(start 83.810094 -440.974734)
				(mid 83.731108 -440.993945)
				(end 83.650074 -441.000388)
			)
			(arc
				(start 83.650074 -441.000388)
				(mid 83.569038 -440.993957)
				(end 83.490054 -440.974734)
			)
			(xy 83.48218 -440.97194) (xy 79.817976 -440.97194)
			(arc
				(start 79.810102 -440.974734)
				(mid 79.731116 -440.993945)
				(end 79.650082 -441.000388)
			)
			(arc
				(start 79.650082 -441.000388)
				(mid 79.569046 -440.993957)
				(end 79.490062 -440.974734)
			)
			(xy 79.482188 -440.97194) (xy 75.817984 -440.97194)
			(arc
				(start 75.81011 -440.974734)
				(mid 75.731124 -440.993945)
				(end 75.65009 -441.000388)
			)
			(arc
				(start 75.65009 -441.000388)
				(mid 75.569054 -440.993957)
				(end 75.49007 -440.974734)
			)
			(xy 75.482196 -440.97194) (xy 70.817994 -440.97194)
			(arc
				(start 70.81012 -440.974734)
				(mid 70.731134 -440.993945)
				(end 70.6501 -441.000388)
			)
			(arc
				(start 70.6501 -441.000388)
				(mid 70.569064 -440.993957)
				(end 70.49008 -440.974734)
			)
			(xy 70.482206 -440.97194) (xy 66.818002 -440.97194)
			(arc
				(start 66.810128 -440.974734)
				(mid 66.731142 -440.993945)
				(end 66.650108 -441.000388)
			)
			(arc
				(start 66.650108 -441.000388)
				(mid 66.569072 -440.993957)
				(end 66.490088 -440.974734)
			)
			(xy 66.482214 -440.97194) (xy 62.81801 -440.97194)
			(arc
				(start 62.810136 -440.974734)
				(mid 62.73115 -440.993945)
				(end 62.650116 -441.000388)
			)
			(arc
				(start 62.650116 -441.000388)
				(mid 62.56908 -440.993957)
				(end 62.490096 -440.974734)
			)
			(xy 62.482222 -440.97194) (xy 58.818018 -440.97194)
			(arc
				(start 58.810144 -440.974734)
				(mid 58.731158 -440.993945)
				(end 58.650124 -441.000388)
			)
			(arc
				(start 58.650124 -441.000388)
				(mid 58.569088 -440.993957)
				(end 58.490104 -440.974734)
			)
			(xy 58.48223 -440.97194)
			(arc
				(start 8.50011 -440.97194)
				(mid 7.805667 -440.684345)
				(end 7.517892 -439.989976)
			)
			(arc
				(start 7.517892 -409.528264)
				(mid 7.287997 -408.373534)
				(end 6.633718 -407.394664)
			)
			(arc
				(start 3.305302 -404.066248)
				(mid 3.092701 -403.747829)
				(end 3.018028 -403.37232)
			)
			(arc
				(start 3.018028 -81.32826)
				(mid 2.788133 -80.17353)
				(end 2.133854 -79.19466)
			)
			(arc
				(start 1.305306 -78.366112)
				(mid 1.092705 -78.047693)
				(end 1.018032 -77.672184)
			)
			(arc
				(start 1.018032 -42.244772)
				(mid 1.013298 -42.223357)
				(end 0.999998 -42.20591)
			)
			(arc
				(start 0.999998 -42.20591)
				(mid 0.873253 -41.933622)
				(end 0.999998 -41.661334)
			)
			(arc
				(start 0.999998 -41.661334)
				(mid 1.013327 -41.6439)
				(end 1.018032 -41.622472)
			)
			(arc
				(start 1.018032 -41.222422)
				(mid 1.013298 -41.201007)
				(end 0.999998 -41.18356)
			)
			(arc
				(start 0.999998 -41.18356)
				(mid 0.873253 -40.911272)
				(end 0.999998 -40.638984)
			)
			(arc
				(start 0.999998 -40.638984)
				(mid 1.013327 -40.62155)
				(end 1.018032 -40.600122)
			)
			(arc
				(start 1.018032 -40.167814)
				(mid 1.012748 -40.145255)
				(end 0.997966 -40.127428)
			)
			(arc
				(start 0.997966 -40.127428)
				(mid 0.84779 -39.824152)
				(end 0.997966 -39.520876)
			)
			(arc
				(start 0.997966 -39.520876)
				(mid 1.012704 -39.503027)
				(end 1.018032 -39.48049)
			)
			(arc
				(start 1.018032 -39.099998)
				(mid 1.013298 -39.078583)
				(end 0.999998 -39.061136)
			)
			(arc
				(start 0.999998 -39.061136)
				(mid 0.873253 -38.788848)
				(end 0.999998 -38.51656)
			)
			(arc
				(start 0.999998 -38.51656)
				(mid 1.013327 -38.499126)
				(end 1.018032 -38.477698)
			)
			(arc
				(start 1.018032 -38.110414)
				(mid 1.011311 -38.085415)
				(end 0.99314 -38.06698)
			)
			(arc
				(start 0.99314 -38.06698)
				(mid 0.807128 -37.73932)
				(end 0.99314 -37.41166)
			)
			(arc
				(start 0.99314 -37.41166)
				(mid 1.011304 -37.393221)
				(end 1.018032 -37.368226)
			)
			(arc
				(start 1.018032 -37.067236)
				(mid 1.011311 -37.042237)
				(end 0.99314 -37.023802)
			)
			(arc
				(start 0.99314 -37.023802)
				(mid 0.807128 -36.696142)
				(end 0.99314 -36.368482)
			)
			(arc
				(start 0.99314 -36.368482)
				(mid 1.011304 -36.350043)
				(end 1.018032 -36.325048)
			)
			(arc
				(start 1.018032 -35.987228)
				(mid 1.011311 -35.962229)
				(end 0.99314 -35.943794)
			)
			(arc
				(start 0.99314 -35.943794)
				(mid 0.807128 -35.616134)
				(end 0.99314 -35.288474)
			)
			(arc
				(start 0.99314 -35.288474)
				(mid 1.011304 -35.270035)
				(end 1.018032 -35.24504)
			)
			(arc
				(start 1.018032 -26.980642)
				(mid 1.010858 -26.954615)
				(end 0.991362 -26.935938)
			)
			(arc
				(start 0.991362 -26.935938)
				(mid 0.827352 -26.84333)
				(end 0.66675 -26.74493)
			)
			(xy 0.654812 -26.73731) (xy 0.62738 -26.736294)
			(arc
				(start 0.536956 -26.786078)
				(mid 0.517713 -26.8047)
				(end 0.51054 -26.830528)
			)
			(arc
				(start 0.51054 -77.671676)
				(mid 0.623884 -78.241583)
				(end 0.946658 -78.72476)
			)
			(arc
				(start 1.775206 -79.553308)
				(mid 2.319424 -80.367648)
				(end 2.510536 -81.32826)
			)
			(arc
				(start 2.510536 -403.371812)
				(mid 2.62388 -403.941719)
				(end 2.946654 -404.424896)
			)
			(arc
				(start 6.27507 -407.753312)
				(mid 6.819424 -408.567623)
				(end 7.010654 -409.528264)
			)
			(arc
				(start 7.010654 -439.989976)
				(mid 7.446906 -441.04318)
				(end 8.50011 -441.479432)
			)
		)
		(stroke
			(width 0)
			(type solid)
		)
		(fill yes)
		(layer "In15.Cu")
		(net "GND")
	)
	(gr_poly
		(pts
			(xy 193.192908 -31.844488) (xy 193.206716 -31.844026) (xy 193.233321 -31.83662) (xy 193.256967 -31.822353)
			(xy 193.275922 -31.80227) (xy 193.288799 -31.777839) (xy 193.294655 -31.750851) (xy 193.293062 -31.723281)
			(xy 193.284136 -31.697147) (xy 193.276728 -31.685484) (xy 193.261004 -31.661564) (xy 193.236131 -31.610008)
			(xy 193.219239 -31.555315) (xy 193.210705 -31.498713) (xy 193.21018 -31.470092) (xy 193.210666 -31.442841)
			(xy 193.218422 -31.388893) (xy 193.233777 -31.336598) (xy 193.256419 -31.287021) (xy 193.285885 -31.241171)
			(xy 193.321576 -31.19998) (xy 193.362767 -31.164289) (xy 193.408617 -31.134823) (xy 193.458194 -31.112181)
			(xy 193.510489 -31.096826) (xy 193.564437 -31.08907) (xy 193.618939 -31.08907) (xy 193.672887 -31.096826)
			(xy 193.725182 -31.112181) (xy 193.774759 -31.134823) (xy 193.820609 -31.164289) (xy 193.8618 -31.19998)
			(xy 193.897491 -31.241171) (xy 193.926957 -31.287021) (xy 193.949599 -31.336598) (xy 193.964954 -31.388893)
			(xy 193.97271 -31.442841) (xy 193.973196 -31.470092) (xy 193.972686 -31.498714) (xy 193.964144 -31.555316)
			(xy 193.947249 -31.610009) (xy 193.92238 -31.661568) (xy 193.906648 -31.685484) (xy 193.899225 -31.69714)
			(xy 193.8903 -31.72328) (xy 193.888707 -31.750856) (xy 193.894565 -31.777849) (xy 193.907443 -31.802285)
			(xy 193.9264 -31.822375) (xy 193.950048 -31.836648) (xy 193.976657 -31.84406) (xy 193.990468 -31.844488)
			(xy 201.3204 -31.844488) (xy 201.88428 -31.280608) (xy 201.88428 -29.157168) (xy 197.96506 -25.237948)
			(xy 197.96506 -17.153128) (xy 193.70548 -12.893548) (xy 191.47028 -12.893548) (xy 191.19088 -13.172948)
			(xy 191.19088 -14.60246) (xy 191.235584 -14.60754) (xy 191.263078 -14.611283) (xy 191.31666 -14.625693)
			(xy 191.36759 -14.647711) (xy 191.414795 -14.676874) (xy 191.457278 -14.712565) (xy 191.494143 -14.754034)
			(xy 191.524615 -14.800404) (xy 191.548049 -14.850699) (xy 191.563951 -14.903857) (xy 191.571987 -14.958758)
			(xy 191.571987 -15.014244) (xy 191.563951 -15.069145) (xy 191.548048 -15.122303) (xy 191.524614 -15.172598)
			(xy 191.494142 -15.218968) (xy 191.457276 -15.260436) (xy 191.414793 -15.296127) (xy 191.367589 -15.325289)
			(xy 191.316658 -15.347307) (xy 191.263076 -15.361717) (xy 191.235584 -15.365476) (xy 191.19088 -15.370556)
			(xy 191.19088 -17.503648) (xy 196.228968 -17.503648) (xy 196.233039 -17.448026) (xy 196.245165 -17.393589)
			(xy 196.265088 -17.341498) (xy 196.292384 -17.292863) (xy 196.32647 -17.24872) (xy 196.366619 -17.210011)
			(xy 196.411977 -17.17756) (xy 196.461577 -17.152059) (xy 196.514361 -17.134052) (xy 196.569204 -17.123922)
			(xy 196.624938 -17.121885) (xy 196.680375 -17.127985) (xy 196.734332 -17.142091) (xy 196.785661 -17.163903)
			(xy 196.833267 -17.192957) (xy 196.876135 -17.228632) (xy 196.913352 -17.270169) (xy 196.944125 -17.316682)
			(xy 196.967797 -17.367179) (xy 196.983865 -17.420586) (xy 196.991985 -17.475762) (xy 196.992494 -17.503648)
			(xy 196.991985 -17.531534) (xy 196.983865 -17.58671) (xy 196.967797 -17.640117) (xy 196.944125 -17.690614)
			(xy 196.913352 -17.737127) (xy 196.876135 -17.778664) (xy 196.833267 -17.814339) (xy 196.785661 -17.843393)
			(xy 196.734332 -17.865205) (xy 196.680375 -17.879311) (xy 196.624938 -17.885411) (xy 196.569204 -17.883374)
			(xy 196.514361 -17.873244) (xy 196.461577 -17.855237) (xy 196.411977 -17.829736) (xy 196.366619 -17.797285)
			(xy 196.32647 -17.758576) (xy 196.292384 -17.714433) (xy 196.265088 -17.665798) (xy 196.245165 -17.613707)
			(xy 196.233039 -17.55927) (xy 196.228968 -17.503648) (xy 191.19088 -17.503648) (xy 191.19088 -18.83537)
			(xy 191.191307 -18.849283) (xy 191.198816 -18.876077) (xy 191.213285 -18.899846) (xy 191.233636 -18.918823)
			(xy 191.258358 -18.931596) (xy 191.285611 -18.937216) (xy 191.313368 -18.935264) (xy 191.339567 -18.925887)
			(xy 191.351154 -18.918174) (xy 191.375467 -18.901643) (xy 191.428104 -18.875457) (xy 191.484134 -18.85765)
			(xy 191.54223 -18.848641) (xy 191.571626 -18.84807) (xy 191.598878 -18.848558) (xy 191.652826 -18.856318)
			(xy 191.70512 -18.871676) (xy 191.754697 -18.89432) (xy 191.800547 -18.923788) (xy 191.841736 -18.959482)
			(xy 191.877427 -19.000674) (xy 191.906893 -19.046526) (xy 191.929533 -19.096104) (xy 191.942844 -19.14144)
			(xy 195.064378 -19.14144) (xy 195.068449 -19.085818) (xy 195.080575 -19.031381) (xy 195.100498 -18.97929)
			(xy 195.127794 -18.930655) (xy 195.16188 -18.886512) (xy 195.202029 -18.847803) (xy 195.247387 -18.815352)
			(xy 195.296987 -18.789851) (xy 195.349771 -18.771844) (xy 195.404614 -18.761714) (xy 195.460348 -18.759677)
			(xy 195.515785 -18.765777) (xy 195.569742 -18.779883) (xy 195.621071 -18.801695) (xy 195.668677 -18.830749)
			(xy 195.711545 -18.866424) (xy 195.748762 -18.907961) (xy 195.779535 -18.954474) (xy 195.803207 -19.004971)
			(xy 195.819275 -19.058378) (xy 195.827395 -19.113554) (xy 195.827904 -19.14144) (xy 195.827395 -19.169326)
			(xy 195.819275 -19.224502) (xy 195.803207 -19.277909) (xy 195.779535 -19.328406) (xy 195.748762 -19.374919)
			(xy 195.711545 -19.416456) (xy 195.668677 -19.452131) (xy 195.621071 -19.481185) (xy 195.569742 -19.502997)
			(xy 195.515785 -19.517103) (xy 195.460348 -19.523203) (xy 195.404614 -19.521166) (xy 195.349771 -19.511036)
			(xy 195.296987 -19.493029) (xy 195.247387 -19.467528) (xy 195.202029 -19.435077) (xy 195.16188 -19.396368)
			(xy 195.127794 -19.352225) (xy 195.100498 -19.30359) (xy 195.080575 -19.251499) (xy 195.068449 -19.197062)
			(xy 195.064378 -19.14144) (xy 191.942844 -19.14144) (xy 191.944888 -19.1484) (xy 191.952644 -19.202348)
			(xy 191.952644 -19.256852) (xy 191.944888 -19.3108) (xy 191.929533 -19.363096) (xy 191.906893 -19.412674)
			(xy 191.877427 -19.458526) (xy 191.841736 -19.499718) (xy 191.800547 -19.535412) (xy 191.754697 -19.56488)
			(xy 191.70512 -19.587524) (xy 191.652826 -19.602882) (xy 191.598878 -19.610642) (xy 191.571626 -19.611086)
			(xy 191.542229 -19.610546) (xy 191.484129 -19.601534) (xy 191.428098 -19.583719) (xy 191.375462 -19.557523)
			(xy 191.351154 -19.540982) (xy 191.339538 -19.533344) (xy 191.313363 -19.524012) (xy 191.285642 -19.522087)
			(xy 191.258429 -19.527712) (xy 191.233742 -19.540471) (xy 191.213413 -19.559416) (xy 191.198949 -19.583143)
			(xy 191.191422 -19.609892) (xy 191.19088 -19.623786) (xy 191.19088 -21.358352) (xy 193.259454 -21.358352)
			(xy 193.263525 -21.30273) (xy 193.275651 -21.248293) (xy 193.295574 -21.196202) (xy 193.32287 -21.147567)
			(xy 193.356956 -21.103424) (xy 193.397105 -21.064715) (xy 193.442463 -21.032264) (xy 193.492063 -21.006763)
			(xy 193.544847 -20.988756) (xy 193.59969 -20.978626) (xy 193.655424 -20.976589) (xy 193.710861 -20.982689)
			(xy 193.764818 -20.996795) (xy 193.816147 -21.018607) (xy 193.863753 -21.047661) (xy 193.906621 -21.083336)
			(xy 193.943838 -21.124873) (xy 193.974611 -21.171386) (xy 193.998283 -21.221883) (xy 194.014351 -21.27529)
			(xy 194.022471 -21.330466) (xy 194.02298 -21.358352) (xy 194.022471 -21.386238) (xy 194.014351 -21.441414)
			(xy 193.998283 -21.494821) (xy 193.974611 -21.545318) (xy 193.943838 -21.591831) (xy 193.906621 -21.633368)
			(xy 193.863753 -21.669043) (xy 193.816147 -21.698097) (xy 193.764818 -21.719909) (xy 193.710861 -21.734015)
			(xy 193.655424 -21.740115) (xy 193.59969 -21.738078) (xy 193.544847 -21.727948) (xy 193.492063 -21.709941)
			(xy 193.442463 -21.68444) (xy 193.397105 -21.651989) (xy 193.356956 -21.61328) (xy 193.32287 -21.569137)
			(xy 193.295574 -21.520502) (xy 193.275651 -21.468411) (xy 193.263525 -21.413974) (xy 193.259454 -21.358352)
			(xy 191.19088 -21.358352) (xy 191.19088 -22.18436) (xy 194.145914 -22.18436) (xy 194.149985 -22.128738)
			(xy 194.162111 -22.074301) (xy 194.182034 -22.02221) (xy 194.20933 -21.973575) (xy 194.243416 -21.929432)
			(xy 194.283565 -21.890723) (xy 194.328923 -21.858272) (xy 194.378523 -21.832771) (xy 194.431307 -21.814764)
			(xy 194.48615 -21.804634) (xy 194.541884 -21.802597) (xy 194.597321 -21.808697) (xy 194.651278 -21.822803)
			(xy 194.702607 -21.844615) (xy 194.750213 -21.873669) (xy 194.793081 -21.909344) (xy 194.830298 -21.950881)
			(xy 194.861071 -21.997394) (xy 194.884743 -22.047891) (xy 194.900811 -22.101298) (xy 194.908931 -22.156474)
			(xy 194.90944 -22.18436) (xy 194.908931 -22.212246) (xy 194.900811 -22.267422) (xy 194.884743 -22.320829)
			(xy 194.861071 -22.371326) (xy 194.830298 -22.417839) (xy 194.793081 -22.459376) (xy 194.750213 -22.495051)
			(xy 194.702607 -22.524105) (xy 194.651278 -22.545917) (xy 194.597321 -22.560023) (xy 194.541884 -22.566123)
			(xy 194.48615 -22.564086) (xy 194.431307 -22.553956) (xy 194.378523 -22.535949) (xy 194.328923 -22.510448)
			(xy 194.283565 -22.477997) (xy 194.243416 -22.439288) (xy 194.20933 -22.395145) (xy 194.182034 -22.34651)
			(xy 194.162111 -22.294419) (xy 194.149985 -22.239982) (xy 194.145914 -22.18436) (xy 191.19088 -22.18436)
			(xy 191.19088 -23.510748) (xy 191.982342 -23.510748) (xy 191.986413 -23.455126) (xy 191.998539 -23.400689)
			(xy 192.018462 -23.348598) (xy 192.045758 -23.299963) (xy 192.079844 -23.25582) (xy 192.119993 -23.217111)
			(xy 192.165351 -23.18466) (xy 192.214951 -23.159159) (xy 192.267735 -23.141152) (xy 192.322578 -23.131022)
			(xy 192.378312 -23.128985) (xy 192.433749 -23.135085) (xy 192.487706 -23.149191) (xy 192.539035 -23.171003)
			(xy 192.586641 -23.200057) (xy 192.629509 -23.235732) (xy 192.631953 -23.23846) (xy 194.443094 -23.23846)
			(xy 194.447165 -23.182838) (xy 194.459291 -23.128401) (xy 194.479214 -23.07631) (xy 194.50651 -23.027675)
			(xy 194.540596 -22.983532) (xy 194.580745 -22.944823) (xy 194.626103 -22.912372) (xy 194.675703 -22.886871)
			(xy 194.728487 -22.868864) (xy 194.78333 -22.858734) (xy 194.839064 -22.856697) (xy 194.894501 -22.862797)
			(xy 194.948458 -22.876903) (xy 194.999787 -22.898715) (xy 195.047393 -22.927769) (xy 195.090261 -22.963444)
			(xy 195.127478 -23.004981) (xy 195.158251 -23.051494) (xy 195.181923 -23.101991) (xy 195.197991 -23.155398)
			(xy 195.206111 -23.210574) (xy 195.20662 -23.23846) (xy 195.206111 -23.266346) (xy 195.197991 -23.321522)
			(xy 195.181923 -23.374929) (xy 195.158251 -23.425426) (xy 195.127478 -23.471939) (xy 195.090261 -23.513476)
			(xy 195.047393 -23.549151) (xy 194.999787 -23.578205) (xy 194.948458 -23.600017) (xy 194.894501 -23.614123)
			(xy 194.839064 -23.620223) (xy 194.78333 -23.618186) (xy 194.728487 -23.608056) (xy 194.675703 -23.590049)
			(xy 194.626103 -23.564548) (xy 194.580745 -23.532097) (xy 194.540596 -23.493388) (xy 194.50651 -23.449245)
			(xy 194.479214 -23.40061) (xy 194.459291 -23.348519) (xy 194.447165 -23.294082) (xy 194.443094 -23.23846)
			(xy 192.631953 -23.23846) (xy 192.666726 -23.277269) (xy 192.697499 -23.323782) (xy 192.721171 -23.374279)
			(xy 192.737239 -23.427686) (xy 192.745359 -23.482862) (xy 192.745868 -23.510748) (xy 192.745359 -23.538634)
			(xy 192.737239 -23.59381) (xy 192.721171 -23.647217) (xy 192.697499 -23.697714) (xy 192.666726 -23.744227)
			(xy 192.629509 -23.785764) (xy 192.586641 -23.821439) (xy 192.539035 -23.850493) (xy 192.487706 -23.872305)
			(xy 192.433749 -23.886411) (xy 192.378312 -23.892511) (xy 192.322578 -23.890474) (xy 192.267735 -23.880344)
			(xy 192.214951 -23.862337) (xy 192.165351 -23.836836) (xy 192.119993 -23.804385) (xy 192.079844 -23.765676)
			(xy 192.045758 -23.721533) (xy 192.018462 -23.672898) (xy 191.998539 -23.620807) (xy 191.986413 -23.56637)
			(xy 191.982342 -23.510748) (xy 191.19088 -23.510748) (xy 191.19088 -24.686049) (xy 191.338206 -24.686049)
			(xy 191.338206 -24.631551) (xy 191.345962 -24.577607) (xy 191.361316 -24.525316) (xy 191.383956 -24.475743)
			(xy 191.41342 -24.429896) (xy 191.449109 -24.388709) (xy 191.490296 -24.35302) (xy 191.536143 -24.323556)
			(xy 191.585716 -24.300916) (xy 191.638007 -24.285562) (xy 191.691951 -24.277806) (xy 191.7192 -24.27732)
			(xy 191.744806 -24.277739) (xy 191.795561 -24.284561) (xy 191.844948 -24.298108) (xy 191.892081 -24.318138)
			(xy 191.936111 -24.344291) (xy 191.956436 -24.35987) (xy 191.968626 -24.368901) (xy 191.996881 -24.379922)
			(xy 192.027124 -24.38217) (xy 192.056698 -24.375449) (xy 192.082999 -24.360349) (xy 192.103714 -24.3382)
			(xy 192.110868 -24.324818) (xy 192.122938 -24.301012) (xy 192.152705 -24.256709) (xy 192.188359 -24.216989)
			(xy 192.229202 -24.182629) (xy 192.274438 -24.1543) (xy 192.323182 -24.132555) (xy 192.374481 -24.117818)
			(xy 192.427335 -24.110379) (xy 192.454022 -24.109934) (xy 192.481275 -24.110337) (xy 192.535227 -24.118097)
			(xy 192.587524 -24.133456) (xy 192.637104 -24.156101) (xy 192.682957 -24.185571) (xy 192.724149 -24.221266)
			(xy 192.759842 -24.262461) (xy 192.78931 -24.308315) (xy 192.811952 -24.357896) (xy 192.816633 -24.37384)
			(xy 194.447412 -24.37384) (xy 194.451483 -24.318218) (xy 194.463609 -24.263781) (xy 194.483532 -24.21169)
			(xy 194.510828 -24.163055) (xy 194.544914 -24.118912) (xy 194.585063 -24.080203) (xy 194.630421 -24.047752)
			(xy 194.680021 -24.022251) (xy 194.732805 -24.004244) (xy 194.787648 -23.994114) (xy 194.843382 -23.992077)
			(xy 194.898819 -23.998177) (xy 194.952776 -24.012283) (xy 195.004105 -24.034095) (xy 195.051711 -24.063149)
			(xy 195.094579 -24.098824) (xy 195.131796 -24.140361) (xy 195.162569 -24.186874) (xy 195.186241 -24.237371)
			(xy 195.202309 -24.290778) (xy 195.210429 -24.345954) (xy 195.210938 -24.37384) (xy 195.210429 -24.401726)
			(xy 195.202309 -24.456902) (xy 195.186241 -24.510309) (xy 195.162569 -24.560806) (xy 195.131796 -24.607319)
			(xy 195.094579 -24.648856) (xy 195.051711 -24.684531) (xy 195.004105 -24.713585) (xy 194.952776 -24.735397)
			(xy 194.898819 -24.749503) (xy 194.843382 -24.755603) (xy 194.787648 -24.753566) (xy 194.732805 -24.743436)
			(xy 194.680021 -24.725429) (xy 194.630421 -24.699928) (xy 194.585063 -24.667477) (xy 194.544914 -24.628768)
			(xy 194.510828 -24.584625) (xy 194.483532 -24.53599) (xy 194.463609 -24.483899) (xy 194.451483 -24.429462)
			(xy 194.447412 -24.37384) (xy 192.816633 -24.37384) (xy 192.827307 -24.410195) (xy 192.835064 -24.464147)
			(xy 192.835064 -24.518653) (xy 192.827307 -24.572605) (xy 192.811952 -24.624904) (xy 192.78931 -24.674485)
			(xy 192.759842 -24.720339) (xy 192.724149 -24.761534) (xy 192.682957 -24.797229) (xy 192.637104 -24.826699)
			(xy 192.587524 -24.849344) (xy 192.535227 -24.864703) (xy 192.481275 -24.872463) (xy 192.454022 -24.87295)
			(xy 192.428416 -24.872525) (xy 192.377661 -24.865706) (xy 192.328273 -24.85216) (xy 192.281141 -24.832131)
			(xy 192.237111 -24.805979) (xy 192.216786 -24.7904) (xy 192.204572 -24.781406) (xy 192.176326 -24.770387)
			(xy 192.146091 -24.768136) (xy 192.116524 -24.77485) (xy 192.090227 -24.789939) (xy 192.069511 -24.812077)
			(xy 192.062354 -24.825452) (xy 192.050254 -24.849242) (xy 192.020492 -24.893546) (xy 191.984844 -24.933267)
			(xy 191.944005 -24.967629) (xy 191.898773 -24.99596) (xy 191.850033 -25.017708) (xy 191.798737 -25.032447)
			(xy 191.745886 -25.039889) (xy 191.7192 -25.040336) (xy 191.691951 -25.039794) (xy 191.638007 -25.032038)
			(xy 191.585716 -25.016684) (xy 191.536143 -24.994044) (xy 191.490296 -24.96458) (xy 191.449109 -24.928891)
			(xy 191.41342 -24.887704) (xy 191.383956 -24.841857) (xy 191.361316 -24.792284) (xy 191.345962 -24.739993)
			(xy 191.338206 -24.686049) (xy 191.19088 -24.686049) (xy 191.19088 -25.565862) (xy 192.072004 -25.565862)
			(xy 192.076075 -25.51024) (xy 192.088201 -25.455803) (xy 192.108124 -25.403712) (xy 192.13542 -25.355077)
			(xy 192.169506 -25.310934) (xy 192.209655 -25.272225) (xy 192.255013 -25.239774) (xy 192.304613 -25.214273)
			(xy 192.357397 -25.196266) (xy 192.41224 -25.186136) (xy 192.467974 -25.184099) (xy 192.523411 -25.190199)
			(xy 192.577368 -25.204305) (xy 192.628697 -25.226117) (xy 192.676303 -25.255171) (xy 192.719171 -25.290846)
			(xy 192.756388 -25.332383) (xy 192.787161 -25.378896) (xy 192.792172 -25.389586) (xy 194.451476 -25.389586)
			(xy 194.455547 -25.333964) (xy 194.467673 -25.279527) (xy 194.487596 -25.227436) (xy 194.514892 -25.178801)
			(xy 194.548978 -25.134658) (xy 194.589127 -25.095949) (xy 194.634485 -25.063498) (xy 194.684085 -25.037997)
			(xy 194.736869 -25.01999) (xy 194.791712 -25.00986) (xy 194.847446 -25.007823) (xy 194.902883 -25.013923)
			(xy 194.95684 -25.028029) (xy 195.008169 -25.049841) (xy 195.055775 -25.078895) (xy 195.098643 -25.11457)
			(xy 195.13586 -25.156107) (xy 195.166633 -25.20262) (xy 195.190305 -25.253117) (xy 195.206373 -25.306524)
			(xy 195.214493 -25.3617) (xy 195.215002 -25.389586) (xy 195.214493 -25.417472) (xy 195.206373 -25.472648)
			(xy 195.190305 -25.526055) (xy 195.166633 -25.576552) (xy 195.13586 -25.623065) (xy 195.098643 -25.664602)
			(xy 195.055775 -25.700277) (xy 195.008169 -25.729331) (xy 194.95684 -25.751143) (xy 194.902883 -25.765249)
			(xy 194.847446 -25.771349) (xy 194.791712 -25.769312) (xy 194.736869 -25.759182) (xy 194.684085 -25.741175)
			(xy 194.634485 -25.715674) (xy 194.589127 -25.683223) (xy 194.548978 -25.644514) (xy 194.514892 -25.600371)
			(xy 194.487596 -25.551736) (xy 194.467673 -25.499645) (xy 194.455547 -25.445208) (xy 194.451476 -25.389586)
			(xy 192.792172 -25.389586) (xy 192.810833 -25.429393) (xy 192.826901 -25.4828) (xy 192.835021 -25.537976)
			(xy 192.83553 -25.565862) (xy 192.835021 -25.593748) (xy 192.826901 -25.648924) (xy 192.810833 -25.702331)
			(xy 192.787161 -25.752828) (xy 192.756388 -25.799341) (xy 192.719171 -25.840878) (xy 192.676303 -25.876553)
			(xy 192.628697 -25.905607) (xy 192.577368 -25.927419) (xy 192.523411 -25.941525) (xy 192.467974 -25.947625)
			(xy 192.41224 -25.945588) (xy 192.357397 -25.935458) (xy 192.304613 -25.917451) (xy 192.255013 -25.89195)
			(xy 192.209655 -25.859499) (xy 192.169506 -25.82079) (xy 192.13542 -25.776647) (xy 192.108124 -25.728012)
			(xy 192.088201 -25.675921) (xy 192.076075 -25.621484) (xy 192.072004 -25.565862) (xy 191.19088 -25.565862)
			(xy 191.19088 -27.505152) (xy 191.295274 -27.505152) (xy 191.295802 -27.476235) (xy 191.304525 -27.419063)
			(xy 191.321779 -27.363863) (xy 191.347169 -27.311901) (xy 191.380112 -27.264367) (xy 191.419854 -27.222351)
			(xy 191.44234 -27.204162) (xy 191.454198 -27.19432) (xy 191.471723 -27.168983) (xy 191.480898 -27.139574)
			(xy 191.480889 -27.108767) (xy 191.471697 -27.079363) (xy 191.454157 -27.054037) (xy 191.44234 -27.044142)
			(xy 191.419885 -27.025917) (xy 191.380146 -26.983906) (xy 191.347203 -26.936378) (xy 191.321809 -26.884423)
			(xy 191.304547 -26.829231) (xy 191.295812 -26.772066) (xy 191.295274 -26.743152) (xy 191.29576 -26.715901)
			(xy 191.303516 -26.661953) (xy 191.318871 -26.609658) (xy 191.341513 -26.560081) (xy 191.370979 -26.514231)
			(xy 191.40667 -26.47304) (xy 191.447861 -26.437349) (xy 191.493711 -26.407883) (xy 191.543288 -26.385241)
			(xy 191.595583 -26.369886) (xy 191.649531 -26.36213) (xy 191.704033 -26.36213) (xy 191.757981 -26.369886)
			(xy 191.810276 -26.385241) (xy 191.819229 -26.38933) (xy 195.016118 -26.38933) (xy 195.020189 -26.333708)
			(xy 195.032315 -26.279271) (xy 195.052238 -26.22718) (xy 195.079534 -26.178545) (xy 195.11362 -26.134402)
			(xy 195.153769 -26.095693) (xy 195.199127 -26.063242) (xy 195.248727 -26.037741) (xy 195.301511 -26.019734)
			(xy 195.356354 -26.009604) (xy 195.412088 -26.007567) (xy 195.467525 -26.013667) (xy 195.521482 -26.027773)
			(xy 195.572811 -26.049585) (xy 195.620417 -26.078639) (xy 195.663285 -26.114314) (xy 195.700502 -26.155851)
			(xy 195.731275 -26.202364) (xy 195.754947 -26.252861) (xy 195.771015 -26.306268) (xy 195.779135 -26.361444)
			(xy 195.779644 -26.38933) (xy 195.779135 -26.417216) (xy 195.771015 -26.472392) (xy 195.754947 -26.525799)
			(xy 195.731275 -26.576296) (xy 195.700502 -26.622809) (xy 195.663285 -26.664346) (xy 195.620417 -26.700021)
			(xy 195.572811 -26.729075) (xy 195.521482 -26.750887) (xy 195.467525 -26.764993) (xy 195.412088 -26.771093)
			(xy 195.356354 -26.769056) (xy 195.301511 -26.758926) (xy 195.248727 -26.740919) (xy 195.199127 -26.715418)
			(xy 195.153769 -26.682967) (xy 195.11362 -26.644258) (xy 195.079534 -26.600115) (xy 195.052238 -26.55148)
			(xy 195.032315 -26.499389) (xy 195.020189 -26.444952) (xy 195.016118 -26.38933) (xy 191.819229 -26.38933)
			(xy 191.859853 -26.407883) (xy 191.905703 -26.437349) (xy 191.946894 -26.47304) (xy 191.982585 -26.514231)
			(xy 192.012051 -26.560081) (xy 192.034693 -26.609658) (xy 192.050048 -26.661953) (xy 192.057804 -26.715901)
			(xy 192.05829 -26.743152) (xy 192.057741 -26.772068) (xy 192.049019 -26.829238) (xy 192.031767 -26.884436)
			(xy 192.006381 -26.936398) (xy 191.973443 -26.983933) (xy 191.933707 -27.025951) (xy 191.911224 -27.044142)
			(xy 191.899466 -27.054091) (xy 191.881945 -27.0794) (xy 191.872764 -27.10878) (xy 191.872755 -27.139561)
			(xy 191.881919 -27.168947) (xy 191.899425 -27.194265) (xy 191.911224 -27.204162) (xy 191.933694 -27.222368)
			(xy 191.973429 -27.264386) (xy 192.006369 -27.311918) (xy 192.031759 -27.363876) (xy 192.049019 -27.41907)
			(xy 192.050102 -27.426158) (xy 195.140832 -27.426158) (xy 195.144903 -27.370536) (xy 195.157029 -27.316099)
			(xy 195.176952 -27.264008) (xy 195.204248 -27.215373) (xy 195.238334 -27.17123) (xy 195.278483 -27.132521)
			(xy 195.323841 -27.10007) (xy 195.373441 -27.074569) (xy 195.426225 -27.056562) (xy 195.481068 -27.046432)
			(xy 195.536802 -27.044395) (xy 195.592239 -27.050495) (xy 195.646196 -27.064601) (xy 195.697525 -27.086413)
			(xy 195.745131 -27.115467) (xy 195.787999 -27.151142) (xy 195.825216 -27.192679) (xy 195.855989 -27.239192)
			(xy 195.879661 -27.289689) (xy 195.895729 -27.343096) (xy 195.903849 -27.398272) (xy 195.904358 -27.426158)
			(xy 195.903849 -27.454044) (xy 195.895729 -27.50922) (xy 195.879661 -27.562627) (xy 195.855989 -27.613124)
			(xy 195.825216 -27.659637) (xy 195.787999 -27.701174) (xy 195.745131 -27.736849) (xy 195.697525 -27.765903)
			(xy 195.646196 -27.787715) (xy 195.592239 -27.801821) (xy 195.536802 -27.807921) (xy 195.481068 -27.805884)
			(xy 195.426225 -27.795754) (xy 195.373441 -27.777747) (xy 195.323841 -27.752246) (xy 195.278483 -27.719795)
			(xy 195.238334 -27.681086) (xy 195.204248 -27.636943) (xy 195.176952 -27.588308) (xy 195.157029 -27.536217)
			(xy 195.144903 -27.48178) (xy 195.140832 -27.426158) (xy 192.050102 -27.426158) (xy 192.057752 -27.476237)
			(xy 192.05829 -27.505152) (xy 192.057804 -27.532403) (xy 192.050048 -27.586351) (xy 192.034693 -27.638646)
			(xy 192.012051 -27.688223) (xy 191.982585 -27.734073) (xy 191.946894 -27.775264) (xy 191.905703 -27.810955)
			(xy 191.859853 -27.840421) (xy 191.810276 -27.863063) (xy 191.757981 -27.878418) (xy 191.704033 -27.886174)
			(xy 191.649531 -27.886174) (xy 191.595583 -27.878418) (xy 191.543288 -27.863063) (xy 191.493711 -27.840421)
			(xy 191.447861 -27.810955) (xy 191.40667 -27.775264) (xy 191.370979 -27.734073) (xy 191.341513 -27.688223)
			(xy 191.318871 -27.638646) (xy 191.303516 -27.586351) (xy 191.29576 -27.532403) (xy 191.295274 -27.505152)
			(xy 191.19088 -27.505152) (xy 191.19088 -28.39974) (xy 192.757042 -28.39974) (xy 192.761113 -28.344118)
			(xy 192.773239 -28.289681) (xy 192.793162 -28.23759) (xy 192.820458 -28.188955) (xy 192.854544 -28.144812)
			(xy 192.894693 -28.106103) (xy 192.940051 -28.073652) (xy 192.989651 -28.048151) (xy 193.042435 -28.030144)
			(xy 193.097278 -28.020014) (xy 193.153012 -28.017977) (xy 193.208449 -28.024077) (xy 193.262406 -28.038183)
			(xy 193.313735 -28.059995) (xy 193.361341 -28.089049) (xy 193.404209 -28.124724) (xy 193.441426 -28.166261)
			(xy 193.472199 -28.212774) (xy 193.495871 -28.263271) (xy 193.511939 -28.316678) (xy 193.520059 -28.371854)
			(xy 193.520466 -28.394152) (xy 195.485256 -28.394152) (xy 195.489327 -28.33853) (xy 195.501453 -28.284093)
			(xy 195.521376 -28.232002) (xy 195.548672 -28.183367) (xy 195.582758 -28.139224) (xy 195.622907 -28.100515)
			(xy 195.668265 -28.068064) (xy 195.717865 -28.042563) (xy 195.770649 -28.024556) (xy 195.825492 -28.014426)
			(xy 195.881226 -28.012389) (xy 195.936663 -28.018489) (xy 195.99062 -28.032595) (xy 196.041949 -28.054407)
			(xy 196.089555 -28.083461) (xy 196.132423 -28.119136) (xy 196.16964 -28.160673) (xy 196.200413 -28.207186)
			(xy 196.224085 -28.257683) (xy 196.240153 -28.31109) (xy 196.248273 -28.366266) (xy 196.248782 -28.394152)
			(xy 196.248273 -28.422038) (xy 196.240153 -28.477214) (xy 196.224085 -28.530621) (xy 196.200413 -28.581118)
			(xy 196.16964 -28.627631) (xy 196.132423 -28.669168) (xy 196.089555 -28.704843) (xy 196.041949 -28.733897)
			(xy 195.99062 -28.755709) (xy 195.936663 -28.769815) (xy 195.881226 -28.775915) (xy 195.825492 -28.773878)
			(xy 195.770649 -28.763748) (xy 195.717865 -28.745741) (xy 195.668265 -28.72024) (xy 195.622907 -28.687789)
			(xy 195.582758 -28.64908) (xy 195.548672 -28.604937) (xy 195.521376 -28.556302) (xy 195.501453 -28.504211)
			(xy 195.489327 -28.449774) (xy 195.485256 -28.394152) (xy 193.520466 -28.394152) (xy 193.520568 -28.39974)
			(xy 193.520059 -28.427626) (xy 193.511939 -28.482802) (xy 193.495871 -28.536209) (xy 193.472199 -28.586706)
			(xy 193.441426 -28.633219) (xy 193.404209 -28.674756) (xy 193.361341 -28.710431) (xy 193.313735 -28.739485)
			(xy 193.262406 -28.761297) (xy 193.208449 -28.775403) (xy 193.153012 -28.781503) (xy 193.097278 -28.779466)
			(xy 193.042435 -28.769336) (xy 192.989651 -28.751329) (xy 192.940051 -28.725828) (xy 192.894693 -28.693377)
			(xy 192.854544 -28.654668) (xy 192.820458 -28.610525) (xy 192.793162 -28.56189) (xy 192.773239 -28.509799)
			(xy 192.761113 -28.455362) (xy 192.757042 -28.39974) (xy 191.19088 -28.39974) (xy 191.19088 -29.116782)
			(xy 196.199504 -29.116782) (xy 196.203575 -29.06116) (xy 196.215701 -29.006723) (xy 196.235624 -28.954632)
			(xy 196.26292 -28.905997) (xy 196.297006 -28.861854) (xy 196.337155 -28.823145) (xy 196.382513 -28.790694)
			(xy 196.432113 -28.765193) (xy 196.484897 -28.747186) (xy 196.53974 -28.737056) (xy 196.595474 -28.735019)
			(xy 196.650911 -28.741119) (xy 196.704868 -28.755225) (xy 196.756197 -28.777037) (xy 196.803803 -28.806091)
			(xy 196.846671 -28.841766) (xy 196.883888 -28.883303) (xy 196.914661 -28.929816) (xy 196.938333 -28.980313)
			(xy 196.954401 -29.03372) (xy 196.962521 -29.088896) (xy 196.96303 -29.116782) (xy 196.962521 -29.144668)
			(xy 196.954401 -29.199844) (xy 196.938333 -29.253251) (xy 196.914661 -29.303748) (xy 196.883888 -29.350261)
			(xy 196.846671 -29.391798) (xy 196.803803 -29.427473) (xy 196.756197 -29.456527) (xy 196.704868 -29.478339)
			(xy 196.650911 -29.492445) (xy 196.595474 -29.498545) (xy 196.53974 -29.496508) (xy 196.484897 -29.486378)
			(xy 196.432113 -29.468371) (xy 196.382513 -29.44287) (xy 196.337155 -29.410419) (xy 196.297006 -29.37171)
			(xy 196.26292 -29.327567) (xy 196.235624 -29.278932) (xy 196.215701 -29.226841) (xy 196.203575 -29.172404)
			(xy 196.199504 -29.116782) (xy 191.19088 -29.116782) (xy 191.19088 -29.839666) (xy 196.907402 -29.839666)
			(xy 196.911473 -29.784044) (xy 196.923599 -29.729607) (xy 196.943522 -29.677516) (xy 196.970818 -29.628881)
			(xy 197.004904 -29.584738) (xy 197.045053 -29.546029) (xy 197.090411 -29.513578) (xy 197.140011 -29.488077)
			(xy 197.192795 -29.47007) (xy 197.247638 -29.45994) (xy 197.303372 -29.457903) (xy 197.358809 -29.464003)
			(xy 197.412766 -29.478109) (xy 197.464095 -29.499921) (xy 197.511701 -29.528975) (xy 197.554569 -29.56465)
			(xy 197.591786 -29.606187) (xy 197.622559 -29.6527) (xy 197.646231 -29.703197) (xy 197.662299 -29.756604)
			(xy 197.670419 -29.81178) (xy 197.670928 -29.839666) (xy 197.670419 -29.867552) (xy 197.662299 -29.922728)
			(xy 197.646231 -29.976135) (xy 197.622559 -30.026632) (xy 197.591786 -30.073145) (xy 197.554569 -30.114682)
			(xy 197.511701 -30.150357) (xy 197.464095 -30.179411) (xy 197.412766 -30.201223) (xy 197.358809 -30.215329)
			(xy 197.303372 -30.221429) (xy 197.247638 -30.219392) (xy 197.192795 -30.209262) (xy 197.140011 -30.191255)
			(xy 197.090411 -30.165754) (xy 197.045053 -30.133303) (xy 197.004904 -30.094594) (xy 196.970818 -30.050451)
			(xy 196.943522 -30.001816) (xy 196.923599 -29.949725) (xy 196.911473 -29.895288) (xy 196.907402 -29.839666)
			(xy 191.19088 -29.839666) (xy 191.19088 -30.521148) (xy 192.51422 -31.844488)
		)
		(stroke
			(width 0)
			(type solid)
		)
		(fill yes)
		(layer "In15.Cu")
		(net "P12V_SCM")
	)
	(gr_poly
		(pts
			(xy 301.79264 -439.00344) (xy 301.79264 -430.64938) (xy 298.91228 -427.76902) (xy 294.54348 -427.76902)
			(xy 294.145462 -427.371002) (xy 294.119808 -427.375574) (xy 294.103926 -427.378084) (xy 294.071879 -427.380754)
			(xy 294.0558 -427.380908) (xy 294.028549 -427.380422) (xy 293.974601 -427.372666) (xy 293.922306 -427.357311)
			(xy 293.872729 -427.334669) (xy 293.826879 -427.305203) (xy 293.785688 -427.269512) (xy 293.749997 -427.228321)
			(xy 293.720531 -427.182471) (xy 293.697889 -427.132894) (xy 293.682534 -427.080599) (xy 293.674778 -427.026651)
			(xy 293.674292 -426.9994) (xy 293.674436 -426.983321) (xy 293.677105 -426.951273) (xy 293.679626 -426.935392)
			(xy 293.684198 -426.909738) (xy 293.3319 -426.55744) (xy 293.3319 -423.869104) (xy 293.331369 -423.854112)
			(xy 293.322665 -423.825417) (xy 293.306007 -423.800486) (xy 293.282829 -423.781463) (xy 293.255126 -423.769988)
			(xy 293.225286 -423.767049) (xy 293.195877 -423.772899) (xy 293.169433 -423.787035) (xy 293.158418 -423.797222)
			(xy 289.95116 -427.00448) (xy 289.93244 -427.022497) (xy 289.890427 -427.05306) (xy 289.844155 -427.076684)
			(xy 289.79476 -427.092789) (xy 289.743456 -427.10098) (xy 289.71748 -427.101508) (xy 281.70378 -427.101508)
			(xy 281.681963 -427.113593) (xy 281.635861 -427.132619) (xy 281.587671 -427.145472) (xy 281.538217 -427.151933)
			(xy 281.51328 -427.152308) (xy 281.48603 -427.151821) (xy 281.432084 -427.144062) (xy 281.379792 -427.128705)
			(xy 281.330217 -427.106063) (xy 281.284369 -427.076596) (xy 281.243181 -427.040905) (xy 281.207492 -426.999715)
			(xy 281.178028 -426.953865) (xy 281.155388 -426.904289) (xy 281.140034 -426.851996) (xy 281.132278 -426.79805)
			(xy 281.132278 -426.74355) (xy 281.140034 -426.689604) (xy 281.155388 -426.637311) (xy 281.178028 -426.587735)
			(xy 281.207492 -426.541885) (xy 281.243181 -426.500695) (xy 281.284369 -426.465004) (xy 281.330217 -426.435537)
			(xy 281.379792 -426.412895) (xy 281.432084 -426.397538) (xy 281.48603 -426.389779) (xy 281.51328 -426.389292)
			(xy 281.538216 -426.389682) (xy 281.587668 -426.396148) (xy 281.635857 -426.408996) (xy 281.681963 -426.42801)
			(xy 281.70378 -426.440092) (xy 289.580574 -426.440092) (xy 293.133272 -422.887394) (xy 293.133272 -418.363146)
			(xy 290.76396 -415.99358) (xy 276.8981 -415.99358) (xy 275.86686 -417.02482) (xy 276.170642 -417.02482)
			(xy 276.174713 -416.969198) (xy 276.186839 -416.914761) (xy 276.206762 -416.86267) (xy 276.234058 -416.814035)
			(xy 276.268144 -416.769892) (xy 276.308293 -416.731183) (xy 276.353651 -416.698732) (xy 276.403251 -416.673231)
			(xy 276.456035 -416.655224) (xy 276.510878 -416.645094) (xy 276.566612 -416.643057) (xy 276.622049 -416.649157)
			(xy 276.676006 -416.663263) (xy 276.727335 -416.685075) (xy 276.774941 -416.714129) (xy 276.817809 -416.749804)
			(xy 276.855026 -416.791341) (xy 276.885799 -416.837854) (xy 276.907361 -416.88385) (xy 280.663902 -416.88385)
			(xy 280.667973 -416.828228) (xy 280.680099 -416.773791) (xy 280.700022 -416.7217) (xy 280.727318 -416.673065)
			(xy 280.761404 -416.628922) (xy 280.801553 -416.590213) (xy 280.846911 -416.557762) (xy 280.896511 -416.532261)
			(xy 280.949295 -416.514254) (xy 281.004138 -416.504124) (xy 281.059872 -416.502087) (xy 281.115309 -416.508187)
			(xy 281.169266 -416.522293) (xy 281.220595 -416.544105) (xy 281.268201 -416.573159) (xy 281.311069 -416.608834)
			(xy 281.348286 -416.650371) (xy 281.379059 -416.696884) (xy 281.402731 -416.747381) (xy 281.418799 -416.800788)
			(xy 281.426919 -416.855964) (xy 281.427428 -416.88385) (xy 281.426919 -416.911736) (xy 281.418799 -416.966912)
			(xy 281.402731 -417.020319) (xy 281.379059 -417.070816) (xy 281.348286 -417.117329) (xy 281.311069 -417.158866)
			(xy 281.268201 -417.194541) (xy 281.220595 -417.223595) (xy 281.169266 -417.245407) (xy 281.115309 -417.259513)
			(xy 281.059872 -417.265613) (xy 281.004138 -417.263576) (xy 280.949295 -417.253446) (xy 280.896511 -417.235439)
			(xy 280.846911 -417.209938) (xy 280.801553 -417.177487) (xy 280.761404 -417.138778) (xy 280.727318 -417.094635)
			(xy 280.700022 -417.046) (xy 280.680099 -416.993909) (xy 280.667973 -416.939472) (xy 280.663902 -416.88385)
			(xy 276.907361 -416.88385) (xy 276.909471 -416.888351) (xy 276.925539 -416.941758) (xy 276.933659 -416.996934)
			(xy 276.934168 -417.02482) (xy 276.933659 -417.052706) (xy 276.925539 -417.107882) (xy 276.909471 -417.161289)
			(xy 276.885799 -417.211786) (xy 276.855026 -417.258299) (xy 276.817809 -417.299836) (xy 276.774941 -417.335511)
			(xy 276.727335 -417.364565) (xy 276.676006 -417.386377) (xy 276.622049 -417.400483) (xy 276.566612 -417.406583)
			(xy 276.510878 -417.404546) (xy 276.456035 -417.394416) (xy 276.403251 -417.376409) (xy 276.353651 -417.350908)
			(xy 276.308293 -417.318457) (xy 276.268144 -417.279748) (xy 276.234058 -417.235605) (xy 276.206762 -417.18697)
			(xy 276.186839 -417.134879) (xy 276.174713 -417.080442) (xy 276.170642 -417.02482) (xy 275.86686 -417.02482)
			(xy 274.52574 -418.36594) (xy 274.953982 -418.36594) (xy 274.958053 -418.310318) (xy 274.970179 -418.255881)
			(xy 274.990102 -418.20379) (xy 275.017398 -418.155155) (xy 275.051484 -418.111012) (xy 275.091633 -418.072303)
			(xy 275.136991 -418.039852) (xy 275.186591 -418.014351) (xy 275.239375 -417.996344) (xy 275.294218 -417.986214)
			(xy 275.349952 -417.984177) (xy 275.405389 -417.990277) (xy 275.459346 -418.004383) (xy 275.510675 -418.026195)
			(xy 275.558281 -418.055249) (xy 275.601149 -418.090924) (xy 275.638366 -418.132461) (xy 275.669139 -418.178974)
			(xy 275.692811 -418.229471) (xy 275.708879 -418.282878) (xy 275.716999 -418.338054) (xy 275.717508 -418.36594)
			(xy 275.716999 -418.393826) (xy 275.708879 -418.449002) (xy 275.692811 -418.502409) (xy 275.669139 -418.552906)
			(xy 275.638366 -418.599419) (xy 275.601149 -418.640956) (xy 275.558281 -418.676631) (xy 275.510675 -418.705685)
			(xy 275.459346 -418.727497) (xy 275.405389 -418.741603) (xy 275.349952 -418.747703) (xy 275.294218 -418.745666)
			(xy 275.239375 -418.735536) (xy 275.186591 -418.717529) (xy 275.136991 -418.692028) (xy 275.091633 -418.659577)
			(xy 275.051484 -418.620868) (xy 275.017398 -418.576725) (xy 274.990102 -418.52809) (xy 274.970179 -418.475999)
			(xy 274.958053 -418.421562) (xy 274.953982 -418.36594) (xy 274.52574 -418.36594) (xy 270.7767 -422.11498)
			(xy 243.33835 -422.11498) (xy 243.324552 -422.115446) (xy 243.297968 -422.12285) (xy 243.274337 -422.137103)
			(xy 243.255387 -422.157163) (xy 243.242501 -422.181567) (xy 243.236622 -422.208529) (xy 243.238178 -422.236082)
			(xy 243.247057 -422.262211) (xy 243.262609 -422.285007) (xy 243.272818 -422.294304) (xy 243.293707 -422.312515)
			(xy 243.330514 -422.353944) (xy 243.360932 -422.400267) (xy 243.384319 -422.450507) (xy 243.400183 -422.503605)
			(xy 243.408188 -422.558441) (xy 243.408708 -422.58615) (xy 243.408189 -422.614558) (xy 243.39977 -422.670747)
			(xy 243.383112 -422.725065) (xy 243.358582 -422.776313) (xy 243.326723 -422.823356) (xy 243.288239 -422.865154)
			(xy 243.243983 -422.900782) (xy 243.219732 -422.915588) (xy 243.2077 -422.923181) (xy 243.188072 -422.943761)
			(xy 243.174877 -422.968954) (xy 243.169137 -422.996808) (xy 243.171298 -423.025165) (xy 243.181191 -423.051828)
			(xy 243.198051 -423.074731) (xy 243.209064 -423.083736) (xy 243.231804 -423.101929) (xy 243.272023 -423.144043)
			(xy 243.305378 -423.191778) (xy 243.331094 -423.244026) (xy 243.342679 -423.28084) (xy 282.347922 -423.28084)
			(xy 282.351993 -423.225218) (xy 282.364119 -423.170781) (xy 282.384042 -423.11869) (xy 282.411338 -423.070055)
			(xy 282.445424 -423.025912) (xy 282.485573 -422.987203) (xy 282.530931 -422.954752) (xy 282.580531 -422.929251)
			(xy 282.633315 -422.911244) (xy 282.688158 -422.901114) (xy 282.743892 -422.899077) (xy 282.799329 -422.905177)
			(xy 282.853286 -422.919283) (xy 282.904615 -422.941095) (xy 282.952221 -422.970149) (xy 282.995089 -423.005824)
			(xy 283.032306 -423.047361) (xy 283.063079 -423.093874) (xy 283.086751 -423.144371) (xy 283.102819 -423.197778)
			(xy 283.110939 -423.252954) (xy 283.111448 -423.28084) (xy 283.110939 -423.308726) (xy 283.102819 -423.363902)
			(xy 283.086751 -423.417309) (xy 283.063079 -423.467806) (xy 283.032306 -423.514319) (xy 282.995089 -423.555856)
			(xy 282.952221 -423.591531) (xy 282.904615 -423.620585) (xy 282.853286 -423.642397) (xy 282.799329 -423.656503)
			(xy 282.743892 -423.662603) (xy 282.688158 -423.660566) (xy 282.633315 -423.650436) (xy 282.580531 -423.632429)
			(xy 282.530931 -423.606928) (xy 282.485573 -423.574477) (xy 282.445424 -423.535768) (xy 282.411338 -423.491625)
			(xy 282.384042 -423.44299) (xy 282.364119 -423.390899) (xy 282.351993 -423.336462) (xy 282.347922 -423.28084)
			(xy 243.342679 -423.28084) (xy 243.348575 -423.299574) (xy 243.357414 -423.357133) (xy 243.357908 -423.38625)
			(xy 243.357422 -423.413501) (xy 243.349666 -423.467449) (xy 243.334311 -423.519744) (xy 243.311669 -423.569321)
			(xy 243.282203 -423.615171) (xy 243.246512 -423.656362) (xy 243.205321 -423.692053) (xy 243.159471 -423.721519)
			(xy 243.109894 -423.744161) (xy 243.057599 -423.759516) (xy 243.003651 -423.767272) (xy 242.949149 -423.767272)
			(xy 242.895201 -423.759516) (xy 242.842906 -423.744161) (xy 242.793329 -423.721519) (xy 242.747479 -423.692053)
			(xy 242.706288 -423.656362) (xy 242.670597 -423.615171) (xy 242.641131 -423.569321) (xy 242.618489 -423.519744)
			(xy 242.603134 -423.467449) (xy 242.595378 -423.413501) (xy 242.594892 -423.38625) (xy 242.595411 -423.357842)
			(xy 242.60383 -423.301653) (xy 242.620488 -423.247335) (xy 242.645018 -423.196087) (xy 242.676877 -423.149044)
			(xy 242.715361 -423.107246) (xy 242.759617 -423.071618) (xy 242.783868 -423.056812) (xy 242.7959 -423.049219)
			(xy 242.815528 -423.028639) (xy 242.828723 -423.003446) (xy 242.834463 -422.975592) (xy 242.832302 -422.947235)
			(xy 242.822409 -422.920572) (xy 242.805549 -422.897669) (xy 242.794536 -422.888664) (xy 242.770641 -422.869478)
			(xy 242.728708 -422.824797) (xy 242.694453 -422.77399) (xy 242.668757 -422.718361) (xy 242.659916 -422.68902)
			(xy 242.655315 -422.674573) (xy 242.63898 -422.649048) (xy 242.61588 -422.629434) (xy 242.588045 -422.617455)
			(xy 242.55792 -422.614162) (xy 242.528154 -422.619847) (xy 242.501363 -422.634008) (xy 242.490244 -422.644316)
			(xy 241.11966 -424.0149) (xy 241.11966 -425.152148) (xy 276.956434 -425.152148) (xy 276.956435 -425.097638)
			(xy 276.964194 -425.043684) (xy 276.979553 -424.991382) (xy 277.002198 -424.941799) (xy 277.03167 -424.895943)
			(xy 277.067367 -424.854749) (xy 277.108565 -424.819054) (xy 277.154422 -424.789585) (xy 277.204007 -424.766943)
			(xy 277.25631 -424.751588) (xy 277.310265 -424.743834) (xy 277.33752 -424.743372) (xy 277.360289 -424.743721)
			(xy 277.405495 -424.749201) (xy 277.42769 -424.754294) (xy 277.441172 -424.757127) (xy 277.468696 -424.756194)
			(xy 277.494973 -424.747948) (xy 277.518097 -424.732989) (xy 277.536389 -424.7124) (xy 277.548522 -424.687677)
			(xy 277.553617 -424.660612) (xy 277.552912 -424.646852) (xy 277.551642 -424.61434) (xy 277.552112 -424.587083)
			(xy 277.559865 -424.533123) (xy 277.575219 -424.480815) (xy 277.597861 -424.431226) (xy 277.62733 -424.385363)
			(xy 277.663026 -424.344162) (xy 277.704223 -424.30846) (xy 277.750082 -424.278985) (xy 277.799668 -424.256336)
			(xy 277.851974 -424.240976) (xy 277.905933 -424.233216) (xy 277.960447 -424.233214) (xy 278.014407 -424.240971)
			(xy 278.066713 -424.256329) (xy 278.116301 -424.278975) (xy 278.162161 -424.308448) (xy 278.20336 -424.344147)
			(xy 278.239058 -424.385347) (xy 278.26853 -424.431208) (xy 278.291174 -424.480797) (xy 278.306531 -424.533103)
			(xy 278.314286 -424.587063) (xy 278.314284 -424.641577) (xy 278.306522 -424.695536) (xy 278.29116 -424.747841)
			(xy 278.268511 -424.797427) (xy 278.239034 -424.843285) (xy 278.203331 -424.884481) (xy 278.162129 -424.920176)
			(xy 278.116266 -424.949644) (xy 278.066675 -424.972285) (xy 278.014367 -424.987637) (xy 277.960407 -424.995389)
			(xy 277.93315 -424.995848) (xy 277.910382 -424.995486) (xy 277.865175 -424.990015) (xy 277.84298 -424.984926)
			(xy 277.829492 -424.982146) (xy 277.80198 -424.983087) (xy 277.775716 -424.991331) (xy 277.752601 -425.006283)
			(xy 277.734312 -425.026857) (xy 277.722173 -425.051564) (xy 277.717063 -425.078614) (xy 277.717758 -425.092368)
			(xy 277.719028 -425.12488) (xy 277.718566 -425.152135) (xy 277.710812 -425.20609) (xy 277.695457 -425.258393)
			(xy 277.672815 -425.307978) (xy 277.643346 -425.353835) (xy 277.607651 -425.395033) (xy 277.566457 -425.43073)
			(xy 277.520601 -425.460202) (xy 277.471018 -425.482847) (xy 277.418716 -425.498206) (xy 277.364762 -425.505965)
			(xy 277.310252 -425.505966) (xy 277.256297 -425.498209) (xy 277.203995 -425.482852) (xy 277.154411 -425.460208)
			(xy 277.108554 -425.430738) (xy 277.067358 -425.395042) (xy 277.031662 -425.353846) (xy 277.002192 -425.307989)
			(xy 276.979548 -425.258405) (xy 276.964191 -425.206103) (xy 276.956434 -425.152148) (xy 241.11966 -425.152148)
			(xy 241.11966 -433.04206) (xy 267.01141 -433.04206) (xy 267.01543 -432.866756) (xy 267.027484 -432.69182)
			(xy 267.047545 -432.517622) (xy 267.075571 -432.344526) (xy 267.111504 -432.172897) (xy 267.155267 -432.003095)
			(xy 267.20677 -431.835479) (xy 267.265903 -431.6704) (xy 267.332542 -431.508206) (xy 267.406547 -431.349238)
			(xy 267.487762 -431.19383) (xy 267.576017 -431.042308) (xy 267.671126 -430.894992) (xy 267.772888 -430.752191)
			(xy 267.881091 -430.614206) (xy 267.995506 -430.481327) (xy 268.115893 -430.353833) (xy 268.241998 -430.231992)
			(xy 268.373557 -430.116061) (xy 268.510292 -430.006284) (xy 268.651917 -429.902891) (xy 268.798133 -429.806099)
			(xy 268.948632 -429.716113) (xy 269.103099 -429.633121) (xy 269.261209 -429.557298) (xy 269.422628 -429.488804)
			(xy 269.587018 -429.427782) (xy 269.754033 -429.374362) (xy 269.923321 -429.328654) (xy 270.094527 -429.290756)
			(xy 270.26729 -429.260747) (xy 270.441247 -429.23869) (xy 270.616033 -429.224631) (xy 270.79128 -429.218601)
			(xy 270.966618 -429.220611) (xy 271.14168 -429.230658) (xy 271.316098 -429.248721) (xy 271.489504 -429.274761)
			(xy 271.661533 -429.308723) (xy 271.831825 -429.350537) (xy 272.000021 -429.400114) (xy 272.165767 -429.457351)
			(xy 272.328714 -429.522126) (xy 272.488521 -429.594303) (xy 272.64485 -429.673731) (xy 272.797374 -429.760243)
			(xy 272.94577 -429.853656) (xy 273.089728 -429.953775) (xy 273.228945 -430.060389) (xy 273.363127 -430.173273)
			(xy 273.491993 -430.29219) (xy 273.615272 -430.41689) (xy 273.732703 -430.547111) (xy 273.844042 -430.682578)
			(xy 273.949052 -430.823008) (xy 274.047513 -430.968105) (xy 274.139219 -431.117563) (xy 274.223977 -431.271068)
			(xy 274.301607 -431.428298) (xy 274.371948 -431.588921) (xy 274.43485 -431.752601) (xy 274.490182 -431.918992)
			(xy 274.537828 -432.087745) (xy 274.577686 -432.258505) (xy 274.609674 -432.430913) (xy 274.633724 -432.604606)
			(xy 274.649786 -432.779219) (xy 274.657825 -432.954385) (xy 274.658328 -433.04206) (xy 274.657825 -433.129735)
			(xy 274.649786 -433.304901) (xy 274.633724 -433.479514) (xy 274.609674 -433.653207) (xy 274.577686 -433.825615)
			(xy 274.537828 -433.996375) (xy 274.490182 -434.165128) (xy 274.43485 -434.331519) (xy 274.371948 -434.495199)
			(xy 274.301607 -434.655822) (xy 274.223977 -434.813052) (xy 274.139219 -434.966557) (xy 274.047513 -435.116015)
			(xy 273.949052 -435.261112) (xy 273.844042 -435.401542) (xy 273.732703 -435.537009) (xy 273.615272 -435.66723)
			(xy 273.491993 -435.79193) (xy 273.363127 -435.910847) (xy 273.228945 -436.023731) (xy 273.089728 -436.130345)
			(xy 272.94577 -436.230464) (xy 272.797374 -436.323877) (xy 272.64485 -436.410389) (xy 272.488521 -436.489817)
			(xy 272.328714 -436.561994) (xy 272.165767 -436.626769) (xy 272.000021 -436.684006) (xy 271.831825 -436.733583)
			(xy 271.661533 -436.775397) (xy 271.489504 -436.809359) (xy 271.316098 -436.835399) (xy 271.14168 -436.853462)
			(xy 270.966618 -436.863509) (xy 270.79128 -436.865519) (xy 270.616033 -436.859489) (xy 270.441247 -436.84543)
			(xy 270.26729 -436.823373) (xy 270.094527 -436.793364) (xy 269.923321 -436.755466) (xy 269.754033 -436.709758)
			(xy 269.587018 -436.656338) (xy 269.422628 -436.595316) (xy 269.261209 -436.526822) (xy 269.103099 -436.450999)
			(xy 268.948632 -436.368007) (xy 268.798133 -436.278021) (xy 268.651917 -436.181229) (xy 268.510292 -436.077836)
			(xy 268.373557 -435.968059) (xy 268.241998 -435.852128) (xy 268.115893 -435.730287) (xy 267.995506 -435.602793)
			(xy 267.881091 -435.469914) (xy 267.772888 -435.331929) (xy 267.671126 -435.189128) (xy 267.576017 -435.041812)
			(xy 267.487762 -434.89029) (xy 267.406547 -434.734882) (xy 267.332542 -434.575914) (xy 267.265903 -434.41372)
			(xy 267.20677 -434.248641) (xy 267.155267 -434.081025) (xy 267.111504 -433.911223) (xy 267.075571 -433.739594)
			(xy 267.047545 -433.566498) (xy 267.027484 -433.3923) (xy 267.01543 -433.217364) (xy 267.01141 -433.04206)
			(xy 241.11966 -433.04206) (xy 241.11966 -437.130952) (xy 277.12924 -437.130952) (xy 277.154229 -437.131414)
			(xy 277.203592 -437.139234) (xy 277.251121 -437.154689) (xy 277.295642 -437.1774) (xy 277.336056 -437.206804)
			(xy 277.35403 -437.22417) (xy 278.520652 -438.390792) (xy 278.732742 -438.390792) (xy 278.746429 -438.390315)
			(xy 278.772804 -438.382976) (xy 278.796279 -438.36889) (xy 278.815166 -438.349072) (xy 278.828106 -438.324946)
			(xy 278.834168 -438.298249) (xy 278.832916 -438.270901) (xy 278.824441 -438.24487) (xy 278.809351 -438.222027)
			(xy 278.79929 -438.212738) (xy 278.767379 -438.184225) (xy 278.708513 -438.122106) (xy 278.655791 -438.054693)
			(xy 278.609688 -437.982592) (xy 278.570617 -437.90645) (xy 278.538928 -437.826952) (xy 278.514908 -437.744812)
			(xy 278.498771 -437.660766) (xy 278.490662 -437.57557) (xy 278.490172 -437.53278) (xy 278.490654 -437.491091)
			(xy 278.498349 -437.408069) (xy 278.513671 -437.32611) (xy 278.53649 -437.245915) (xy 278.56661 -437.168168)
			(xy 278.603776 -437.093531) (xy 278.647669 -437.022642) (xy 278.697916 -436.956105) (xy 278.754088 -436.894488)
			(xy 278.815705 -436.838316) (xy 278.882242 -436.788069) (xy 278.953131 -436.744176) (xy 279.027768 -436.70701)
			(xy 279.105515 -436.67689) (xy 279.18571 -436.654071) (xy 279.267669 -436.638749) (xy 279.350691 -436.631054)
			(xy 279.39238 -436.630572) (xy 279.434397 -436.631053) (xy 279.518067 -436.638865) (xy 279.600648 -436.654424)
			(xy 279.681424 -436.677594) (xy 279.759696 -436.708176) (xy 279.834785 -436.745903) (xy 279.90604 -436.790449)
			(xy 279.972845 -436.841428) (xy 280.034619 -436.898398) (xy 280.090829 -436.960866) (xy 280.11628 -436.9943)
			(xy 280.125104 -437.005335) (xy 280.147569 -437.022453) (xy 280.173864 -437.03276) (xy 280.201978 -437.035464)
			(xy 280.229756 -437.03036) (xy 280.255072 -437.017838) (xy 280.275986 -436.998856) (xy 280.290897 -436.97487)
			(xy 280.298663 -436.947715) (xy 280.29916 -436.933594) (xy 280.29916 -435.591966) (xy 280.298707 -435.577835)
			(xy 280.290969 -435.550655) (xy 280.276068 -435.526642) (xy 280.255149 -435.50764) (xy 280.229819 -435.495108)
			(xy 280.202022 -435.49001) (xy 280.173893 -435.492736) (xy 280.147592 -435.503077) (xy 280.12514 -435.52024)
			(xy 280.11628 -435.53126) (xy 280.090816 -435.564685) (xy 280.034609 -435.627154) (xy 279.972837 -435.684125)
			(xy 279.906034 -435.735106) (xy 279.83478 -435.779653) (xy 279.759692 -435.817381) (xy 279.681422 -435.847963)
			(xy 279.600646 -435.871134) (xy 279.518066 -435.886694) (xy 279.434397 -435.894506) (xy 279.39238 -435.894988)
			(xy 279.349857 -435.894496) (xy 279.26519 -435.886491) (xy 279.181651 -435.870554) (xy 279.099984 -435.846825)
			(xy 279.020911 -435.815517) (xy 278.945136 -435.776906) (xy 278.873331 -435.731335) (xy 278.806133 -435.679209)
			(xy 278.744139 -435.620991) (xy 278.687898 -435.557197) (xy 278.637911 -435.488393) (xy 278.59462 -435.41519)
			(xy 278.558411 -435.338239) (xy 278.529603 -435.258221) (xy 278.508454 -435.175848) (xy 278.495151 -435.09185)
			(xy 278.489812 -435.006972) (xy 278.492484 -434.921969) (xy 278.503143 -434.837595) (xy 278.521696 -434.754598)
			(xy 278.547976 -434.673715) (xy 278.581752 -434.595665) (xy 278.622723 -434.521139) (xy 278.670526 -434.4508)
			(xy 278.724736 -434.385272) (xy 278.784872 -434.325136) (xy 278.8504 -434.270926) (xy 278.920739 -434.223123)
			(xy 278.995265 -434.182152) (xy 279.073315 -434.148376) (xy 279.154198 -434.122096) (xy 279.237195 -434.103543)
			(xy 279.321569 -434.092884) (xy 279.406572 -434.090212) (xy 279.49145 -434.095551) (xy 279.575448 -434.108854)
			(xy 279.657821 -434.130003) (xy 279.737839 -434.158811) (xy 279.81479 -434.19502) (xy 279.887993 -434.238311)
			(xy 279.956797 -434.288298) (xy 280.020591 -434.344539) (xy 280.078809 -434.406533) (xy 280.130935 -434.473731)
			(xy 280.176506 -434.545536) (xy 280.215117 -434.621311) (xy 280.246425 -434.700384) (xy 280.270154 -434.782051)
			(xy 280.286091 -434.86559) (xy 280.294096 -434.950257) (xy 280.294588 -434.99278) (xy 280.294334 -435.012084)
			(xy 280.294603 -435.022401) (xy 280.302319 -435.041522) (xy 280.316924 -435.056077) (xy 280.336071 -435.063728)
			(xy 280.356684 -435.063246) (xy 280.375453 -435.054709) (xy 280.382726 -435.04739) (xy 280.392378 -435.03723)
			(xy 282.137612 -433.291996) (xy 282.141168 -433.278026) (xy 282.148264 -433.250619) (xy 282.16945 -433.19812)
			(xy 282.198169 -433.149333) (xy 282.233788 -433.105331) (xy 282.275526 -433.067082) (xy 282.322462 -433.035428)
			(xy 282.373564 -433.011065) (xy 282.427707 -432.99453) (xy 282.483702 -432.986186) (xy 282.512008 -432.985672)
			(xy 282.539259 -432.986158) (xy 282.593207 -432.993916) (xy 282.645502 -433.009271) (xy 282.69508 -433.031913)
			(xy 282.740931 -433.061379) (xy 282.782122 -433.09707) (xy 282.817814 -433.13826) (xy 282.847282 -433.18411)
			(xy 282.869925 -433.233686) (xy 282.885282 -433.285981) (xy 282.893041 -433.339929) (xy 282.893516 -433.36718)
			(xy 282.893053 -433.394456) (xy 282.885288 -433.448452) (xy 282.869913 -433.500793) (xy 282.847242 -433.550411)
			(xy 282.817737 -433.596295) (xy 282.781999 -433.63751) (xy 282.76169 -433.655724) (xy 282.751273 -433.66541)
			(xy 282.73579 -433.689258) (xy 282.727469 -433.716446) (xy 282.726953 -433.744875) (xy 282.734281 -433.772347)
			(xy 282.748889 -433.796742) (xy 282.758896 -433.806854) (xy 282.778933 -433.826267) (xy 282.813729 -433.869875)
			(xy 282.841817 -433.918077) (xy 282.862601 -433.969849) (xy 282.86964 -433.996846) (xy 282.873196 -434.010816)
			(xy 283.21381 -434.35143) (xy 283.231156 -434.36942) (xy 283.260542 -434.409839) (xy 283.283243 -434.454357)
			(xy 283.298699 -434.501879) (xy 283.30653 -434.551234) (xy 283.307028 -434.57622) (xy 283.307028 -435.022498)
			(xy 283.306562 -435.047485) (xy 283.298734 -435.096843) (xy 283.28327 -435.144366) (xy 283.260554 -435.188879)
			(xy 283.231145 -435.229285) (xy 283.21381 -435.247288) (xy 283.159454 -435.301644) (xy 283.150263 -435.311393)
			(xy 283.136888 -435.3346) (xy 283.130014 -435.360487) (xy 283.130114 -435.387272) (xy 283.137183 -435.413107)
			(xy 283.150732 -435.436212) (xy 283.169827 -435.454995) (xy 283.181298 -435.461918) (xy 283.206179 -435.476531)
			(xy 283.251623 -435.512085) (xy 283.291194 -435.554078) (xy 283.323988 -435.601552) (xy 283.349257 -435.653424)
			(xy 283.366426 -435.70851) (xy 283.375101 -435.765554) (xy 283.375608 -435.794404) (xy 283.375122 -435.821655)
			(xy 283.367365 -435.875602) (xy 283.352009 -435.927897) (xy 283.329368 -435.977473) (xy 283.299902 -436.023323)
			(xy 283.26421 -436.064513) (xy 283.22302 -436.100204) (xy 283.17717 -436.12967) (xy 283.127593 -436.152311)
			(xy 283.075298 -436.167666) (xy 283.021351 -436.175422) (xy 282.9941 -436.175912) (xy 282.965255 -436.175376)
			(xy 282.908223 -436.16668) (xy 282.85315 -436.1495) (xy 282.801289 -436.124228) (xy 282.753822 -436.091439)
			(xy 282.711829 -436.051881) (xy 282.676268 -436.006455) (xy 282.661614 -435.981602) (xy 282.654667 -435.970159)
			(xy 282.635876 -435.951104) (xy 282.61278 -435.937585) (xy 282.586964 -435.930533) (xy 282.560203 -435.930432)
			(xy 282.534334 -435.937288) (xy 282.511136 -435.950631) (xy 282.50134 -435.959758) (xy 282.277566 -436.183532)
			(xy 282.268427 -436.193228) (xy 282.255108 -436.216295) (xy 282.24822 -436.242025) (xy 282.248231 -436.268661)
			(xy 282.255142 -436.294385) (xy 282.26848 -436.317441) (xy 282.287335 -436.336255) (xy 282.298648 -436.343298)
			(xy 282.32318 -436.358) (xy 282.367942 -436.393598) (xy 282.406888 -436.43548) (xy 282.439146 -436.482705)
			(xy 282.463994 -436.534216) (xy 282.480875 -436.58886) (xy 282.489411 -436.64541) (xy 282.48991 -436.674006)
			(xy 282.489424 -436.701257) (xy 282.481667 -436.755204) (xy 282.466311 -436.807498) (xy 282.44367 -436.857075)
			(xy 282.414203 -436.902925) (xy 282.378512 -436.944114) (xy 282.337322 -436.979806) (xy 282.291471 -437.009271)
			(xy 282.241895 -437.031912) (xy 282.1896 -437.047267) (xy 282.135653 -437.055024) (xy 282.108402 -437.055514)
			(xy 282.085284 -437.055173) (xy 282.039388 -437.049587) (xy 281.9945 -437.038507) (xy 281.972766 -437.030622)
			(xy 281.959444 -437.026003) (xy 281.931371 -437.023493) (xy 281.903681 -437.028752) (xy 281.878482 -437.041379)
			(xy 281.857695 -437.060413) (xy 281.842902 -437.084404) (xy 281.835229 -437.111525) (xy 281.834844 -437.125618)
			(xy 281.834844 -437.5658) (xy 282.650182 -437.5658) (xy 282.654253 -437.510178) (xy 282.666379 -437.455741)
			(xy 282.686302 -437.40365) (xy 282.713598 -437.355015) (xy 282.747684 -437.310872) (xy 282.787833 -437.272163)
			(xy 282.833191 -437.239712) (xy 282.882791 -437.214211) (xy 282.935575 -437.196204) (xy 282.990418 -437.186074)
			(xy 283.046152 -437.184037) (xy 283.101589 -437.190137) (xy 283.155546 -437.204243) (xy 283.206875 -437.226055)
			(xy 283.254481 -437.255109) (xy 283.297349 -437.290784) (xy 283.334566 -437.332321) (xy 283.365339 -437.378834)
			(xy 283.389011 -437.429331) (xy 283.405079 -437.482738) (xy 283.413199 -437.537914) (xy 283.413708 -437.5658)
			(xy 283.413199 -437.593686) (xy 283.405079 -437.648862) (xy 283.389011 -437.702269) (xy 283.365339 -437.752766)
			(xy 283.334566 -437.799279) (xy 283.297349 -437.840816) (xy 283.254481 -437.876491) (xy 283.206875 -437.905545)
			(xy 283.155546 -437.927357) (xy 283.101589 -437.941463) (xy 283.046152 -437.947563) (xy 282.990418 -437.945526)
			(xy 282.935575 -437.935396) (xy 282.882791 -437.917389) (xy 282.833191 -437.891888) (xy 282.787833 -437.859437)
			(xy 282.747684 -437.820728) (xy 282.713598 -437.776585) (xy 282.686302 -437.72795) (xy 282.666379 -437.675859)
			(xy 282.654253 -437.621422) (xy 282.650182 -437.5658) (xy 281.834844 -437.5658) (xy 281.834844 -438.78627)
			(xy 281.834404 -438.81125) (xy 281.826632 -438.8606) (xy 281.811229 -438.908125) (xy 281.788574 -438.952651)
			(xy 281.759226 -438.993081) (xy 281.74188 -439.01106) (xy 281.25674 -439.4962) (xy 283.895292 -439.4962)
			(xy 283.895717 -439.470224) (xy 283.90276 -439.418751) (xy 283.916731 -439.368713) (xy 283.937369 -439.321036)
			(xy 283.964293 -439.276604) (xy 283.997002 -439.236242) (xy 284.034891 -439.200697) (xy 284.05582 -439.185304)
			(xy 284.066833 -439.176895) (xy 284.084255 -439.155363) (xy 284.095248 -439.129941) (xy 284.099005 -439.1025)
			(xy 284.095248 -439.075059) (xy 284.084255 -439.049637) (xy 284.066833 -439.028105) (xy 284.05582 -439.019696)
			(xy 284.034878 -439.004323) (xy 283.997003 -438.968765) (xy 283.964305 -438.928395) (xy 283.93739 -438.88396)
			(xy 283.916755 -438.836282) (xy 283.902783 -438.786246) (xy 283.895731 -438.734775) (xy 283.895292 -438.7088)
			(xy 283.895749 -438.681934) (xy 283.903276 -438.628732) (xy 283.918196 -438.577113) (xy 283.940213 -438.528099)
			(xy 283.968892 -438.48266) (xy 284.003663 -438.441696) (xy 284.04384 -438.406018) (xy 284.06598 -438.390792)
			(xy 284.077295 -438.382758) (xy 284.095473 -438.361805) (xy 284.107329 -438.336728) (xy 284.111986 -438.309383)
			(xy 284.109099 -438.281795) (xy 284.098882 -438.256006) (xy 284.082091 -438.233927) (xy 284.071314 -438.225184)
			(xy 284.048329 -438.207012) (xy 284.007658 -438.164837) (xy 283.973912 -438.116941) (xy 283.947882 -438.06445)
			(xy 283.930182 -438.008597) (xy 283.921226 -437.950695) (xy 283.920692 -437.9214) (xy 283.921178 -437.894149)
			(xy 283.928934 -437.840201) (xy 283.944289 -437.787906) (xy 283.966931 -437.738329) (xy 283.996397 -437.692479)
			(xy 284.032088 -437.651288) (xy 284.073279 -437.615597) (xy 284.119129 -437.586131) (xy 284.168706 -437.563489)
			(xy 284.221001 -437.548134) (xy 284.274949 -437.540378) (xy 284.329451 -437.540378) (xy 284.383399 -437.548134)
			(xy 284.435694 -437.563489) (xy 284.485271 -437.586131) (xy 284.531121 -437.615597) (xy 284.572312 -437.651288)
			(xy 284.608003 -437.692479) (xy 284.637469 -437.738329) (xy 284.660111 -437.787906) (xy 284.675466 -437.840201)
			(xy 284.683222 -437.894149) (xy 284.683708 -437.9214) (xy 284.683251 -437.948266) (xy 284.675724 -438.001468)
			(xy 284.660804 -438.053087) (xy 284.638787 -438.102101) (xy 284.610108 -438.14754) (xy 284.575337 -438.188504)
			(xy 284.53516 -438.224182) (xy 284.51302 -438.239408) (xy 284.501705 -438.247442) (xy 284.483527 -438.268395)
			(xy 284.471671 -438.293472) (xy 284.467014 -438.320817) (xy 284.469901 -438.348405) (xy 284.480118 -438.374194)
			(xy 284.496909 -438.396273) (xy 284.507686 -438.405016) (xy 284.530671 -438.423188) (xy 284.571342 -438.465363)
			(xy 284.605088 -438.513259) (xy 284.631118 -438.56575) (xy 284.648818 -438.621603) (xy 284.657774 -438.679505)
			(xy 284.658308 -438.7088) (xy 284.657883 -438.734776) (xy 284.65084 -438.786249) (xy 284.636869 -438.836287)
			(xy 284.616231 -438.883964) (xy 284.589307 -438.928396) (xy 284.556598 -438.968758) (xy 284.518709 -439.004303)
			(xy 284.49778 -439.019696) (xy 284.486767 -439.028105) (xy 284.469345 -439.049637) (xy 284.458352 -439.075059)
			(xy 284.454595 -439.1025) (xy 284.458352 -439.129941) (xy 284.469345 -439.155363) (xy 284.486767 -439.176895)
			(xy 284.49778 -439.185304) (xy 284.518722 -439.200677) (xy 284.556597 -439.236235) (xy 284.589295 -439.276605)
			(xy 284.61621 -439.32104) (xy 284.636845 -439.368718) (xy 284.650817 -439.418754) (xy 284.657869 -439.470225)
			(xy 284.658308 -439.4962) (xy 284.657822 -439.523451) (xy 284.650066 -439.577399) (xy 284.634711 -439.629694)
			(xy 284.612069 -439.679271) (xy 284.582603 -439.725121) (xy 284.546912 -439.766312) (xy 284.505721 -439.802003)
			(xy 284.459871 -439.831469) (xy 284.410294 -439.854111) (xy 284.357999 -439.869466) (xy 284.304051 -439.877222)
			(xy 284.249549 -439.877222) (xy 284.195601 -439.869466) (xy 284.143306 -439.854111) (xy 284.093729 -439.831469)
			(xy 284.047879 -439.802003) (xy 284.006688 -439.766312) (xy 283.970997 -439.725121) (xy 283.941531 -439.679271)
			(xy 283.918889 -439.629694) (xy 283.903534 -439.577399) (xy 283.895778 -439.523451) (xy 283.895292 -439.4962)
			(xy 281.25674 -439.4962) (xy 280.91257 -439.84037) (xy 280.894581 -439.857717) (xy 280.854163 -439.887108)
			(xy 280.809645 -439.909811) (xy 280.762122 -439.92527) (xy 280.712767 -439.933102) (xy 280.68778 -439.933588)
			(xy 278.680418 -439.933588) (xy 278.665444 -439.934116) (xy 278.636784 -439.942801) (xy 278.611877 -439.959429)
			(xy 278.592867 -439.982569) (xy 278.58139 -440.01023) (xy 278.578434 -440.040031) (xy 278.584252 -440.069408)
			(xy 278.598345 -440.095832) (xy 278.608536 -440.106816) (xy 278.98598 -440.48426) (xy 300.31182 -440.48426)
		)
		(stroke
			(width 0)
			(type solid)
		)
		(fill yes)
		(layer "In15.Cu")
		(net "GND")
	)
	(gr_poly
		(pts
			(xy 468.19566 -79.058008) (xy 468.19566 -59.738768) (xy 467.346538 -58.889646) (xy 467.336005 -58.879819)
			(xy 467.310769 -58.865953) (xy 467.282666 -58.859683) (xy 467.25393 -58.861506) (xy 467.226845 -58.871278)
			(xy 467.203564 -58.888221) (xy 467.185937 -58.910989) (xy 467.180168 -58.92419) (xy 467.167585 -58.954188)
			(xy 467.133742 -59.009739) (xy 467.112858 -59.03468) (xy 467.103622 -59.046009) (xy 467.091445 -59.072568)
			(xy 467.08727 -59.101486) (xy 467.091437 -59.130406) (xy 467.103607 -59.156968) (xy 467.112858 -59.168284)
			(xy 467.130503 -59.189214) (xy 467.160234 -59.235179) (xy 467.183082 -59.284926) (xy 467.198576 -59.33743)
			(xy 467.206398 -59.391611) (xy 467.206838 -59.418982) (xy 467.206353 -59.446235) (xy 467.198599 -59.500186)
			(xy 467.183246 -59.552485) (xy 467.160606 -59.602066) (xy 467.131141 -59.647921) (xy 467.09545 -59.689116)
			(xy 467.054259 -59.724812) (xy 467.008408 -59.754283) (xy 466.95883 -59.776929) (xy 466.906533 -59.792289)
			(xy 466.852583 -59.80005) (xy 466.82533 -59.80049) (xy 466.796412 -59.799958) (xy 466.739239 -59.791235)
			(xy 466.684037 -59.773984) (xy 466.63207 -59.7486) (xy 466.584529 -59.715664) (xy 466.542502 -59.675932)
			(xy 466.52434 -59.653424) (xy 466.514443 -59.641619) (xy 466.489119 -59.6241) (xy 466.459726 -59.614924)
			(xy 466.428934 -59.614924) (xy 466.399541 -59.6241) (xy 466.374217 -59.641619) (xy 466.36432 -59.653424)
			(xy 466.346129 -59.675906) (xy 466.30411 -59.71564) (xy 466.256575 -59.748575) (xy 466.204613 -59.773958)
			(xy 466.149414 -59.791206) (xy 466.092245 -59.799925) (xy 466.06333 -59.80049) (xy 466.03459 -59.799971)
			(xy 465.97776 -59.791352) (xy 465.922867 -59.774305) (xy 465.871152 -59.749216) (xy 465.823786 -59.716652)
			(xy 465.802472 -59.697366) (xy 465.790938 -59.687294) (xy 465.763392 -59.673952) (xy 465.73313 -59.669367)
			(xy 465.702868 -59.673952) (xy 465.675322 -59.687294) (xy 465.663788 -59.697366) (xy 465.642461 -59.716636)
			(xy 465.595098 -59.749201) (xy 465.543387 -59.774292) (xy 465.488496 -59.791342) (xy 465.431669 -59.799964)
			(xy 465.374191 -59.799964) (xy 465.317364 -59.791342) (xy 465.262473 -59.774292) (xy 465.210762 -59.749201)
			(xy 465.163399 -59.716636) (xy 465.142072 -59.697366) (xy 465.130538 -59.687294) (xy 465.102992 -59.673952)
			(xy 465.07273 -59.669367) (xy 465.042468 -59.673952) (xy 465.014922 -59.687294) (xy 465.003388 -59.697366)
			(xy 464.982061 -59.716636) (xy 464.934698 -59.749201) (xy 464.882987 -59.774292) (xy 464.828096 -59.791342)
			(xy 464.771269 -59.799964) (xy 464.713791 -59.799964) (xy 464.656964 -59.791342) (xy 464.602073 -59.774292)
			(xy 464.550362 -59.749201) (xy 464.502999 -59.716636) (xy 464.481672 -59.697366) (xy 464.470138 -59.687294)
			(xy 464.442592 -59.673952) (xy 464.41233 -59.669367) (xy 464.382068 -59.673952) (xy 464.354522 -59.687294)
			(xy 464.342988 -59.697366) (xy 464.321662 -59.716639) (xy 464.274301 -59.749209) (xy 464.222589 -59.774305)
			(xy 464.167698 -59.79136) (xy 464.11087 -59.799987) (xy 464.08213 -59.80049) (xy 464.053212 -59.799958)
			(xy 463.996039 -59.791235) (xy 463.940837 -59.773984) (xy 463.88887 -59.7486) (xy 463.841329 -59.715664)
			(xy 463.799302 -59.675932) (xy 463.78114 -59.653424) (xy 463.771243 -59.641619) (xy 463.745919 -59.6241)
			(xy 463.716526 -59.614924) (xy 463.685734 -59.614924) (xy 463.656341 -59.6241) (xy 463.631017 -59.641619)
			(xy 463.62112 -59.653424) (xy 463.602929 -59.675906) (xy 463.56091 -59.71564) (xy 463.513375 -59.748575)
			(xy 463.461413 -59.773958) (xy 463.406214 -59.791206) (xy 463.349045 -59.799925) (xy 463.32013 -59.80049)
			(xy 463.292876 -59.800029) (xy 463.238923 -59.792275) (xy 463.186623 -59.776921) (xy 463.13704 -59.75428)
			(xy 463.091184 -59.724813) (xy 463.049989 -59.689119) (xy 463.014294 -59.647925) (xy 462.984825 -59.602071)
			(xy 462.962183 -59.552489) (xy 462.946827 -59.500189) (xy 462.939072 -59.446236) (xy 462.938622 -59.418982)
			(xy 462.939095 -59.391613) (xy 462.946922 -59.337436) (xy 462.962411 -59.284934) (xy 462.985246 -59.235186)
			(xy 463.014957 -59.189212) (xy 463.032602 -59.168284) (xy 463.041836 -59.156957) (xy 463.054008 -59.1304)
			(xy 463.058177 -59.101486) (xy 463.054001 -59.072573) (xy 463.041821 -59.04602) (xy 463.032602 -59.03468)
			(xy 463.014961 -59.013748) (xy 462.985237 -58.967781) (xy 462.962397 -58.918034) (xy 462.946909 -58.865531)
			(xy 462.939093 -58.811352) (xy 462.938622 -58.783982) (xy 462.939045 -58.758001) (xy 462.946055 -58.706515)
			(xy 462.952592 -58.681366) (xy 462.955781 -58.668366) (xy 462.955989 -58.641607) (xy 462.949235 -58.615714)
			(xy 462.935983 -58.592466) (xy 462.917145 -58.573461) (xy 462.894014 -58.560006) (xy 462.868181 -58.553025)
			(xy 462.854802 -58.552588) (xy 444.24092 -58.552588) (xy 442.26988 -60.523628) (xy 442.26988 -68.56215)
			(xy 463.017866 -68.56215) (xy 463.017866 -68.477454) (xy 463.025917 -68.39314) (xy 463.041946 -68.309974)
			(xy 463.065807 -68.228707) (xy 463.097286 -68.150077) (xy 463.136097 -68.074796) (xy 463.181887 -68.003544)
			(xy 463.234243 -67.936968) (xy 463.292691 -67.87567) (xy 463.356701 -67.820205) (xy 463.425693 -67.771076)
			(xy 463.499043 -67.728727) (xy 463.576086 -67.693543) (xy 463.656125 -67.665841) (xy 463.738434 -67.645873)
			(xy 463.822269 -67.63382) (xy 463.90687 -67.62979) (xy 463.991471 -67.63382) (xy 464.075306 -67.645873)
			(xy 464.157615 -67.665841) (xy 464.237654 -67.693543) (xy 464.314697 -67.728727) (xy 464.388047 -67.771076)
			(xy 464.457039 -67.820205) (xy 464.521049 -67.87567) (xy 464.579497 -67.936968) (xy 464.631853 -68.003544)
			(xy 464.677643 -68.074796) (xy 464.716454 -68.150077) (xy 464.747933 -68.228707) (xy 464.771794 -68.309974)
			(xy 464.787823 -68.39314) (xy 464.795874 -68.477454) (xy 464.796378 -68.519802) (xy 465.542379 -68.519802)
			(xy 465.546415 -68.436355) (xy 465.558487 -68.353687) (xy 465.57848 -68.27257) (xy 465.606209 -68.193761)
			(xy 465.641415 -68.117996) (xy 465.683769 -68.045983) (xy 465.732875 -67.978394) (xy 465.788276 -67.91586)
			(xy 465.849453 -67.858965) (xy 465.915836 -67.808239) (xy 465.986804 -67.764158) (xy 466.061696 -67.727132)
			(xy 466.139812 -67.697506) (xy 466.220422 -67.675558) (xy 466.302774 -67.661493) (xy 466.3861 -67.655441)
			(xy 466.46962 -67.65746) (xy 466.552556 -67.66753) (xy 466.634132 -67.685558) (xy 466.713588 -67.711375)
			(xy 466.790181 -67.74474) (xy 466.863197 -67.785341) (xy 466.931953 -67.8328) (xy 466.995807 -67.886673)
			(xy 467.054164 -67.946458) (xy 467.106479 -68.011595) (xy 467.152262 -68.081478) (xy 467.191087 -68.155453)
			(xy 467.222592 -68.23283) (xy 467.246481 -68.312887) (xy 467.262532 -68.394875) (xy 467.270595 -68.47803)
			(xy 467.2711 -68.519802) (xy 467.270595 -68.561574) (xy 467.262532 -68.644729) (xy 467.246481 -68.726717)
			(xy 467.222592 -68.806774) (xy 467.191087 -68.884151) (xy 467.152262 -68.958126) (xy 467.106479 -69.028009)
			(xy 467.054164 -69.093146) (xy 466.995807 -69.152931) (xy 466.931953 -69.206804) (xy 466.863197 -69.254263)
			(xy 466.790181 -69.294864) (xy 466.713588 -69.328229) (xy 466.634132 -69.354046) (xy 466.552556 -69.372074)
			(xy 466.46962 -69.382144) (xy 466.3861 -69.384163) (xy 466.302774 -69.378111) (xy 466.220422 -69.364046)
			(xy 466.139812 -69.342098) (xy 466.061696 -69.312472) (xy 465.986804 -69.275446) (xy 465.915836 -69.231365)
			(xy 465.849453 -69.180639) (xy 465.788276 -69.123744) (xy 465.732875 -69.06121) (xy 465.683769 -68.993621)
			(xy 465.641415 -68.921608) (xy 465.606209 -68.845843) (xy 465.57848 -68.767034) (xy 465.558487 -68.685917)
			(xy 465.546415 -68.603249) (xy 465.542379 -68.519802) (xy 464.796378 -68.519802) (xy 464.795874 -68.56215)
			(xy 464.787823 -68.646464) (xy 464.771794 -68.72963) (xy 464.747933 -68.810897) (xy 464.716454 -68.889527)
			(xy 464.677643 -68.964808) (xy 464.631853 -69.03606) (xy 464.579497 -69.102636) (xy 464.521049 -69.163934)
			(xy 464.457039 -69.219399) (xy 464.388047 -69.268528) (xy 464.314697 -69.310877) (xy 464.237654 -69.346061)
			(xy 464.157615 -69.373763) (xy 464.075306 -69.393731) (xy 463.991471 -69.405784) (xy 463.90687 -69.409815)
			(xy 463.822269 -69.405784) (xy 463.738434 -69.393731) (xy 463.656125 -69.373763) (xy 463.576086 -69.346061)
			(xy 463.499043 -69.310877) (xy 463.425693 -69.268528) (xy 463.356701 -69.219399) (xy 463.292691 -69.163934)
			(xy 463.234243 -69.102636) (xy 463.181887 -69.03606) (xy 463.136097 -68.964808) (xy 463.097286 -68.889527)
			(xy 463.065807 -68.810897) (xy 463.041946 -68.72963) (xy 463.025917 -68.646464) (xy 463.017866 -68.56215)
			(xy 442.26988 -68.56215) (xy 442.26988 -71.039228) (xy 443.224918 -71.039228) (xy 443.228989 -70.983606)
			(xy 443.241115 -70.929169) (xy 443.261038 -70.877078) (xy 443.288334 -70.828443) (xy 443.32242 -70.7843)
			(xy 443.362569 -70.745591) (xy 443.407927 -70.71314) (xy 443.457527 -70.687639) (xy 443.510311 -70.669632)
			(xy 443.565154 -70.659502) (xy 443.620888 -70.657465) (xy 443.676325 -70.663565) (xy 443.730282 -70.677671)
			(xy 443.781611 -70.699483) (xy 443.829217 -70.728537) (xy 443.872085 -70.764212) (xy 443.909302 -70.805749)
			(xy 443.940075 -70.852262) (xy 443.963747 -70.902759) (xy 443.979815 -70.956166) (xy 443.987935 -71.011342)
			(xy 443.988444 -71.039228) (xy 443.987935 -71.067114) (xy 443.979815 -71.12229) (xy 443.963747 -71.175697)
			(xy 443.940075 -71.226194) (xy 443.909302 -71.272707) (xy 443.872085 -71.314244) (xy 443.829217 -71.349919)
			(xy 443.781611 -71.378973) (xy 443.730282 -71.400785) (xy 443.676325 -71.414891) (xy 443.620888 -71.420991)
			(xy 443.565154 -71.418954) (xy 443.510311 -71.408824) (xy 443.457527 -71.390817) (xy 443.407927 -71.365316)
			(xy 443.362569 -71.332865) (xy 443.32242 -71.294156) (xy 443.288334 -71.250013) (xy 443.261038 -71.201378)
			(xy 443.241115 -71.149287) (xy 443.228989 -71.09485) (xy 443.224918 -71.039228) (xy 442.26988 -71.039228)
			(xy 442.26988 -73.088052) (xy 452.643969 -73.088052) (xy 452.643969 -73.033548) (xy 452.651726 -72.979599)
			(xy 452.667082 -72.927303) (xy 452.689723 -72.877724) (xy 452.719191 -72.831873) (xy 452.754883 -72.790682)
			(xy 452.796074 -72.754989) (xy 452.841926 -72.725522) (xy 452.891505 -72.702881) (xy 452.943801 -72.687526)
			(xy 452.99775 -72.679769) (xy 453.025002 -72.679306) (xy 453.052711 -72.679821) (xy 453.107544 -72.687844)
			(xy 453.160639 -72.703721) (xy 453.210876 -72.727117) (xy 453.257196 -72.75754) (xy 453.27824 -72.775572)
			(xy 453.289642 -72.78504) (xy 453.316492 -72.797557) (xy 453.345804 -72.80185) (xy 453.375116 -72.797557)
			(xy 453.401966 -72.78504) (xy 453.413368 -72.775572) (xy 453.434411 -72.757537) (xy 453.480729 -72.727108)
			(xy 453.530966 -72.703707) (xy 453.584061 -72.687827) (xy 453.638896 -72.679803) (xy 453.666606 -72.679306)
			(xy 453.693858 -72.679764) (xy 453.747807 -72.687522) (xy 453.800103 -72.702878) (xy 453.849681 -72.72552)
			(xy 453.895533 -72.754988) (xy 453.936724 -72.790681) (xy 453.972416 -72.831872) (xy 454.001883 -72.877724)
			(xy 454.024524 -72.927303) (xy 454.03988 -72.979599) (xy 454.047636 -73.033548) (xy 454.047636 -73.088052)
			(xy 454.047636 -73.088053) (xy 454.467669 -73.088053) (xy 454.467669 -73.033547) (xy 454.475427 -72.979596)
			(xy 454.490783 -72.927299) (xy 454.513426 -72.877719) (xy 454.542895 -72.831866) (xy 454.57859 -72.790675)
			(xy 454.619784 -72.754982) (xy 454.665638 -72.725516) (xy 454.715219 -72.702876) (xy 454.767518 -72.687522)
			(xy 454.821469 -72.679768) (xy 454.848722 -72.679306) (xy 454.876431 -72.679809) (xy 454.931265 -72.687835)
			(xy 454.98436 -72.703715) (xy 455.034596 -72.727113) (xy 455.080916 -72.757538) (xy 455.10196 -72.775572)
			(xy 455.113362 -72.78504) (xy 455.140212 -72.797557) (xy 455.169524 -72.80185) (xy 455.198836 -72.797557)
			(xy 455.225686 -72.78504) (xy 455.237088 -72.775572) (xy 455.258124 -72.757528) (xy 455.304444 -72.7271)
			(xy 455.354682 -72.703701) (xy 455.407779 -72.687823) (xy 455.462616 -72.679801) (xy 455.490326 -72.679306)
			(xy 455.517577 -72.679766) (xy 455.571524 -72.687525) (xy 455.623817 -72.702883) (xy 455.673393 -72.725527)
			(xy 455.719242 -72.754995) (xy 455.760431 -72.790688) (xy 455.796121 -72.831879) (xy 455.825586 -72.87773)
			(xy 455.848226 -72.927307) (xy 455.86358 -72.979602) (xy 455.871336 -73.033549) (xy 455.871336 -73.088051)
			(xy 455.86358 -73.141998) (xy 455.848226 -73.194293) (xy 455.825586 -73.24387) (xy 455.796121 -73.289721)
			(xy 455.760431 -73.330912) (xy 455.719242 -73.366605) (xy 455.673393 -73.396073) (xy 455.623817 -73.418717)
			(xy 455.571524 -73.434075) (xy 455.517577 -73.441834) (xy 455.490326 -73.442322) (xy 455.462616 -73.441843)
			(xy 455.407781 -73.43381) (xy 455.354686 -73.417924) (xy 455.30445 -73.39452) (xy 455.258131 -73.364091)
			(xy 455.237088 -73.346056) (xy 455.225686 -73.336588) (xy 455.198836 -73.324071) (xy 455.169524 -73.319778)
			(xy 455.140212 -73.324071) (xy 455.113362 -73.336588) (xy 455.10196 -73.346056) (xy 455.08091 -73.364082)
			(xy 455.034593 -73.394511) (xy 454.984358 -73.417914) (xy 454.931265 -73.433796) (xy 454.876431 -73.441823)
			(xy 454.848722 -73.442322) (xy 454.821469 -73.441832) (xy 454.767518 -73.434078) (xy 454.715219 -73.418724)
			(xy 454.665638 -73.396084) (xy 454.619784 -73.366618) (xy 454.57859 -73.330925) (xy 454.542895 -73.289734)
			(xy 454.513426 -73.243881) (xy 454.490783 -73.194301) (xy 454.475427 -73.142004) (xy 454.467669 -73.088053)
			(xy 454.047636 -73.088053) (xy 454.03988 -73.142001) (xy 454.024524 -73.194297) (xy 454.001883 -73.243876)
			(xy 453.972416 -73.289728) (xy 453.936724 -73.330919) (xy 453.895533 -73.366612) (xy 453.849681 -73.39608)
			(xy 453.800103 -73.418722) (xy 453.747807 -73.434078) (xy 453.693858 -73.441836) (xy 453.666606 -73.442322)
			(xy 453.638898 -73.441795) (xy 453.584065 -73.433774) (xy 453.530971 -73.4179) (xy 453.480734 -73.394506)
			(xy 453.434413 -73.364087) (xy 453.413368 -73.346056) (xy 453.401966 -73.336588) (xy 453.375116 -73.324071)
			(xy 453.345804 -73.319778) (xy 453.316492 -73.324071) (xy 453.289642 -73.336588) (xy 453.27824 -73.346056)
			(xy 453.257197 -73.364091) (xy 453.210879 -73.394519) (xy 453.160642 -73.41792) (xy 453.107547 -73.4338)
			(xy 453.052712 -73.441825) (xy 453.025002 -73.442322) (xy 452.99775 -73.441831) (xy 452.943801 -73.434074)
			(xy 452.891505 -73.418719) (xy 452.841926 -73.396078) (xy 452.796074 -73.366611) (xy 452.754883 -73.330918)
			(xy 452.719191 -73.289727) (xy 452.689723 -73.243876) (xy 452.667082 -73.194297) (xy 452.651726 -73.142001)
			(xy 452.643969 -73.088052) (xy 442.26988 -73.088052) (xy 442.26988 -74.640948) (xy 443.978282 -74.640948)
			(xy 443.982353 -74.585326) (xy 443.994479 -74.530889) (xy 444.014402 -74.478798) (xy 444.041698 -74.430163)
			(xy 444.075784 -74.38602) (xy 444.115933 -74.347311) (xy 444.161291 -74.31486) (xy 444.210891 -74.289359)
			(xy 444.263675 -74.271352) (xy 444.318518 -74.261222) (xy 444.374252 -74.259185) (xy 444.429689 -74.265285)
			(xy 444.483646 -74.279391) (xy 444.534975 -74.301203) (xy 444.582581 -74.330257) (xy 444.625449 -74.365932)
			(xy 444.662666 -74.407469) (xy 444.693439 -74.453982) (xy 444.717111 -74.504479) (xy 444.733179 -74.557886)
			(xy 444.741299 -74.613062) (xy 444.741808 -74.640948) (xy 444.741299 -74.668834) (xy 444.733179 -74.72401)
			(xy 444.717111 -74.777417) (xy 444.693439 -74.827914) (xy 444.662666 -74.874427) (xy 444.625449 -74.915964)
			(xy 444.582581 -74.951639) (xy 444.534975 -74.980693) (xy 444.483646 -75.002505) (xy 444.429689 -75.016611)
			(xy 444.374252 -75.022711) (xy 444.318518 -75.020674) (xy 444.263675 -75.010544) (xy 444.210891 -74.992537)
			(xy 444.161291 -74.967036) (xy 444.115933 -74.934585) (xy 444.075784 -74.895876) (xy 444.041698 -74.851733)
			(xy 444.014402 -74.803098) (xy 443.994479 -74.751007) (xy 443.982353 -74.69657) (xy 443.978282 -74.640948)
			(xy 442.26988 -74.640948) (xy 442.26988 -75.054206) (xy 451.065898 -75.054206) (xy 451.069969 -74.998584)
			(xy 451.082095 -74.944147) (xy 451.102018 -74.892056) (xy 451.129314 -74.843421) (xy 451.1634 -74.799278)
			(xy 451.203549 -74.760569) (xy 451.248907 -74.728118) (xy 451.298507 -74.702617) (xy 451.351291 -74.68461)
			(xy 451.406134 -74.67448) (xy 451.461868 -74.672443) (xy 451.517305 -74.678543) (xy 451.571262 -74.692649)
			(xy 451.622591 -74.714461) (xy 451.670197 -74.743515) (xy 451.713065 -74.77919) (xy 451.745377 -74.815253)
			(xy 454.048569 -74.815253) (xy 454.048569 -74.760747) (xy 454.056327 -74.706796) (xy 454.071683 -74.654499)
			(xy 454.094326 -74.604919) (xy 454.123795 -74.559066) (xy 454.15949 -74.517875) (xy 454.200684 -74.482182)
			(xy 454.246538 -74.452716) (xy 454.296119 -74.430076) (xy 454.348418 -74.414722) (xy 454.402369 -74.406968)
			(xy 454.429622 -74.406506) (xy 454.457331 -74.407009) (xy 454.512165 -74.415035) (xy 454.56526 -74.430915)
			(xy 454.615496 -74.454313) (xy 454.661816 -74.484738) (xy 454.68286 -74.502772) (xy 454.694262 -74.51224)
			(xy 454.721112 -74.524757) (xy 454.750424 -74.52905) (xy 454.779736 -74.524757) (xy 454.806586 -74.51224)
			(xy 454.817988 -74.502772) (xy 454.839024 -74.484728) (xy 454.885344 -74.4543) (xy 454.935582 -74.430901)
			(xy 454.988679 -74.415023) (xy 455.043516 -74.407001) (xy 455.071226 -74.406506) (xy 455.098477 -74.406966)
			(xy 455.152424 -74.414725) (xy 455.204717 -74.430083) (xy 455.254293 -74.452727) (xy 455.300142 -74.482195)
			(xy 455.341331 -74.517888) (xy 455.377021 -74.559079) (xy 455.406486 -74.60493) (xy 455.429126 -74.654507)
			(xy 455.44448 -74.706802) (xy 455.452236 -74.760749) (xy 455.452236 -74.815251) (xy 455.44448 -74.869198)
			(xy 455.429126 -74.921493) (xy 455.406486 -74.97107) (xy 455.377021 -75.016921) (xy 455.341331 -75.058112)
			(xy 455.300142 -75.093805) (xy 455.254293 -75.123273) (xy 455.204717 -75.145917) (xy 455.152424 -75.161275)
			(xy 455.098477 -75.169034) (xy 455.071226 -75.169522) (xy 455.043516 -75.169043) (xy 454.988681 -75.16101)
			(xy 454.935586 -75.145124) (xy 454.88535 -75.12172) (xy 454.839031 -75.091291) (xy 454.817988 -75.073256)
			(xy 454.806586 -75.063788) (xy 454.779736 -75.051271) (xy 454.750424 -75.046978) (xy 454.721112 -75.051271)
			(xy 454.694262 -75.063788) (xy 454.68286 -75.073256) (xy 454.66181 -75.091282) (xy 454.615493 -75.121711)
			(xy 454.565258 -75.145114) (xy 454.512165 -75.160996) (xy 454.457331 -75.169023) (xy 454.429622 -75.169522)
			(xy 454.402369 -75.169032) (xy 454.348418 -75.161278) (xy 454.296119 -75.145924) (xy 454.246538 -75.123284)
			(xy 454.200684 -75.093818) (xy 454.15949 -75.058125) (xy 454.123795 -75.016934) (xy 454.094326 -74.971081)
			(xy 454.071683 -74.921501) (xy 454.056327 -74.869204) (xy 454.048569 -74.815253) (xy 451.745377 -74.815253)
			(xy 451.750282 -74.820727) (xy 451.781055 -74.86724) (xy 451.804727 -74.917737) (xy 451.820795 -74.971144)
			(xy 451.828915 -75.02632) (xy 451.829424 -75.054206) (xy 451.828915 -75.082092) (xy 451.820795 -75.137268)
			(xy 451.804727 -75.190675) (xy 451.781055 -75.241172) (xy 451.750282 -75.287685) (xy 451.713065 -75.329222)
			(xy 451.670197 -75.364897) (xy 451.622591 -75.393951) (xy 451.571262 -75.415763) (xy 451.517305 -75.429869)
			(xy 451.461868 -75.435969) (xy 451.406134 -75.433932) (xy 451.351291 -75.423802) (xy 451.298507 -75.405795)
			(xy 451.248907 -75.380294) (xy 451.203549 -75.347843) (xy 451.1634 -75.309134) (xy 451.129314 -75.264991)
			(xy 451.102018 -75.216356) (xy 451.082095 -75.164265) (xy 451.069969 -75.109828) (xy 451.065898 -75.054206)
			(xy 442.26988 -75.054206) (xy 442.26988 -76.002572) (xy 463.017866 -76.002572) (xy 463.017866 -75.917876)
			(xy 463.025917 -75.833562) (xy 463.041946 -75.750396) (xy 463.065807 -75.669129) (xy 463.097286 -75.590499)
			(xy 463.136097 -75.515218) (xy 463.181887 -75.443966) (xy 463.234243 -75.37739) (xy 463.292691 -75.316092)
			(xy 463.356701 -75.260627) (xy 463.425693 -75.211498) (xy 463.499043 -75.169149) (xy 463.576086 -75.133965)
			(xy 463.656125 -75.106263) (xy 463.738434 -75.086295) (xy 463.822269 -75.074242) (xy 463.90687 -75.070212)
			(xy 463.991471 -75.074242) (xy 464.075306 -75.086295) (xy 464.157615 -75.106263) (xy 464.237654 -75.133965)
			(xy 464.314697 -75.169149) (xy 464.388047 -75.211498) (xy 464.457039 -75.260627) (xy 464.521049 -75.316092)
			(xy 464.579497 -75.37739) (xy 464.631853 -75.443966) (xy 464.677643 -75.515218) (xy 464.716454 -75.590499)
			(xy 464.747933 -75.669129) (xy 464.771794 -75.750396) (xy 464.787823 -75.833562) (xy 464.795874 -75.917876)
			(xy 464.796378 -75.960224) (xy 465.542379 -75.960224) (xy 465.546415 -75.876777) (xy 465.558487 -75.794109)
			(xy 465.57848 -75.712992) (xy 465.606209 -75.634183) (xy 465.641415 -75.558418) (xy 465.683769 -75.486405)
			(xy 465.732875 -75.418816) (xy 465.788276 -75.356282) (xy 465.849453 -75.299387) (xy 465.915836 -75.248661)
			(xy 465.986804 -75.20458) (xy 466.061696 -75.167554) (xy 466.139812 -75.137928) (xy 466.220422 -75.11598)
			(xy 466.302774 -75.101915) (xy 466.3861 -75.095863) (xy 466.46962 -75.097882) (xy 466.552556 -75.107952)
			(xy 466.634132 -75.12598) (xy 466.713588 -75.151797) (xy 466.790181 -75.185162) (xy 466.863197 -75.225763)
			(xy 466.931953 -75.273222) (xy 466.995807 -75.327095) (xy 467.054164 -75.38688) (xy 467.106479 -75.452017)
			(xy 467.152262 -75.5219) (xy 467.191087 -75.595875) (xy 467.222592 -75.673252) (xy 467.246481 -75.753309)
			(xy 467.262532 -75.835297) (xy 467.270595 -75.918452) (xy 467.2711 -75.960224) (xy 467.270595 -76.001996)
			(xy 467.262532 -76.085151) (xy 467.246481 -76.167139) (xy 467.222592 -76.247196) (xy 467.191087 -76.324573)
			(xy 467.152262 -76.398548) (xy 467.106479 -76.468431) (xy 467.054164 -76.533568) (xy 466.995807 -76.593353)
			(xy 466.931953 -76.647226) (xy 466.863197 -76.694685) (xy 466.790181 -76.735286) (xy 466.713588 -76.768651)
			(xy 466.634132 -76.794468) (xy 466.552556 -76.812496) (xy 466.46962 -76.822566) (xy 466.3861 -76.824585)
			(xy 466.302774 -76.818533) (xy 466.220422 -76.804468) (xy 466.139812 -76.78252) (xy 466.061696 -76.752894)
			(xy 465.986804 -76.715868) (xy 465.915836 -76.671787) (xy 465.849453 -76.621061) (xy 465.788276 -76.564166)
			(xy 465.732875 -76.501632) (xy 465.683769 -76.434043) (xy 465.641415 -76.36203) (xy 465.606209 -76.286265)
			(xy 465.57848 -76.207456) (xy 465.558487 -76.126339) (xy 465.546415 -76.043671) (xy 465.542379 -75.960224)
			(xy 464.796378 -75.960224) (xy 464.795874 -76.002572) (xy 464.787823 -76.086886) (xy 464.771794 -76.170052)
			(xy 464.747933 -76.251319) (xy 464.716454 -76.329949) (xy 464.677643 -76.40523) (xy 464.631853 -76.476482)
			(xy 464.579497 -76.543058) (xy 464.521049 -76.604356) (xy 464.457039 -76.659821) (xy 464.388047 -76.70895)
			(xy 464.314697 -76.751299) (xy 464.237654 -76.786483) (xy 464.157615 -76.814185) (xy 464.075306 -76.834153)
			(xy 463.991471 -76.846206) (xy 463.90687 -76.850237) (xy 463.822269 -76.846206) (xy 463.738434 -76.834153)
			(xy 463.656125 -76.814185) (xy 463.576086 -76.786483) (xy 463.499043 -76.751299) (xy 463.425693 -76.70895)
			(xy 463.356701 -76.659821) (xy 463.292691 -76.604356) (xy 463.234243 -76.543058) (xy 463.181887 -76.476482)
			(xy 463.136097 -76.40523) (xy 463.097286 -76.329949) (xy 463.065807 -76.251319) (xy 463.041946 -76.170052)
			(xy 463.025917 -76.086886) (xy 463.017866 -76.002572) (xy 442.26988 -76.002572) (xy 442.26988 -76.63053)
			(xy 445.693798 -76.63053) (xy 445.697869 -76.574908) (xy 445.709995 -76.520471) (xy 445.729918 -76.46838)
			(xy 445.757214 -76.419745) (xy 445.7913 -76.375602) (xy 445.831449 -76.336893) (xy 445.876807 -76.304442)
			(xy 445.926407 -76.278941) (xy 445.979191 -76.260934) (xy 446.034034 -76.250804) (xy 446.089768 -76.248767)
			(xy 446.145205 -76.254867) (xy 446.199162 -76.268973) (xy 446.250491 -76.290785) (xy 446.298097 -76.319839)
			(xy 446.340965 -76.355514) (xy 446.378182 -76.397051) (xy 446.408955 -76.443564) (xy 446.432627 -76.494061)
			(xy 446.448695 -76.547468) (xy 446.456815 -76.602644) (xy 446.457106 -76.618592) (xy 446.684398 -76.618592)
			(xy 446.688469 -76.56297) (xy 446.700595 -76.508533) (xy 446.720518 -76.456442) (xy 446.747814 -76.407807)
			(xy 446.7819 -76.363664) (xy 446.822049 -76.324955) (xy 446.867407 -76.292504) (xy 446.917007 -76.267003)
			(xy 446.969791 -76.248996) (xy 447.024634 -76.238866) (xy 447.080368 -76.236829) (xy 447.135805 -76.242929)
			(xy 447.189762 -76.257035) (xy 447.241091 -76.278847) (xy 447.288697 -76.307901) (xy 447.331565 -76.343576)
			(xy 447.368782 -76.385113) (xy 447.399555 -76.431626) (xy 447.423227 -76.482123) (xy 447.439295 -76.53553)
			(xy 447.447415 -76.590706) (xy 447.447924 -76.618592) (xy 447.447548 -76.639166) (xy 452.504554 -76.639166)
			(xy 452.508625 -76.583544) (xy 452.520751 -76.529107) (xy 452.540674 -76.477016) (xy 452.56797 -76.428381)
			(xy 452.602056 -76.384238) (xy 452.642205 -76.345529) (xy 452.687563 -76.313078) (xy 452.737163 -76.287577)
			(xy 452.789947 -76.26957) (xy 452.84479 -76.25944) (xy 452.900524 -76.257403) (xy 452.955961 -76.263503)
			(xy 453.009918 -76.277609) (xy 453.061247 -76.299421) (xy 453.108853 -76.328475) (xy 453.151721 -76.36415)
			(xy 453.188938 -76.405687) (xy 453.219711 -76.4522) (xy 453.243383 -76.502697) (xy 453.259451 -76.556104)
			(xy 453.267571 -76.61128) (xy 453.26808 -76.639166) (xy 453.267571 -76.667052) (xy 453.259451 -76.722228)
			(xy 453.243383 -76.775635) (xy 453.219711 -76.826132) (xy 453.188938 -76.872645) (xy 453.151721 -76.914182)
			(xy 453.108853 -76.949857) (xy 453.061247 -76.978911) (xy 453.009918 -77.000723) (xy 452.955961 -77.014829)
			(xy 452.900524 -77.020929) (xy 452.84479 -77.018892) (xy 452.789947 -77.008762) (xy 452.737163 -76.990755)
			(xy 452.687563 -76.965254) (xy 452.642205 -76.932803) (xy 452.602056 -76.894094) (xy 452.56797 -76.849951)
			(xy 452.540674 -76.801316) (xy 452.520751 -76.749225) (xy 452.508625 -76.694788) (xy 452.504554 -76.639166)
			(xy 447.447548 -76.639166) (xy 447.447415 -76.646478) (xy 447.439295 -76.701654) (xy 447.423227 -76.755061)
			(xy 447.399555 -76.805558) (xy 447.368782 -76.852071) (xy 447.331565 -76.893608) (xy 447.288697 -76.929283)
			(xy 447.241091 -76.958337) (xy 447.189762 -76.980149) (xy 447.135805 -76.994255) (xy 447.080368 -77.000355)
			(xy 447.024634 -76.998318) (xy 446.969791 -76.988188) (xy 446.917007 -76.970181) (xy 446.867407 -76.94468)
			(xy 446.822049 -76.912229) (xy 446.7819 -76.87352) (xy 446.747814 -76.829377) (xy 446.720518 -76.780742)
			(xy 446.700595 -76.728651) (xy 446.688469 -76.674214) (xy 446.684398 -76.618592) (xy 446.457106 -76.618592)
			(xy 446.457324 -76.63053) (xy 446.456815 -76.658416) (xy 446.448695 -76.713592) (xy 446.432627 -76.766999)
			(xy 446.408955 -76.817496) (xy 446.378182 -76.864009) (xy 446.340965 -76.905546) (xy 446.298097 -76.941221)
			(xy 446.250491 -76.970275) (xy 446.199162 -76.992087) (xy 446.145205 -77.006193) (xy 446.089768 -77.012293)
			(xy 446.034034 -77.010256) (xy 445.979191 -77.000126) (xy 445.926407 -76.982119) (xy 445.876807 -76.956618)
			(xy 445.831449 -76.924167) (xy 445.7913 -76.885458) (xy 445.757214 -76.841315) (xy 445.729918 -76.79268)
			(xy 445.709995 -76.740589) (xy 445.697869 -76.686152) (xy 445.693798 -76.63053) (xy 442.26988 -76.63053)
			(xy 442.26988 -77.866748) (xy 444.625982 -77.866748) (xy 444.630053 -77.811126) (xy 444.642179 -77.756689)
			(xy 444.662102 -77.704598) (xy 444.689398 -77.655963) (xy 444.723484 -77.61182) (xy 444.763633 -77.573111)
			(xy 444.808991 -77.54066) (xy 444.858591 -77.515159) (xy 444.911375 -77.497152) (xy 444.966218 -77.487022)
			(xy 445.021952 -77.484985) (xy 445.077389 -77.491085) (xy 445.131346 -77.505191) (xy 445.182675 -77.527003)
			(xy 445.230281 -77.556057) (xy 445.273149 -77.591732) (xy 445.310366 -77.633269) (xy 445.341139 -77.679782)
			(xy 445.364811 -77.730279) (xy 445.380879 -77.783686) (xy 445.388999 -77.838862) (xy 445.389508 -77.866748)
			(xy 445.388999 -77.894634) (xy 445.380879 -77.94981) (xy 445.364811 -78.003217) (xy 445.341139 -78.053714)
			(xy 445.310366 -78.100227) (xy 445.273149 -78.141764) (xy 445.230281 -78.177439) (xy 445.182675 -78.206493)
			(xy 445.131346 -78.228305) (xy 445.077389 -78.242411) (xy 445.021952 -78.248511) (xy 444.966218 -78.246474)
			(xy 444.911375 -78.236344) (xy 444.858591 -78.218337) (xy 444.808991 -78.192836) (xy 444.763633 -78.160385)
			(xy 444.723484 -78.121676) (xy 444.689398 -78.077533) (xy 444.662102 -78.028898) (xy 444.642179 -77.976807)
			(xy 444.630053 -77.92237) (xy 444.625982 -77.866748) (xy 442.26988 -77.866748) (xy 442.26988 -78.628748)
			(xy 442.561218 -78.920086) (xy 447.149726 -78.920086) (xy 447.153797 -78.864464) (xy 447.165923 -78.810027)
			(xy 447.185846 -78.757936) (xy 447.213142 -78.709301) (xy 447.247228 -78.665158) (xy 447.287377 -78.626449)
			(xy 447.332735 -78.593998) (xy 447.382335 -78.568497) (xy 447.435119 -78.55049) (xy 447.489962 -78.54036)
			(xy 447.545696 -78.538323) (xy 447.601133 -78.544423) (xy 447.65509 -78.558529) (xy 447.706419 -78.580341)
			(xy 447.754025 -78.609395) (xy 447.796893 -78.64507) (xy 447.83411 -78.686607) (xy 447.864883 -78.73312)
			(xy 447.888555 -78.783617) (xy 447.904623 -78.837024) (xy 447.908212 -78.861412) (xy 449.002402 -78.861412)
			(xy 449.006473 -78.80579) (xy 449.018599 -78.751353) (xy 449.038522 -78.699262) (xy 449.065818 -78.650627)
			(xy 449.099904 -78.606484) (xy 449.140053 -78.567775) (xy 449.185411 -78.535324) (xy 449.235011 -78.509823)
			(xy 449.287795 -78.491816) (xy 449.342638 -78.481686) (xy 449.398372 -78.479649) (xy 449.453809 -78.485749)
			(xy 449.507766 -78.499855) (xy 449.559095 -78.521667) (xy 449.606701 -78.550721) (xy 449.649569 -78.586396)
			(xy 449.686786 -78.627933) (xy 449.717559 -78.674446) (xy 449.741231 -78.724943) (xy 449.757299 -78.77835)
			(xy 449.765419 -78.833526) (xy 449.765928 -78.861412) (xy 449.765419 -78.889298) (xy 449.757299 -78.944474)
			(xy 449.741231 -78.997881) (xy 449.717559 -79.048378) (xy 449.686786 -79.094891) (xy 449.649569 -79.136428)
			(xy 449.606701 -79.172103) (xy 449.559095 -79.201157) (xy 449.507766 -79.222969) (xy 449.453809 -79.237075)
			(xy 449.398372 -79.243175) (xy 449.342638 -79.241138) (xy 449.287795 -79.231008) (xy 449.235011 -79.213001)
			(xy 449.185411 -79.1875) (xy 449.140053 -79.155049) (xy 449.099904 -79.11634) (xy 449.065818 -79.072197)
			(xy 449.038522 -79.023562) (xy 449.018599 -78.971471) (xy 449.006473 -78.917034) (xy 449.002402 -78.861412)
			(xy 447.908212 -78.861412) (xy 447.912743 -78.8922) (xy 447.913252 -78.920086) (xy 447.912743 -78.947972)
			(xy 447.904623 -79.003148) (xy 447.888555 -79.056555) (xy 447.864883 -79.107052) (xy 447.83411 -79.153565)
			(xy 447.796893 -79.195102) (xy 447.754025 -79.230777) (xy 447.706419 -79.259831) (xy 447.65509 -79.281643)
			(xy 447.601133 -79.295749) (xy 447.545696 -79.301849) (xy 447.489962 -79.299812) (xy 447.435119 -79.289682)
			(xy 447.382335 -79.271675) (xy 447.332735 -79.246174) (xy 447.287377 -79.213723) (xy 447.247228 -79.175014)
			(xy 447.213142 -79.130871) (xy 447.185846 -79.082236) (xy 447.165923 -79.030145) (xy 447.153797 -78.975708)
			(xy 447.149726 -78.920086) (xy 442.561218 -78.920086) (xy 444.8683 -81.227168) (xy 466.0265 -81.227168)
		)
		(stroke
			(width 0)
			(type solid)
		)
		(fill yes)
		(layer "In15.Cu")
		(net "GND")
	)
	(gr_poly
		(pts
			(xy 465.316316 -395.996414) (xy 466.925914 -394.386816) (xy 466.925914 -378.984002) (xy 465.741258 -377.799346)
			(xy 459.504288 -377.799346) (xy 459.489314 -377.799921) (xy 459.460675 -377.808689) (xy 459.435806 -377.825382)
			(xy 459.416843 -377.848566) (xy 459.405413 -377.87625) (xy 459.402497 -377.906059) (xy 459.408345 -377.935434)
			(xy 459.422457 -377.961853) (xy 459.43266 -377.972828) (xy 460.754984 -379.295152) (xy 460.768954 -379.298708)
			(xy 460.796364 -379.305802) (xy 460.84887 -379.326985) (xy 460.897664 -379.355701) (xy 460.941674 -379.391319)
			(xy 460.979931 -379.433056) (xy 461.011594 -379.479992) (xy 461.035966 -379.531095) (xy 461.05251 -379.585241)
			(xy 461.060863 -379.641239) (xy 461.061308 -379.669548) (xy 461.060819 -379.696797) (xy 461.053057 -379.75074)
			(xy 461.037698 -379.803029) (xy 461.015054 -379.8526) (xy 460.985586 -379.898444) (xy 460.949895 -379.939629)
			(xy 460.908706 -379.975315) (xy 460.862858 -380.004777) (xy 460.813284 -380.027414) (xy 460.760993 -380.042767)
			(xy 460.707049 -380.050522) (xy 460.6798 -380.051056) (xy 460.651499 -380.050534) (xy 460.595522 -380.042155)
			(xy 460.541396 -380.025597) (xy 460.490312 -380.001223) (xy 460.44339 -379.969567) (xy 460.401661 -379.931326)
			(xy 460.366041 -379.887338) (xy 460.337312 -379.83857) (xy 460.316105 -379.786091) (xy 460.30896 -379.758702)
			(xy 460.305404 -379.744732) (xy 458.360018 -377.799346) (xy 435.53888 -377.799346) (xy 435.53888 -378.526548)
			(xy 438.052462 -378.526548) (xy 438.056533 -378.470926) (xy 438.068659 -378.416489) (xy 438.088582 -378.364398)
			(xy 438.115878 -378.315763) (xy 438.149964 -378.27162) (xy 438.190113 -378.232911) (xy 438.235471 -378.20046)
			(xy 438.285071 -378.174959) (xy 438.337855 -378.156952) (xy 438.392698 -378.146822) (xy 438.448432 -378.144785)
			(xy 438.503869 -378.150885) (xy 438.557826 -378.164991) (xy 438.609155 -378.186803) (xy 438.656761 -378.215857)
			(xy 438.699629 -378.251532) (xy 438.736846 -378.293069) (xy 438.767619 -378.339582) (xy 438.791291 -378.390079)
			(xy 438.807359 -378.443486) (xy 438.815479 -378.498662) (xy 438.815988 -378.526548) (xy 438.815479 -378.554434)
			(xy 438.807359 -378.60961) (xy 438.791291 -378.663017) (xy 438.767619 -378.713514) (xy 438.736846 -378.760027)
			(xy 438.699629 -378.801564) (xy 438.656761 -378.837239) (xy 438.609155 -378.866293) (xy 438.557826 -378.888105)
			(xy 438.503869 -378.902211) (xy 438.448432 -378.908311) (xy 438.392698 -378.906274) (xy 438.337855 -378.896144)
			(xy 438.285071 -378.878137) (xy 438.235471 -378.852636) (xy 438.190113 -378.820185) (xy 438.149964 -378.781476)
			(xy 438.115878 -378.737333) (xy 438.088582 -378.688698) (xy 438.068659 -378.636607) (xy 438.056533 -378.58217)
			(xy 438.052462 -378.526548) (xy 435.53888 -378.526548) (xy 435.53888 -380.05258) (xy 438.059828 -380.05258)
			(xy 438.063899 -379.996958) (xy 438.076025 -379.942521) (xy 438.095948 -379.89043) (xy 438.123244 -379.841795)
			(xy 438.15733 -379.797652) (xy 438.197479 -379.758943) (xy 438.242837 -379.726492) (xy 438.292437 -379.700991)
			(xy 438.345221 -379.682984) (xy 438.400064 -379.672854) (xy 438.455798 -379.670817) (xy 438.511235 -379.676917)
			(xy 438.565192 -379.691023) (xy 438.616521 -379.712835) (xy 438.664127 -379.741889) (xy 438.706995 -379.777564)
			(xy 438.744212 -379.819101) (xy 438.774985 -379.865614) (xy 438.798657 -379.916111) (xy 438.814725 -379.969518)
			(xy 438.822845 -380.024694) (xy 438.823354 -380.05258) (xy 438.822845 -380.080466) (xy 438.814725 -380.135642)
			(xy 438.798657 -380.189049) (xy 438.774985 -380.239546) (xy 438.744212 -380.286059) (xy 438.706995 -380.327596)
			(xy 438.664127 -380.363271) (xy 438.616521 -380.392325) (xy 438.565192 -380.414137) (xy 438.511235 -380.428243)
			(xy 438.455798 -380.434343) (xy 438.400064 -380.432306) (xy 438.345221 -380.422176) (xy 438.292437 -380.404169)
			(xy 438.242837 -380.378668) (xy 438.197479 -380.346217) (xy 438.15733 -380.307508) (xy 438.123244 -380.263365)
			(xy 438.095948 -380.21473) (xy 438.076025 -380.162639) (xy 438.063899 -380.108202) (xy 438.059828 -380.05258)
			(xy 435.53888 -380.05258) (xy 435.53888 -381.404114) (xy 461.463388 -381.404114) (xy 461.467459 -381.348492)
			(xy 461.479585 -381.294055) (xy 461.499508 -381.241964) (xy 461.526804 -381.193329) (xy 461.56089 -381.149186)
			(xy 461.601039 -381.110477) (xy 461.646397 -381.078026) (xy 461.695997 -381.052525) (xy 461.748781 -381.034518)
			(xy 461.803624 -381.024388) (xy 461.859358 -381.022351) (xy 461.914795 -381.028451) (xy 461.968752 -381.042557)
			(xy 462.020081 -381.064369) (xy 462.067687 -381.093423) (xy 462.110555 -381.129098) (xy 462.147772 -381.170635)
			(xy 462.178545 -381.217148) (xy 462.202217 -381.267645) (xy 462.218285 -381.321052) (xy 462.226405 -381.376228)
			(xy 462.226914 -381.404114) (xy 462.226405 -381.432) (xy 462.218285 -381.487176) (xy 462.202217 -381.540583)
			(xy 462.193558 -381.559054) (xy 463.166712 -381.559054) (xy 463.170783 -381.503432) (xy 463.182909 -381.448995)
			(xy 463.202832 -381.396904) (xy 463.230128 -381.348269) (xy 463.264214 -381.304126) (xy 463.304363 -381.265417)
			(xy 463.349721 -381.232966) (xy 463.399321 -381.207465) (xy 463.452105 -381.189458) (xy 463.506948 -381.179328)
			(xy 463.562682 -381.177291) (xy 463.618119 -381.183391) (xy 463.672076 -381.197497) (xy 463.689681 -381.204978)
			(xy 464.315048 -381.204978) (xy 464.315541 -381.17613) (xy 464.324227 -381.119091) (xy 464.341412 -381.064014)
			(xy 464.366703 -381.012157) (xy 464.399522 -380.964704) (xy 464.418934 -380.943358) (xy 464.429105 -380.931769)
			(xy 464.442652 -380.904088) (xy 464.447314 -380.873626) (xy 464.442667 -380.843161) (xy 464.429135 -380.815473)
			(xy 464.418934 -380.803912) (xy 464.399513 -380.782577) (xy 464.366716 -380.735113) (xy 464.341441 -380.683251)
			(xy 464.324264 -380.628174) (xy 464.315577 -380.571139) (xy 464.315048 -380.542292) (xy 464.31557 -380.515043)
			(xy 464.323327 -380.461098) (xy 464.338681 -380.408807) (xy 464.361319 -380.359233) (xy 464.390782 -380.313384)
			(xy 464.42647 -380.272195) (xy 464.467656 -380.236504) (xy 464.513501 -380.207037) (xy 464.563073 -380.184393)
			(xy 464.615363 -380.169034) (xy 464.669307 -380.161273) (xy 464.696556 -380.160784) (xy 464.725296 -380.161278)
			(xy 464.782124 -380.169908) (xy 464.837015 -380.186966) (xy 464.888727 -380.212064) (xy 464.936088 -380.244635)
			(xy 464.957414 -380.263908) (xy 464.968948 -380.27398) (xy 464.996494 -380.287322) (xy 465.026756 -380.291907)
			(xy 465.057018 -380.287322) (xy 465.084564 -380.27398) (xy 465.096098 -380.263908) (xy 465.117398 -380.244606)
			(xy 465.164768 -380.212045) (xy 465.216486 -380.186959) (xy 465.271383 -380.169916) (xy 465.328215 -380.161301)
			(xy 465.356956 -380.160784) (xy 465.384207 -380.161296) (xy 465.438156 -380.169047) (xy 465.490453 -380.184397)
			(xy 465.540032 -380.207034) (xy 465.585885 -380.236496) (xy 465.627078 -380.272185) (xy 465.662772 -380.313373)
			(xy 465.692241 -380.359222) (xy 465.714885 -380.408799) (xy 465.730242 -380.461093) (xy 465.738 -380.515041)
			(xy 465.738464 -380.542292) (xy 465.737949 -380.571139) (xy 465.729268 -380.628177) (xy 465.712088 -380.683254)
			(xy 465.686802 -380.735112) (xy 465.653988 -380.782565) (xy 465.634578 -380.803912) (xy 465.624387 -380.815468)
			(xy 465.610927 -380.843173) (xy 465.606307 -380.873626) (xy 465.610943 -380.904076) (xy 465.624416 -380.931774)
			(xy 465.634578 -380.943358) (xy 465.653987 -380.964704) (xy 465.686785 -381.012165) (xy 465.712063 -381.064025)
			(xy 465.729243 -381.119099) (xy 465.737933 -381.176132) (xy 465.738464 -381.204978) (xy 465.738024 -381.232232)
			(xy 465.730269 -381.286186) (xy 465.714913 -381.338487) (xy 465.69227 -381.38807) (xy 465.662801 -381.433926)
			(xy 465.627104 -381.47512) (xy 465.585908 -381.510814) (xy 465.540051 -381.540281) (xy 465.490467 -381.562921)
			(xy 465.438165 -381.578274) (xy 465.38421 -381.586026) (xy 465.356956 -381.586486) (xy 465.328217 -381.585966)
			(xy 465.271391 -381.577339) (xy 465.216501 -381.560287) (xy 465.164789 -381.535195) (xy 465.117426 -381.502631)
			(xy 465.096098 -381.483362) (xy 465.084564 -381.47329) (xy 465.057018 -381.459948) (xy 465.026756 -381.455363)
			(xy 464.996494 -381.459948) (xy 464.968948 -381.47329) (xy 464.957414 -381.483362) (xy 464.936105 -381.502654)
			(xy 464.888738 -381.535217) (xy 464.837022 -381.560305) (xy 464.782127 -381.577351) (xy 464.725296 -381.585968)
			(xy 464.696556 -381.586486) (xy 464.669303 -381.586063) (xy 464.615352 -381.5783) (xy 464.563054 -381.562938)
			(xy 464.513475 -381.54029) (xy 464.467624 -381.510817) (xy 464.426434 -381.475119) (xy 464.390743 -381.433923)
			(xy 464.361278 -381.388067) (xy 464.338639 -381.338484) (xy 464.323286 -381.286184) (xy 464.315532 -381.232231)
			(xy 464.315048 -381.204978) (xy 463.689681 -381.204978) (xy 463.723405 -381.219309) (xy 463.771011 -381.248363)
			(xy 463.813879 -381.284038) (xy 463.851096 -381.325575) (xy 463.881869 -381.372088) (xy 463.905541 -381.422585)
			(xy 463.921609 -381.475992) (xy 463.929729 -381.531168) (xy 463.930238 -381.559054) (xy 463.929729 -381.58694)
			(xy 463.921609 -381.642116) (xy 463.905541 -381.695523) (xy 463.881869 -381.74602) (xy 463.851096 -381.792533)
			(xy 463.813879 -381.83407) (xy 463.771011 -381.869745) (xy 463.723405 -381.898799) (xy 463.672076 -381.920611)
			(xy 463.618119 -381.934717) (xy 463.562682 -381.940817) (xy 463.506948 -381.93878) (xy 463.452105 -381.92865)
			(xy 463.399321 -381.910643) (xy 463.349721 -381.885142) (xy 463.304363 -381.852691) (xy 463.264214 -381.813982)
			(xy 463.230128 -381.769839) (xy 463.202832 -381.721204) (xy 463.182909 -381.669113) (xy 463.170783 -381.614676)
			(xy 463.166712 -381.559054) (xy 462.193558 -381.559054) (xy 462.178545 -381.59108) (xy 462.147772 -381.637593)
			(xy 462.110555 -381.67913) (xy 462.067687 -381.714805) (xy 462.020081 -381.743859) (xy 461.968752 -381.765671)
			(xy 461.914795 -381.779777) (xy 461.859358 -381.785877) (xy 461.803624 -381.78384) (xy 461.748781 -381.77371)
			(xy 461.695997 -381.755703) (xy 461.646397 -381.730202) (xy 461.601039 -381.697751) (xy 461.56089 -381.659042)
			(xy 461.526804 -381.614899) (xy 461.499508 -381.566264) (xy 461.479585 -381.514173) (xy 461.467459 -381.459736)
			(xy 461.463388 -381.404114) (xy 435.53888 -381.404114) (xy 435.53888 -382.524553) (xy 437.679785 -382.524553)
			(xy 437.679785 -382.470047) (xy 437.687543 -382.416096) (xy 437.7029 -382.363799) (xy 437.725544 -382.31422)
			(xy 437.755014 -382.268368) (xy 437.79071 -382.227177) (xy 437.831905 -382.191487) (xy 437.87776 -382.162022)
			(xy 437.927342 -382.139384) (xy 437.979641 -382.124033) (xy 438.033593 -382.116282) (xy 438.060846 -382.115822)
			(xy 438.090076 -382.11638) (xy 438.147851 -382.125317) (xy 438.203586 -382.142959) (xy 438.25598 -382.168894)
			(xy 438.303805 -382.202516) (xy 438.345945 -382.243038) (xy 438.364122 -382.265936) (xy 438.37256 -382.276333)
			(xy 438.393764 -382.29267) (xy 438.418483 -382.302943) (xy 438.445021 -382.306448) (xy 438.471559 -382.302943)
			(xy 438.496278 -382.29267) (xy 438.517482 -382.276333) (xy 438.52592 -382.265936) (xy 438.544107 -382.243043)
			(xy 438.586231 -382.2025) (xy 438.634051 -382.168863) (xy 438.686444 -382.14292) (xy 438.742184 -382.125279)
			(xy 438.799964 -382.116353) (xy 438.829196 -382.115822) (xy 438.856451 -382.116225) (xy 438.910407 -382.123982)
			(xy 438.962709 -382.139339) (xy 439.012294 -382.161983) (xy 439.058151 -382.191453) (xy 439.099348 -382.227149)
			(xy 439.135045 -382.268346) (xy 439.164515 -382.314203) (xy 439.171008 -382.32842) (xy 456.932282 -382.32842)
			(xy 456.936353 -382.272798) (xy 456.948479 -382.218361) (xy 456.968402 -382.16627) (xy 456.995698 -382.117635)
			(xy 457.029784 -382.073492) (xy 457.069933 -382.034783) (xy 457.115291 -382.002332) (xy 457.164891 -381.976831)
			(xy 457.217675 -381.958824) (xy 457.272518 -381.948694) (xy 457.328252 -381.946657) (xy 457.383689 -381.952757)
			(xy 457.437646 -381.966863) (xy 457.488975 -381.988675) (xy 457.536581 -382.017729) (xy 457.579449 -382.053404)
			(xy 457.616666 -382.094941) (xy 457.647439 -382.141454) (xy 457.671111 -382.191951) (xy 457.687179 -382.245358)
			(xy 457.695299 -382.300534) (xy 457.695808 -382.32842) (xy 457.695299 -382.356306) (xy 457.687179 -382.411482)
			(xy 457.678163 -382.44145) (xy 458.634082 -382.44145) (xy 458.638153 -382.385828) (xy 458.650279 -382.331391)
			(xy 458.670202 -382.2793) (xy 458.697498 -382.230665) (xy 458.731584 -382.186522) (xy 458.771733 -382.147813)
			(xy 458.817091 -382.115362) (xy 458.866691 -382.089861) (xy 458.919475 -382.071854) (xy 458.974318 -382.061724)
			(xy 459.030052 -382.059687) (xy 459.085489 -382.065787) (xy 459.139446 -382.079893) (xy 459.190775 -382.101705)
			(xy 459.238381 -382.130759) (xy 459.281249 -382.166434) (xy 459.318466 -382.207971) (xy 459.349239 -382.254484)
			(xy 459.372911 -382.304981) (xy 459.388979 -382.358388) (xy 459.389017 -382.358646) (xy 459.737458 -382.358646)
			(xy 459.741529 -382.303024) (xy 459.753655 -382.248587) (xy 459.773578 -382.196496) (xy 459.800874 -382.147861)
			(xy 459.83496 -382.103718) (xy 459.875109 -382.065009) (xy 459.920467 -382.032558) (xy 459.970067 -382.007057)
			(xy 460.022851 -381.98905) (xy 460.077694 -381.97892) (xy 460.133428 -381.976883) (xy 460.188865 -381.982983)
			(xy 460.242822 -381.997089) (xy 460.294151 -382.018901) (xy 460.341757 -382.047955) (xy 460.384625 -382.08363)
			(xy 460.421842 -382.125167) (xy 460.452615 -382.17168) (xy 460.476287 -382.222177) (xy 460.492355 -382.275584)
			(xy 460.500475 -382.33076) (xy 460.500984 -382.358646) (xy 460.500475 -382.386532) (xy 460.492355 -382.441708)
			(xy 460.476287 -382.495115) (xy 460.452615 -382.545612) (xy 460.421842 -382.592125) (xy 460.384625 -382.633662)
			(xy 460.341757 -382.669337) (xy 460.294151 -382.698391) (xy 460.242822 -382.720203) (xy 460.188865 -382.734309)
			(xy 460.133428 -382.740409) (xy 460.077694 -382.738372) (xy 460.022851 -382.728242) (xy 459.970067 -382.710235)
			(xy 459.920467 -382.684734) (xy 459.875109 -382.652283) (xy 459.83496 -382.613574) (xy 459.800874 -382.569431)
			(xy 459.773578 -382.520796) (xy 459.753655 -382.468705) (xy 459.741529 -382.414268) (xy 459.737458 -382.358646)
			(xy 459.389017 -382.358646) (xy 459.397099 -382.413564) (xy 459.397608 -382.44145) (xy 459.397099 -382.469336)
			(xy 459.388979 -382.524512) (xy 459.372911 -382.577919) (xy 459.349239 -382.628416) (xy 459.318466 -382.674929)
			(xy 459.281249 -382.716466) (xy 459.238381 -382.752141) (xy 459.190775 -382.781195) (xy 459.139446 -382.803007)
			(xy 459.085489 -382.817113) (xy 459.030052 -382.823213) (xy 458.974318 -382.821176) (xy 458.919475 -382.811046)
			(xy 458.866691 -382.793039) (xy 458.817091 -382.767538) (xy 458.771733 -382.735087) (xy 458.731584 -382.696378)
			(xy 458.697498 -382.652235) (xy 458.670202 -382.6036) (xy 458.650279 -382.551509) (xy 458.638153 -382.497072)
			(xy 458.634082 -382.44145) (xy 457.678163 -382.44145) (xy 457.671111 -382.464889) (xy 457.647439 -382.515386)
			(xy 457.616666 -382.561899) (xy 457.579449 -382.603436) (xy 457.536581 -382.639111) (xy 457.488975 -382.668165)
			(xy 457.437646 -382.689977) (xy 457.383689 -382.704083) (xy 457.328252 -382.710183) (xy 457.272518 -382.708146)
			(xy 457.217675 -382.698016) (xy 457.164891 -382.680009) (xy 457.115291 -382.654508) (xy 457.069933 -382.622057)
			(xy 457.029784 -382.583348) (xy 456.995698 -382.539205) (xy 456.968402 -382.49057) (xy 456.948479 -382.438479)
			(xy 456.936353 -382.384042) (xy 456.932282 -382.32842) (xy 439.171008 -382.32842) (xy 439.18716 -382.363787)
			(xy 439.202517 -382.416089) (xy 439.210275 -382.470045) (xy 439.210275 -382.524555) (xy 439.202517 -382.578511)
			(xy 439.18716 -382.630813) (xy 439.164515 -382.680397) (xy 439.135045 -382.726254) (xy 439.099348 -382.767451)
			(xy 439.058151 -382.803147) (xy 439.012294 -382.832617) (xy 438.962709 -382.855261) (xy 438.910407 -382.870618)
			(xy 438.856451 -382.878375) (xy 438.829196 -382.878838) (xy 438.799966 -382.878266) (xy 438.742192 -382.869334)
			(xy 438.686456 -382.851696) (xy 438.634062 -382.825763) (xy 438.586236 -382.792143) (xy 438.544097 -382.751622)
			(xy 438.52592 -382.728724) (xy 438.517509 -382.718283) (xy 438.496323 -382.701865) (xy 438.471591 -382.691536)
			(xy 438.445021 -382.688012) (xy 438.418451 -382.691536) (xy 438.393719 -382.701865) (xy 438.372533 -382.718283)
			(xy 438.364122 -382.728724) (xy 438.345962 -382.751639) (xy 438.303829 -382.792173) (xy 438.256003 -382.825801)
			(xy 438.203604 -382.851735) (xy 438.14786 -382.869367) (xy 438.090079 -382.878283) (xy 438.060846 -382.878838)
			(xy 438.033593 -382.878318) (xy 437.979641 -382.870567) (xy 437.927342 -382.855216) (xy 437.87776 -382.832578)
			(xy 437.831905 -382.803113) (xy 437.79071 -382.767423) (xy 437.755014 -382.726232) (xy 437.725544 -382.68038)
			(xy 437.7029 -382.630801) (xy 437.687543 -382.578504) (xy 437.679785 -382.524553) (xy 435.53888 -382.524553)
			(xy 435.53888 -382.903853) (xy 442.76693 -382.903853) (xy 442.76693 -382.849347) (xy 442.774686 -382.795396)
			(xy 442.790041 -382.743098) (xy 442.812682 -382.693518) (xy 442.842148 -382.647664) (xy 442.87784 -382.606469)
			(xy 442.91903 -382.570773) (xy 442.964881 -382.541302) (xy 443.014459 -382.518656) (xy 443.066755 -382.503295)
			(xy 443.120705 -382.495533) (xy 443.147958 -382.495044) (xy 443.176875 -382.495576) (xy 443.234046 -382.5043)
			(xy 443.289245 -382.521554) (xy 443.341207 -382.546943) (xy 443.388742 -382.579885) (xy 443.430758 -382.619625)
			(xy 443.448948 -382.64211) (xy 443.458845 -382.653915) (xy 443.484169 -382.671434) (xy 443.513562 -382.68061)
			(xy 443.544354 -382.68061) (xy 443.573747 -382.671434) (xy 443.599071 -382.653915) (xy 443.608968 -382.64211)
			(xy 443.62718 -382.619644) (xy 443.669195 -382.579907) (xy 443.716725 -382.546966) (xy 443.768683 -382.521574)
			(xy 443.823877 -382.504314) (xy 443.881043 -382.495581) (xy 443.909958 -382.495044) (xy 443.937209 -382.4956)
			(xy 443.991158 -382.503351) (xy 444.043454 -382.518702) (xy 444.093034 -382.541339) (xy 444.138886 -382.570802)
			(xy 444.180079 -382.606492) (xy 444.215772 -382.64768) (xy 444.245241 -382.69353) (xy 444.267883 -382.743106)
			(xy 444.28324 -382.795401) (xy 444.290997 -382.849349) (xy 444.290997 -382.903851) (xy 444.28324 -382.957799)
			(xy 444.26958 -383.004314) (xy 460.372458 -383.004314) (xy 460.376529 -382.948692) (xy 460.388655 -382.894255)
			(xy 460.408578 -382.842164) (xy 460.435874 -382.793529) (xy 460.46996 -382.749386) (xy 460.510109 -382.710677)
			(xy 460.555467 -382.678226) (xy 460.605067 -382.652725) (xy 460.657851 -382.634718) (xy 460.712694 -382.624588)
			(xy 460.768428 -382.622551) (xy 460.823865 -382.628651) (xy 460.877822 -382.642757) (xy 460.929151 -382.664569)
			(xy 460.976757 -382.693623) (xy 461.019625 -382.729298) (xy 461.056842 -382.770835) (xy 461.087615 -382.817348)
			(xy 461.111287 -382.867845) (xy 461.127355 -382.921252) (xy 461.135475 -382.976428) (xy 461.135984 -383.004314)
			(xy 461.135475 -383.0322) (xy 461.127355 -383.087376) (xy 461.111287 -383.140783) (xy 461.087615 -383.19128)
			(xy 461.056842 -383.237793) (xy 461.019625 -383.27933) (xy 460.976757 -383.315005) (xy 460.929151 -383.344059)
			(xy 460.877822 -383.365871) (xy 460.823865 -383.379977) (xy 460.768428 -383.386077) (xy 460.712694 -383.38404)
			(xy 460.657851 -383.37391) (xy 460.605067 -383.355903) (xy 460.555467 -383.330402) (xy 460.510109 -383.297951)
			(xy 460.46996 -383.259242) (xy 460.435874 -383.215099) (xy 460.408578 -383.166464) (xy 460.388655 -383.114373)
			(xy 460.376529 -383.059936) (xy 460.372458 -383.004314) (xy 444.26958 -383.004314) (xy 444.267883 -383.010094)
			(xy 444.245241 -383.05967) (xy 444.215772 -383.10552) (xy 444.180079 -383.146708) (xy 444.138886 -383.182398)
			(xy 444.093034 -383.211861) (xy 444.043454 -383.234498) (xy 443.991158 -383.249849) (xy 443.937209 -383.2576)
			(xy 443.909958 -383.25806) (xy 443.881042 -383.257515) (xy 443.823871 -383.248794) (xy 443.768672 -383.231542)
			(xy 443.71671 -383.206156) (xy 443.669176 -383.173216) (xy 443.627158 -383.133478) (xy 443.608968 -383.110994)
			(xy 443.599071 -383.099189) (xy 443.573747 -383.08167) (xy 443.544354 -383.072494) (xy 443.513562 -383.072494)
			(xy 443.484169 -383.08167) (xy 443.458845 -383.099189) (xy 443.448948 -383.110994) (xy 443.430728 -383.133453)
			(xy 443.388715 -383.17319) (xy 443.341186 -383.206132) (xy 443.28923 -383.231525) (xy 443.234038 -383.248786)
			(xy 443.176872 -383.257522) (xy 443.147958 -383.25806) (xy 443.120705 -383.257667) (xy 443.066755 -383.249905)
			(xy 443.014459 -383.234544) (xy 442.964881 -383.211898) (xy 442.91903 -383.182427) (xy 442.87784 -383.146731)
			(xy 442.842148 -383.105536) (xy 442.812682 -383.059682) (xy 442.790041 -383.010102) (xy 442.774686 -382.957804)
			(xy 442.76693 -382.903853) (xy 435.53888 -382.903853) (xy 435.53888 -383.758948) (xy 434.728575 -384.569253)
			(xy 437.679785 -384.569253) (xy 437.679785 -384.514747) (xy 437.687543 -384.460796) (xy 437.7029 -384.408499)
			(xy 437.725544 -384.35892) (xy 437.755014 -384.313068) (xy 437.79071 -384.271877) (xy 437.831905 -384.236187)
			(xy 437.87776 -384.206722) (xy 437.927342 -384.184084) (xy 437.979641 -384.168733) (xy 438.033593 -384.160982)
			(xy 438.060846 -384.160522) (xy 438.090076 -384.16108) (xy 438.147851 -384.170017) (xy 438.203586 -384.187659)
			(xy 438.25598 -384.213594) (xy 438.303805 -384.247216) (xy 438.345945 -384.287738) (xy 438.364122 -384.310636)
			(xy 438.37256 -384.321033) (xy 438.393764 -384.33737) (xy 438.418483 -384.347643) (xy 438.445021 -384.351148)
			(xy 438.471559 -384.347643) (xy 438.496278 -384.33737) (xy 438.517482 -384.321033) (xy 438.52592 -384.310636)
			(xy 438.544107 -384.287743) (xy 438.586231 -384.2472) (xy 438.634051 -384.213563) (xy 438.686444 -384.18762)
			(xy 438.742184 -384.169979) (xy 438.799964 -384.161053) (xy 438.829196 -384.160522) (xy 438.856451 -384.160925)
			(xy 438.910407 -384.168682) (xy 438.962709 -384.184039) (xy 439.012294 -384.206683) (xy 439.058151 -384.236153)
			(xy 439.099348 -384.271849) (xy 439.135045 -384.313046) (xy 439.164515 -384.358903) (xy 439.18716 -384.408487)
			(xy 439.202517 -384.460789) (xy 439.210275 -384.514745) (xy 439.210275 -384.569255) (xy 439.202517 -384.623211)
			(xy 439.18716 -384.675513) (xy 439.164515 -384.725097) (xy 439.135045 -384.770954) (xy 439.099348 -384.812151)
			(xy 439.058151 -384.847847) (xy 439.012294 -384.877317) (xy 438.962709 -384.899961) (xy 438.910407 -384.915318)
			(xy 438.856451 -384.923075) (xy 438.829196 -384.923538) (xy 438.799966 -384.922966) (xy 438.742192 -384.914034)
			(xy 438.686456 -384.896396) (xy 438.634062 -384.870463) (xy 438.586236 -384.836843) (xy 438.544097 -384.796322)
			(xy 438.52592 -384.773424) (xy 438.517509 -384.762983) (xy 438.496323 -384.746565) (xy 438.471591 -384.736236)
			(xy 438.445021 -384.732712) (xy 438.418451 -384.736236) (xy 438.393719 -384.746565) (xy 438.372533 -384.762983)
			(xy 438.364122 -384.773424) (xy 438.345962 -384.796339) (xy 438.303829 -384.836873) (xy 438.256003 -384.870501)
			(xy 438.203604 -384.896435) (xy 438.14786 -384.914067) (xy 438.090079 -384.922983) (xy 438.060846 -384.923538)
			(xy 438.033593 -384.923018) (xy 437.979641 -384.915267) (xy 437.927342 -384.899916) (xy 437.87776 -384.877278)
			(xy 437.831905 -384.847813) (xy 437.79071 -384.812123) (xy 437.755014 -384.770932) (xy 437.725544 -384.72508)
			(xy 437.7029 -384.675501) (xy 437.687543 -384.623204) (xy 437.679785 -384.569253) (xy 434.728575 -384.569253)
			(xy 433.74818 -385.549648) (xy 433.74818 -386.348858) (xy 438.101609 -386.348858) (xy 438.101609 -386.294342)
			(xy 438.109368 -386.240381) (xy 438.124728 -386.188074) (xy 438.147376 -386.138485) (xy 438.176851 -386.092624)
			(xy 438.212554 -386.051425) (xy 438.253756 -386.015727) (xy 438.29962 -385.986257) (xy 438.349211 -385.963614)
			(xy 438.40152 -385.94826) (xy 438.455482 -385.940506) (xy 438.48274 -385.940046) (xy 438.511656 -385.94059)
			(xy 438.568827 -385.949311) (xy 438.624026 -385.966563) (xy 438.675988 -385.991949) (xy 438.723523 -386.024889)
			(xy 438.76554 -386.064628) (xy 438.78373 -386.087112) (xy 438.793627 -386.098917) (xy 438.818951 -386.116436)
			(xy 438.848344 -386.125612) (xy 438.879136 -386.125612) (xy 438.908529 -386.116436) (xy 438.933853 -386.098917)
			(xy 438.94375 -386.087112) (xy 438.960503 -386.066329) (xy 438.998857 -386.029199) (xy 439.042011 -385.997777)
			(xy 439.089125 -385.972678) (xy 439.139277 -385.954392) (xy 439.191488 -385.943275) (xy 439.24474 -385.939545)
			(xy 439.297992 -385.943275) (xy 439.350203 -385.954392) (xy 439.400355 -385.972678) (xy 439.447469 -385.997777)
			(xy 439.490623 -386.029199) (xy 439.528977 -386.066329) (xy 439.54573 -386.087112) (xy 439.555627 -386.098917)
			(xy 439.580951 -386.116436) (xy 439.610344 -386.125612) (xy 439.641136 -386.125612) (xy 439.670529 -386.116436)
			(xy 439.695853 -386.098917) (xy 439.70575 -386.087112) (xy 439.722503 -386.066329) (xy 439.760857 -386.029199)
			(xy 439.804011 -385.997777) (xy 439.851125 -385.972678) (xy 439.901277 -385.954392) (xy 439.953488 -385.943275)
			(xy 440.00674 -385.939545) (xy 440.059992 -385.943275) (xy 440.112203 -385.954392) (xy 440.162355 -385.972678)
			(xy 440.209469 -385.997777) (xy 440.252623 -386.029199) (xy 440.290977 -386.066329) (xy 440.30773 -386.087112)
			(xy 440.317627 -386.098917) (xy 440.342951 -386.116436) (xy 440.372344 -386.125612) (xy 440.403136 -386.125612)
			(xy 440.432529 -386.116436) (xy 440.457853 -386.098917) (xy 440.46775 -386.087112) (xy 440.485972 -386.064655)
			(xy 440.527985 -386.024918) (xy 440.575513 -385.991975) (xy 440.627469 -385.966582) (xy 440.682661 -385.94932)
			(xy 440.739826 -385.940585) (xy 440.76874 -385.940046) (xy 440.795986 -385.940627) (xy 440.849923 -385.948387)
			(xy 440.902206 -385.963744) (xy 440.951773 -385.986384) (xy 440.997612 -386.015848) (xy 441.038793 -386.051535)
			(xy 441.074476 -386.09272) (xy 441.103935 -386.138563) (xy 441.12657 -386.188131) (xy 441.141921 -386.240416)
			(xy 441.149676 -386.294354) (xy 441.149676 -386.348846) (xy 441.141921 -386.402784) (xy 441.12657 -386.455069)
			(xy 441.103935 -386.504637) (xy 441.074476 -386.55048) (xy 441.038793 -386.591665) (xy 440.997612 -386.627352)
			(xy 440.951773 -386.656816) (xy 440.902206 -386.679456) (xy 440.849923 -386.694813) (xy 440.795986 -386.702573)
			(xy 440.76874 -386.703062) (xy 440.739823 -386.702529) (xy 440.682652 -386.693805) (xy 440.627453 -386.676551)
			(xy 440.575491 -386.651162) (xy 440.527957 -386.618221) (xy 440.48594 -386.578481) (xy 440.46775 -386.555996)
			(xy 440.457853 -386.544191) (xy 440.432529 -386.526672) (xy 440.403136 -386.517496) (xy 440.372344 -386.517496)
			(xy 440.342951 -386.526672) (xy 440.317627 -386.544191) (xy 440.30773 -386.555996) (xy 440.290977 -386.576779)
			(xy 440.252623 -386.613909) (xy 440.209469 -386.645331) (xy 440.162355 -386.67043) (xy 440.112203 -386.688716)
			(xy 440.059992 -386.699833) (xy 440.00674 -386.703563) (xy 439.953488 -386.699833) (xy 439.901277 -386.688716)
			(xy 439.851125 -386.67043) (xy 439.804011 -386.645331) (xy 439.760857 -386.613909) (xy 439.722503 -386.576779)
			(xy 439.70575 -386.555996) (xy 439.695853 -386.544191) (xy 439.670529 -386.526672) (xy 439.641136 -386.517496)
			(xy 439.610344 -386.517496) (xy 439.580951 -386.526672) (xy 439.555627 -386.544191) (xy 439.54573 -386.555996)
			(xy 439.528977 -386.576779) (xy 439.490623 -386.613909) (xy 439.447469 -386.645331) (xy 439.400355 -386.67043)
			(xy 439.350203 -386.688716) (xy 439.297992 -386.699833) (xy 439.24474 -386.703563) (xy 439.191488 -386.699833)
			(xy 439.139277 -386.688716) (xy 439.089125 -386.67043) (xy 439.042011 -386.645331) (xy 438.998857 -386.613909)
			(xy 438.960503 -386.576779) (xy 438.94375 -386.555996) (xy 438.933853 -386.544191) (xy 438.908529 -386.526672)
			(xy 438.879136 -386.517496) (xy 438.848344 -386.517496) (xy 438.818951 -386.526672) (xy 438.793627 -386.544191)
			(xy 438.78373 -386.555996) (xy 438.765521 -386.578464) (xy 438.723505 -386.618201) (xy 438.675974 -386.651142)
			(xy 438.624016 -386.676533) (xy 438.568822 -386.693792) (xy 438.511655 -386.702525) (xy 438.48274 -386.703062)
			(xy 438.455482 -386.702694) (xy 438.40152 -386.69494) (xy 438.349211 -386.679586) (xy 438.29962 -386.656943)
			(xy 438.253756 -386.627473) (xy 438.212554 -386.591775) (xy 438.176851 -386.550576) (xy 438.147376 -386.504715)
			(xy 438.124728 -386.455126) (xy 438.109368 -386.402819) (xy 438.101609 -386.348858) (xy 433.74818 -386.348858)
			(xy 433.74818 -387.371153) (xy 442.672159 -387.371153) (xy 442.672159 -387.316647) (xy 442.679917 -387.262695)
			(xy 442.695273 -387.210396) (xy 442.717917 -387.160816) (xy 442.747386 -387.114962) (xy 442.783081 -387.07377)
			(xy 442.824275 -387.038076) (xy 442.87013 -387.008609) (xy 442.919711 -386.985968) (xy 442.972011 -386.970613)
			(xy 443.025963 -386.962858) (xy 443.053216 -386.962396) (xy 443.082132 -386.962938) (xy 443.139304 -386.971657)
			(xy 443.194504 -386.988908) (xy 443.246467 -387.014295) (xy 443.294001 -387.047236) (xy 443.336017 -387.086977)
			(xy 443.354206 -387.109462) (xy 443.364103 -387.121267) (xy 443.389427 -387.138786) (xy 443.41882 -387.147962)
			(xy 443.449612 -387.147962) (xy 443.479005 -387.138786) (xy 443.504329 -387.121267) (xy 443.514226 -387.109462)
			(xy 443.532393 -387.086958) (xy 443.574419 -387.047226) (xy 443.621959 -387.01429) (xy 443.673925 -386.988906)
			(xy 443.729126 -386.971654) (xy 443.786299 -386.962929) (xy 443.815216 -386.962396) (xy 443.842467 -386.962875)
			(xy 443.896413 -386.970633) (xy 443.948707 -386.98599) (xy 443.998282 -387.008632) (xy 444.044131 -387.038099)
			(xy 444.08532 -387.073791) (xy 444.12101 -387.114981) (xy 444.150475 -387.160832) (xy 444.173116 -387.210408)
			(xy 444.18847 -387.262702) (xy 444.191125 -387.281166) (xy 455.690476 -387.281166) (xy 455.694547 -387.225544)
			(xy 455.706673 -387.171107) (xy 455.726596 -387.119016) (xy 455.753892 -387.070381) (xy 455.787978 -387.026238)
			(xy 455.828127 -386.987529) (xy 455.873485 -386.955078) (xy 455.923085 -386.929577) (xy 455.975869 -386.91157)
			(xy 456.030712 -386.90144) (xy 456.086446 -386.899403) (xy 456.141883 -386.905503) (xy 456.19584 -386.919609)
			(xy 456.247169 -386.941421) (xy 456.294775 -386.970475) (xy 456.337643 -387.00615) (xy 456.37486 -387.047687)
			(xy 456.405633 -387.0942) (xy 456.429305 -387.144697) (xy 456.445373 -387.198104) (xy 456.453493 -387.25328)
			(xy 456.454002 -387.281166) (xy 456.453493 -387.309052) (xy 456.445373 -387.364228) (xy 456.429305 -387.417635)
			(xy 456.405633 -387.468132) (xy 456.37486 -387.514645) (xy 456.337643 -387.556182) (xy 456.294775 -387.591857)
			(xy 456.247169 -387.620911) (xy 456.19584 -387.642723) (xy 456.141883 -387.656829) (xy 456.086446 -387.662929)
			(xy 456.030712 -387.660892) (xy 455.975869 -387.650762) (xy 455.923085 -387.632755) (xy 455.873485 -387.607254)
			(xy 455.828127 -387.574803) (xy 455.787978 -387.536094) (xy 455.753892 -387.491951) (xy 455.726596 -387.443316)
			(xy 455.706673 -387.391225) (xy 455.694547 -387.336788) (xy 455.690476 -387.281166) (xy 444.191125 -387.281166)
			(xy 444.196226 -387.316649) (xy 444.196226 -387.371151) (xy 444.18847 -387.425098) (xy 444.173116 -387.477392)
			(xy 444.150475 -387.526968) (xy 444.12101 -387.572819) (xy 444.08532 -387.614009) (xy 444.044131 -387.649701)
			(xy 443.998282 -387.679168) (xy 443.948707 -387.70181) (xy 443.896413 -387.717167) (xy 443.842467 -387.724925)
			(xy 443.815216 -387.725412) (xy 443.786298 -387.724916) (xy 443.729124 -387.716187) (xy 443.673923 -387.698927)
			(xy 443.621961 -387.673531) (xy 443.574428 -387.640582) (xy 443.532414 -387.600835) (xy 443.514226 -387.578346)
			(xy 443.504329 -387.566541) (xy 443.479005 -387.549022) (xy 443.449612 -387.539846) (xy 443.41882 -387.539846)
			(xy 443.389427 -387.549022) (xy 443.364103 -387.566541) (xy 443.354206 -387.578346) (xy 443.336023 -387.600836)
			(xy 443.294 -387.640569) (xy 443.246463 -387.673506) (xy 443.194501 -387.698893) (xy 443.139302 -387.716148)
			(xy 443.082132 -387.724877) (xy 443.053216 -387.725412) (xy 443.025963 -387.724942) (xy 442.972011 -387.717187)
			(xy 442.919711 -387.701832) (xy 442.87013 -387.679191) (xy 442.824275 -387.649724) (xy 442.783081 -387.61403)
			(xy 442.747386 -387.572838) (xy 442.717917 -387.526984) (xy 442.695273 -387.477404) (xy 442.679917 -387.425105)
			(xy 442.672159 -387.371153) (xy 433.74818 -387.371153) (xy 433.74818 -388.760253) (xy 438.101685 -388.760253)
			(xy 438.101685 -388.705747) (xy 438.109443 -388.651797) (xy 438.1248 -388.5995) (xy 438.147443 -388.549921)
			(xy 438.176913 -388.50407) (xy 438.212608 -388.46288) (xy 438.253802 -388.427189) (xy 438.299657 -388.397724)
			(xy 438.349238 -388.375086) (xy 438.401536 -388.359734) (xy 438.455487 -388.351983) (xy 438.48274 -388.351522)
			(xy 438.511656 -388.352075) (xy 438.568826 -388.360796) (xy 438.624024 -388.378046) (xy 438.675986 -388.403431)
			(xy 438.723521 -388.436369) (xy 438.765539 -388.476105) (xy 438.78373 -388.498588) (xy 438.793627 -388.510393)
			(xy 438.818951 -388.527912) (xy 438.848344 -388.537088) (xy 438.879136 -388.537088) (xy 438.908529 -388.527912)
			(xy 438.933853 -388.510393) (xy 438.94375 -388.498588) (xy 438.960503 -388.477805) (xy 438.998857 -388.440675)
			(xy 439.042011 -388.409253) (xy 439.089125 -388.384154) (xy 439.139277 -388.365868) (xy 439.191488 -388.354751)
			(xy 439.24474 -388.351021) (xy 439.297992 -388.354751) (xy 439.350203 -388.365868) (xy 439.400355 -388.384154)
			(xy 439.447469 -388.409253) (xy 439.490623 -388.440675) (xy 439.528977 -388.477805) (xy 439.54573 -388.498588)
			(xy 439.555627 -388.510393) (xy 439.580951 -388.527912) (xy 439.610344 -388.537088) (xy 439.641136 -388.537088)
			(xy 439.670529 -388.527912) (xy 439.695853 -388.510393) (xy 439.70575 -388.498588) (xy 439.722503 -388.477805)
			(xy 439.760857 -388.440675) (xy 439.804011 -388.409253) (xy 439.851125 -388.384154) (xy 439.901277 -388.365868)
			(xy 439.953488 -388.354751) (xy 440.00674 -388.351021) (xy 440.059992 -388.354751) (xy 440.112203 -388.365868)
			(xy 440.162355 -388.384154) (xy 440.209469 -388.409253) (xy 440.252623 -388.440675) (xy 440.290977 -388.477805)
			(xy 440.30773 -388.498588) (xy 440.317627 -388.510393) (xy 440.342951 -388.527912) (xy 440.372344 -388.537088)
			(xy 440.403136 -388.537088) (xy 440.432529 -388.527912) (xy 440.457853 -388.510393) (xy 440.46775 -388.498588)
			(xy 440.485966 -388.476126) (xy 440.527981 -388.43639) (xy 440.575511 -388.403449) (xy 440.627467 -388.378057)
			(xy 440.68266 -388.360796) (xy 440.739826 -388.352061) (xy 440.76874 -388.351522) (xy 440.795992 -388.351951)
			(xy 440.849939 -388.359712) (xy 440.902233 -388.375072) (xy 440.951809 -388.397717) (xy 440.997658 -388.427187)
			(xy 441.038847 -388.462881) (xy 441.074537 -388.504074) (xy 441.104002 -388.549926) (xy 441.126642 -388.599504)
			(xy 441.141996 -388.6518) (xy 441.149752 -388.705748) (xy 441.149752 -388.760252) (xy 441.141996 -388.8142)
			(xy 441.126642 -388.866496) (xy 441.104002 -388.916074) (xy 441.074537 -388.961926) (xy 441.038847 -389.003119)
			(xy 440.997658 -389.038813) (xy 440.951809 -389.068283) (xy 440.902233 -389.090928) (xy 440.849939 -389.106288)
			(xy 440.795992 -389.114049) (xy 440.76874 -389.114538) (xy 440.739823 -389.114015) (xy 440.682651 -389.10529)
			(xy 440.627451 -389.088035) (xy 440.575489 -389.062644) (xy 440.527955 -389.0297) (xy 440.485939 -388.989958)
			(xy 440.46775 -388.967472) (xy 440.457853 -388.955667) (xy 440.432529 -388.938148) (xy 440.403136 -388.928972)
			(xy 440.372344 -388.928972) (xy 440.342951 -388.938148) (xy 440.317627 -388.955667) (xy 440.30773 -388.967472)
			(xy 440.290977 -388.988255) (xy 440.252623 -389.025385) (xy 440.209469 -389.056807) (xy 440.162355 -389.081906)
			(xy 440.112203 -389.100192) (xy 440.059992 -389.111309) (xy 440.00674 -389.115039) (xy 439.953488 -389.111309)
			(xy 439.901277 -389.100192) (xy 439.851125 -389.081906) (xy 439.804011 -389.056807) (xy 439.760857 -389.025385)
			(xy 439.722503 -388.988255) (xy 439.70575 -388.967472) (xy 439.695853 -388.955667) (xy 439.670529 -388.938148)
			(xy 439.641136 -388.928972) (xy 439.610344 -388.928972) (xy 439.580951 -388.938148) (xy 439.555627 -388.955667)
			(xy 439.54573 -388.967472) (xy 439.528977 -388.988255) (xy 439.490623 -389.025385) (xy 439.447469 -389.056807)
			(xy 439.400355 -389.081906) (xy 439.350203 -389.100192) (xy 439.297992 -389.111309) (xy 439.24474 -389.115039)
			(xy 439.191488 -389.111309) (xy 439.139277 -389.100192) (xy 439.089125 -389.081906) (xy 439.042011 -389.056807)
			(xy 438.998857 -389.025385) (xy 438.960503 -388.988255) (xy 438.94375 -388.967472) (xy 438.933853 -388.955667)
			(xy 438.908529 -388.938148) (xy 438.879136 -388.928972) (xy 438.848344 -388.928972) (xy 438.818951 -388.938148)
			(xy 438.793627 -388.955667) (xy 438.78373 -388.967472) (xy 438.765515 -388.989935) (xy 438.723501 -389.029673)
			(xy 438.675971 -389.062615) (xy 438.624015 -389.088007) (xy 438.568821 -389.105268) (xy 438.511655 -389.114001)
			(xy 438.48274 -389.114538) (xy 438.455487 -389.114017) (xy 438.401536 -389.106266) (xy 438.349238 -389.090914)
			(xy 438.299657 -389.068276) (xy 438.253802 -389.038811) (xy 438.212608 -389.00312) (xy 438.176913 -388.96193)
			(xy 438.147443 -388.916079) (xy 438.1248 -388.8665) (xy 438.109443 -388.814203) (xy 438.101685 -388.760253)
			(xy 433.74818 -388.760253) (xy 433.74818 -393.077446) (xy 436.68188 -396.011146) (xy 465.30133 -396.011146)
		)
		(stroke
			(width 0)
			(type solid)
		)
		(fill yes)
		(layer "In15.Cu")
		(net "GND")
	)
	(gr_poly
		(pts
			(xy 261.046722 -58.617104) (xy 261.49808 -58.165746) (xy 261.49808 -47.015146) (xy 261.059168 -46.576488)
			(xy 255.561592 -46.576488) (xy 255.5295 -46.576022) (xy 255.465721 -46.568804) (xy 255.403152 -46.554495)
			(xy 255.342576 -46.533273) (xy 255.284756 -46.505406) (xy 255.230418 -46.471243) (xy 255.180245 -46.431213)
			(xy 255.157224 -46.408848) (xy 254.427482 -45.679106) (xy 252.02134 -45.679106) (xy 251.75464 -45.945806)
			(xy 251.75464 -46.877986) (xy 251.9426 -47.065946) (xy 253.419862 -47.065946) (xy 253.423933 -47.010324)
			(xy 253.436059 -46.955887) (xy 253.455982 -46.903796) (xy 253.483278 -46.855161) (xy 253.517364 -46.811018)
			(xy 253.557513 -46.772309) (xy 253.602871 -46.739858) (xy 253.652471 -46.714357) (xy 253.705255 -46.69635)
			(xy 253.760098 -46.68622) (xy 253.815832 -46.684183) (xy 253.871269 -46.690283) (xy 253.925226 -46.704389)
			(xy 253.976555 -46.726201) (xy 254.024161 -46.755255) (xy 254.067029 -46.79093) (xy 254.104246 -46.832467)
			(xy 254.135019 -46.87898) (xy 254.158691 -46.929477) (xy 254.174759 -46.982884) (xy 254.182879 -47.03806)
			(xy 254.183388 -47.065946) (xy 254.308862 -47.065946) (xy 254.312933 -47.010324) (xy 254.325059 -46.955887)
			(xy 254.344982 -46.903796) (xy 254.372278 -46.855161) (xy 254.406364 -46.811018) (xy 254.446513 -46.772309)
			(xy 254.491871 -46.739858) (xy 254.541471 -46.714357) (xy 254.594255 -46.69635) (xy 254.649098 -46.68622)
			(xy 254.704832 -46.684183) (xy 254.760269 -46.690283) (xy 254.814226 -46.704389) (xy 254.865555 -46.726201)
			(xy 254.913161 -46.755255) (xy 254.956029 -46.79093) (xy 254.993246 -46.832467) (xy 255.024019 -46.87898)
			(xy 255.047691 -46.929477) (xy 255.063759 -46.982884) (xy 255.071879 -47.03806) (xy 255.072388 -47.065946)
			(xy 255.197862 -47.065946) (xy 255.201933 -47.010324) (xy 255.214059 -46.955887) (xy 255.233982 -46.903796)
			(xy 255.261278 -46.855161) (xy 255.295364 -46.811018) (xy 255.335513 -46.772309) (xy 255.380871 -46.739858)
			(xy 255.430471 -46.714357) (xy 255.483255 -46.69635) (xy 255.538098 -46.68622) (xy 255.593832 -46.684183)
			(xy 255.649269 -46.690283) (xy 255.703226 -46.704389) (xy 255.754555 -46.726201) (xy 255.802161 -46.755255)
			(xy 255.845029 -46.79093) (xy 255.882246 -46.832467) (xy 255.913019 -46.87898) (xy 255.936691 -46.929477)
			(xy 255.952759 -46.982884) (xy 255.960879 -47.03806) (xy 255.961388 -47.065946) (xy 255.960891 -47.093148)
			(xy 256.667024 -47.093148) (xy 256.667024 -47.038652) (xy 256.67478 -46.984711) (xy 256.690133 -46.932423)
			(xy 256.712771 -46.882851) (xy 256.742234 -46.837006) (xy 256.777921 -46.795821) (xy 256.819106 -46.760134)
			(xy 256.864951 -46.730671) (xy 256.914523 -46.708033) (xy 256.966811 -46.69268) (xy 257.020752 -46.684924)
			(xy 257.048 -46.684438) (xy 257.075575 -46.68489) (xy 257.130149 -46.692844) (xy 257.18301 -46.708571)
			(xy 257.233056 -46.731743) (xy 257.279245 -46.761879) (xy 257.320615 -46.798349) (xy 257.33883 -46.819058)
			(xy 257.348728 -46.829956) (xy 257.373378 -46.846031) (xy 257.401586 -46.854415) (xy 257.431014 -46.854415)
			(xy 257.459222 -46.846031) (xy 257.483872 -46.829956) (xy 257.49377 -46.819058) (xy 257.511985 -46.798352)
			(xy 257.553356 -46.761887) (xy 257.599546 -46.73176) (xy 257.649593 -46.708597) (xy 257.702454 -46.692881)
			(xy 257.757026 -46.684941) (xy 257.812174 -46.684941) (xy 257.866746 -46.692881) (xy 257.919607 -46.708597)
			(xy 257.969654 -46.73176) (xy 258.015844 -46.761887) (xy 258.057215 -46.798352) (xy 258.07543 -46.819058)
			(xy 258.085328 -46.829956) (xy 258.109978 -46.846031) (xy 258.138186 -46.854415) (xy 258.167614 -46.854415)
			(xy 258.195822 -46.846031) (xy 258.220472 -46.829956) (xy 258.23037 -46.819058) (xy 258.248584 -46.79835)
			(xy 258.289953 -46.761881) (xy 258.336143 -46.73175) (xy 258.38619 -46.708584) (xy 258.439052 -46.692866)
			(xy 258.493626 -46.684925) (xy 258.5212 -46.684438) (xy 258.548455 -46.684832) (xy 258.602409 -46.692589)
			(xy 258.65471 -46.707946) (xy 258.704293 -46.73059) (xy 258.750149 -46.76006) (xy 258.791344 -46.795756)
			(xy 258.82704 -46.836951) (xy 258.85651 -46.882807) (xy 258.879154 -46.93239) (xy 258.894511 -46.984691)
			(xy 258.902268 -47.038645) (xy 258.902268 -47.093155) (xy 258.894511 -47.147109) (xy 258.879154 -47.19941)
			(xy 258.85651 -47.248993) (xy 258.82704 -47.294849) (xy 258.791344 -47.336044) (xy 258.750149 -47.37174)
			(xy 258.704293 -47.40121) (xy 258.65471 -47.423854) (xy 258.602409 -47.439211) (xy 258.548455 -47.446968)
			(xy 258.5212 -47.447454) (xy 258.493625 -47.447004) (xy 258.43905 -47.439051) (xy 258.38619 -47.423324)
			(xy 258.336143 -47.400151) (xy 258.289954 -47.370015) (xy 258.248585 -47.333543) (xy 258.23037 -47.312834)
			(xy 258.220472 -47.301936) (xy 258.195822 -47.285861) (xy 258.167614 -47.277477) (xy 258.138186 -47.277477)
			(xy 258.109978 -47.285861) (xy 258.085328 -47.301936) (xy 258.07543 -47.312834) (xy 258.057215 -47.33354)
			(xy 258.015844 -47.370005) (xy 257.969654 -47.400132) (xy 257.919607 -47.423295) (xy 257.866746 -47.439011)
			(xy 257.812174 -47.446951) (xy 257.757026 -47.446951) (xy 257.702454 -47.439011) (xy 257.649593 -47.423295)
			(xy 257.599546 -47.400132) (xy 257.553356 -47.370005) (xy 257.511985 -47.33354) (xy 257.49377 -47.312834)
			(xy 257.483872 -47.301936) (xy 257.459222 -47.285861) (xy 257.431014 -47.277477) (xy 257.401586 -47.277477)
			(xy 257.373378 -47.285861) (xy 257.348728 -47.301936) (xy 257.33883 -47.312834) (xy 257.320614 -47.333541)
			(xy 257.279246 -47.37001) (xy 257.233056 -47.400142) (xy 257.183009 -47.423308) (xy 257.130148 -47.439026)
			(xy 257.075574 -47.446967) (xy 257.048 -47.447454) (xy 257.020752 -47.446876) (xy 256.966811 -47.43912)
			(xy 256.914523 -47.423767) (xy 256.864951 -47.401129) (xy 256.819106 -47.371666) (xy 256.777921 -47.335979)
			(xy 256.742234 -47.294794) (xy 256.712771 -47.248949) (xy 256.690133 -47.199377) (xy 256.67478 -47.147089)
			(xy 256.667024 -47.093148) (xy 255.960891 -47.093148) (xy 255.960879 -47.093832) (xy 255.952759 -47.149008)
			(xy 255.936691 -47.202415) (xy 255.913019 -47.252912) (xy 255.882246 -47.299425) (xy 255.845029 -47.340962)
			(xy 255.802161 -47.376637) (xy 255.754555 -47.405691) (xy 255.703226 -47.427503) (xy 255.649269 -47.441609)
			(xy 255.593832 -47.447709) (xy 255.538098 -47.445672) (xy 255.483255 -47.435542) (xy 255.430471 -47.417535)
			(xy 255.380871 -47.392034) (xy 255.335513 -47.359583) (xy 255.295364 -47.320874) (xy 255.261278 -47.276731)
			(xy 255.233982 -47.228096) (xy 255.214059 -47.176005) (xy 255.201933 -47.121568) (xy 255.197862 -47.065946)
			(xy 255.072388 -47.065946) (xy 255.071879 -47.093832) (xy 255.063759 -47.149008) (xy 255.047691 -47.202415)
			(xy 255.024019 -47.252912) (xy 254.993246 -47.299425) (xy 254.956029 -47.340962) (xy 254.913161 -47.376637)
			(xy 254.865555 -47.405691) (xy 254.814226 -47.427503) (xy 254.760269 -47.441609) (xy 254.704832 -47.447709)
			(xy 254.649098 -47.445672) (xy 254.594255 -47.435542) (xy 254.541471 -47.417535) (xy 254.491871 -47.392034)
			(xy 254.446513 -47.359583) (xy 254.406364 -47.320874) (xy 254.372278 -47.276731) (xy 254.344982 -47.228096)
			(xy 254.325059 -47.176005) (xy 254.312933 -47.121568) (xy 254.308862 -47.065946) (xy 254.183388 -47.065946)
			(xy 254.182879 -47.093832) (xy 254.174759 -47.149008) (xy 254.158691 -47.202415) (xy 254.135019 -47.252912)
			(xy 254.104246 -47.299425) (xy 254.067029 -47.340962) (xy 254.024161 -47.376637) (xy 253.976555 -47.405691)
			(xy 253.925226 -47.427503) (xy 253.871269 -47.441609) (xy 253.815832 -47.447709) (xy 253.760098 -47.445672)
			(xy 253.705255 -47.435542) (xy 253.652471 -47.417535) (xy 253.602871 -47.392034) (xy 253.557513 -47.359583)
			(xy 253.517364 -47.320874) (xy 253.483278 -47.276731) (xy 253.455982 -47.228096) (xy 253.436059 -47.176005)
			(xy 253.423933 -47.121568) (xy 253.419862 -47.065946) (xy 251.9426 -47.065946) (xy 252.39726 -47.520606)
			(xy 252.39726 -48.386746) (xy 258.861812 -48.386746) (xy 258.865883 -48.331124) (xy 258.878009 -48.276687)
			(xy 258.897932 -48.224596) (xy 258.925228 -48.175961) (xy 258.959314 -48.131818) (xy 258.999463 -48.093109)
			(xy 259.044821 -48.060658) (xy 259.094421 -48.035157) (xy 259.147205 -48.01715) (xy 259.202048 -48.00702)
			(xy 259.257782 -48.004983) (xy 259.313219 -48.011083) (xy 259.367176 -48.025189) (xy 259.418505 -48.047001)
			(xy 259.466111 -48.076055) (xy 259.508979 -48.11173) (xy 259.546196 -48.153267) (xy 259.576969 -48.19978)
			(xy 259.600641 -48.250277) (xy 259.616709 -48.303684) (xy 259.624829 -48.35886) (xy 259.625338 -48.386746)
			(xy 259.624829 -48.414632) (xy 259.616709 -48.469808) (xy 259.600641 -48.523215) (xy 259.576969 -48.573712)
			(xy 259.546196 -48.620225) (xy 259.508979 -48.661762) (xy 259.466111 -48.697437) (xy 259.418505 -48.726491)
			(xy 259.367176 -48.748303) (xy 259.313219 -48.762409) (xy 259.257782 -48.768509) (xy 259.202048 -48.766472)
			(xy 259.147205 -48.756342) (xy 259.094421 -48.738335) (xy 259.044821 -48.712834) (xy 258.999463 -48.680383)
			(xy 258.959314 -48.641674) (xy 258.925228 -48.597531) (xy 258.897932 -48.548896) (xy 258.878009 -48.496805)
			(xy 258.865883 -48.442368) (xy 258.861812 -48.386746) (xy 252.39726 -48.386746) (xy 252.39726 -48.8165)
			(xy 253.187506 -48.8165) (xy 253.191489 -48.763355) (xy 253.203347 -48.711398) (xy 253.222817 -48.661788)
			(xy 253.249462 -48.615633) (xy 253.282689 -48.573965) (xy 253.321754 -48.537715) (xy 253.365786 -48.507691)
			(xy 253.4138 -48.484565) (xy 253.464725 -48.468853) (xy 253.517423 -48.460906) (xy 253.54407 -48.460406)
			(xy 253.57139 -48.460944) (xy 253.625391 -48.469278) (xy 253.677487 -48.485754) (xy 253.726459 -48.509989)
			(xy 253.771159 -48.541412) (xy 253.791212 -48.559974) (xy 253.802834 -48.570371) (xy 253.830768 -48.584195)
			(xy 253.86157 -48.588951) (xy 253.892372 -48.584195) (xy 253.920306 -48.570371) (xy 253.931928 -48.559974)
			(xy 253.951933 -48.541352) (xy 253.996629 -48.509898) (xy 254.04561 -48.485651) (xy 254.097723 -48.469181)
			(xy 254.151742 -48.460877) (xy 254.17907 -48.460406) (xy 254.205724 -48.460849) (xy 254.258436 -48.46879)
			(xy 254.309376 -48.484499) (xy 254.357406 -48.507625) (xy 254.401452 -48.537652) (xy 254.44053 -48.573909)
			(xy 254.473768 -48.615585) (xy 254.500423 -48.661749) (xy 254.5199 -48.711371) (xy 254.531762 -48.763342)
			(xy 254.535746 -48.8165) (xy 254.531762 -48.869658) (xy 254.5199 -48.921629) (xy 254.500423 -48.971251)
			(xy 254.473768 -49.017415) (xy 254.44053 -49.059091) (xy 254.401452 -49.095348) (xy 254.357406 -49.125375)
			(xy 254.309376 -49.148501) (xy 254.258436 -49.16421) (xy 254.205724 -49.172151) (xy 254.17907 -49.172622)
			(xy 254.151749 -49.172113) (xy 254.097747 -49.163771) (xy 254.045651 -49.147287) (xy 253.996679 -49.123047)
			(xy 253.95198 -49.091618) (xy 253.931928 -49.073054) (xy 253.920306 -49.062657) (xy 253.892372 -49.048833)
			(xy 253.86157 -49.044077) (xy 253.830768 -49.048833) (xy 253.802834 -49.062657) (xy 253.791212 -49.073054)
			(xy 253.771179 -49.091645) (xy 253.726492 -49.123106) (xy 253.677519 -49.14736) (xy 253.625411 -49.163837)
			(xy 253.571396 -49.172148) (xy 253.54407 -49.172622) (xy 253.517423 -49.172094) (xy 253.464725 -49.164147)
			(xy 253.4138 -49.148435) (xy 253.365786 -49.125309) (xy 253.321754 -49.095285) (xy 253.282689 -49.059035)
			(xy 253.249462 -49.017367) (xy 253.222817 -48.971212) (xy 253.203347 -48.921602) (xy 253.191489 -48.869645)
			(xy 253.187506 -48.8165) (xy 252.39726 -48.8165) (xy 252.39726 -49.7167) (xy 253.187482 -49.7167)
			(xy 253.191465 -49.663552) (xy 253.203324 -49.611591) (xy 253.222795 -49.561977) (xy 253.249442 -49.51582)
			(xy 253.282671 -49.474149) (xy 253.321739 -49.437896) (xy 253.365774 -49.40787) (xy 253.413792 -49.384742)
			(xy 253.46472 -49.369029) (xy 253.517421 -49.361082) (xy 253.54407 -49.360582) (xy 253.57139 -49.361126)
			(xy 253.62539 -49.36946) (xy 253.677486 -49.385935) (xy 253.726458 -49.410168) (xy 253.771159 -49.441589)
			(xy 253.791212 -49.46015) (xy 253.802834 -49.470547) (xy 253.830768 -49.484371) (xy 253.86157 -49.489127)
			(xy 253.892372 -49.484371) (xy 253.920306 -49.470547) (xy 253.931928 -49.46015) (xy 253.951945 -49.441541)
			(xy 253.996636 -49.410082) (xy 254.045613 -49.385831) (xy 254.097725 -49.369359) (xy 254.151743 -49.361053)
			(xy 254.17907 -49.360582) (xy 254.205722 -49.361073) (xy 254.258431 -49.369014) (xy 254.309367 -49.384722)
			(xy 254.357394 -49.407846) (xy 254.401437 -49.437871) (xy 254.440513 -49.474125) (xy 254.473748 -49.515798)
			(xy 254.500402 -49.56196) (xy 254.519877 -49.611578) (xy 254.531738 -49.663545) (xy 254.535722 -49.7167)
			(xy 254.531738 -49.769855) (xy 254.519877 -49.821822) (xy 254.500402 -49.87144) (xy 254.473748 -49.917602)
			(xy 254.440513 -49.959275) (xy 254.401437 -49.995529) (xy 254.357394 -50.025554) (xy 254.309367 -50.048678)
			(xy 254.258431 -50.064386) (xy 254.205722 -50.072327) (xy 254.17907 -50.072798) (xy 254.151749 -50.072296)
			(xy 254.097746 -50.063953) (xy 254.045649 -50.047468) (xy 253.996678 -50.023226) (xy 253.95198 -49.991795)
			(xy 253.931928 -49.97323) (xy 253.920306 -49.962833) (xy 253.892372 -49.949009) (xy 253.86157 -49.944253)
			(xy 253.830768 -49.949009) (xy 253.802834 -49.962833) (xy 253.791212 -49.97323) (xy 253.771191 -49.991834)
			(xy 253.7265 -50.02329) (xy 253.677523 -50.047541) (xy 253.625413 -50.064015) (xy 253.571396 -50.072324)
			(xy 253.54407 -50.072798) (xy 253.517421 -50.072318) (xy 253.46472 -50.064371) (xy 253.413792 -50.048658)
			(xy 253.365774 -50.02553) (xy 253.321739 -49.995504) (xy 253.282671 -49.959251) (xy 253.249442 -49.91758)
			(xy 253.222795 -49.871423) (xy 253.203324 -49.821809) (xy 253.191465 -49.769848) (xy 253.187482 -49.7167)
			(xy 252.39726 -49.7167) (xy 252.39726 -50.6166) (xy 253.187504 -50.6166) (xy 253.191487 -50.563455)
			(xy 253.203345 -50.511497) (xy 253.222815 -50.461887) (xy 253.249461 -50.415732) (xy 253.282687 -50.374064)
			(xy 253.321753 -50.337813) (xy 253.365785 -50.307789) (xy 253.4138 -50.284663) (xy 253.464725 -50.268951)
			(xy 253.517423 -50.261004) (xy 253.54407 -50.260504) (xy 253.57139 -50.261042) (xy 253.625391 -50.269376)
			(xy 253.677487 -50.285853) (xy 253.726459 -50.310087) (xy 253.771159 -50.34151) (xy 253.791212 -50.360072)
			(xy 253.802834 -50.370469) (xy 253.830768 -50.384293) (xy 253.86157 -50.389049) (xy 253.892372 -50.384293)
			(xy 253.920306 -50.370469) (xy 253.931928 -50.360072) (xy 253.951933 -50.341449) (xy 253.996628 -50.309995)
			(xy 254.045609 -50.285748) (xy 254.097723 -50.269279) (xy 254.151742 -50.260975) (xy 254.17907 -50.260504)
			(xy 254.205724 -50.260951) (xy 254.258436 -50.268892) (xy 254.309375 -50.284601) (xy 254.357405 -50.307727)
			(xy 254.40145 -50.337754) (xy 254.43235 -50.366422) (xy 255.680462 -50.366422) (xy 255.684533 -50.3108)
			(xy 255.696659 -50.256363) (xy 255.716582 -50.204272) (xy 255.743878 -50.155637) (xy 255.777964 -50.111494)
			(xy 255.818113 -50.072785) (xy 255.863471 -50.040334) (xy 255.913071 -50.014833) (xy 255.965855 -49.996826)
			(xy 256.020698 -49.986696) (xy 256.076432 -49.984659) (xy 256.131869 -49.990759) (xy 256.185826 -50.004865)
			(xy 256.237155 -50.026677) (xy 256.284761 -50.055731) (xy 256.327629 -50.091406) (xy 256.364846 -50.132943)
			(xy 256.395619 -50.179456) (xy 256.419291 -50.229953) (xy 256.435359 -50.28336) (xy 256.443479 -50.338536)
			(xy 256.443988 -50.366422) (xy 256.443479 -50.394308) (xy 256.435359 -50.449484) (xy 256.419291 -50.502891)
			(xy 256.395619 -50.553388) (xy 256.364846 -50.599901) (xy 256.327629 -50.641438) (xy 256.284761 -50.677113)
			(xy 256.237155 -50.706167) (xy 256.185826 -50.727979) (xy 256.131869 -50.742085) (xy 256.076432 -50.748185)
			(xy 256.020698 -50.746148) (xy 255.965855 -50.736018) (xy 255.913071 -50.718011) (xy 255.863471 -50.69251)
			(xy 255.818113 -50.660059) (xy 255.777964 -50.62135) (xy 255.743878 -50.577207) (xy 255.716582 -50.528572)
			(xy 255.696659 -50.476481) (xy 255.684533 -50.422044) (xy 255.680462 -50.366422) (xy 254.43235 -50.366422)
			(xy 254.440529 -50.37401) (xy 254.473767 -50.415686) (xy 254.500421 -50.46185) (xy 254.519898 -50.511472)
			(xy 254.53176 -50.563442) (xy 254.535744 -50.6166) (xy 254.53176 -50.669758) (xy 254.519898 -50.721728)
			(xy 254.500421 -50.77135) (xy 254.473767 -50.817514) (xy 254.440529 -50.85919) (xy 254.40145 -50.895446)
			(xy 254.357405 -50.925473) (xy 254.309375 -50.948599) (xy 254.258436 -50.964308) (xy 254.205724 -50.972249)
			(xy 254.17907 -50.97272) (xy 254.151749 -50.972212) (xy 254.097747 -50.96387) (xy 254.045651 -50.947386)
			(xy 253.996679 -50.923145) (xy 253.95198 -50.891716) (xy 253.931928 -50.873152) (xy 253.920306 -50.862755)
			(xy 253.892372 -50.848931) (xy 253.86157 -50.844175) (xy 253.830768 -50.848931) (xy 253.802834 -50.862755)
			(xy 253.791212 -50.873152) (xy 253.771179 -50.891743) (xy 253.726492 -50.923204) (xy 253.677519 -50.947458)
			(xy 253.625411 -50.963935) (xy 253.571396 -50.972246) (xy 253.54407 -50.97272) (xy 253.517423 -50.972196)
			(xy 253.464725 -50.964249) (xy 253.4138 -50.948537) (xy 253.365785 -50.925411) (xy 253.321753 -50.895387)
			(xy 253.282687 -50.859136) (xy 253.249461 -50.817468) (xy 253.222815 -50.771313) (xy 253.203345 -50.721703)
			(xy 253.191487 -50.669745) (xy 253.187504 -50.6166) (xy 252.39726 -50.6166) (xy 252.39726 -51.5165)
			(xy 253.187527 -51.5165) (xy 253.191509 -51.463358) (xy 253.203367 -51.411404) (xy 253.222835 -51.361797)
			(xy 253.249479 -51.315645) (xy 253.282704 -51.273979) (xy 253.321767 -51.237731) (xy 253.365796 -51.207709)
			(xy 253.413808 -51.184584) (xy 253.46473 -51.168873) (xy 253.517425 -51.160926) (xy 253.54407 -51.160426)
			(xy 253.57139 -51.160958) (xy 253.625392 -51.169293) (xy 253.677488 -51.18577) (xy 253.72646 -51.210006)
			(xy 253.77116 -51.241431) (xy 253.791212 -51.259994) (xy 253.802834 -51.270391) (xy 253.830768 -51.284215)
			(xy 253.86157 -51.288971) (xy 253.892372 -51.284215) (xy 253.920306 -51.270391) (xy 253.931928 -51.259994)
			(xy 253.951936 -51.241375) (xy 253.99663 -51.20992) (xy 254.045611 -51.185672) (xy 254.097724 -51.169202)
			(xy 254.151743 -51.160897) (xy 254.17907 -51.160426) (xy 254.205725 -51.160829) (xy 254.258441 -51.168771)
			(xy 254.309383 -51.184481) (xy 254.357416 -51.207608) (xy 254.401464 -51.237637) (xy 254.440545 -51.273895)
			(xy 254.473785 -51.315573) (xy 254.494197 -51.350926) (xy 256.493262 -51.350926) (xy 256.497333 -51.295304)
			(xy 256.509459 -51.240867) (xy 256.529382 -51.188776) (xy 256.556678 -51.140141) (xy 256.590764 -51.095998)
			(xy 256.630913 -51.057289) (xy 256.676271 -51.024838) (xy 256.725871 -50.999337) (xy 256.778655 -50.98133)
			(xy 256.833498 -50.9712) (xy 256.889232 -50.969163) (xy 256.944669 -50.975263) (xy 256.998626 -50.989369)
			(xy 257.049955 -51.011181) (xy 257.097561 -51.040235) (xy 257.140429 -51.07591) (xy 257.177646 -51.117447)
			(xy 257.208419 -51.16396) (xy 257.232091 -51.214457) (xy 257.248159 -51.267864) (xy 257.256279 -51.32304)
			(xy 257.256788 -51.350926) (xy 257.256279 -51.378812) (xy 257.248159 -51.433988) (xy 257.232091 -51.487395)
			(xy 257.208419 -51.537892) (xy 257.177646 -51.584405) (xy 257.140429 -51.625942) (xy 257.097561 -51.661617)
			(xy 257.049955 -51.690671) (xy 256.998626 -51.712483) (xy 256.944669 -51.726589) (xy 256.889232 -51.732689)
			(xy 256.833498 -51.730652) (xy 256.778655 -51.720522) (xy 256.725871 -51.702515) (xy 256.676271 -51.677014)
			(xy 256.630913 -51.644563) (xy 256.590764 -51.605854) (xy 256.556678 -51.561711) (xy 256.529382 -51.513076)
			(xy 256.509459 -51.460985) (xy 256.497333 -51.406548) (xy 256.493262 -51.350926) (xy 254.494197 -51.350926)
			(xy 254.500441 -51.361741) (xy 254.519919 -51.411365) (xy 254.531782 -51.463339) (xy 254.535766 -51.5165)
			(xy 254.531782 -51.569661) (xy 254.519919 -51.621635) (xy 254.500441 -51.671259) (xy 254.473785 -51.717427)
			(xy 254.440545 -51.759105) (xy 254.401464 -51.795363) (xy 254.357416 -51.825392) (xy 254.309383 -51.848519)
			(xy 254.258441 -51.864229) (xy 254.205725 -51.872171) (xy 254.17907 -51.872642) (xy 254.151748 -51.872156)
			(xy 254.097744 -51.863811) (xy 254.045646 -51.847323) (xy 253.996675 -51.823077) (xy 253.951978 -51.791642)
			(xy 253.931928 -51.773074) (xy 253.920306 -51.762677) (xy 253.892372 -51.748853) (xy 253.86157 -51.744097)
			(xy 253.830768 -51.748853) (xy 253.802834 -51.762677) (xy 253.791212 -51.773074) (xy 253.771182 -51.791668)
			(xy 253.726494 -51.823128) (xy 253.67752 -51.847382) (xy 253.625411 -51.863857) (xy 253.571396 -51.872168)
			(xy 253.54407 -51.872642) (xy 253.517425 -51.872074) (xy 253.46473 -51.864127) (xy 253.413808 -51.848416)
			(xy 253.365796 -51.825291) (xy 253.321767 -51.795269) (xy 253.282704 -51.759021) (xy 253.249479 -51.717355)
			(xy 253.222835 -51.671203) (xy 253.203367 -51.621596) (xy 253.191509 -51.569642) (xy 253.187527 -51.5165)
			(xy 252.39726 -51.5165) (xy 252.39726 -51.957986) (xy 252.01118 -52.344066) (xy 245.67642 -52.344066)
			(xy 245.08079 -52.939696) (xy 256.159252 -52.939696) (xy 256.163323 -52.884074) (xy 256.175449 -52.829637)
			(xy 256.195372 -52.777546) (xy 256.222668 -52.728911) (xy 256.256754 -52.684768) (xy 256.296903 -52.646059)
			(xy 256.342261 -52.613608) (xy 256.391861 -52.588107) (xy 256.444645 -52.5701) (xy 256.499488 -52.55997)
			(xy 256.555222 -52.557933) (xy 256.610659 -52.564033) (xy 256.664616 -52.578139) (xy 256.715945 -52.599951)
			(xy 256.763551 -52.629005) (xy 256.806419 -52.66468) (xy 256.843636 -52.706217) (xy 256.874409 -52.75273)
			(xy 256.898081 -52.803227) (xy 256.914149 -52.856634) (xy 256.922269 -52.91181) (xy 256.922778 -52.939696)
			(xy 256.922269 -52.967582) (xy 256.914149 -53.022758) (xy 256.898081 -53.076165) (xy 256.874409 -53.126662)
			(xy 256.843636 -53.173175) (xy 256.806419 -53.214712) (xy 256.763551 -53.250387) (xy 256.715945 -53.279441)
			(xy 256.664616 -53.301253) (xy 256.610659 -53.315359) (xy 256.555222 -53.321459) (xy 256.499488 -53.319422)
			(xy 256.444645 -53.309292) (xy 256.391861 -53.291285) (xy 256.342261 -53.265784) (xy 256.296903 -53.233333)
			(xy 256.256754 -53.194624) (xy 256.222668 -53.150481) (xy 256.195372 -53.101846) (xy 256.175449 -53.049755)
			(xy 256.163323 -52.995318) (xy 256.159252 -52.939696) (xy 245.08079 -52.939696) (xy 244.41658 -53.603906)
			(xy 253.772922 -53.603906) (xy 253.776993 -53.548284) (xy 253.789119 -53.493847) (xy 253.809042 -53.441756)
			(xy 253.836338 -53.393121) (xy 253.870424 -53.348978) (xy 253.910573 -53.310269) (xy 253.955931 -53.277818)
			(xy 254.005531 -53.252317) (xy 254.058315 -53.23431) (xy 254.113158 -53.22418) (xy 254.168892 -53.222143)
			(xy 254.224329 -53.228243) (xy 254.278286 -53.242349) (xy 254.329615 -53.264161) (xy 254.377221 -53.293215)
			(xy 254.420089 -53.32889) (xy 254.457306 -53.370427) (xy 254.488079 -53.41694) (xy 254.511751 -53.467437)
			(xy 254.527819 -53.520844) (xy 254.535939 -53.57602) (xy 254.536123 -53.586126) (xy 255.050542 -53.586126)
			(xy 255.054613 -53.530504) (xy 255.066739 -53.476067) (xy 255.086662 -53.423976) (xy 255.113958 -53.375341)
			(xy 255.148044 -53.331198) (xy 255.188193 -53.292489) (xy 255.233551 -53.260038) (xy 255.283151 -53.234537)
			(xy 255.335935 -53.21653) (xy 255.390778 -53.2064) (xy 255.446512 -53.204363) (xy 255.501949 -53.210463)
			(xy 255.555906 -53.224569) (xy 255.607235 -53.246381) (xy 255.654841 -53.275435) (xy 255.697709 -53.31111)
			(xy 255.734926 -53.352647) (xy 255.765699 -53.39916) (xy 255.789371 -53.449657) (xy 255.805439 -53.503064)
			(xy 255.813559 -53.55824) (xy 255.814068 -53.586126) (xy 255.813559 -53.614012) (xy 255.805439 -53.669188)
			(xy 255.789371 -53.722595) (xy 255.765699 -53.773092) (xy 255.734926 -53.819605) (xy 255.697709 -53.861142)
			(xy 255.654841 -53.896817) (xy 255.607235 -53.925871) (xy 255.555906 -53.947683) (xy 255.501949 -53.961789)
			(xy 255.446512 -53.967889) (xy 255.390778 -53.965852) (xy 255.335935 -53.955722) (xy 255.283151 -53.937715)
			(xy 255.233551 -53.912214) (xy 255.188193 -53.879763) (xy 255.148044 -53.841054) (xy 255.113958 -53.796911)
			(xy 255.086662 -53.748276) (xy 255.066739 -53.696185) (xy 255.054613 -53.641748) (xy 255.050542 -53.586126)
			(xy 254.536123 -53.586126) (xy 254.536448 -53.603906) (xy 254.535939 -53.631792) (xy 254.527819 -53.686968)
			(xy 254.511751 -53.740375) (xy 254.488079 -53.790872) (xy 254.457306 -53.837385) (xy 254.420089 -53.878922)
			(xy 254.377221 -53.914597) (xy 254.329615 -53.943651) (xy 254.278286 -53.965463) (xy 254.224329 -53.979569)
			(xy 254.168892 -53.985669) (xy 254.113158 -53.983632) (xy 254.058315 -53.973502) (xy 254.005531 -53.955495)
			(xy 253.955931 -53.929994) (xy 253.910573 -53.897543) (xy 253.870424 -53.858834) (xy 253.836338 -53.814691)
			(xy 253.809042 -53.766056) (xy 253.789119 -53.713965) (xy 253.776993 -53.659528) (xy 253.772922 -53.603906)
			(xy 244.41658 -53.603906) (xy 244.37848 -53.642006) (xy 244.37848 -54.381146) (xy 258.64769 -54.381146)
			(xy 258.651761 -54.325524) (xy 258.663887 -54.271087) (xy 258.68381 -54.218996) (xy 258.711106 -54.170361)
			(xy 258.745192 -54.126218) (xy 258.785341 -54.087509) (xy 258.830699 -54.055058) (xy 258.880299 -54.029557)
			(xy 258.933083 -54.01155) (xy 258.987926 -54.00142) (xy 259.04366 -53.999383) (xy 259.099097 -54.005483)
			(xy 259.153054 -54.019589) (xy 259.204383 -54.041401) (xy 259.251989 -54.070455) (xy 259.294857 -54.10613)
			(xy 259.332074 -54.147667) (xy 259.362847 -54.19418) (xy 259.386519 -54.244677) (xy 259.402587 -54.298084)
			(xy 259.410707 -54.35326) (xy 259.411216 -54.381146) (xy 259.410707 -54.409032) (xy 259.402587 -54.464208)
			(xy 259.386519 -54.517615) (xy 259.362847 -54.568112) (xy 259.332074 -54.614625) (xy 259.294857 -54.656162)
			(xy 259.251989 -54.691837) (xy 259.204383 -54.720891) (xy 259.153054 -54.742703) (xy 259.099097 -54.756809)
			(xy 259.04366 -54.762909) (xy 258.987926 -54.760872) (xy 258.933083 -54.750742) (xy 258.880299 -54.732735)
			(xy 258.830699 -54.707234) (xy 258.785341 -54.674783) (xy 258.745192 -54.636074) (xy 258.711106 -54.591931)
			(xy 258.68381 -54.543296) (xy 258.663887 -54.491205) (xy 258.651761 -54.436768) (xy 258.64769 -54.381146)
			(xy 244.37848 -54.381146) (xy 244.37848 -55.022242) (xy 248.993912 -55.022242) (xy 248.997983 -54.96662)
			(xy 249.010109 -54.912183) (xy 249.030032 -54.860092) (xy 249.057328 -54.811457) (xy 249.091414 -54.767314)
			(xy 249.131563 -54.728605) (xy 249.176921 -54.696154) (xy 249.226521 -54.670653) (xy 249.279305 -54.652646)
			(xy 249.334148 -54.642516) (xy 249.389882 -54.640479) (xy 249.445319 -54.646579) (xy 249.499276 -54.660685)
			(xy 249.550605 -54.682497) (xy 249.598211 -54.711551) (xy 249.641079 -54.747226) (xy 249.678296 -54.788763)
			(xy 249.709069 -54.835276) (xy 249.732741 -54.885773) (xy 249.748809 -54.93918) (xy 249.756929 -54.994356)
			(xy 249.757438 -55.022242) (xy 249.756929 -55.050128) (xy 249.753557 -55.073042) (xy 251.127512 -55.073042)
			(xy 251.131583 -55.01742) (xy 251.143709 -54.962983) (xy 251.163632 -54.910892) (xy 251.190928 -54.862257)
			(xy 251.225014 -54.818114) (xy 251.265163 -54.779405) (xy 251.310521 -54.746954) (xy 251.360121 -54.721453)
			(xy 251.412905 -54.703446) (xy 251.467748 -54.693316) (xy 251.523482 -54.691279) (xy 251.578919 -54.697379)
			(xy 251.632876 -54.711485) (xy 251.684205 -54.733297) (xy 251.731811 -54.762351) (xy 251.774679 -54.798026)
			(xy 251.811896 -54.839563) (xy 251.842669 -54.886076) (xy 251.866341 -54.936573) (xy 251.882409 -54.98998)
			(xy 251.890529 -55.045156) (xy 251.891038 -55.073042) (xy 251.890529 -55.100928) (xy 251.882409 -55.156104)
			(xy 251.866341 -55.209511) (xy 251.842669 -55.260008) (xy 251.811896 -55.306521) (xy 251.774679 -55.348058)
			(xy 251.731811 -55.383733) (xy 251.684205 -55.412787) (xy 251.632876 -55.434599) (xy 251.578919 -55.448705)
			(xy 251.523482 -55.454805) (xy 251.467748 -55.452768) (xy 251.412905 -55.442638) (xy 251.360121 -55.424631)
			(xy 251.310521 -55.39913) (xy 251.265163 -55.366679) (xy 251.225014 -55.32797) (xy 251.190928 -55.283827)
			(xy 251.163632 -55.235192) (xy 251.143709 -55.183101) (xy 251.131583 -55.128664) (xy 251.127512 -55.073042)
			(xy 249.753557 -55.073042) (xy 249.748809 -55.105304) (xy 249.732741 -55.158711) (xy 249.709069 -55.209208)
			(xy 249.678296 -55.255721) (xy 249.641079 -55.297258) (xy 249.598211 -55.332933) (xy 249.550605 -55.361987)
			(xy 249.499276 -55.383799) (xy 249.445319 -55.397905) (xy 249.389882 -55.404005) (xy 249.334148 -55.401968)
			(xy 249.279305 -55.391838) (xy 249.226521 -55.373831) (xy 249.176921 -55.34833) (xy 249.131563 -55.315879)
			(xy 249.091414 -55.27717) (xy 249.057328 -55.233027) (xy 249.030032 -55.184392) (xy 249.010109 -55.132301)
			(xy 248.997983 -55.077864) (xy 248.993912 -55.022242) (xy 244.37848 -55.022242) (xy 244.37848 -55.854092)
			(xy 253.921512 -55.854092) (xy 253.925583 -55.79847) (xy 253.937709 -55.744033) (xy 253.957632 -55.691942)
			(xy 253.984928 -55.643307) (xy 254.019014 -55.599164) (xy 254.059163 -55.560455) (xy 254.104521 -55.528004)
			(xy 254.154121 -55.502503) (xy 254.206905 -55.484496) (xy 254.261748 -55.474366) (xy 254.317482 -55.472329)
			(xy 254.372919 -55.478429) (xy 254.376794 -55.479442) (xy 258.534152 -55.479442) (xy 258.538223 -55.42382)
			(xy 258.550349 -55.369383) (xy 258.570272 -55.317292) (xy 258.597568 -55.268657) (xy 258.631654 -55.224514)
			(xy 258.671803 -55.185805) (xy 258.717161 -55.153354) (xy 258.766761 -55.127853) (xy 258.819545 -55.109846)
			(xy 258.874388 -55.099716) (xy 258.930122 -55.097679) (xy 258.985559 -55.103779) (xy 259.039516 -55.117885)
			(xy 259.090845 -55.139697) (xy 259.138451 -55.168751) (xy 259.181319 -55.204426) (xy 259.218536 -55.245963)
			(xy 259.249309 -55.292476) (xy 259.272981 -55.342973) (xy 259.289049 -55.39638) (xy 259.297169 -55.451556)
			(xy 259.297678 -55.479442) (xy 259.297169 -55.507328) (xy 259.289049 -55.562504) (xy 259.272981 -55.615911)
			(xy 259.249309 -55.666408) (xy 259.218536 -55.712921) (xy 259.181319 -55.754458) (xy 259.138451 -55.790133)
			(xy 259.090845 -55.819187) (xy 259.039516 -55.840999) (xy 258.985559 -55.855105) (xy 258.930122 -55.861205)
			(xy 258.874388 -55.859168) (xy 258.819545 -55.849038) (xy 258.766761 -55.831031) (xy 258.717161 -55.80553)
			(xy 258.671803 -55.773079) (xy 258.631654 -55.73437) (xy 258.597568 -55.690227) (xy 258.570272 -55.641592)
			(xy 258.550349 -55.589501) (xy 258.538223 -55.535064) (xy 258.534152 -55.479442) (xy 254.376794 -55.479442)
			(xy 254.426876 -55.492535) (xy 254.478205 -55.514347) (xy 254.525811 -55.543401) (xy 254.568679 -55.579076)
			(xy 254.605896 -55.620613) (xy 254.636669 -55.667126) (xy 254.660341 -55.717623) (xy 254.676409 -55.77103)
			(xy 254.684529 -55.826206) (xy 254.685038 -55.854092) (xy 254.684529 -55.881978) (xy 254.676409 -55.937154)
			(xy 254.660341 -55.990561) (xy 254.636669 -56.041058) (xy 254.605896 -56.087571) (xy 254.568679 -56.129108)
			(xy 254.525811 -56.164783) (xy 254.478205 -56.193837) (xy 254.426876 -56.215649) (xy 254.372919 -56.229755)
			(xy 254.317482 -56.235855) (xy 254.261748 -56.233818) (xy 254.206905 -56.223688) (xy 254.154121 -56.205681)
			(xy 254.104521 -56.18018) (xy 254.059163 -56.147729) (xy 254.019014 -56.10902) (xy 253.984928 -56.064877)
			(xy 253.957632 -56.016242) (xy 253.937709 -55.964151) (xy 253.925583 -55.909714) (xy 253.921512 -55.854092)
			(xy 244.37848 -55.854092) (xy 244.37848 -56.413146) (xy 244.460776 -56.495442) (xy 258.534152 -56.495442)
			(xy 258.538223 -56.43982) (xy 258.550349 -56.385383) (xy 258.570272 -56.333292) (xy 258.597568 -56.284657)
			(xy 258.631654 -56.240514) (xy 258.671803 -56.201805) (xy 258.717161 -56.169354) (xy 258.766761 -56.143853)
			(xy 258.819545 -56.125846) (xy 258.874388 -56.115716) (xy 258.930122 -56.113679) (xy 258.985559 -56.119779)
			(xy 259.039516 -56.133885) (xy 259.090845 -56.155697) (xy 259.138451 -56.184751) (xy 259.181319 -56.220426)
			(xy 259.218536 -56.261963) (xy 259.249309 -56.308476) (xy 259.272981 -56.358973) (xy 259.289049 -56.41238)
			(xy 259.297169 -56.467556) (xy 259.297678 -56.495442) (xy 259.297169 -56.523328) (xy 259.289049 -56.578504)
			(xy 259.272981 -56.631911) (xy 259.249309 -56.682408) (xy 259.218536 -56.728921) (xy 259.181319 -56.770458)
			(xy 259.138451 -56.806133) (xy 259.090845 -56.835187) (xy 259.039516 -56.856999) (xy 258.985559 -56.871105)
			(xy 258.930122 -56.877205) (xy 258.874388 -56.875168) (xy 258.819545 -56.865038) (xy 258.766761 -56.847031)
			(xy 258.717161 -56.82153) (xy 258.671803 -56.789079) (xy 258.631654 -56.75037) (xy 258.597568 -56.706227)
			(xy 258.570272 -56.657592) (xy 258.550349 -56.605501) (xy 258.538223 -56.551064) (xy 258.534152 -56.495442)
			(xy 244.460776 -56.495442) (xy 245.476776 -57.511442) (xy 258.578602 -57.511442) (xy 258.582673 -57.45582)
			(xy 258.594799 -57.401383) (xy 258.614722 -57.349292) (xy 258.642018 -57.300657) (xy 258.676104 -57.256514)
			(xy 258.716253 -57.217805) (xy 258.761611 -57.185354) (xy 258.811211 -57.159853) (xy 258.863995 -57.141846)
			(xy 258.918838 -57.131716) (xy 258.974572 -57.129679) (xy 259.030009 -57.135779) (xy 259.083966 -57.149885)
			(xy 259.135295 -57.171697) (xy 259.182901 -57.200751) (xy 259.225769 -57.236426) (xy 259.262986 -57.277963)
			(xy 259.293759 -57.324476) (xy 259.317431 -57.374973) (xy 259.333499 -57.42838) (xy 259.341619 -57.483556)
			(xy 259.342128 -57.511442) (xy 259.341619 -57.539328) (xy 259.333499 -57.594504) (xy 259.317431 -57.647911)
			(xy 259.293759 -57.698408) (xy 259.262986 -57.744921) (xy 259.225769 -57.786458) (xy 259.182901 -57.822133)
			(xy 259.135295 -57.851187) (xy 259.083966 -57.872999) (xy 259.030009 -57.887105) (xy 258.974572 -57.893205)
			(xy 258.918838 -57.891168) (xy 258.863995 -57.881038) (xy 258.811211 -57.863031) (xy 258.761611 -57.83753)
			(xy 258.716253 -57.805079) (xy 258.676104 -57.76637) (xy 258.642018 -57.722227) (xy 258.614722 -57.673592)
			(xy 258.594799 -57.621501) (xy 258.582673 -57.567064) (xy 258.578602 -57.511442) (xy 245.476776 -57.511442)
			(xy 246.513881 -58.548547) (xy 254.919524 -58.548547) (xy 254.919524 -58.494053) (xy 254.927279 -58.440114)
			(xy 254.942631 -58.387827) (xy 254.965268 -58.338257) (xy 254.994729 -58.292413) (xy 255.030414 -58.251228)
			(xy 255.071597 -58.215541) (xy 255.117439 -58.186078) (xy 255.167008 -58.163438) (xy 255.219294 -58.148083)
			(xy 255.273233 -58.140326) (xy 255.30048 -58.139838) (xy 255.325411 -58.140271) (xy 255.37485 -58.146749)
			(xy 255.423024 -58.159611) (xy 255.469112 -58.178637) (xy 255.51233 -58.203504) (xy 255.532382 -58.218324)
			(xy 255.543442 -58.226213) (xy 255.568586 -58.236467) (xy 255.595544 -58.239725) (xy 255.622407 -58.235758)
			(xy 255.647272 -58.224845) (xy 255.668379 -58.20776) (xy 255.676654 -58.196988) (xy 255.692073 -58.176275)
			(xy 255.727596 -58.138799) (xy 255.767852 -58.106459) (xy 255.812103 -58.079846) (xy 255.859541 -58.059448)
			(xy 255.909297 -58.045638) (xy 255.960461 -58.038668) (xy 255.98628 -58.038238) (xy 256.013537 -58.038608)
			(xy 256.067497 -58.046363) (xy 256.119803 -58.061719) (xy 256.169392 -58.084363) (xy 256.215253 -58.113835)
			(xy 256.256453 -58.149533) (xy 256.292153 -58.190731) (xy 256.321627 -58.23659) (xy 256.344274 -58.286178)
			(xy 256.359633 -58.338484) (xy 256.360361 -58.343546) (xy 256.594862 -58.343546) (xy 256.598933 -58.287924)
			(xy 256.611059 -58.233487) (xy 256.630982 -58.181396) (xy 256.658278 -58.132761) (xy 256.692364 -58.088618)
			(xy 256.732513 -58.049909) (xy 256.777871 -58.017458) (xy 256.827471 -57.991957) (xy 256.880255 -57.97395)
			(xy 256.935098 -57.96382) (xy 256.990832 -57.961783) (xy 257.046269 -57.967883) (xy 257.100226 -57.981989)
			(xy 257.151555 -58.003801) (xy 257.199161 -58.032855) (xy 257.242029 -58.06853) (xy 257.279246 -58.110067)
			(xy 257.310019 -58.15658) (xy 257.333691 -58.207077) (xy 257.349759 -58.260484) (xy 257.357879 -58.31566)
			(xy 257.358388 -58.343546) (xy 257.357879 -58.371432) (xy 257.349759 -58.426608) (xy 257.333691 -58.480015)
			(xy 257.310019 -58.530512) (xy 257.279246 -58.577025) (xy 257.242029 -58.618562) (xy 257.199161 -58.654237)
			(xy 257.151555 -58.683291) (xy 257.100226 -58.705103) (xy 257.046269 -58.719209) (xy 256.990832 -58.725309)
			(xy 256.935098 -58.723272) (xy 256.880255 -58.713142) (xy 256.827471 -58.695135) (xy 256.777871 -58.669634)
			(xy 256.732513 -58.637183) (xy 256.692364 -58.598474) (xy 256.658278 -58.554331) (xy 256.630982 -58.505696)
			(xy 256.611059 -58.453605) (xy 256.598933 -58.399168) (xy 256.594862 -58.343546) (xy 256.360361 -58.343546)
			(xy 256.367391 -58.392443) (xy 256.367391 -58.446957) (xy 256.359633 -58.500916) (xy 256.344274 -58.553222)
			(xy 256.321627 -58.60281) (xy 256.292153 -58.648669) (xy 256.256453 -58.689867) (xy 256.215253 -58.725565)
			(xy 256.169392 -58.755037) (xy 256.119803 -58.777681) (xy 256.067497 -58.793037) (xy 256.013537 -58.800792)
			(xy 255.98628 -58.801254) (xy 255.961348 -58.800845) (xy 255.911909 -58.794361) (xy 255.863734 -58.781494)
			(xy 255.817646 -58.762462) (xy 255.774429 -58.737591) (xy 255.754378 -58.722768) (xy 255.743346 -58.714837)
			(xy 255.718192 -58.704589) (xy 255.691227 -58.701338) (xy 255.664358 -58.705314) (xy 255.63949 -58.716235)
			(xy 255.618382 -58.733328) (xy 255.610106 -58.744104) (xy 255.594648 -58.764787) (xy 255.559132 -58.802265)
			(xy 255.518883 -58.834607) (xy 255.474638 -58.861223) (xy 255.427207 -58.881626) (xy 255.377456 -58.895443)
			(xy 255.326297 -58.90242) (xy 255.30048 -58.902854) (xy 255.273233 -58.902274) (xy 255.219294 -58.894517)
			(xy 255.167008 -58.879162) (xy 255.117439 -58.856522) (xy 255.071597 -58.827059) (xy 255.030414 -58.791372)
			(xy 254.994729 -58.750187) (xy 254.965268 -58.704343) (xy 254.942631 -58.654773) (xy 254.927279 -58.602486)
			(xy 254.919524 -58.548547) (xy 246.513881 -58.548547) (xy 247.24868 -59.283346) (xy 257.268472 -59.283346)
		)
		(stroke
			(width 0)
			(type solid)
		)
		(fill yes)
		(layer "In15.Cu")
		(net "GND")
	)
	(gr_poly
		(pts
			(xy 225.63328 -399.06194) (xy 228.8159 -399.06194) (xy 230.44404 -400.69008) (xy 238.6457 -400.69008)
			(xy 239.12068 -400.2151) (xy 239.12068 -396.77848) (xy 239.45596 -396.4432) (xy 278.66848 -396.4432)
			(xy 279.10282 -396.00886) (xy 279.10282 -395.353032) (xy 279.07758 -395.319628) (xy 279.032791 -395.248884)
			(xy 278.994851 -395.174243) (xy 278.964096 -395.096366) (xy 278.9408 -395.015942) (xy 278.925167 -394.933684)
			(xy 278.917337 -394.850321) (xy 278.916892 -394.808456) (xy 278.917365 -394.766593) (xy 278.925213 -394.683236)
			(xy 278.940856 -394.600984) (xy 278.964154 -394.520565) (xy 278.994902 -394.442689) (xy 279.032827 -394.368046)
			(xy 279.077596 -394.297294) (xy 279.10282 -394.26388) (xy 279.10282 -389.885428) (xy 273.561302 -384.34391)
			(xy 273.55169 -384.334865) (xy 273.528887 -384.321595) (xy 273.50344 -384.314628) (xy 273.477058 -384.314432)
			(xy 273.45151 -384.321021) (xy 273.428513 -384.333952) (xy 273.418808 -384.342894) (xy 273.387711 -384.372409)
			(xy 273.320768 -384.425981) (xy 273.24898 -384.472864) (xy 273.173016 -384.512624) (xy 273.093578 -384.54489)
			(xy 273.011405 -384.569364) (xy 272.927258 -384.585818) (xy 272.841918 -384.594101) (xy 272.799048 -384.594608)
			(xy 272.79854 -384.594608) (xy 272.757436 -384.59415) (xy 272.675577 -384.586568) (xy 272.594768 -384.571465)
			(xy 272.515697 -384.548971) (xy 272.439038 -384.519276) (xy 272.365447 -384.482635) (xy 272.29555 -384.43936)
			(xy 272.229945 -384.38982) (xy 272.169191 -384.334437) (xy 272.113806 -384.273686) (xy 272.064263 -384.208083)
			(xy 272.020985 -384.138188) (xy 271.98434 -384.064598) (xy 271.954642 -383.987941) (xy 271.932144 -383.908871)
			(xy 271.917038 -383.828062) (xy 271.909452 -383.746204) (xy 271.909032 -383.7051) (xy 271.909032 -383.704592)
			(xy 271.909555 -383.661722) (xy 271.917827 -383.57638) (xy 271.934273 -383.492231) (xy 271.958741 -383.410056)
			(xy 271.991005 -383.330616) (xy 272.030763 -383.25465) (xy 272.077648 -383.182864) (xy 272.131224 -383.115922)
			(xy 272.160746 -383.084832) (xy 272.169607 -383.075073) (xy 272.182472 -383.052076) (xy 272.189029 -383.026554)
			(xy 272.188841 -383.000205) (xy 272.181922 -382.974779) (xy 272.168732 -382.951967) (xy 272.15973 -382.942338)
			(xy 258.70408 -369.486688) (xy 233.37774 -369.486688) (xy 230.124 -366.232948) (xy 173.8884 -366.232948)
			(xy 173.4312 -365.775748) (xy 173.4312 -361.991148) (xy 172.9994 -361.559348) (xy 167.8178 -361.559348)
			(xy 167.3098 -362.067348) (xy 167.3098 -368.557048) (xy 167.537382 -368.557048) (xy 167.541453 -368.501426)
			(xy 167.553579 -368.446989) (xy 167.573502 -368.394898) (xy 167.600798 -368.346263) (xy 167.634884 -368.30212)
			(xy 167.675033 -368.263411) (xy 167.720391 -368.23096) (xy 167.769991 -368.205459) (xy 167.822775 -368.187452)
			(xy 167.877618 -368.177322) (xy 167.933352 -368.175285) (xy 167.988789 -368.181385) (xy 168.042746 -368.195491)
			(xy 168.094075 -368.217303) (xy 168.141681 -368.246357) (xy 168.184549 -368.282032) (xy 168.221766 -368.323569)
			(xy 168.252539 -368.370082) (xy 168.276211 -368.420579) (xy 168.292279 -368.473986) (xy 168.300399 -368.529162)
			(xy 168.300908 -368.557048) (xy 168.300399 -368.584934) (xy 168.292279 -368.64011) (xy 168.276211 -368.693517)
			(xy 168.252539 -368.744014) (xy 168.221766 -368.790527) (xy 168.184549 -368.832064) (xy 168.141681 -368.867739)
			(xy 168.094075 -368.896793) (xy 168.042746 -368.918605) (xy 167.988789 -368.932711) (xy 167.933352 -368.938811)
			(xy 167.877618 -368.936774) (xy 167.822775 -368.926644) (xy 167.769991 -368.908637) (xy 167.720391 -368.883136)
			(xy 167.675033 -368.850685) (xy 167.634884 -368.811976) (xy 167.600798 -368.767833) (xy 167.573502 -368.719198)
			(xy 167.553579 -368.667107) (xy 167.541453 -368.61267) (xy 167.537382 -368.557048) (xy 167.3098 -368.557048)
			(xy 167.3098 -369.171728) (xy 167.285924 -369.195604) (xy 167.285924 -386.144713) (xy 269.99209 -386.144713)
			(xy 269.99209 -386.059991) (xy 270.000143 -385.975654) (xy 270.016177 -385.892464) (xy 270.040045 -385.811174)
			(xy 270.071533 -385.732522) (xy 270.110355 -385.657219) (xy 270.156158 -385.585947) (xy 270.208529 -385.519351)
			(xy 270.266994 -385.458036) (xy 270.331022 -385.402555) (xy 270.400034 -385.353412) (xy 270.473404 -385.311052)
			(xy 270.550469 -385.275857) (xy 270.630531 -385.248148) (xy 270.712864 -385.228174) (xy 270.796723 -385.216117)
			(xy 270.881348 -385.212086) (xy 270.965973 -385.216117) (xy 271.049832 -385.228174) (xy 271.132165 -385.248148)
			(xy 271.212227 -385.275857) (xy 271.289292 -385.311052) (xy 271.362662 -385.353412) (xy 271.431674 -385.402555)
			(xy 271.495702 -385.458036) (xy 271.554167 -385.519351) (xy 271.606538 -385.585947) (xy 271.652341 -385.657219)
			(xy 271.691163 -385.732522) (xy 271.722651 -385.811174) (xy 271.746519 -385.892464) (xy 271.762553 -385.975654)
			(xy 271.770606 -386.059991) (xy 271.77111 -386.102352) (xy 271.770606 -386.144713) (xy 271.762553 -386.22905)
			(xy 271.746519 -386.31224) (xy 271.722651 -386.39353) (xy 271.691163 -386.472182) (xy 271.652341 -386.547485)
			(xy 271.606538 -386.618757) (xy 271.554167 -386.685353) (xy 271.495702 -386.746668) (xy 271.431674 -386.802149)
			(xy 271.362662 -386.851292) (xy 271.289292 -386.893652) (xy 271.212227 -386.928847) (xy 271.132165 -386.956556)
			(xy 271.049832 -386.97653) (xy 270.965973 -386.988587) (xy 270.881348 -386.992619) (xy 270.796723 -386.988587)
			(xy 270.712864 -386.97653) (xy 270.630531 -386.956556) (xy 270.550469 -386.928847) (xy 270.473404 -386.893652)
			(xy 270.400034 -386.851292) (xy 270.331022 -386.802149) (xy 270.266994 -386.746668) (xy 270.208529 -386.685353)
			(xy 270.156158 -386.618757) (xy 270.110355 -386.547485) (xy 270.071533 -386.472182) (xy 270.040045 -386.39353)
			(xy 270.016177 -386.31224) (xy 270.000143 -386.22905) (xy 269.99209 -386.144713) (xy 167.285924 -386.144713)
			(xy 167.285924 -387.641592) (xy 167.657272 -388.01294) (xy 233.776012 -388.01294) (xy 233.776499 -387.98557)
			(xy 233.784311 -387.931392) (xy 233.799795 -387.878889) (xy 233.822632 -387.829142) (xy 233.852353 -387.783174)
			(xy 233.869992 -387.762242) (xy 233.879191 -387.750886) (xy 233.891374 -387.724339) (xy 233.895555 -387.69543)
			(xy 233.891391 -387.666519) (xy 233.879224 -387.639965) (xy 233.869992 -387.628638) (xy 233.852356 -387.607703)
			(xy 233.822644 -387.561731) (xy 233.799808 -387.511984) (xy 233.784316 -387.459484) (xy 233.776487 -387.405309)
			(xy 233.776012 -387.37794) (xy 233.776493 -387.350687) (xy 233.784245 -387.296736) (xy 233.799597 -387.244437)
			(xy 233.822236 -387.194856) (xy 233.851702 -387.149002) (xy 233.887394 -387.107808) (xy 233.928585 -387.072114)
			(xy 233.974438 -387.042645) (xy 234.024018 -387.020004) (xy 234.076316 -387.004649) (xy 234.130267 -386.996894)
			(xy 234.15752 -386.996432) (xy 234.184891 -386.996879) (xy 234.239071 -387.0047) (xy 234.291575 -387.020193)
			(xy 234.341321 -387.043039) (xy 234.387287 -387.072769) (xy 234.408218 -387.090412) (xy 234.419546 -387.099648)
			(xy 234.446103 -387.111824) (xy 234.47502 -387.115997) (xy 234.503937 -387.111824) (xy 234.530494 -387.099648)
			(xy 234.541822 -387.090412) (xy 234.562755 -387.072771) (xy 234.608723 -387.043047) (xy 234.658469 -387.020201)
			(xy 234.710971 -387.004705) (xy 234.765149 -386.996876) (xy 234.819891 -386.996876) (xy 234.874069 -387.004705)
			(xy 234.926571 -387.020201) (xy 234.976317 -387.043047) (xy 235.022285 -387.072771) (xy 235.043218 -387.090412)
			(xy 235.054546 -387.099648) (xy 235.081103 -387.111824) (xy 235.11002 -387.115997) (xy 235.138937 -387.111824)
			(xy 235.165494 -387.099648) (xy 235.176822 -387.090412) (xy 235.197755 -387.072771) (xy 235.243723 -387.043047)
			(xy 235.293469 -387.020201) (xy 235.345971 -387.004705) (xy 235.400149 -386.996876) (xy 235.454891 -386.996876)
			(xy 235.509069 -387.004705) (xy 235.561571 -387.020201) (xy 235.611317 -387.043047) (xy 235.657285 -387.072771)
			(xy 235.678218 -387.090412) (xy 235.689546 -387.099648) (xy 235.716103 -387.111824) (xy 235.74502 -387.115997)
			(xy 235.773937 -387.111824) (xy 235.800494 -387.099648) (xy 235.811822 -387.090412) (xy 235.832755 -387.072771)
			(xy 235.878723 -387.043047) (xy 235.928469 -387.020201) (xy 235.980971 -387.004705) (xy 236.035149 -386.996876)
			(xy 236.089891 -386.996876) (xy 236.144069 -387.004705) (xy 236.196571 -387.020201) (xy 236.246317 -387.043047)
			(xy 236.292285 -387.072771) (xy 236.313218 -387.090412) (xy 236.324546 -387.099648) (xy 236.351103 -387.111824)
			(xy 236.38002 -387.115997) (xy 236.408937 -387.111824) (xy 236.435494 -387.099648) (xy 236.446822 -387.090412)
			(xy 236.467755 -387.072771) (xy 236.513723 -387.043047) (xy 236.563469 -387.020201) (xy 236.615971 -387.004705)
			(xy 236.670149 -386.996876) (xy 236.724891 -386.996876) (xy 236.779069 -387.004705) (xy 236.831571 -387.020201)
			(xy 236.881317 -387.043047) (xy 236.927285 -387.072771) (xy 236.948218 -387.090412) (xy 236.959546 -387.099648)
			(xy 236.986103 -387.111824) (xy 237.01502 -387.115997) (xy 237.043937 -387.111824) (xy 237.070494 -387.099648)
			(xy 237.081822 -387.090412) (xy 237.102755 -387.072771) (xy 237.148723 -387.043047) (xy 237.198469 -387.020201)
			(xy 237.250971 -387.004705) (xy 237.305149 -386.996876) (xy 237.359891 -386.996876) (xy 237.414069 -387.004705)
			(xy 237.466571 -387.020201) (xy 237.516317 -387.043047) (xy 237.562285 -387.072771) (xy 237.583218 -387.090412)
			(xy 237.594546 -387.099648) (xy 237.621103 -387.111824) (xy 237.65002 -387.115997) (xy 237.678937 -387.111824)
			(xy 237.705494 -387.099648) (xy 237.716822 -387.090412) (xy 237.737755 -387.072771) (xy 237.783723 -387.043047)
			(xy 237.833469 -387.020201) (xy 237.885971 -387.004705) (xy 237.940149 -386.996876) (xy 237.994891 -386.996876)
			(xy 238.049069 -387.004705) (xy 238.101571 -387.020201) (xy 238.151317 -387.043047) (xy 238.197285 -387.072771)
			(xy 238.218218 -387.090412) (xy 238.229546 -387.099648) (xy 238.256103 -387.111824) (xy 238.28502 -387.115997)
			(xy 238.313937 -387.111824) (xy 238.340494 -387.099648) (xy 238.351822 -387.090412) (xy 238.372774 -387.072798)
			(xy 238.418741 -387.043082) (xy 238.468484 -387.020241) (xy 238.52098 -387.004744) (xy 238.575152 -386.996909)
			(xy 238.60252 -386.996432) (xy 238.629775 -386.996836) (xy 238.68373 -387.004597) (xy 238.736032 -387.019958)
			(xy 238.785615 -387.042605) (xy 238.83147 -387.072079) (xy 238.872663 -387.107779) (xy 238.908357 -387.148978)
			(xy 238.937823 -387.194838) (xy 238.960463 -387.244424) (xy 238.975816 -387.296728) (xy 238.983568 -387.350685)
			(xy 238.984028 -387.37794) (xy 238.983544 -387.40531) (xy 238.975733 -387.459489) (xy 238.960249 -387.511992)
			(xy 238.937411 -387.56174) (xy 238.907689 -387.607707) (xy 238.890048 -387.628638) (xy 238.880776 -387.639938)
			(xy 238.86861 -387.666507) (xy 238.864447 -387.69543) (xy 238.868627 -387.724352) (xy 238.880809 -387.750913)
			(xy 238.890048 -387.762242) (xy 238.907665 -387.783192) (xy 238.937382 -387.829159) (xy 238.960223 -387.878902)
			(xy 238.975719 -387.931399) (xy 238.983552 -387.985572) (xy 238.984028 -388.01294) (xy 238.983559 -388.040191)
			(xy 238.975798 -388.094139) (xy 238.960439 -388.146432) (xy 238.937794 -388.196009) (xy 238.908326 -388.241858)
			(xy 238.872633 -388.283047) (xy 238.831442 -388.318738) (xy 238.785591 -388.348204) (xy 238.736014 -388.370846)
			(xy 238.683719 -388.386202) (xy 238.629771 -388.393961) (xy 238.60252 -388.394448) (xy 238.57515 -388.393983)
			(xy 238.52097 -388.386167) (xy 238.468466 -388.370678) (xy 238.418719 -388.347836) (xy 238.372753 -388.31811)
			(xy 238.351822 -388.300468) (xy 238.340494 -388.291232) (xy 238.313937 -388.279056) (xy 238.28502 -388.274883)
			(xy 238.256103 -388.279056) (xy 238.229546 -388.291232) (xy 238.218218 -388.300468) (xy 238.197285 -388.318109)
			(xy 238.151317 -388.347833) (xy 238.101571 -388.370679) (xy 238.049069 -388.386175) (xy 237.994891 -388.394004)
			(xy 237.940149 -388.394004) (xy 237.885971 -388.386175) (xy 237.833469 -388.370679) (xy 237.783723 -388.347833)
			(xy 237.737755 -388.318109) (xy 237.716822 -388.300468) (xy 237.705494 -388.291232) (xy 237.678937 -388.279056)
			(xy 237.65002 -388.274883) (xy 237.621103 -388.279056) (xy 237.594546 -388.291232) (xy 237.583218 -388.300468)
			(xy 237.562285 -388.318109) (xy 237.516317 -388.347833) (xy 237.466571 -388.370679) (xy 237.414069 -388.386175)
			(xy 237.359891 -388.394004) (xy 237.305149 -388.394004) (xy 237.250971 -388.386175) (xy 237.198469 -388.370679)
			(xy 237.148723 -388.347833) (xy 237.102755 -388.318109) (xy 237.081822 -388.300468) (xy 237.070494 -388.291232)
			(xy 237.043937 -388.279056) (xy 237.01502 -388.274883) (xy 236.986103 -388.279056) (xy 236.959546 -388.291232)
			(xy 236.948218 -388.300468) (xy 236.927285 -388.318109) (xy 236.881317 -388.347833) (xy 236.831571 -388.370679)
			(xy 236.779069 -388.386175) (xy 236.724891 -388.394004) (xy 236.670149 -388.394004) (xy 236.615971 -388.386175)
			(xy 236.563469 -388.370679) (xy 236.513723 -388.347833) (xy 236.467755 -388.318109) (xy 236.446822 -388.300468)
			(xy 236.435494 -388.291232) (xy 236.408937 -388.279056) (xy 236.38002 -388.274883) (xy 236.351103 -388.279056)
			(xy 236.324546 -388.291232) (xy 236.313218 -388.300468) (xy 236.292285 -388.318109) (xy 236.246317 -388.347833)
			(xy 236.196571 -388.370679) (xy 236.144069 -388.386175) (xy 236.089891 -388.394004) (xy 236.035149 -388.394004)
			(xy 235.980971 -388.386175) (xy 235.928469 -388.370679) (xy 235.878723 -388.347833) (xy 235.832755 -388.318109)
			(xy 235.811822 -388.300468) (xy 235.800494 -388.291232) (xy 235.773937 -388.279056) (xy 235.74502 -388.274883)
			(xy 235.716103 -388.279056) (xy 235.689546 -388.291232) (xy 235.678218 -388.300468) (xy 235.657285 -388.318109)
			(xy 235.611317 -388.347833) (xy 235.561571 -388.370679) (xy 235.509069 -388.386175) (xy 235.454891 -388.394004)
			(xy 235.400149 -388.394004) (xy 235.345971 -388.386175) (xy 235.293469 -388.370679) (xy 235.243723 -388.347833)
			(xy 235.197755 -388.318109) (xy 235.176822 -388.300468) (xy 235.165494 -388.291232) (xy 235.138937 -388.279056)
			(xy 235.11002 -388.274883) (xy 235.081103 -388.279056) (xy 235.054546 -388.291232) (xy 235.043218 -388.300468)
			(xy 235.022285 -388.318109) (xy 234.976317 -388.347833) (xy 234.926571 -388.370679) (xy 234.874069 -388.386175)
			(xy 234.819891 -388.394004) (xy 234.765149 -388.394004) (xy 234.710971 -388.386175) (xy 234.658469 -388.370679)
			(xy 234.608723 -388.347833) (xy 234.562755 -388.318109) (xy 234.541822 -388.300468) (xy 234.530494 -388.291232)
			(xy 234.503937 -388.279056) (xy 234.47502 -388.274883) (xy 234.446103 -388.279056) (xy 234.419546 -388.291232)
			(xy 234.408218 -388.300468) (xy 234.387286 -388.318107) (xy 234.341314 -388.34782) (xy 234.291566 -388.370657)
			(xy 234.239065 -388.386147) (xy 234.184889 -388.393975) (xy 234.15752 -388.394448) (xy 234.130271 -388.393903)
			(xy 234.076328 -388.386151) (xy 234.024036 -388.3708) (xy 233.974462 -388.348164) (xy 233.928614 -388.318704)
			(xy 233.887424 -388.283018) (xy 233.851732 -388.241835) (xy 233.822265 -388.195991) (xy 233.799621 -388.14642)
			(xy 233.784262 -388.094131) (xy 233.776501 -388.040189) (xy 233.776012 -388.01294) (xy 167.657272 -388.01294)
			(xy 171.711112 -392.06678) (xy 180.19014 -392.06678) (xy 181.15534 -393.03198) (xy 181.812182 -393.03198)
			(xy 181.816253 -392.976358) (xy 181.828379 -392.921921) (xy 181.848302 -392.86983) (xy 181.875598 -392.821195)
			(xy 181.909684 -392.777052) (xy 181.949833 -392.738343) (xy 181.995191 -392.705892) (xy 182.044791 -392.680391)
			(xy 182.097575 -392.662384) (xy 182.152418 -392.652254) (xy 182.208152 -392.650217) (xy 182.263589 -392.656317)
			(xy 182.317546 -392.670423) (xy 182.368875 -392.692235) (xy 182.416481 -392.721289) (xy 182.459349 -392.756964)
			(xy 182.496566 -392.798501) (xy 182.527339 -392.845014) (xy 182.551011 -392.895511) (xy 182.567079 -392.948918)
			(xy 182.575199 -393.004094) (xy 182.575708 -393.03198) (xy 182.575199 -393.059866) (xy 182.567079 -393.115042)
			(xy 182.551011 -393.168449) (xy 182.527339 -393.218946) (xy 182.496566 -393.265459) (xy 182.459349 -393.306996)
			(xy 182.416481 -393.342671) (xy 182.368875 -393.371725) (xy 182.317546 -393.393537) (xy 182.263589 -393.407643)
			(xy 182.208152 -393.413743) (xy 182.152418 -393.411706) (xy 182.097575 -393.401576) (xy 182.044791 -393.383569)
			(xy 181.995191 -393.358068) (xy 181.949833 -393.325617) (xy 181.909684 -393.286908) (xy 181.875598 -393.242765)
			(xy 181.848302 -393.19413) (xy 181.828379 -393.142039) (xy 181.816253 -393.087602) (xy 181.812182 -393.03198)
			(xy 181.15534 -393.03198) (xy 182.93186 -394.8085) (xy 243.179528 -394.8085) (xy 243.183558 -394.723892)
			(xy 243.195613 -394.640051) (xy 243.215583 -394.557735) (xy 243.243287 -394.47769) (xy 243.278475 -394.400641)
			(xy 243.320827 -394.327286) (xy 243.36996 -394.258289) (xy 243.42543 -394.194274) (xy 243.486733 -394.135823)
			(xy 243.553315 -394.083463) (xy 243.624573 -394.03767) (xy 243.699861 -393.998857) (xy 243.778498 -393.967377)
			(xy 243.859771 -393.943515) (xy 243.942944 -393.927486) (xy 244.027264 -393.919435) (xy 244.069616 -393.918948)
			(xy 244.11084 -393.919417) (xy 244.192933 -393.927053) (xy 244.273968 -393.94225) (xy 244.35325 -393.964876)
			(xy 244.430099 -393.994739) (xy 244.503857 -394.031582) (xy 244.573891 -394.075088) (xy 244.639601 -394.124886)
			(xy 244.670326 -394.152374) (xy 244.677558 -394.158461) (xy 244.695171 -394.165287) (xy 244.714061 -394.165287)
			(xy 244.731674 -394.158461) (xy 244.738906 -394.152374) (xy 244.769639 -394.124894) (xy 244.835341 -394.075085)
			(xy 244.905371 -394.03157) (xy 244.979128 -393.994723) (xy 245.055977 -393.964858) (xy 245.13526 -393.942233)
			(xy 245.216297 -393.927041) (xy 245.298392 -393.919413) (xy 245.339616 -393.918948) (xy 245.381408 -393.919476)
			(xy 245.464624 -393.927312) (xy 245.546738 -393.942923) (xy 245.627024 -393.96617) (xy 245.704775 -393.996849)
			(xy 245.779303 -394.034689) (xy 245.849951 -394.079356) (xy 245.916096 -394.130456) (xy 245.977154 -394.187537)
			(xy 246.032585 -394.250097) (xy 246.081902 -394.317582) (xy 246.124667 -394.389397) (xy 246.143018 -394.426948)
			(xy 246.170089 -394.428781) (xy 246.223268 -394.43954) (xy 246.274197 -394.458246) (xy 246.321697 -394.484466)
			(xy 246.364667 -394.51759) (xy 246.402111 -394.556853) (xy 246.433163 -394.601345) (xy 246.457102 -394.650034)
			(xy 246.473374 -394.701792) (xy 246.481601 -394.75542) (xy 246.482108 -394.782548) (xy 246.481601 -394.8085)
			(xy 249.114543 -394.8085) (xy 249.118574 -394.723896) (xy 249.130628 -394.640058) (xy 249.150596 -394.557746)
			(xy 249.178298 -394.477704) (xy 249.213483 -394.400658) (xy 249.255833 -394.327305) (xy 249.304963 -394.25831)
			(xy 249.360429 -394.194298) (xy 249.421729 -394.135847) (xy 249.488307 -394.083488) (xy 249.55956 -394.037695)
			(xy 249.634844 -393.998882) (xy 249.713476 -393.967401) (xy 249.794745 -393.943537) (xy 249.877914 -393.927506)
			(xy 249.96223 -393.919453) (xy 250.00458 -393.918948) (xy 250.045803 -393.919439) (xy 250.127896 -393.927072)
			(xy 250.20893 -393.942266) (xy 250.288212 -393.964889) (xy 250.365061 -393.994749) (xy 250.438819 -394.031588)
			(xy 250.508854 -394.075092) (xy 250.574564 -394.124887) (xy 250.60529 -394.152374) (xy 250.612522 -394.158461)
			(xy 250.630135 -394.165287) (xy 250.649025 -394.165287) (xy 250.666638 -394.158461) (xy 250.67387 -394.152374)
			(xy 250.704576 -394.124863) (xy 250.770283 -394.075057) (xy 250.840317 -394.031545) (xy 250.914078 -393.994701)
			(xy 250.990931 -393.96484) (xy 251.070218 -393.942219) (xy 251.151257 -393.927032) (xy 251.233355 -393.91941)
			(xy 251.27458 -393.918948) (xy 251.316356 -393.919458) (xy 251.399539 -393.927298) (xy 251.481621 -393.942901)
			(xy 251.561879 -393.966129) (xy 251.639606 -393.996779) (xy 251.714118 -394.03458) (xy 251.784758 -394.079199)
			(xy 251.850904 -394.130243) (xy 251.911974 -394.187264) (xy 251.96743 -394.249758) (xy 252.016784 -394.317175)
			(xy 252.059601 -394.388922) (xy 252.077982 -394.42644) (xy 252.086364 -394.42644) (xy 252.114351 -394.426946)
			(xy 252.169636 -394.435698) (xy 252.222871 -394.452992) (xy 252.272744 -394.478402) (xy 252.318028 -394.511302)
			(xy 252.357606 -394.550881) (xy 252.390505 -394.596166) (xy 252.415913 -394.646041) (xy 252.433205 -394.699276)
			(xy 252.441955 -394.754561) (xy 252.442472 -394.782548) (xy 252.441992 -394.8085) (xy 255.049428 -394.8085)
			(xy 255.053459 -394.723891) (xy 255.065514 -394.640048) (xy 255.085484 -394.55773) (xy 255.11319 -394.477684)
			(xy 255.148379 -394.400634) (xy 255.190732 -394.327277) (xy 255.239868 -394.258279) (xy 255.295339 -394.194265)
			(xy 255.356645 -394.135813) (xy 255.423229 -394.083453) (xy 255.494489 -394.03766) (xy 255.56978 -393.998849)
			(xy 255.648419 -393.96737) (xy 255.729694 -393.943509) (xy 255.812869 -393.927482) (xy 255.897191 -393.919434)
			(xy 255.939544 -393.918948) (xy 255.980768 -393.919399) (xy 256.062862 -393.927038) (xy 256.143897 -393.942237)
			(xy 256.223179 -393.964866) (xy 256.300029 -393.994731) (xy 256.373786 -394.031576) (xy 256.44382 -394.075085)
			(xy 256.509529 -394.124885) (xy 256.540254 -394.152374) (xy 256.547486 -394.158461) (xy 256.565099 -394.165287)
			(xy 256.583989 -394.165287) (xy 256.601602 -394.158461) (xy 256.608834 -394.152374) (xy 256.639555 -394.12488)
			(xy 256.70526 -394.075073) (xy 256.775292 -394.031559) (xy 256.849049 -393.994713) (xy 256.925901 -393.96485)
			(xy 257.005185 -393.942227) (xy 257.086223 -393.927037) (xy 257.168319 -393.919412) (xy 257.209544 -393.918948)
			(xy 257.251493 -393.919491) (xy 257.335018 -393.927401) (xy 257.417428 -393.943137) (xy 257.497991 -393.96656)
			(xy 257.575991 -393.997462) (xy 257.650737 -394.035568) (xy 257.721565 -394.08054) (xy 257.787845 -394.131979)
			(xy 257.848989 -394.189427) (xy 257.904455 -394.252376) (xy 257.95375 -394.320266) (xy 257.996436 -394.392494)
			(xy 258.014724 -394.43025) (xy 258.027542 -394.428485) (xy 258.053348 -394.426578) (xy 258.066286 -394.42644)
			(xy 258.067048 -394.42644) (xy 258.093699 -394.426845) (xy 258.146403 -394.434796) (xy 258.197335 -394.450512)
			(xy 258.245356 -394.473643) (xy 258.289393 -394.503673) (xy 258.328463 -394.539929) (xy 258.361693 -394.581604)
			(xy 258.388341 -394.627765) (xy 258.407813 -394.677383) (xy 258.419673 -394.729348) (xy 258.423656 -394.7825)
			(xy 258.421708 -394.8085) (xy 260.984428 -394.8085) (xy 260.988458 -394.723893) (xy 261.000513 -394.640052)
			(xy 261.020483 -394.557736) (xy 261.048186 -394.477692) (xy 261.083374 -394.400643) (xy 261.125725 -394.327288)
			(xy 261.174858 -394.258291) (xy 261.230327 -394.194277) (xy 261.29163 -394.135826) (xy 261.358212 -394.083466)
			(xy 261.429469 -394.037672) (xy 261.504756 -393.99886) (xy 261.583392 -393.967379) (xy 261.664664 -393.943516)
			(xy 261.747837 -393.927487) (xy 261.832156 -393.919436) (xy 261.874508 -393.918948) (xy 261.915732 -393.919422)
			(xy 261.997825 -393.927057) (xy 262.078859 -393.942253) (xy 262.158141 -393.964879) (xy 262.234991 -393.994741)
			(xy 262.308749 -394.031583) (xy 262.378783 -394.075089) (xy 262.444493 -394.124886) (xy 262.475218 -394.152374)
			(xy 262.48245 -394.158461) (xy 262.500063 -394.165287) (xy 262.518953 -394.165287) (xy 262.536566 -394.158461)
			(xy 262.543798 -394.152374) (xy 262.574534 -394.124897) (xy 262.640236 -394.075089) (xy 262.710266 -394.031574)
			(xy 262.784021 -393.994725) (xy 262.86087 -393.96486) (xy 262.940153 -393.942234) (xy 263.021189 -393.927042)
			(xy 263.103284 -393.919413) (xy 263.144508 -393.918948) (xy 263.18635 -393.919404) (xy 263.269665 -393.927258)
			(xy 263.351874 -393.942906) (xy 263.432248 -393.966208) (xy 263.510078 -393.996959) (xy 263.584674 -394.034887)
			(xy 263.655376 -394.079656) (xy 263.721559 -394.130869) (xy 263.782638 -394.188075) (xy 263.838071 -394.250766)
			(xy 263.887369 -394.318389) (xy 263.930095 -394.390344) (xy 263.948418 -394.427964) (xy 263.981692 -394.42644)
			(xy 264.008347 -394.426817) (xy 264.061062 -394.434761) (xy 264.112004 -394.450474) (xy 264.160035 -394.473603)
			(xy 264.204083 -394.503633) (xy 264.243162 -394.539893) (xy 264.276401 -394.581572) (xy 264.303057 -394.62774)
			(xy 264.322533 -394.677365) (xy 264.334396 -394.729339) (xy 264.33838 -394.7825) (xy 264.336432 -394.8085)
			(xy 266.919443 -394.8085) (xy 266.923474 -394.723896) (xy 266.935527 -394.640059) (xy 266.955496 -394.557747)
			(xy 266.983198 -394.477706) (xy 267.018382 -394.40066) (xy 267.060731 -394.327308) (xy 267.109861 -394.258313)
			(xy 267.165326 -394.194301) (xy 267.226625 -394.13585) (xy 267.293203 -394.083491) (xy 267.364456 -394.037698)
			(xy 267.439739 -393.998885) (xy 267.51837 -393.967403) (xy 267.599638 -393.943538) (xy 267.682807 -393.927507)
			(xy 267.767122 -393.919453) (xy 267.809472 -393.918948) (xy 267.850695 -393.919444) (xy 267.932787 -393.927077)
			(xy 268.013822 -393.942269) (xy 268.093103 -393.964892) (xy 268.169953 -393.994751) (xy 268.243711 -394.03159)
			(xy 268.313746 -394.075093) (xy 268.379456 -394.124888) (xy 268.410182 -394.152374) (xy 268.417414 -394.158461)
			(xy 268.435027 -394.165287) (xy 268.453917 -394.165287) (xy 268.47153 -394.158461) (xy 268.478762 -394.152374)
			(xy 268.509471 -394.124866) (xy 268.575178 -394.07506) (xy 268.645212 -394.031548) (xy 268.718971 -393.994703)
			(xy 268.795824 -393.964842) (xy 268.87511 -393.942221) (xy 268.95615 -393.927033) (xy 269.038247 -393.91941)
			(xy 269.079472 -393.918948) (xy 269.121265 -393.919428) (xy 269.204483 -393.927269) (xy 269.286598 -393.942885)
			(xy 269.366885 -393.966137) (xy 269.444636 -393.996821) (xy 269.519164 -394.034666) (xy 269.589812 -394.079337)
			(xy 269.655956 -394.130441) (xy 269.717013 -394.187526) (xy 269.772444 -394.250089) (xy 269.821759 -394.317577)
			(xy 269.864524 -394.389396) (xy 269.882874 -394.426948) (xy 269.909949 -394.428731) (xy 269.963129 -394.439499)
			(xy 270.014058 -394.458212) (xy 270.061558 -394.484438) (xy 270.104527 -394.517569) (xy 270.141971 -394.556837)
			(xy 270.173021 -394.601333) (xy 270.19696 -394.650026) (xy 270.213231 -394.701787) (xy 270.221458 -394.755419)
			(xy 270.221964 -394.782548) (xy 270.221496 -394.8085) (xy 272.854328 -394.8085) (xy 272.858359 -394.723891)
			(xy 272.870414 -394.640048) (xy 272.890384 -394.557731) (xy 272.918089 -394.477686) (xy 272.953277 -394.400636)
			(xy 272.995631 -394.32728) (xy 273.044766 -394.258282) (xy 273.100237 -394.194267) (xy 273.161542 -394.135816)
			(xy 273.228125 -394.083456) (xy 273.299385 -394.037663) (xy 273.374675 -393.998851) (xy 273.453313 -393.967372)
			(xy 273.534587 -393.943511) (xy 273.617762 -393.927483) (xy 273.702084 -393.919434) (xy 273.744436 -393.918948)
			(xy 273.78566 -393.919404) (xy 273.867754 -393.927042) (xy 273.948789 -393.942241) (xy 274.028071 -393.964869)
			(xy 274.10492 -393.994734) (xy 274.178678 -394.031578) (xy 274.248712 -394.075086) (xy 274.314421 -394.124886)
			(xy 274.345146 -394.152374) (xy 274.352378 -394.158461) (xy 274.369991 -394.165287) (xy 274.388881 -394.165287)
			(xy 274.406494 -394.158461) (xy 274.413726 -394.152374) (xy 274.44445 -394.124884) (xy 274.510154 -394.075076)
			(xy 274.580186 -394.031562) (xy 274.653943 -393.994716) (xy 274.730794 -393.964852) (xy 274.810078 -393.942228)
			(xy 274.891116 -393.927038) (xy 274.973211 -393.919412) (xy 275.014436 -393.918948) (xy 275.056229 -393.919459)
			(xy 275.139445 -393.927297) (xy 275.221559 -393.942909) (xy 275.301846 -393.966158) (xy 275.379596 -393.996839)
			(xy 275.454125 -394.034681) (xy 275.524773 -394.079349) (xy 275.590918 -394.130451) (xy 275.651975 -394.187533)
			(xy 275.707406 -394.250094) (xy 275.756722 -394.31758) (xy 275.799488 -394.389397) (xy 275.817838 -394.426948)
			(xy 275.844911 -394.428763) (xy 275.898089 -394.439526) (xy 275.949019 -394.458234) (xy 275.996518 -394.484456)
			(xy 276.039488 -394.517583) (xy 276.076932 -394.556848) (xy 276.107984 -394.601341) (xy 276.131922 -394.650031)
			(xy 276.148194 -394.70179) (xy 276.156421 -394.75542) (xy 276.156928 -394.782548) (xy 276.156404 -394.808503)
			(xy 276.148874 -394.859865) (xy 276.133965 -394.909589) (xy 276.111994 -394.956621) (xy 276.083427 -394.999964)
			(xy 276.048869 -395.038699) (xy 276.009052 -395.072006) (xy 275.964821 -395.099179) (xy 275.917114 -395.11964)
			(xy 275.86694 -395.132958) (xy 275.841206 -395.13637) (xy 275.825747 -395.174161) (xy 275.788816 -395.246988)
			(xy 275.745365 -395.316123) (xy 275.695761 -395.380985) (xy 275.64042 -395.441027) (xy 275.579808 -395.495744)
			(xy 275.514437 -395.544676) (xy 275.444856 -395.587409) (xy 275.371651 -395.623585) (xy 275.295438 -395.652899)
			(xy 275.216859 -395.675104) (xy 275.136576 -395.690013) (xy 275.055264 -395.6975) (xy 275.014436 -395.697964)
			(xy 274.973213 -395.69746) (xy 274.891121 -395.689828) (xy 274.810087 -395.674636) (xy 274.730806 -395.652015)
			(xy 274.653956 -395.622157) (xy 274.580198 -395.585319) (xy 274.510163 -395.541817) (xy 274.444452 -395.492024)
			(xy 274.413726 -395.464538) (xy 274.406494 -395.458451) (xy 274.388881 -395.451625) (xy 274.369991 -395.451625)
			(xy 274.352378 -395.458451) (xy 274.345146 -395.464538) (xy 274.314435 -395.492044) (xy 274.248729 -395.54185)
			(xy 274.178695 -395.585362) (xy 274.104936 -395.622207) (xy 274.028083 -395.652068) (xy 273.948797 -395.67469)
			(xy 273.867758 -395.689878) (xy 273.785661 -395.697501) (xy 273.744436 -395.697964) (xy 273.702084 -395.697566)
			(xy 273.617762 -395.689517) (xy 273.534587 -395.673489) (xy 273.453313 -395.649628) (xy 273.374675 -395.618149)
			(xy 273.299385 -395.579337) (xy 273.228125 -395.533544) (xy 273.161542 -395.481184) (xy 273.100237 -395.422733)
			(xy 273.044766 -395.358718) (xy 272.995631 -395.28972) (xy 272.953277 -395.216364) (xy 272.918089 -395.139314)
			(xy 272.890384 -395.059269) (xy 272.870414 -394.976952) (xy 272.858359 -394.893109) (xy 272.854328 -394.8085)
			(xy 270.221496 -394.8085) (xy 270.221496 -394.808506) (xy 270.213964 -394.859873) (xy 270.199053 -394.909601)
			(xy 270.177077 -394.956636) (xy 270.148504 -394.999982) (xy 270.113939 -395.038718) (xy 270.074115 -395.072025)
			(xy 270.029876 -395.099194) (xy 269.98216 -395.119651) (xy 269.93198 -395.132962) (xy 269.906242 -395.13637)
			(xy 269.890753 -395.174148) (xy 269.853824 -395.246974) (xy 269.810375 -395.316109) (xy 269.760773 -395.38097)
			(xy 269.705435 -395.441012) (xy 269.644826 -395.49573) (xy 269.579457 -395.544662) (xy 269.509879 -395.587396)
			(xy 269.436676 -395.623574) (xy 269.360466 -395.652889) (xy 269.28189 -395.675096) (xy 269.201609 -395.690008)
			(xy 269.120299 -395.697499) (xy 269.079472 -395.697964) (xy 269.038248 -395.6975) (xy 268.956155 -395.689862)
			(xy 268.87512 -395.674665) (xy 268.795838 -395.652037) (xy 268.718989 -395.622174) (xy 268.645231 -395.585331)
			(xy 268.575197 -395.541824) (xy 268.509487 -395.492026) (xy 268.478762 -395.464538) (xy 268.47153 -395.458451)
			(xy 268.453917 -395.451625) (xy 268.435027 -395.451625) (xy 268.417414 -395.458451) (xy 268.410182 -395.464538)
			(xy 268.379456 -395.492026) (xy 268.313752 -395.541834) (xy 268.243721 -395.585348) (xy 268.169964 -395.622194)
			(xy 268.093113 -395.652058) (xy 268.013829 -395.674682) (xy 267.932792 -395.689873) (xy 267.850696 -395.6975)
			(xy 267.809472 -395.697964) (xy 267.767122 -395.697547) (xy 267.682807 -395.689493) (xy 267.599638 -395.673462)
			(xy 267.51837 -395.649597) (xy 267.439739 -395.618115) (xy 267.364456 -395.579302) (xy 267.293203 -395.533509)
			(xy 267.226625 -395.48115) (xy 267.165326 -395.422699) (xy 267.109861 -395.358687) (xy 267.060731 -395.289692)
			(xy 267.018382 -395.21634) (xy 266.983198 -395.139294) (xy 266.955496 -395.059253) (xy 266.935527 -394.976941)
			(xy 266.923474 -394.893104) (xy 266.919443 -394.8085) (xy 264.336432 -394.8085) (xy 264.334396 -394.835661)
			(xy 264.322533 -394.887635) (xy 264.303057 -394.93726) (xy 264.276401 -394.983428) (xy 264.243162 -395.025107)
			(xy 264.204083 -395.061367) (xy 264.160035 -395.091397) (xy 264.112004 -395.114526) (xy 264.061062 -395.130239)
			(xy 264.008347 -395.138183) (xy 263.981692 -395.138656) (xy 263.970516 -395.138402) (xy 263.954928 -395.17605)
			(xy 263.917915 -395.248648) (xy 263.874417 -395.317555) (xy 263.824797 -395.382194) (xy 263.769471 -395.442023)
			(xy 263.708905 -395.496539) (xy 263.643605 -395.545287) (xy 263.57412 -395.587856) (xy 263.501032 -395.623891)
			(xy 263.424953 -395.653088) (xy 263.346523 -395.675203) (xy 263.266399 -395.69005) (xy 263.185252 -395.697505)
			(xy 263.144508 -395.697964) (xy 263.103285 -395.697477) (xy 263.021192 -395.689843) (xy 262.940158 -395.674649)
			(xy 262.860876 -395.652025) (xy 262.784027 -395.622164) (xy 262.710269 -395.585324) (xy 262.640234 -395.54182)
			(xy 262.574524 -395.492025) (xy 262.543798 -395.464538) (xy 262.536566 -395.458451) (xy 262.518953 -395.451625)
			(xy 262.500063 -395.451625) (xy 262.48245 -395.458451) (xy 262.475218 -395.464538) (xy 262.444477 -395.492009)
			(xy 262.378775 -395.541818) (xy 262.308747 -395.585333) (xy 262.234992 -395.622182) (xy 262.158144 -395.652048)
			(xy 262.078861 -395.674675) (xy 261.997826 -395.689868) (xy 261.915732 -395.697498) (xy 261.874508 -395.697964)
			(xy 261.832156 -395.697564) (xy 261.747837 -395.689513) (xy 261.664664 -395.673484) (xy 261.583392 -395.649621)
			(xy 261.504756 -395.61814) (xy 261.429469 -395.579328) (xy 261.358212 -395.533534) (xy 261.29163 -395.481174)
			(xy 261.230327 -395.422723) (xy 261.174858 -395.358709) (xy 261.125725 -395.289712) (xy 261.083374 -395.216357)
			(xy 261.048186 -395.139308) (xy 261.020483 -395.059264) (xy 261.000513 -394.976948) (xy 260.988458 -394.893107)
			(xy 260.984428 -394.8085) (xy 258.421708 -394.8085) (xy 258.419673 -394.835652) (xy 258.407813 -394.887617)
			(xy 258.388341 -394.937235) (xy 258.361693 -394.983396) (xy 258.328463 -395.025071) (xy 258.289393 -395.061327)
			(xy 258.245356 -395.091357) (xy 258.197335 -395.114488) (xy 258.146403 -395.130204) (xy 258.093699 -395.138155)
			(xy 258.067048 -395.138656) (xy 258.03606 -395.137386) (xy 258.020546 -395.175113) (xy 257.983557 -395.247826)
			(xy 257.940067 -395.316846) (xy 257.89044 -395.381595) (xy 257.835094 -395.441529) (xy 257.774494 -395.496144)
			(xy 257.709147 -395.544982) (xy 257.639604 -395.587632) (xy 257.566448 -395.623736) (xy 257.490294 -395.65299)
			(xy 257.411782 -395.67515) (xy 257.331571 -395.690029) (xy 257.250334 -395.697502) (xy 257.209544 -395.697964)
			(xy 257.168321 -395.697455) (xy 257.08623 -395.689824) (xy 257.005196 -395.674633) (xy 256.925914 -395.652012)
			(xy 256.849065 -395.622155) (xy 256.775306 -395.585317) (xy 256.705271 -395.541816) (xy 256.63956 -395.492023)
			(xy 256.608834 -395.464538) (xy 256.601602 -395.458451) (xy 256.583989 -395.451625) (xy 256.565099 -395.451625)
			(xy 256.547486 -395.458451) (xy 256.540254 -395.464538) (xy 256.50954 -395.49204) (xy 256.443834 -395.541846)
			(xy 256.373801 -395.585359) (xy 256.300042 -395.622204) (xy 256.22319 -395.652066) (xy 256.143904 -395.674688)
			(xy 256.062865 -395.689877) (xy 255.980769 -395.697501) (xy 255.939544 -395.697964) (xy 255.897191 -395.697566)
			(xy 255.812869 -395.689518) (xy 255.729694 -395.673491) (xy 255.648419 -395.64963) (xy 255.56978 -395.618151)
			(xy 255.494489 -395.57934) (xy 255.423229 -395.533547) (xy 255.356645 -395.481187) (xy 255.295339 -395.422735)
			(xy 255.239868 -395.358721) (xy 255.190732 -395.289723) (xy 255.148379 -395.216366) (xy 255.11319 -395.139316)
			(xy 255.085484 -395.05927) (xy 255.065514 -394.976952) (xy 255.053459 -394.893109) (xy 255.049428 -394.8085)
			(xy 252.441992 -394.8085) (xy 252.441968 -394.809821) (xy 252.433657 -394.863731) (xy 252.417221 -394.915743)
			(xy 252.393046 -394.964639) (xy 252.361695 -395.009276) (xy 252.323904 -395.04861) (xy 252.280556 -395.081721)
			(xy 252.232666 -395.107832) (xy 252.181353 -395.126335) (xy 252.127819 -395.136795) (xy 252.100588 -395.138402)
			(xy 252.085024 -395.17606) (xy 252.048009 -395.248659) (xy 252.004509 -395.317566) (xy 251.954887 -395.382206)
			(xy 251.89956 -395.442034) (xy 251.838991 -395.496551) (xy 251.773689 -395.545298) (xy 251.704202 -395.587866)
			(xy 251.631111 -395.623899) (xy 251.555031 -395.653095) (xy 251.476599 -395.675208) (xy 251.396473 -395.690054)
			(xy 251.315325 -395.697507) (xy 251.27458 -395.697964) (xy 251.233356 -395.697495) (xy 251.151263 -395.689858)
			(xy 251.070228 -395.674661) (xy 250.990947 -395.652035) (xy 250.914097 -395.622172) (xy 250.840339 -395.58533)
			(xy 250.770305 -395.541823) (xy 250.704595 -395.492026) (xy 250.67387 -395.464538) (xy 250.666638 -395.458451)
			(xy 250.649025 -395.451625) (xy 250.630135 -395.451625) (xy 250.612522 -395.458451) (xy 250.60529 -395.464538)
			(xy 250.574561 -395.492023) (xy 250.508857 -395.54183) (xy 250.438827 -395.585344) (xy 250.36507 -395.622192)
			(xy 250.28822 -395.652056) (xy 250.208936 -395.67468) (xy 250.127899 -395.689872) (xy 250.045804 -395.697499)
			(xy 250.00458 -395.697964) (xy 249.96223 -395.697547) (xy 249.877914 -395.689494) (xy 249.794745 -395.673463)
			(xy 249.713476 -395.649599) (xy 249.634844 -395.618118) (xy 249.55956 -395.579305) (xy 249.488307 -395.533512)
			(xy 249.421729 -395.481153) (xy 249.360429 -395.422702) (xy 249.304963 -395.35869) (xy 249.255833 -395.289695)
			(xy 249.213483 -395.216342) (xy 249.178298 -395.139296) (xy 249.150596 -395.059254) (xy 249.130628 -394.976942)
			(xy 249.118574 -394.893104) (xy 249.114543 -394.8085) (xy 246.481601 -394.8085) (xy 246.481601 -394.808504)
			(xy 246.474071 -394.859867) (xy 246.459161 -394.909593) (xy 246.437189 -394.956626) (xy 246.40862 -394.999969)
			(xy 246.374059 -395.038705) (xy 246.334241 -395.072012) (xy 246.290007 -395.099183) (xy 246.242297 -395.119644)
			(xy 246.192121 -395.132959) (xy 246.166386 -395.13637) (xy 246.15086 -395.174132) (xy 246.113933 -395.246957)
			(xy 246.070488 -395.316091) (xy 246.020888 -395.380952) (xy 245.965553 -395.440994) (xy 245.904948 -395.495712)
			(xy 245.839582 -395.544645) (xy 245.770007 -395.587381) (xy 245.696808 -395.62356) (xy 245.620601 -395.652878)
			(xy 245.542028 -395.675088) (xy 245.461749 -395.690002) (xy 245.380442 -395.697497) (xy 245.339616 -395.697964)
			(xy 245.298393 -395.697472) (xy 245.216301 -395.689839) (xy 245.135266 -395.674645) (xy 245.055985 -395.652022)
			(xy 244.979135 -395.622162) (xy 244.905377 -395.585323) (xy 244.835342 -395.541819) (xy 244.769632 -395.492024)
			(xy 244.738906 -395.464538) (xy 244.731674 -395.458451) (xy 244.714061 -395.451625) (xy 244.695171 -395.451625)
			(xy 244.677558 -395.458451) (xy 244.670326 -395.464538) (xy 244.639624 -395.492053) (xy 244.573916 -395.541859)
			(xy 244.503881 -395.58537) (xy 244.43012 -395.622214) (xy 244.353266 -395.652074) (xy 244.273979 -395.674694)
			(xy 244.192939 -395.68988) (xy 244.110841 -395.697502) (xy 244.069616 -395.697964) (xy 244.027264 -395.697565)
			(xy 243.942944 -395.689514) (xy 243.859771 -395.673485) (xy 243.778498 -395.649623) (xy 243.699861 -395.618143)
			(xy 243.624573 -395.57933) (xy 243.553315 -395.533537) (xy 243.486733 -395.481177) (xy 243.42543 -395.422726)
			(xy 243.36996 -395.358711) (xy 243.320827 -395.289714) (xy 243.278475 -395.216359) (xy 243.243287 -395.13931)
			(xy 243.215583 -395.059265) (xy 243.195613 -394.976949) (xy 243.183558 -394.893108) (xy 243.179528 -394.8085)
			(xy 182.93186 -394.8085) (xy 185.94324 -397.81988) (xy 185.94324 -399.97888) (xy 186.1312 -400.16684)
			(xy 192.56248 -400.16684) (xy 194.3481 -398.38122) (xy 196.56298 -398.38122) (xy 198.83882 -400.65706)
			(xy 202.61326 -400.65706) (xy 204.30998 -398.96034) (xy 207.29194 -398.96034) (xy 209.00136 -400.66976)
			(xy 213.26348 -400.66976) (xy 215.0618 -398.87144) (xy 217.97518 -398.87144) (xy 219.80652 -400.70278)
			(xy 223.99244 -400.70278)
		)
		(stroke
			(width 0)
			(type solid)
		)
		(fill yes)
		(layer "In15.Cu")
		(net "P12V_AUX")
	)
	(gr_poly
		(pts
			(xy 104.395778 -418.958014) (xy 104.403574 -418.931493) (xy 104.425752 -418.880861) (xy 104.454999 -418.833956)
			(xy 104.490704 -418.791758) (xy 104.532119 -418.755148) (xy 104.57838 -418.724893) (xy 104.62852 -418.701623)
			(xy 104.681491 -418.685826) (xy 104.736186 -418.677831) (xy 104.763824 -418.677344) (xy 104.787954 -418.678106)
			(xy 104.810814 -418.67963) (xy 108.333794 -415.15665) (xy 108.333794 -413.283146) (xy 110.85195 -410.76499)
			(xy 112.134396 -410.76499) (xy 112.14862 -410.764558) (xy 112.175982 -410.756786) (xy 112.200135 -410.741762)
			(xy 112.2192 -410.720652) (xy 112.231695 -410.695099) (xy 112.236649 -410.667089) (xy 112.233677 -410.6388)
			(xy 112.223009 -410.612432) (xy 112.21466 -410.600906) (xy 112.199416 -410.580721) (xy 112.173825 -410.537089)
			(xy 112.154231 -410.490456) (xy 112.140977 -410.441641) (xy 112.134298 -410.391501) (xy 112.133888 -410.36621)
			(xy 112.134374 -410.338959) (xy 112.14213 -410.285011) (xy 112.157485 -410.232716) (xy 112.180127 -410.183139)
			(xy 112.209593 -410.137289) (xy 112.245284 -410.096098) (xy 112.286475 -410.060407) (xy 112.332325 -410.030941)
			(xy 112.381902 -410.008299) (xy 112.434197 -409.992944) (xy 112.488145 -409.985188) (xy 112.542647 -409.985188)
			(xy 112.596595 -409.992944) (xy 112.64889 -410.008299) (xy 112.698467 -410.030941) (xy 112.740344 -410.057854)
			(xy 113.455956 -410.057854) (xy 113.460027 -410.002232) (xy 113.472153 -409.947795) (xy 113.492076 -409.895704)
			(xy 113.519372 -409.847069) (xy 113.553458 -409.802926) (xy 113.593607 -409.764217) (xy 113.638965 -409.731766)
			(xy 113.688565 -409.706265) (xy 113.741349 -409.688258) (xy 113.796192 -409.678128) (xy 113.851926 -409.676091)
			(xy 113.907363 -409.682191) (xy 113.96132 -409.696297) (xy 114.012649 -409.718109) (xy 114.060255 -409.747163)
			(xy 114.103123 -409.782838) (xy 114.14034 -409.824375) (xy 114.171113 -409.870888) (xy 114.194785 -409.921385)
			(xy 114.210853 -409.974792) (xy 114.218973 -410.029968) (xy 114.219482 -410.057854) (xy 114.218973 -410.08574)
			(xy 114.210853 -410.140916) (xy 114.194785 -410.194323) (xy 114.171113 -410.24482) (xy 114.14034 -410.291333)
			(xy 114.103123 -410.33287) (xy 114.060255 -410.368545) (xy 114.012649 -410.397599) (xy 113.96132 -410.419411)
			(xy 113.907363 -410.433517) (xy 113.851926 -410.439617) (xy 113.796192 -410.43758) (xy 113.741349 -410.42745)
			(xy 113.688565 -410.409443) (xy 113.638965 -410.383942) (xy 113.593607 -410.351491) (xy 113.553458 -410.312782)
			(xy 113.519372 -410.268639) (xy 113.492076 -410.220004) (xy 113.472153 -410.167913) (xy 113.460027 -410.113476)
			(xy 113.455956 -410.057854) (xy 112.740344 -410.057854) (xy 112.744317 -410.060407) (xy 112.785508 -410.096098)
			(xy 112.821199 -410.137289) (xy 112.850665 -410.183139) (xy 112.873307 -410.232716) (xy 112.888662 -410.285011)
			(xy 112.896418 -410.338959) (xy 112.896904 -410.36621) (xy 112.896492 -410.391501) (xy 112.889806 -410.44164)
			(xy 112.876554 -410.490455) (xy 112.856966 -410.537092) (xy 112.831388 -410.58073) (xy 112.816132 -410.600906)
			(xy 112.807757 -410.612405) (xy 112.797122 -410.638776) (xy 112.794174 -410.667058) (xy 112.79914 -410.695056)
			(xy 112.811636 -410.720599) (xy 112.830692 -410.741704) (xy 112.85483 -410.756734) (xy 112.882178 -410.764524)
			(xy 112.896396 -410.76499) (xy 115.581176 -410.76499) (xy 116.226336 -410.11983) (xy 116.226336 -409.9052)
			(xy 115.704112 -409.382976) (xy 115.704112 -409.214066) (xy 115.70357 -409.198638) (xy 115.694354 -409.16919)
			(xy 115.676773 -409.143832) (xy 115.652428 -409.124874) (xy 115.623535 -409.114042) (xy 115.592727 -409.112323)
			(xy 115.57762 -409.115514) (xy 115.554575 -409.120982) (xy 115.507576 -409.126842) (xy 115.483894 -409.127198)
			(xy 115.456644 -409.126711) (xy 115.402698 -409.118954) (xy 115.350406 -409.103599) (xy 115.30083 -409.080958)
			(xy 115.254982 -409.051493) (xy 115.213794 -409.015802) (xy 115.178104 -408.974613) (xy 115.148639 -408.928764)
			(xy 115.125999 -408.879189) (xy 115.110644 -408.826896) (xy 115.102888 -408.77295) (xy 115.102888 -408.71845)
			(xy 115.110644 -408.664504) (xy 115.125999 -408.612211) (xy 115.148639 -408.562636) (xy 115.178104 -408.516787)
			(xy 115.213794 -408.475598) (xy 115.254982 -408.439907) (xy 115.30083 -408.410442) (xy 115.350406 -408.387801)
			(xy 115.402698 -408.372446) (xy 115.456644 -408.364689) (xy 115.483894 -408.364182) (xy 115.507576 -408.364539)
			(xy 115.554575 -408.370398) (xy 115.57762 -408.375866) (xy 115.592715 -408.379124) (xy 115.623532 -408.377406)
			(xy 115.652431 -408.366565) (xy 115.676776 -408.34759) (xy 115.694344 -408.322213) (xy 115.703535 -408.292747)
			(xy 115.704112 -408.277314) (xy 115.704112 -406.044146) (xy 115.703567 -406.02872) (xy 115.694348 -405.999277)
			(xy 115.676767 -405.973925) (xy 115.652423 -405.954971) (xy 115.623534 -405.944141) (xy 115.592729 -405.942422)
			(xy 115.57762 -405.945594) (xy 115.554576 -405.951063) (xy 115.507576 -405.956922) (xy 115.483894 -405.957278)
			(xy 115.456645 -405.956791) (xy 115.402702 -405.949035) (xy 115.350413 -405.93368) (xy 115.30084 -405.911041)
			(xy 115.254994 -405.881577) (xy 115.213808 -405.845888) (xy 115.17812 -405.804701) (xy 115.148656 -405.758855)
			(xy 115.126018 -405.709282) (xy 115.110664 -405.656992) (xy 115.102908 -405.603049) (xy 115.102908 -405.548551)
			(xy 115.110664 -405.494608) (xy 115.126018 -405.442318) (xy 115.148656 -405.392745) (xy 115.17812 -405.346899)
			(xy 115.213808 -405.305712) (xy 115.254994 -405.270023) (xy 115.30084 -405.240559) (xy 115.350413 -405.21792)
			(xy 115.402702 -405.202565) (xy 115.456645 -405.194809) (xy 115.483894 -405.194262) (xy 115.507576 -405.194619)
			(xy 115.554576 -405.200477) (xy 115.57762 -405.205946) (xy 115.592714 -405.209205) (xy 115.62353 -405.207487)
			(xy 115.652427 -405.196645) (xy 115.676768 -405.17767) (xy 115.694333 -405.152292) (xy 115.703518 -405.122827)
			(xy 115.704112 -405.107394) (xy 115.704112 -401.786598) (xy 115.673886 -401.773136) (xy 115.648979 -401.76152)
			(xy 115.602503 -401.732191) (xy 115.560715 -401.696498) (xy 115.524482 -401.655178) (xy 115.494551 -401.609087)
			(xy 115.471543 -401.559178) (xy 115.455933 -401.506485) (xy 115.448046 -401.452098) (xy 115.448043 -401.397141)
			(xy 115.455925 -401.342753) (xy 115.471529 -401.290058) (xy 115.494532 -401.240147) (xy 115.524458 -401.194053)
			(xy 115.560688 -401.15273) (xy 115.602471 -401.117032) (xy 115.648945 -401.087699) (xy 115.673886 -401.07616)
			(xy 115.704112 -401.062698) (xy 115.704112 -399.060416) (xy 117.944138 -396.82039) (xy 119.817896 -396.82039)
			(xy 120.89257 -395.745716) (xy 120.89257 -393.690094) (xy 120.892045 -393.674746) (xy 120.882937 -393.645431)
			(xy 120.865542 -393.620139) (xy 120.841427 -393.601145) (xy 120.812763 -393.59016) (xy 120.782131 -393.588173)
			(xy 120.767094 -393.591288) (xy 120.745141 -393.596261) (xy 120.700447 -393.601614) (xy 120.67794 -393.601956)
			(xy 120.650682 -393.601496) (xy 120.59672 -393.593742) (xy 120.54441 -393.578388) (xy 120.494819 -393.555745)
			(xy 120.448955 -393.526274) (xy 120.407752 -393.490576) (xy 120.37205 -393.449377) (xy 120.342574 -393.403516)
			(xy 120.319926 -393.353927) (xy 120.304566 -393.301619) (xy 120.296807 -393.247658) (xy 120.296807 -393.193142)
			(xy 120.304566 -393.139181) (xy 120.319926 -393.086873) (xy 120.342574 -393.037284) (xy 120.37205 -392.991423)
			(xy 120.407752 -392.950224) (xy 120.448955 -392.914526) (xy 120.494819 -392.885055) (xy 120.54441 -392.862412)
			(xy 120.59672 -392.847058) (xy 120.650682 -392.839304) (xy 120.67794 -392.83894) (xy 120.700446 -392.839297)
			(xy 120.74514 -392.844641) (xy 120.767094 -392.849608) (xy 120.782137 -392.85271) (xy 120.812776 -392.850748)
			(xy 120.841449 -392.839774) (xy 120.865569 -392.820779) (xy 120.882959 -392.795478) (xy 120.89205 -392.766153)
			(xy 120.89257 -392.750802) (xy 120.89257 -391.507472) (xy 120.431814 -391.046716) (xy 115.11915 -391.046716)
			(xy 113.237518 -392.928348) (xy 116.336062 -392.928348) (xy 116.340133 -392.872726) (xy 116.352259 -392.818289)
			(xy 116.372182 -392.766198) (xy 116.399478 -392.717563) (xy 116.433564 -392.67342) (xy 116.473713 -392.634711)
			(xy 116.519071 -392.60226) (xy 116.568671 -392.576759) (xy 116.621455 -392.558752) (xy 116.676298 -392.548622)
			(xy 116.732032 -392.546585) (xy 116.787469 -392.552685) (xy 116.841426 -392.566791) (xy 116.892755 -392.588603)
			(xy 116.940361 -392.617657) (xy 116.983229 -392.653332) (xy 117.020446 -392.694869) (xy 117.051219 -392.741382)
			(xy 117.074891 -392.791879) (xy 117.090959 -392.845286) (xy 117.099079 -392.900462) (xy 117.099588 -392.928348)
			(xy 117.099079 -392.956234) (xy 117.090959 -393.01141) (xy 117.074891 -393.064817) (xy 117.051219 -393.115314)
			(xy 117.020446 -393.161827) (xy 116.983229 -393.203364) (xy 116.940361 -393.239039) (xy 116.905482 -393.260326)
			(xy 119.026176 -393.260326) (xy 119.030247 -393.204704) (xy 119.042373 -393.150267) (xy 119.062296 -393.098176)
			(xy 119.089592 -393.049541) (xy 119.123678 -393.005398) (xy 119.163827 -392.966689) (xy 119.209185 -392.934238)
			(xy 119.258785 -392.908737) (xy 119.311569 -392.89073) (xy 119.366412 -392.8806) (xy 119.422146 -392.878563)
			(xy 119.477583 -392.884663) (xy 119.53154 -392.898769) (xy 119.582869 -392.920581) (xy 119.630475 -392.949635)
			(xy 119.673343 -392.98531) (xy 119.71056 -393.026847) (xy 119.741333 -393.07336) (xy 119.765005 -393.123857)
			(xy 119.781073 -393.177264) (xy 119.789193 -393.23244) (xy 119.789702 -393.260326) (xy 119.789193 -393.288212)
			(xy 119.781073 -393.343388) (xy 119.765005 -393.396795) (xy 119.741333 -393.447292) (xy 119.71056 -393.493805)
			(xy 119.673343 -393.535342) (xy 119.630475 -393.571017) (xy 119.582869 -393.600071) (xy 119.53154 -393.621883)
			(xy 119.477583 -393.635989) (xy 119.422146 -393.642089) (xy 119.366412 -393.640052) (xy 119.311569 -393.629922)
			(xy 119.258785 -393.611915) (xy 119.209185 -393.586414) (xy 119.163827 -393.553963) (xy 119.123678 -393.515254)
			(xy 119.089592 -393.471111) (xy 119.062296 -393.422476) (xy 119.042373 -393.370385) (xy 119.030247 -393.315948)
			(xy 119.026176 -393.260326) (xy 116.905482 -393.260326) (xy 116.892755 -393.268093) (xy 116.841426 -393.289905)
			(xy 116.787469 -393.304011) (xy 116.732032 -393.310111) (xy 116.676298 -393.308074) (xy 116.621455 -393.297944)
			(xy 116.568671 -393.279937) (xy 116.519071 -393.254436) (xy 116.473713 -393.221985) (xy 116.433564 -393.183276)
			(xy 116.399478 -393.139133) (xy 116.372182 -393.090498) (xy 116.352259 -393.038407) (xy 116.340133 -392.98397)
			(xy 116.336062 -392.928348) (xy 113.237518 -392.928348) (xy 112.092486 -394.07338) (xy 114.831112 -394.07338)
			(xy 114.835183 -394.017758) (xy 114.847309 -393.963321) (xy 114.867232 -393.91123) (xy 114.894528 -393.862595)
			(xy 114.928614 -393.818452) (xy 114.968763 -393.779743) (xy 115.014121 -393.747292) (xy 115.063721 -393.721791)
			(xy 115.116505 -393.703784) (xy 115.171348 -393.693654) (xy 115.227082 -393.691617) (xy 115.282519 -393.697717)
			(xy 115.336476 -393.711823) (xy 115.387805 -393.733635) (xy 115.435411 -393.762689) (xy 115.478279 -393.798364)
			(xy 115.515496 -393.839901) (xy 115.546269 -393.886414) (xy 115.569941 -393.936911) (xy 115.586009 -393.990318)
			(xy 115.594129 -394.045494) (xy 115.594638 -394.07338) (xy 115.594129 -394.101266) (xy 115.586009 -394.156442)
			(xy 115.569941 -394.209849) (xy 115.546269 -394.260346) (xy 115.515496 -394.306859) (xy 115.478279 -394.348396)
			(xy 115.435411 -394.384071) (xy 115.387805 -394.413125) (xy 115.336476 -394.434937) (xy 115.282519 -394.449043)
			(xy 115.227082 -394.455143) (xy 115.171348 -394.453106) (xy 115.116505 -394.442976) (xy 115.063721 -394.424969)
			(xy 115.014121 -394.399468) (xy 114.968763 -394.367017) (xy 114.928614 -394.328308) (xy 114.894528 -394.284165)
			(xy 114.867232 -394.23553) (xy 114.847309 -394.183439) (xy 114.835183 -394.129002) (xy 114.831112 -394.07338)
			(xy 112.092486 -394.07338) (xy 111.042958 -395.122908) (xy 112.371122 -395.122908) (xy 112.375193 -395.067286)
			(xy 112.387319 -395.012849) (xy 112.407242 -394.960758) (xy 112.434538 -394.912123) (xy 112.468624 -394.86798)
			(xy 112.508773 -394.829271) (xy 112.554131 -394.79682) (xy 112.603731 -394.771319) (xy 112.656515 -394.753312)
			(xy 112.711358 -394.743182) (xy 112.767092 -394.741145) (xy 112.822529 -394.747245) (xy 112.876486 -394.761351)
			(xy 112.927815 -394.783163) (xy 112.975421 -394.812217) (xy 113.018289 -394.847892) (xy 113.055506 -394.889429)
			(xy 113.086279 -394.935942) (xy 113.109951 -394.986439) (xy 113.126019 -395.039846) (xy 113.134139 -395.095022)
			(xy 113.134648 -395.122908) (xy 113.134139 -395.150794) (xy 113.126019 -395.20597) (xy 113.109951 -395.259377)
			(xy 113.086279 -395.309874) (xy 113.055506 -395.356387) (xy 113.018289 -395.397924) (xy 113.013631 -395.4018)
			(xy 118.337582 -395.4018) (xy 118.341653 -395.346178) (xy 118.353779 -395.291741) (xy 118.373702 -395.23965)
			(xy 118.400998 -395.191015) (xy 118.435084 -395.146872) (xy 118.475233 -395.108163) (xy 118.520591 -395.075712)
			(xy 118.570191 -395.050211) (xy 118.622975 -395.032204) (xy 118.677818 -395.022074) (xy 118.733552 -395.020037)
			(xy 118.788989 -395.026137) (xy 118.842946 -395.040243) (xy 118.894275 -395.062055) (xy 118.941881 -395.091109)
			(xy 118.984749 -395.126784) (xy 119.021966 -395.168321) (xy 119.052739 -395.214834) (xy 119.076411 -395.265331)
			(xy 119.092479 -395.318738) (xy 119.100599 -395.373914) (xy 119.101108 -395.4018) (xy 119.100599 -395.429686)
			(xy 119.092479 -395.484862) (xy 119.076411 -395.538269) (xy 119.052739 -395.588766) (xy 119.021966 -395.635279)
			(xy 118.984749 -395.676816) (xy 118.941881 -395.712491) (xy 118.894275 -395.741545) (xy 118.842946 -395.763357)
			(xy 118.788989 -395.777463) (xy 118.733552 -395.783563) (xy 118.677818 -395.781526) (xy 118.622975 -395.771396)
			(xy 118.570191 -395.753389) (xy 118.520591 -395.727888) (xy 118.475233 -395.695437) (xy 118.435084 -395.656728)
			(xy 118.400998 -395.612585) (xy 118.373702 -395.56395) (xy 118.353779 -395.511859) (xy 118.341653 -395.457422)
			(xy 118.337582 -395.4018) (xy 113.013631 -395.4018) (xy 112.975421 -395.433599) (xy 112.927815 -395.462653)
			(xy 112.876486 -395.484465) (xy 112.822529 -395.498571) (xy 112.767092 -395.504671) (xy 112.711358 -395.502634)
			(xy 112.656515 -395.492504) (xy 112.603731 -395.474497) (xy 112.554131 -395.448996) (xy 112.508773 -395.416545)
			(xy 112.468624 -395.377836) (xy 112.434538 -395.333693) (xy 112.407242 -395.285058) (xy 112.387319 -395.232967)
			(xy 112.375193 -395.17853) (xy 112.371122 -395.122908) (xy 111.042958 -395.122908) (xy 110.363 -395.802866)
			(xy 110.362492 -395.823186) (xy 110.361395 -395.849572) (xy 110.352829 -395.901682) (xy 110.33716 -395.952113)
			(xy 110.314686 -395.999902) (xy 110.285837 -396.044135) (xy 110.251165 -396.083968) (xy 110.211332 -396.11864)
			(xy 110.167098 -396.147488) (xy 110.134031 -396.163038) (xy 115.686076 -396.163038) (xy 115.690147 -396.107416)
			(xy 115.702273 -396.052979) (xy 115.722196 -396.000888) (xy 115.749492 -395.952253) (xy 115.783578 -395.90811)
			(xy 115.823727 -395.869401) (xy 115.869085 -395.83695) (xy 115.918685 -395.811449) (xy 115.971469 -395.793442)
			(xy 116.026312 -395.783312) (xy 116.082046 -395.781275) (xy 116.137483 -395.787375) (xy 116.19144 -395.801481)
			(xy 116.242769 -395.823293) (xy 116.290375 -395.852347) (xy 116.333243 -395.888022) (xy 116.37046 -395.929559)
			(xy 116.401233 -395.976072) (xy 116.424905 -396.026569) (xy 116.440973 -396.079976) (xy 116.449093 -396.135152)
			(xy 116.449602 -396.163038) (xy 116.449093 -396.190924) (xy 116.440973 -396.2461) (xy 116.424905 -396.299507)
			(xy 116.401233 -396.350004) (xy 116.37046 -396.396517) (xy 116.333243 -396.438054) (xy 116.290375 -396.473729)
			(xy 116.242769 -396.502783) (xy 116.19144 -396.524595) (xy 116.137483 -396.538701) (xy 116.082046 -396.544801)
			(xy 116.026312 -396.542764) (xy 115.971469 -396.532634) (xy 115.918685 -396.514627) (xy 115.869085 -396.489126)
			(xy 115.823727 -396.456675) (xy 115.783578 -396.417966) (xy 115.749492 -396.373823) (xy 115.722196 -396.325188)
			(xy 115.702273 -396.273097) (xy 115.690147 -396.21866) (xy 115.686076 -396.163038) (xy 110.134031 -396.163038)
			(xy 110.119309 -396.169961) (xy 110.068878 -396.18563) (xy 110.016768 -396.194196) (xy 109.990382 -396.195296)
			(xy 109.970062 -396.195804) (xy 109.744764 -396.421102) (xy 109.744764 -396.792958) (xy 113.430048 -396.792958)
			(xy 113.434119 -396.737336) (xy 113.446245 -396.682899) (xy 113.466168 -396.630808) (xy 113.493464 -396.582173)
			(xy 113.52755 -396.53803) (xy 113.567699 -396.499321) (xy 113.613057 -396.46687) (xy 113.662657 -396.441369)
			(xy 113.715441 -396.423362) (xy 113.770284 -396.413232) (xy 113.826018 -396.411195) (xy 113.881455 -396.417295)
			(xy 113.935412 -396.431401) (xy 113.986741 -396.453213) (xy 114.034347 -396.482267) (xy 114.077215 -396.517942)
			(xy 114.114432 -396.559479) (xy 114.145205 -396.605992) (xy 114.168877 -396.656489) (xy 114.184945 -396.709896)
			(xy 114.193065 -396.765072) (xy 114.193574 -396.792958) (xy 114.193065 -396.820844) (xy 114.184945 -396.87602)
			(xy 114.168877 -396.929427) (xy 114.145205 -396.979924) (xy 114.114432 -397.026437) (xy 114.077215 -397.067974)
			(xy 114.034347 -397.103649) (xy 113.986741 -397.132703) (xy 113.935412 -397.154515) (xy 113.881455 -397.168621)
			(xy 113.826018 -397.174721) (xy 113.770284 -397.172684) (xy 113.715441 -397.162554) (xy 113.662657 -397.144547)
			(xy 113.613057 -397.119046) (xy 113.567699 -397.086595) (xy 113.52755 -397.047886) (xy 113.493464 -397.003743)
			(xy 113.466168 -396.955108) (xy 113.446245 -396.903017) (xy 113.434119 -396.84858) (xy 113.430048 -396.792958)
			(xy 109.744764 -396.792958) (xy 109.744764 -397.474948) (xy 114.558062 -397.474948) (xy 114.562133 -397.419326)
			(xy 114.574259 -397.364889) (xy 114.594182 -397.312798) (xy 114.621478 -397.264163) (xy 114.655564 -397.22002)
			(xy 114.695713 -397.181311) (xy 114.741071 -397.14886) (xy 114.790671 -397.123359) (xy 114.843455 -397.105352)
			(xy 114.898298 -397.095222) (xy 114.954032 -397.093185) (xy 115.009469 -397.099285) (xy 115.063426 -397.113391)
			(xy 115.114755 -397.135203) (xy 115.162361 -397.164257) (xy 115.205229 -397.199932) (xy 115.242446 -397.241469)
			(xy 115.273219 -397.287982) (xy 115.296891 -397.338479) (xy 115.312959 -397.391886) (xy 115.321079 -397.447062)
			(xy 115.321588 -397.474948) (xy 115.321079 -397.502834) (xy 115.312959 -397.55801) (xy 115.296891 -397.611417)
			(xy 115.273219 -397.661914) (xy 115.242446 -397.708427) (xy 115.205229 -397.749964) (xy 115.162361 -397.785639)
			(xy 115.114755 -397.814693) (xy 115.063426 -397.836505) (xy 115.009469 -397.850611) (xy 114.954032 -397.856711)
			(xy 114.898298 -397.854674) (xy 114.843455 -397.844544) (xy 114.790671 -397.826537) (xy 114.741071 -397.801036)
			(xy 114.695713 -397.768585) (xy 114.655564 -397.729876) (xy 114.621478 -397.685733) (xy 114.594182 -397.637098)
			(xy 114.574259 -397.585007) (xy 114.562133 -397.53057) (xy 114.558062 -397.474948) (xy 109.744764 -397.474948)
			(xy 109.744764 -398.160748) (xy 109.963202 -398.160748) (xy 109.967273 -398.105126) (xy 109.979399 -398.050689)
			(xy 109.999322 -397.998598) (xy 110.026618 -397.949963) (xy 110.060704 -397.90582) (xy 110.100853 -397.867111)
			(xy 110.146211 -397.83466) (xy 110.195811 -397.809159) (xy 110.248595 -397.791152) (xy 110.303438 -397.781022)
			(xy 110.359172 -397.778985) (xy 110.414609 -397.785085) (xy 110.468566 -397.799191) (xy 110.519895 -397.821003)
			(xy 110.567501 -397.850057) (xy 110.610369 -397.885732) (xy 110.647586 -397.927269) (xy 110.678359 -397.973782)
			(xy 110.702031 -398.024279) (xy 110.718099 -398.077686) (xy 110.726219 -398.132862) (xy 110.726728 -398.160748)
			(xy 110.726219 -398.188634) (xy 110.718099 -398.24381) (xy 110.702031 -398.297217) (xy 110.678359 -398.347714)
			(xy 110.647586 -398.394227) (xy 110.610369 -398.435764) (xy 110.567501 -398.471439) (xy 110.519895 -398.500493)
			(xy 110.468566 -398.522305) (xy 110.414609 -398.536411) (xy 110.359172 -398.542511) (xy 110.303438 -398.540474)
			(xy 110.248595 -398.530344) (xy 110.195811 -398.512337) (xy 110.146211 -398.486836) (xy 110.100853 -398.454385)
			(xy 110.060704 -398.415676) (xy 110.026618 -398.371533) (xy 109.999322 -398.322898) (xy 109.979399 -398.270807)
			(xy 109.967273 -398.21637) (xy 109.963202 -398.160748) (xy 109.744764 -398.160748) (xy 109.744764 -398.884648)
			(xy 112.907062 -398.884648) (xy 112.911133 -398.829026) (xy 112.923259 -398.774589) (xy 112.943182 -398.722498)
			(xy 112.970478 -398.673863) (xy 113.004564 -398.62972) (xy 113.044713 -398.591011) (xy 113.090071 -398.55856)
			(xy 113.139671 -398.533059) (xy 113.192455 -398.515052) (xy 113.247298 -398.504922) (xy 113.303032 -398.502885)
			(xy 113.358469 -398.508985) (xy 113.412426 -398.523091) (xy 113.463755 -398.544903) (xy 113.511361 -398.573957)
			(xy 113.554229 -398.609632) (xy 113.591446 -398.651169) (xy 113.622219 -398.697682) (xy 113.645891 -398.748179)
			(xy 113.661959 -398.801586) (xy 113.670079 -398.856762) (xy 113.670588 -398.884648) (xy 113.923062 -398.884648)
			(xy 113.927133 -398.829026) (xy 113.939259 -398.774589) (xy 113.959182 -398.722498) (xy 113.986478 -398.673863)
			(xy 114.020564 -398.62972) (xy 114.060713 -398.591011) (xy 114.106071 -398.55856) (xy 114.155671 -398.533059)
			(xy 114.208455 -398.515052) (xy 114.263298 -398.504922) (xy 114.319032 -398.502885) (xy 114.374469 -398.508985)
			(xy 114.428426 -398.523091) (xy 114.479755 -398.544903) (xy 114.527361 -398.573957) (xy 114.570229 -398.609632)
			(xy 114.607446 -398.651169) (xy 114.638219 -398.697682) (xy 114.661891 -398.748179) (xy 114.677959 -398.801586)
			(xy 114.686079 -398.856762) (xy 114.686588 -398.884648) (xy 114.686079 -398.912534) (xy 114.677959 -398.96771)
			(xy 114.661891 -399.021117) (xy 114.638219 -399.071614) (xy 114.607446 -399.118127) (xy 114.570229 -399.159664)
			(xy 114.527361 -399.195339) (xy 114.479755 -399.224393) (xy 114.428426 -399.246205) (xy 114.374469 -399.260311)
			(xy 114.319032 -399.266411) (xy 114.263298 -399.264374) (xy 114.208455 -399.254244) (xy 114.155671 -399.236237)
			(xy 114.106071 -399.210736) (xy 114.060713 -399.178285) (xy 114.020564 -399.139576) (xy 113.986478 -399.095433)
			(xy 113.959182 -399.046798) (xy 113.939259 -398.994707) (xy 113.927133 -398.94027) (xy 113.923062 -398.884648)
			(xy 113.670588 -398.884648) (xy 113.670079 -398.912534) (xy 113.661959 -398.96771) (xy 113.645891 -399.021117)
			(xy 113.622219 -399.071614) (xy 113.591446 -399.118127) (xy 113.554229 -399.159664) (xy 113.511361 -399.195339)
			(xy 113.463755 -399.224393) (xy 113.412426 -399.246205) (xy 113.358469 -399.260311) (xy 113.303032 -399.266411)
			(xy 113.247298 -399.264374) (xy 113.192455 -399.254244) (xy 113.139671 -399.236237) (xy 113.090071 -399.210736)
			(xy 113.044713 -399.178285) (xy 113.004564 -399.139576) (xy 112.970478 -399.095433) (xy 112.943182 -399.046798)
			(xy 112.923259 -398.994707) (xy 112.911133 -398.94027) (xy 112.907062 -398.884648) (xy 109.744764 -398.884648)
			(xy 109.744764 -400.536742) (xy 111.38374 -400.536742) (xy 111.383742 -400.482233) (xy 111.391501 -400.428279)
			(xy 111.40686 -400.375979) (xy 111.429506 -400.326396) (xy 111.458978 -400.280542) (xy 111.494676 -400.239349)
			(xy 111.535873 -400.203655) (xy 111.58173 -400.174188) (xy 111.631315 -400.151547) (xy 111.683617 -400.136193)
			(xy 111.737571 -400.128439) (xy 111.764826 -400.127978) (xy 111.775261 -400.128055) (xy 111.796101 -400.129197)
			(xy 111.806482 -400.130264) (xy 111.820863 -400.131284) (xy 111.849232 -400.126232) (xy 111.875065 -400.113465)
			(xy 111.89631 -400.093997) (xy 111.911279 -400.069375) (xy 111.918784 -400.041555) (xy 111.919004 -400.02714)
			(xy 111.919004 -400.019266) (xy 111.919515 -399.992018) (xy 111.927275 -399.938077) (xy 111.942632 -399.88579)
			(xy 111.965275 -399.83622) (xy 111.994741 -399.790377) (xy 112.030431 -399.749194) (xy 112.071619 -399.71351)
			(xy 112.117466 -399.68405) (xy 112.167039 -399.661414) (xy 112.219329 -399.646064) (xy 112.273271 -399.638311)
			(xy 112.327767 -399.638313) (xy 112.381708 -399.646072) (xy 112.433996 -399.661427) (xy 112.483567 -399.684067)
			(xy 112.529411 -399.713532) (xy 112.570595 -399.749221) (xy 112.606281 -399.790407) (xy 112.635743 -399.836253)
			(xy 112.658381 -399.885825) (xy 112.673733 -399.938114) (xy 112.681488 -399.992055) (xy 112.681488 -400.014948)
			(xy 113.597942 -400.014948) (xy 113.602013 -399.959326) (xy 113.614139 -399.904889) (xy 113.634062 -399.852798)
			(xy 113.661358 -399.804163) (xy 113.695444 -399.76002) (xy 113.735593 -399.721311) (xy 113.780951 -399.68886)
			(xy 113.830551 -399.663359) (xy 113.883335 -399.645352) (xy 113.938178 -399.635222) (xy 113.993912 -399.633185)
			(xy 114.049349 -399.639285) (xy 114.103306 -399.653391) (xy 114.154635 -399.675203) (xy 114.202241 -399.704257)
			(xy 114.245109 -399.739932) (xy 114.282326 -399.781469) (xy 114.313099 -399.827982) (xy 114.336771 -399.878479)
			(xy 114.352839 -399.931886) (xy 114.360959 -399.987062) (xy 114.361468 -400.014948) (xy 114.360959 -400.042834)
			(xy 114.352839 -400.09801) (xy 114.336771 -400.151417) (xy 114.313099 -400.201914) (xy 114.282326 -400.248427)
			(xy 114.245109 -400.289964) (xy 114.202241 -400.325639) (xy 114.154635 -400.354693) (xy 114.103306 -400.376505)
			(xy 114.049349 -400.390611) (xy 113.993912 -400.396711) (xy 113.938178 -400.394674) (xy 113.883335 -400.384544)
			(xy 113.830551 -400.366537) (xy 113.780951 -400.341036) (xy 113.735593 -400.308585) (xy 113.695444 -400.269876)
			(xy 113.661358 -400.225733) (xy 113.634062 -400.177098) (xy 113.614139 -400.125007) (xy 113.602013 -400.07057)
			(xy 113.597942 -400.014948) (xy 112.681488 -400.014948) (xy 112.681488 -400.046551) (xy 112.673732 -400.100493)
			(xy 112.658378 -400.152782) (xy 112.63574 -400.202353) (xy 112.606277 -400.248198) (xy 112.57059 -400.289384)
			(xy 112.529405 -400.325072) (xy 112.483561 -400.354536) (xy 112.43399 -400.377175) (xy 112.381701 -400.39253)
			(xy 112.32776 -400.400287) (xy 112.300512 -400.400774) (xy 112.290076 -400.400703) (xy 112.269237 -400.399557)
			(xy 112.258856 -400.398488) (xy 112.244474 -400.397452) (xy 112.216098 -400.402497) (xy 112.190259 -400.415264)
			(xy 112.169011 -400.434736) (xy 112.154043 -400.459366) (xy 112.146547 -400.487194) (xy 112.146334 -400.501612)
			(xy 112.146334 -400.509486) (xy 112.14586 -400.536741) (xy 112.138104 -400.590695) (xy 112.122749 -400.642996)
			(xy 112.100107 -400.69258) (xy 112.070638 -400.738437) (xy 112.034943 -400.779633) (xy 111.993748 -400.815329)
			(xy 111.947893 -400.8448) (xy 111.89831 -400.867444) (xy 111.846009 -400.882801) (xy 111.792055 -400.890559)
			(xy 111.737546 -400.890559) (xy 111.683592 -400.882802) (xy 111.631291 -400.867444) (xy 111.581708 -400.8448)
			(xy 111.535853 -400.81533) (xy 111.494658 -400.779634) (xy 111.458963 -400.738438) (xy 111.429494 -400.692581)
			(xy 111.406851 -400.642998) (xy 111.391496 -400.590696) (xy 111.38374 -400.536742) (xy 109.744764 -400.536742)
			(xy 109.744764 -400.76755) (xy 109.745282 -400.782491) (xy 109.753918 -400.811097) (xy 109.770466 -400.835978)
			(xy 109.793508 -400.855003) (xy 109.821071 -400.866544) (xy 109.850794 -400.869611) (xy 109.880133 -400.863942)
			(xy 109.893608 -400.857466) (xy 109.921109 -400.843699) (xy 109.979446 -400.824235) (xy 110.040151 -400.814384)
			(xy 110.0709 -400.813778) (xy 110.098152 -400.814264) (xy 110.152102 -400.822021) (xy 110.204399 -400.837376)
			(xy 110.253978 -400.860018) (xy 110.29983 -400.889486) (xy 110.341022 -400.925178) (xy 110.376714 -400.96637)
			(xy 110.406182 -401.012222) (xy 110.428824 -401.061801) (xy 110.444179 -401.114098) (xy 110.451936 -401.168048)
			(xy 110.451936 -401.222552) (xy 110.444179 -401.276502) (xy 110.428824 -401.328799) (xy 110.406182 -401.378378)
			(xy 110.376714 -401.42423) (xy 110.376352 -401.424648) (xy 114.431062 -401.424648) (xy 114.435133 -401.369026)
			(xy 114.447259 -401.314589) (xy 114.467182 -401.262498) (xy 114.494478 -401.213863) (xy 114.528564 -401.16972)
			(xy 114.568713 -401.131011) (xy 114.614071 -401.09856) (xy 114.663671 -401.073059) (xy 114.716455 -401.055052)
			(xy 114.771298 -401.044922) (xy 114.827032 -401.042885) (xy 114.882469 -401.048985) (xy 114.936426 -401.063091)
			(xy 114.987755 -401.084903) (xy 115.035361 -401.113957) (xy 115.078229 -401.149632) (xy 115.115446 -401.191169)
			(xy 115.146219 -401.237682) (xy 115.169891 -401.288179) (xy 115.185959 -401.341586) (xy 115.194079 -401.396762)
			(xy 115.194588 -401.424648) (xy 115.194079 -401.452534) (xy 115.185959 -401.50771) (xy 115.169891 -401.561117)
			(xy 115.146219 -401.611614) (xy 115.115446 -401.658127) (xy 115.078229 -401.699664) (xy 115.035361 -401.735339)
			(xy 114.987755 -401.764393) (xy 114.936426 -401.786205) (xy 114.882469 -401.800311) (xy 114.827032 -401.806411)
			(xy 114.771298 -401.804374) (xy 114.716455 -401.794244) (xy 114.663671 -401.776237) (xy 114.614071 -401.750736)
			(xy 114.568713 -401.718285) (xy 114.528564 -401.679576) (xy 114.494478 -401.635433) (xy 114.467182 -401.586798)
			(xy 114.447259 -401.534707) (xy 114.435133 -401.48027) (xy 114.431062 -401.424648) (xy 110.376352 -401.424648)
			(xy 110.341022 -401.465422) (xy 110.29983 -401.501114) (xy 110.253978 -401.530582) (xy 110.204399 -401.553224)
			(xy 110.152102 -401.568579) (xy 110.098152 -401.576336) (xy 110.0709 -401.576794) (xy 110.040152 -401.576177)
			(xy 109.979452 -401.566317) (xy 109.921118 -401.546853) (xy 109.893608 -401.533106) (xy 109.88014 -401.526632)
			(xy 109.850809 -401.520997) (xy 109.8211 -401.524083) (xy 109.793553 -401.535626) (xy 109.77052 -401.554641)
			(xy 109.753967 -401.579503) (xy 109.74531 -401.608088) (xy 109.744764 -401.623022) (xy 109.744764 -406.644602)
			(xy 109.745311 -406.659683) (xy 109.754122 -406.688528) (xy 109.770977 -406.71354) (xy 109.794403 -406.732538)
			(xy 109.822358 -406.743863) (xy 109.852401 -406.746527) (xy 109.881912 -406.740298) (xy 109.895386 -406.733502)
			(xy 109.923738 -406.718645) (xy 109.984175 -406.697578) (xy 110.04728 -406.686893) (xy 110.079282 -406.686258)
			(xy 110.106538 -406.68672) (xy 110.160496 -406.694475) (xy 110.212801 -406.709831) (xy 110.262387 -406.732475)
			(xy 110.308247 -406.761945) (xy 110.349446 -406.797642) (xy 110.385144 -406.838839) (xy 110.414617 -406.884697)
			(xy 110.437263 -406.934282) (xy 110.452621 -406.986586) (xy 110.460379 -407.040544) (xy 110.460379 -407.067766)
			(xy 110.713264 -407.067766) (xy 110.717335 -407.012144) (xy 110.729461 -406.957707) (xy 110.749384 -406.905616)
			(xy 110.77668 -406.856981) (xy 110.810766 -406.812838) (xy 110.850915 -406.774129) (xy 110.896273 -406.741678)
			(xy 110.945873 -406.716177) (xy 110.998657 -406.69817) (xy 111.0535 -406.68804) (xy 111.109234 -406.686003)
			(xy 111.164671 -406.692103) (xy 111.218628 -406.706209) (xy 111.269957 -406.728021) (xy 111.317563 -406.757075)
			(xy 111.360431 -406.79275) (xy 111.397648 -406.834287) (xy 111.428421 -406.8808) (xy 111.452093 -406.931297)
			(xy 111.468161 -406.984704) (xy 111.476281 -407.03988) (xy 111.47679 -407.067766) (xy 111.476281 -407.095652)
			(xy 111.475442 -407.101353) (xy 111.711171 -407.101353) (xy 111.711171 -407.046847) (xy 111.718929 -406.992895)
			(xy 111.734286 -406.940597) (xy 111.75693 -406.891017) (xy 111.7864 -406.845164) (xy 111.822095 -406.803972)
			(xy 111.86329 -406.76828) (xy 111.909145 -406.738814) (xy 111.958727 -406.716175) (xy 112.011027 -406.700822)
			(xy 112.064979 -406.693069) (xy 112.092232 -406.692608) (xy 112.118834 -406.693105) (xy 112.171526 -406.700478)
			(xy 112.22268 -406.715103) (xy 112.271305 -406.736698) (xy 112.316456 -406.764842) (xy 112.357257 -406.798989)
			(xy 112.392914 -406.838477) (xy 112.408208 -406.860248) (xy 112.416542 -406.871728) (xy 112.438286 -406.889932)
			(xy 112.464199 -406.90145) (xy 112.492282 -406.90539) (xy 112.520365 -406.90145) (xy 112.546278 -406.889932)
			(xy 112.568022 -406.871728) (xy 112.576356 -406.860248) (xy 112.591669 -406.838491) (xy 112.627332 -406.799011)
			(xy 112.668132 -406.764867) (xy 112.713279 -406.73672) (xy 112.761898 -406.715115) (xy 112.813045 -406.700472)
			(xy 112.865731 -406.693074) (xy 112.892332 -406.692608) (xy 112.919583 -406.693064) (xy 112.973529 -406.700825)
			(xy 113.025823 -406.716183) (xy 113.075398 -406.738827) (xy 113.121246 -406.768295) (xy 113.162434 -406.803988)
			(xy 113.198124 -406.84518) (xy 113.227588 -406.89103) (xy 113.250228 -406.940607) (xy 113.265582 -406.992902)
			(xy 113.273338 -407.046849) (xy 113.273338 -407.101351) (xy 113.265582 -407.155298) (xy 113.250228 -407.207593)
			(xy 113.227588 -407.25717) (xy 113.198124 -407.30302) (xy 113.162434 -407.344212) (xy 113.121246 -407.379905)
			(xy 113.075398 -407.409373) (xy 113.025823 -407.432017) (xy 112.973529 -407.447375) (xy 112.919583 -407.455136)
			(xy 112.892332 -407.455624) (xy 112.865727 -407.455184) (xy 112.813032 -407.447805) (xy 112.761875 -407.433172)
			(xy 112.713249 -407.411569) (xy 112.668098 -407.383415) (xy 112.6273 -407.349258) (xy 112.591647 -407.30976)
			(xy 112.576356 -407.287984) (xy 112.568022 -407.276504) (xy 112.546278 -407.2583) (xy 112.520365 -407.246782)
			(xy 112.492282 -407.242842) (xy 112.464199 -407.246782) (xy 112.438286 -407.2583) (xy 112.416542 -407.276504)
			(xy 112.408208 -407.287984) (xy 112.392928 -407.309765) (xy 112.357258 -407.349243) (xy 112.316452 -407.383384)
			(xy 112.271299 -407.411528) (xy 112.222676 -407.433129) (xy 112.171524 -407.447768) (xy 112.118835 -407.455161)
			(xy 112.092232 -407.455624) (xy 112.064979 -407.455131) (xy 112.011027 -407.447378) (xy 111.958727 -407.432025)
			(xy 111.909145 -407.409386) (xy 111.86329 -407.37992) (xy 111.822095 -407.344228) (xy 111.786399 -407.303036)
			(xy 111.75693 -407.257183) (xy 111.734286 -407.207603) (xy 111.718929 -407.155305) (xy 111.711171 -407.101353)
			(xy 111.475442 -407.101353) (xy 111.468161 -407.150828) (xy 111.452093 -407.204235) (xy 111.428421 -407.254732)
			(xy 111.397648 -407.301245) (xy 111.360431 -407.342782) (xy 111.317563 -407.378457) (xy 111.269957 -407.407511)
			(xy 111.218628 -407.429323) (xy 111.164671 -407.443429) (xy 111.109234 -407.449529) (xy 111.0535 -407.447492)
			(xy 110.998657 -407.437362) (xy 110.945873 -407.419355) (xy 110.896273 -407.393854) (xy 110.850915 -407.361403)
			(xy 110.810766 -407.322694) (xy 110.77668 -407.278551) (xy 110.749384 -407.229916) (xy 110.729461 -407.177825)
			(xy 110.717335 -407.123388) (xy 110.713264 -407.067766) (xy 110.460379 -407.067766) (xy 110.460379 -407.095056)
			(xy 110.452621 -407.149014) (xy 110.437263 -407.201318) (xy 110.414617 -407.250903) (xy 110.385144 -407.296761)
			(xy 110.349446 -407.337958) (xy 110.308247 -407.373655) (xy 110.262387 -407.403125) (xy 110.212801 -407.425769)
			(xy 110.160496 -407.441125) (xy 110.106538 -407.44888) (xy 110.079282 -407.449274) (xy 110.047281 -407.448621)
			(xy 109.984177 -407.43794) (xy 109.92374 -407.41688) (xy 109.895386 -407.40203) (xy 109.881921 -407.395238)
			(xy 109.852422 -407.38904) (xy 109.822399 -407.391722) (xy 109.794466 -407.403051) (xy 109.771057 -407.42204)
			(xy 109.754209 -407.447035) (xy 109.745391 -407.475859) (xy 109.744764 -407.49093) (xy 109.744764 -407.761186)
			(xy 109.7452 -407.770946) (xy 109.752482 -407.789058) (xy 109.766 -407.80314) (xy 109.783797 -407.811159)
			(xy 109.793532 -407.811986) (xy 109.820076 -407.813472) (xy 109.872401 -407.822881) (xy 109.922912 -407.839465)
			(xy 109.970631 -407.862901) (xy 110.014635 -407.892735) (xy 110.054069 -407.928391) (xy 110.088171 -407.969176)
			(xy 110.116279 -408.014302) (xy 110.13785 -408.062893) (xy 110.152465 -408.114008) (xy 110.159841 -408.166658)
			(xy 110.160308 -408.19324) (xy 110.159819 -408.220489) (xy 110.152058 -408.274433) (xy 110.1367 -408.326723)
			(xy 110.114056 -408.376295) (xy 110.084589 -408.42214) (xy 110.048897 -408.463326) (xy 110.007708 -408.499013)
			(xy 109.96186 -408.528476) (xy 109.912285 -408.551114) (xy 109.859994 -408.566467) (xy 109.806049 -408.574222)
			(xy 109.7788 -408.574748) (xy 109.750106 -408.574223) (xy 109.693366 -408.565616) (xy 109.638555 -408.54861)
			(xy 109.586908 -408.52359) (xy 109.53959 -408.491118) (xy 109.497666 -408.451928) (xy 109.462083 -408.406902)
			(xy 109.433643 -408.357056) (xy 109.412986 -408.303514) (xy 109.400579 -408.247483) (xy 109.398054 -408.218894)
			(xy 109.396784 -408.199844) (xy 109.347508 -408.150314) (xy 109.293406 -408.204416) (xy 109.28985 -408.211274)
			(xy 109.275863 -408.237134) (xy 109.241161 -408.28459) (xy 109.19959 -408.326161) (xy 109.152134 -408.360863)
			(xy 109.126274 -408.37485) (xy 109.119416 -408.378406) (xy 108.761022 -408.7368) (xy 110.168942 -408.7368)
			(xy 110.173013 -408.681178) (xy 110.185139 -408.626741) (xy 110.205062 -408.57465) (xy 110.232358 -408.526015)
			(xy 110.266444 -408.481872) (xy 110.306593 -408.443163) (xy 110.351951 -408.410712) (xy 110.401551 -408.385211)
			(xy 110.454335 -408.367204) (xy 110.509178 -408.357074) (xy 110.564912 -408.355037) (xy 110.620349 -408.361137)
			(xy 110.674306 -408.375243) (xy 110.725635 -408.397055) (xy 110.773241 -408.426109) (xy 110.816109 -408.461784)
			(xy 110.853326 -408.503321) (xy 110.884099 -408.549834) (xy 110.907771 -408.600331) (xy 110.923839 -408.653738)
			(xy 110.931959 -408.708914) (xy 110.932468 -408.7368) (xy 110.931959 -408.764686) (xy 110.923839 -408.819862)
			(xy 110.907771 -408.873269) (xy 110.884099 -408.923766) (xy 110.853326 -408.970279) (xy 110.816109 -409.011816)
			(xy 110.773241 -409.047491) (xy 110.725635 -409.076545) (xy 110.674306 -409.098357) (xy 110.620349 -409.112463)
			(xy 110.564912 -409.118563) (xy 110.509178 -409.116526) (xy 110.454335 -409.106396) (xy 110.401551 -409.088389)
			(xy 110.351951 -409.062888) (xy 110.306593 -409.030437) (xy 110.266444 -408.991728) (xy 110.232358 -408.947585)
			(xy 110.205062 -408.89895) (xy 110.185139 -408.846859) (xy 110.173013 -408.792422) (xy 110.168942 -408.7368)
			(xy 108.761022 -408.7368) (xy 108.376974 -409.120848) (xy 112.343182 -409.120848) (xy 112.347253 -409.065226)
			(xy 112.359379 -409.010789) (xy 112.379302 -408.958698) (xy 112.406598 -408.910063) (xy 112.440684 -408.86592)
			(xy 112.480833 -408.827211) (xy 112.526191 -408.79476) (xy 112.575791 -408.769259) (xy 112.628575 -408.751252)
			(xy 112.683418 -408.741122) (xy 112.739152 -408.739085) (xy 112.794589 -408.745185) (xy 112.848546 -408.759291)
			(xy 112.899875 -408.781103) (xy 112.947481 -408.810157) (xy 112.990349 -408.845832) (xy 113.027566 -408.887369)
			(xy 113.058339 -408.933882) (xy 113.082011 -408.984379) (xy 113.098079 -409.037786) (xy 113.106199 -409.092962)
			(xy 113.106708 -409.120848) (xy 113.106199 -409.148734) (xy 113.098079 -409.20391) (xy 113.082011 -409.257317)
			(xy 113.058339 -409.307814) (xy 113.027566 -409.354327) (xy 112.990349 -409.395864) (xy 112.947481 -409.431539)
			(xy 112.899875 -409.460593) (xy 112.848546 -409.482405) (xy 112.794589 -409.496511) (xy 112.739152 -409.502611)
			(xy 112.683418 -409.500574) (xy 112.628575 -409.490444) (xy 112.575791 -409.472437) (xy 112.526191 -409.446936)
			(xy 112.480833 -409.414485) (xy 112.440684 -409.375776) (xy 112.406598 -409.331633) (xy 112.379302 -409.282998)
			(xy 112.359379 -409.230907) (xy 112.347253 -409.17647) (xy 112.343182 -409.120848) (xy 108.376974 -409.120848)
			(xy 107.587034 -409.910788) (xy 109.472982 -409.910788) (xy 109.477053 -409.855166) (xy 109.489179 -409.800729)
			(xy 109.509102 -409.748638) (xy 109.536398 -409.700003) (xy 109.570484 -409.65586) (xy 109.610633 -409.617151)
			(xy 109.655991 -409.5847) (xy 109.705591 -409.559199) (xy 109.758375 -409.541192) (xy 109.813218 -409.531062)
			(xy 109.868952 -409.529025) (xy 109.924389 -409.535125) (xy 109.978346 -409.549231) (xy 110.029675 -409.571043)
			(xy 110.077281 -409.600097) (xy 110.120149 -409.635772) (xy 110.157366 -409.677309) (xy 110.188139 -409.723822)
			(xy 110.211811 -409.774319) (xy 110.227879 -409.827726) (xy 110.235999 -409.882902) (xy 110.236508 -409.910788)
			(xy 110.235999 -409.938674) (xy 110.227879 -409.99385) (xy 110.211811 -410.047257) (xy 110.188139 -410.097754)
			(xy 110.157366 -410.144267) (xy 110.120149 -410.185804) (xy 110.077281 -410.221479) (xy 110.029675 -410.250533)
			(xy 109.978346 -410.272345) (xy 109.924389 -410.286451) (xy 109.868952 -410.292551) (xy 109.813218 -410.290514)
			(xy 109.758375 -410.280384) (xy 109.705591 -410.262377) (xy 109.655991 -410.236876) (xy 109.610633 -410.204425)
			(xy 109.570484 -410.165716) (xy 109.536398 -410.121573) (xy 109.509102 -410.072938) (xy 109.489179 -410.020847)
			(xy 109.477053 -409.96641) (xy 109.472982 -409.910788) (xy 107.587034 -409.910788) (xy 106.881422 -410.6164)
			(xy 107.517182 -410.6164) (xy 107.521253 -410.560778) (xy 107.533379 -410.506341) (xy 107.553302 -410.45425)
			(xy 107.580598 -410.405615) (xy 107.614684 -410.361472) (xy 107.654833 -410.322763) (xy 107.700191 -410.290312)
			(xy 107.749791 -410.264811) (xy 107.802575 -410.246804) (xy 107.857418 -410.236674) (xy 107.913152 -410.234637)
			(xy 107.968589 -410.240737) (xy 108.022546 -410.254843) (xy 108.073875 -410.276655) (xy 108.121481 -410.305709)
			(xy 108.164349 -410.341384) (xy 108.201566 -410.382921) (xy 108.232339 -410.429434) (xy 108.256011 -410.479931)
			(xy 108.272079 -410.533338) (xy 108.280199 -410.588514) (xy 108.280708 -410.6164) (xy 108.280199 -410.644286)
			(xy 108.272079 -410.699462) (xy 108.256011 -410.752869) (xy 108.232339 -410.803366) (xy 108.201566 -410.849879)
			(xy 108.164349 -410.891416) (xy 108.121481 -410.927091) (xy 108.073875 -410.956145) (xy 108.022546 -410.977957)
			(xy 107.968589 -410.992063) (xy 107.913152 -410.998163) (xy 107.857418 -410.996126) (xy 107.802575 -410.985996)
			(xy 107.749791 -410.967989) (xy 107.700191 -410.942488) (xy 107.654833 -410.910037) (xy 107.614684 -410.871328)
			(xy 107.580598 -410.827185) (xy 107.553302 -410.77855) (xy 107.533379 -410.726459) (xy 107.521253 -410.672022)
			(xy 107.517182 -410.6164) (xy 106.881422 -410.6164) (xy 106.732324 -410.765498) (xy 106.72953 -410.780992)
			(xy 106.72127 -410.822542) (xy 106.698568 -410.904165) (xy 106.668964 -410.983546) (xy 106.632677 -411.060103)
			(xy 106.589973 -411.133275) (xy 106.541165 -411.202524) (xy 106.486611 -411.267344) (xy 106.456988 -411.297628)
			(xy 106.051096 -411.70352) (xy 106.049826 -411.72257) (xy 106.047406 -411.752277) (xy 106.034507 -411.810466)
			(xy 106.012721 -411.865942) (xy 105.982575 -411.917357) (xy 105.944804 -411.963461) (xy 105.900326 -412.003133)
			(xy 105.875582 -412.01975) (xy 105.875582 -413.895032) (xy 104.493568 -415.277046) (xy 103.41864 -415.277046)
			(xy 101.39172 -417.303966) (xy 101.39172 -418.625274) (xy 101.761798 -418.995352) (xy 104.385618 -418.995352)
		)
		(stroke
			(width 0)
			(type solid)
		)
		(fill yes)
		(layer "In15.Cu")
		(net "P3V3")
	)
	(gr_poly
		(pts
			(xy 430.336706 -112.062514) (xy 430.35469 -112.045158) (xy 430.395102 -112.015752) (xy 430.43962 -111.993038)
			(xy 430.487146 -111.977576) (xy 430.536507 -111.969748) (xy 430.561496 -111.969296) (xy 434.082698 -111.969296)
			(xy 436.98668 -109.065568) (xy 436.98668 -97.081848) (xy 436.72252 -96.817688) (xy 436.71233 -96.808166)
			(xy 436.687982 -96.794587) (xy 436.660868 -96.788102) (xy 436.63301 -96.789194) (xy 436.606487 -96.797782)
			(xy 436.583276 -96.813225) (xy 436.565109 -96.834371) (xy 436.553339 -96.859644) (xy 436.550562 -96.873314)
			(xy 436.54582 -96.899826) (xy 436.529856 -96.951265) (xy 436.506817 -96.999947) (xy 436.477161 -97.044905)
			(xy 436.441477 -97.085245) (xy 436.400474 -97.120166) (xy 436.354967 -97.148974) (xy 436.305861 -97.171095)
			(xy 436.254133 -97.186091) (xy 436.200809 -97.193662) (xy 436.17388 -97.194116) (xy 436.146629 -97.193629)
			(xy 436.092683 -97.18587) (xy 436.040391 -97.170513) (xy 435.990815 -97.147871) (xy 435.944967 -97.118404)
			(xy 435.903778 -97.082713) (xy 435.868088 -97.041523) (xy 435.838623 -96.995674) (xy 435.815982 -96.946098)
			(xy 435.800627 -96.893805) (xy 435.79287 -96.839859) (xy 435.792372 -96.812608) (xy 435.792834 -96.785677)
			(xy 435.800406 -96.732351) (xy 435.815401 -96.68062) (xy 435.83752 -96.63151) (xy 435.866325 -96.585999)
			(xy 435.901242 -96.544989) (xy 435.941579 -96.509297) (xy 435.986534 -96.479631) (xy 436.035213 -96.45658)
			(xy 436.08665 -96.440602) (xy 436.113174 -96.435926) (xy 436.126886 -96.43327) (xy 436.152212 -96.421518)
			(xy 436.173405 -96.403342) (xy 436.188878 -96.380102) (xy 436.197474 -96.353538) (xy 436.198547 -96.325638)
			(xy 436.192019 -96.298492) (xy 436.178378 -96.274132) (xy 436.1688 -96.263968) (xy 435.65318 -95.748348)
			(xy 418.15258 -95.748348) (xy 417.08832 -96.812608) (xy 434.902862 -96.812608) (xy 434.906933 -96.756986)
			(xy 434.919059 -96.702549) (xy 434.938982 -96.650458) (xy 434.966278 -96.601823) (xy 435.000364 -96.55768)
			(xy 435.040513 -96.518971) (xy 435.085871 -96.48652) (xy 435.135471 -96.461019) (xy 435.188255 -96.443012)
			(xy 435.243098 -96.432882) (xy 435.298832 -96.430845) (xy 435.354269 -96.436945) (xy 435.408226 -96.451051)
			(xy 435.459555 -96.472863) (xy 435.507161 -96.501917) (xy 435.550029 -96.537592) (xy 435.587246 -96.579129)
			(xy 435.618019 -96.625642) (xy 435.641691 -96.676139) (xy 435.657759 -96.729546) (xy 435.665879 -96.784722)
			(xy 435.666388 -96.812608) (xy 435.665879 -96.840494) (xy 435.657759 -96.89567) (xy 435.641691 -96.949077)
			(xy 435.618019 -96.999574) (xy 435.587246 -97.046087) (xy 435.550029 -97.087624) (xy 435.507161 -97.123299)
			(xy 435.459555 -97.152353) (xy 435.408226 -97.174165) (xy 435.354269 -97.188271) (xy 435.298832 -97.194371)
			(xy 435.243098 -97.192334) (xy 435.188255 -97.182204) (xy 435.135471 -97.164197) (xy 435.085871 -97.138696)
			(xy 435.040513 -97.106245) (xy 435.000364 -97.067536) (xy 434.966278 -97.023393) (xy 434.938982 -96.974758)
			(xy 434.919059 -96.922667) (xy 434.906933 -96.86823) (xy 434.902862 -96.812608) (xy 417.08832 -96.812608)
			(xy 416.19932 -97.701608) (xy 434.902862 -97.701608) (xy 434.906933 -97.645986) (xy 434.919059 -97.591549)
			(xy 434.938982 -97.539458) (xy 434.966278 -97.490823) (xy 435.000364 -97.44668) (xy 435.040513 -97.407971)
			(xy 435.085871 -97.37552) (xy 435.135471 -97.350019) (xy 435.188255 -97.332012) (xy 435.243098 -97.321882)
			(xy 435.298832 -97.319845) (xy 435.354269 -97.325945) (xy 435.408226 -97.340051) (xy 435.459555 -97.361863)
			(xy 435.507161 -97.390917) (xy 435.550029 -97.426592) (xy 435.587246 -97.468129) (xy 435.618019 -97.514642)
			(xy 435.641691 -97.565139) (xy 435.657759 -97.618546) (xy 435.665879 -97.673722) (xy 435.666388 -97.701608)
			(xy 435.791862 -97.701608) (xy 435.795933 -97.645986) (xy 435.808059 -97.591549) (xy 435.827982 -97.539458)
			(xy 435.855278 -97.490823) (xy 435.889364 -97.44668) (xy 435.929513 -97.407971) (xy 435.974871 -97.37552)
			(xy 436.024471 -97.350019) (xy 436.077255 -97.332012) (xy 436.132098 -97.321882) (xy 436.187832 -97.319845)
			(xy 436.243269 -97.325945) (xy 436.297226 -97.340051) (xy 436.348555 -97.361863) (xy 436.396161 -97.390917)
			(xy 436.439029 -97.426592) (xy 436.476246 -97.468129) (xy 436.507019 -97.514642) (xy 436.530691 -97.565139)
			(xy 436.546759 -97.618546) (xy 436.554879 -97.673722) (xy 436.555388 -97.701608) (xy 436.554879 -97.729494)
			(xy 436.546759 -97.78467) (xy 436.530691 -97.838077) (xy 436.507019 -97.888574) (xy 436.476246 -97.935087)
			(xy 436.439029 -97.976624) (xy 436.396161 -98.012299) (xy 436.348555 -98.041353) (xy 436.297226 -98.063165)
			(xy 436.243269 -98.077271) (xy 436.187832 -98.083371) (xy 436.132098 -98.081334) (xy 436.077255 -98.071204)
			(xy 436.024471 -98.053197) (xy 435.974871 -98.027696) (xy 435.929513 -97.995245) (xy 435.889364 -97.956536)
			(xy 435.855278 -97.912393) (xy 435.827982 -97.863758) (xy 435.808059 -97.811667) (xy 435.795933 -97.75723)
			(xy 435.791862 -97.701608) (xy 435.666388 -97.701608) (xy 435.665879 -97.729494) (xy 435.657759 -97.78467)
			(xy 435.641691 -97.838077) (xy 435.618019 -97.888574) (xy 435.587246 -97.935087) (xy 435.550029 -97.976624)
			(xy 435.507161 -98.012299) (xy 435.459555 -98.041353) (xy 435.408226 -98.063165) (xy 435.354269 -98.077271)
			(xy 435.298832 -98.083371) (xy 435.243098 -98.081334) (xy 435.188255 -98.071204) (xy 435.135471 -98.053197)
			(xy 435.085871 -98.027696) (xy 435.040513 -97.995245) (xy 435.000364 -97.956536) (xy 434.966278 -97.912393)
			(xy 434.938982 -97.863758) (xy 434.919059 -97.811667) (xy 434.906933 -97.75723) (xy 434.902862 -97.701608)
			(xy 416.19932 -97.701608) (xy 415.31032 -98.590608) (xy 434.902862 -98.590608) (xy 434.906933 -98.534986)
			(xy 434.919059 -98.480549) (xy 434.938982 -98.428458) (xy 434.966278 -98.379823) (xy 435.000364 -98.33568)
			(xy 435.040513 -98.296971) (xy 435.085871 -98.26452) (xy 435.135471 -98.239019) (xy 435.188255 -98.221012)
			(xy 435.243098 -98.210882) (xy 435.298832 -98.208845) (xy 435.354269 -98.214945) (xy 435.408226 -98.229051)
			(xy 435.459555 -98.250863) (xy 435.507161 -98.279917) (xy 435.550029 -98.315592) (xy 435.587246 -98.357129)
			(xy 435.618019 -98.403642) (xy 435.641691 -98.454139) (xy 435.657759 -98.507546) (xy 435.665879 -98.562722)
			(xy 435.666388 -98.590608) (xy 435.791862 -98.590608) (xy 435.795933 -98.534986) (xy 435.808059 -98.480549)
			(xy 435.827982 -98.428458) (xy 435.855278 -98.379823) (xy 435.889364 -98.33568) (xy 435.929513 -98.296971)
			(xy 435.974871 -98.26452) (xy 436.024471 -98.239019) (xy 436.077255 -98.221012) (xy 436.132098 -98.210882)
			(xy 436.187832 -98.208845) (xy 436.243269 -98.214945) (xy 436.297226 -98.229051) (xy 436.348555 -98.250863)
			(xy 436.396161 -98.279917) (xy 436.439029 -98.315592) (xy 436.476246 -98.357129) (xy 436.507019 -98.403642)
			(xy 436.530691 -98.454139) (xy 436.546759 -98.507546) (xy 436.554879 -98.562722) (xy 436.555388 -98.590608)
			(xy 436.554879 -98.618494) (xy 436.546759 -98.67367) (xy 436.530691 -98.727077) (xy 436.507019 -98.777574)
			(xy 436.476246 -98.824087) (xy 436.439029 -98.865624) (xy 436.396161 -98.901299) (xy 436.348555 -98.930353)
			(xy 436.297226 -98.952165) (xy 436.243269 -98.966271) (xy 436.187832 -98.972371) (xy 436.132098 -98.970334)
			(xy 436.077255 -98.960204) (xy 436.024471 -98.942197) (xy 435.974871 -98.916696) (xy 435.929513 -98.884245)
			(xy 435.889364 -98.845536) (xy 435.855278 -98.801393) (xy 435.827982 -98.752758) (xy 435.808059 -98.700667)
			(xy 435.795933 -98.64623) (xy 435.791862 -98.590608) (xy 435.666388 -98.590608) (xy 435.665879 -98.618494)
			(xy 435.657759 -98.67367) (xy 435.641691 -98.727077) (xy 435.618019 -98.777574) (xy 435.587246 -98.824087)
			(xy 435.550029 -98.865624) (xy 435.507161 -98.901299) (xy 435.459555 -98.930353) (xy 435.408226 -98.952165)
			(xy 435.354269 -98.966271) (xy 435.298832 -98.972371) (xy 435.243098 -98.970334) (xy 435.188255 -98.960204)
			(xy 435.135471 -98.942197) (xy 435.085871 -98.916696) (xy 435.040513 -98.884245) (xy 435.000364 -98.845536)
			(xy 434.966278 -98.801393) (xy 434.938982 -98.752758) (xy 434.919059 -98.700667) (xy 434.906933 -98.64623)
			(xy 434.902862 -98.590608) (xy 415.31032 -98.590608) (xy 414.74644 -99.154488) (xy 414.74644 -99.479608)
			(xy 434.902862 -99.479608) (xy 434.906933 -99.423986) (xy 434.919059 -99.369549) (xy 434.938982 -99.317458)
			(xy 434.966278 -99.268823) (xy 435.000364 -99.22468) (xy 435.040513 -99.185971) (xy 435.085871 -99.15352)
			(xy 435.135471 -99.128019) (xy 435.188255 -99.110012) (xy 435.243098 -99.099882) (xy 435.298832 -99.097845)
			(xy 435.354269 -99.103945) (xy 435.408226 -99.118051) (xy 435.459555 -99.139863) (xy 435.507161 -99.168917)
			(xy 435.550029 -99.204592) (xy 435.587246 -99.246129) (xy 435.618019 -99.292642) (xy 435.641691 -99.343139)
			(xy 435.657759 -99.396546) (xy 435.665879 -99.451722) (xy 435.666388 -99.479608) (xy 435.791862 -99.479608)
			(xy 435.795933 -99.423986) (xy 435.808059 -99.369549) (xy 435.827982 -99.317458) (xy 435.855278 -99.268823)
			(xy 435.889364 -99.22468) (xy 435.929513 -99.185971) (xy 435.974871 -99.15352) (xy 436.024471 -99.128019)
			(xy 436.077255 -99.110012) (xy 436.132098 -99.099882) (xy 436.187832 -99.097845) (xy 436.243269 -99.103945)
			(xy 436.297226 -99.118051) (xy 436.348555 -99.139863) (xy 436.396161 -99.168917) (xy 436.439029 -99.204592)
			(xy 436.476246 -99.246129) (xy 436.507019 -99.292642) (xy 436.530691 -99.343139) (xy 436.546759 -99.396546)
			(xy 436.554879 -99.451722) (xy 436.555388 -99.479608) (xy 436.554879 -99.507494) (xy 436.546759 -99.56267)
			(xy 436.530691 -99.616077) (xy 436.507019 -99.666574) (xy 436.476246 -99.713087) (xy 436.439029 -99.754624)
			(xy 436.396161 -99.790299) (xy 436.348555 -99.819353) (xy 436.297226 -99.841165) (xy 436.243269 -99.855271)
			(xy 436.187832 -99.861371) (xy 436.132098 -99.859334) (xy 436.077255 -99.849204) (xy 436.024471 -99.831197)
			(xy 435.974871 -99.805696) (xy 435.929513 -99.773245) (xy 435.889364 -99.734536) (xy 435.855278 -99.690393)
			(xy 435.827982 -99.641758) (xy 435.808059 -99.589667) (xy 435.795933 -99.53523) (xy 435.791862 -99.479608)
			(xy 435.666388 -99.479608) (xy 435.665879 -99.507494) (xy 435.657759 -99.56267) (xy 435.641691 -99.616077)
			(xy 435.618019 -99.666574) (xy 435.587246 -99.713087) (xy 435.550029 -99.754624) (xy 435.507161 -99.790299)
			(xy 435.459555 -99.819353) (xy 435.408226 -99.841165) (xy 435.354269 -99.855271) (xy 435.298832 -99.861371)
			(xy 435.243098 -99.859334) (xy 435.188255 -99.849204) (xy 435.135471 -99.831197) (xy 435.085871 -99.805696)
			(xy 435.040513 -99.773245) (xy 435.000364 -99.734536) (xy 434.966278 -99.690393) (xy 434.938982 -99.641758)
			(xy 434.919059 -99.589667) (xy 434.906933 -99.53523) (xy 434.902862 -99.479608) (xy 414.74644 -99.479608)
			(xy 414.74644 -102.63945) (xy 429.495968 -102.63945) (xy 429.495968 -102.58495) (xy 429.503724 -102.531003)
			(xy 429.519077 -102.47871) (xy 429.541717 -102.429134) (xy 429.57118 -102.383284) (xy 429.606869 -102.342093)
			(xy 429.648057 -102.306401) (xy 429.693904 -102.276933) (xy 429.743478 -102.254289) (xy 429.79577 -102.238931)
			(xy 429.849716 -102.23117) (xy 429.876966 -102.230682) (xy 429.903569 -102.231164) (xy 429.95626 -102.238541)
			(xy 430.007415 -102.25317) (xy 430.056039 -102.274767) (xy 430.10119 -102.302914) (xy 430.14199 -102.337062)
			(xy 430.177648 -102.376551) (xy 430.192942 -102.398322) (xy 430.201276 -102.409802) (xy 430.22302 -102.428006)
			(xy 430.248933 -102.439524) (xy 430.277016 -102.443464) (xy 430.305099 -102.439524) (xy 430.331012 -102.428006)
			(xy 430.352756 -102.409802) (xy 430.36109 -102.398322) (xy 430.376374 -102.376544) (xy 430.412042 -102.337065)
			(xy 430.452848 -102.302923) (xy 430.498 -102.274779) (xy 430.546623 -102.253178) (xy 430.597775 -102.238539)
			(xy 430.650463 -102.231145) (xy 430.677066 -102.230682) (xy 430.704318 -102.231187) (xy 430.758266 -102.238939)
			(xy 430.810563 -102.25429) (xy 430.860142 -102.276928) (xy 430.905995 -102.306392) (xy 430.947188 -102.342081)
			(xy 430.982882 -102.38327) (xy 431.012351 -102.429119) (xy 431.034994 -102.478696) (xy 431.050352 -102.53099)
			(xy 431.05811 -102.584938) (xy 431.058574 -102.61219) (xy 431.058169 -102.636998) (xy 431.057848 -102.639451)
			(xy 431.370468 -102.639451) (xy 431.370468 -102.584949) (xy 431.378224 -102.531001) (xy 431.393579 -102.478706)
			(xy 431.41622 -102.429128) (xy 431.445685 -102.383277) (xy 431.481376 -102.342086) (xy 431.522566 -102.306394)
			(xy 431.568416 -102.276926) (xy 431.617993 -102.254284) (xy 431.670287 -102.238927) (xy 431.724235 -102.231169)
			(xy 431.751486 -102.230682) (xy 431.780451 -102.231233) (xy 431.837715 -102.240002) (xy 431.892995 -102.257325)
			(xy 431.945022 -102.282805) (xy 431.9926 -102.315856) (xy 432.034635 -102.355719) (xy 432.070163 -102.401477)
			(xy 432.084734 -102.426516) (xy 432.092088 -102.438728) (xy 432.112316 -102.458797) (xy 432.137304 -102.472494)
			(xy 432.165104 -102.47875) (xy 432.19355 -102.47708) (xy 432.220426 -102.467612) (xy 432.243639 -102.451085)
			(xy 432.252882 -102.440232) (xy 432.271098 -102.418176) (xy 432.313 -102.379236) (xy 432.360242 -102.346983)
			(xy 432.411768 -102.322139) (xy 432.466423 -102.30526) (xy 432.522985 -102.296724) (xy 432.551586 -102.296214)
			(xy 432.578841 -102.296632) (xy 432.632797 -102.304388) (xy 432.685099 -102.319743) (xy 432.734684 -102.342386)
			(xy 432.780542 -102.371856) (xy 432.821738 -102.407552) (xy 432.857436 -102.448747) (xy 432.886907 -102.494604)
			(xy 432.909552 -102.544188) (xy 432.924909 -102.59649) (xy 432.932667 -102.650445) (xy 432.932667 -102.704955)
			(xy 432.924909 -102.75891) (xy 432.909552 -102.811212) (xy 432.886907 -102.860796) (xy 432.857436 -102.906653)
			(xy 432.821738 -102.947848) (xy 432.780542 -102.983544) (xy 432.734684 -103.013014) (xy 432.685099 -103.035657)
			(xy 432.632797 -103.051012) (xy 432.578841 -103.058768) (xy 432.551586 -103.05923) (xy 432.522618 -103.058746)
			(xy 432.465349 -103.049971) (xy 432.410065 -103.032639) (xy 432.358036 -103.007149) (xy 432.310459 -102.974086)
			(xy 432.268427 -102.934212) (xy 432.232905 -102.888441) (xy 432.218338 -102.863396) (xy 432.211021 -102.851159)
			(xy 432.190786 -102.831086) (xy 432.16579 -102.817388) (xy 432.137982 -102.811133) (xy 432.109529 -102.812809)
			(xy 432.082648 -102.822285) (xy 432.059433 -102.838822) (xy 432.05019 -102.84968) (xy 432.031993 -102.871752)
			(xy 431.990086 -102.91069) (xy 431.94284 -102.942941) (xy 431.891311 -102.967782) (xy 431.836652 -102.984658)
			(xy 431.780088 -102.99319) (xy 431.751486 -102.993698) (xy 431.724235 -102.993231) (xy 431.670287 -102.985473)
			(xy 431.617993 -102.970116) (xy 431.568416 -102.947474) (xy 431.522566 -102.918006) (xy 431.481376 -102.882314)
			(xy 431.445685 -102.841123) (xy 431.41622 -102.795272) (xy 431.393579 -102.745694) (xy 431.378224 -102.693399)
			(xy 431.370468 -102.639451) (xy 431.057848 -102.639451) (xy 431.051732 -102.686194) (xy 431.038953 -102.734135)
			(xy 431.029872 -102.757224) (xy 431.025139 -102.769969) (xy 431.0218 -102.796937) (xy 431.025686 -102.823832)
			(xy 431.036521 -102.848752) (xy 431.053541 -102.869936) (xy 431.075541 -102.885887) (xy 431.100967 -102.895476)
			(xy 431.114454 -102.897178) (xy 431.142478 -102.90029) (xy 431.197232 -102.913751) (xy 431.249408 -102.935124)
			(xy 431.29787 -102.963943) (xy 431.341562 -102.999582) (xy 431.379534 -103.041264) (xy 431.410956 -103.08808)
			(xy 431.435146 -103.139011) (xy 431.451576 -103.192948) (xy 431.459889 -103.248716) (xy 431.460402 -103.276908)
			(xy 431.459916 -103.304159) (xy 431.45216 -103.358107) (xy 431.436805 -103.410402) (xy 431.414163 -103.459979)
			(xy 431.384697 -103.505829) (xy 431.349006 -103.54702) (xy 431.307815 -103.582711) (xy 431.261965 -103.612177)
			(xy 431.212388 -103.634819) (xy 431.160093 -103.650174) (xy 431.106145 -103.65793) (xy 431.051643 -103.65793)
			(xy 430.997695 -103.650174) (xy 430.9454 -103.634819) (xy 430.895823 -103.612177) (xy 430.849973 -103.582711)
			(xy 430.808782 -103.54702) (xy 430.773091 -103.505829) (xy 430.743625 -103.459979) (xy 430.720983 -103.410402)
			(xy 430.705628 -103.358107) (xy 430.697872 -103.304159) (xy 430.697386 -103.276908) (xy 430.697793 -103.2521)
			(xy 430.704229 -103.202905) (xy 430.717007 -103.154963) (xy 430.726088 -103.131874) (xy 430.730856 -103.11914)
			(xy 430.734198 -103.092165) (xy 430.730311 -103.065263) (xy 430.71947 -103.040337) (xy 430.702443 -103.019151)
			(xy 430.680433 -103.003201) (xy 430.654997 -102.993618) (xy 430.641506 -102.99192) (xy 430.613609 -102.988818)
			(xy 430.559087 -102.975477) (xy 430.50711 -102.95429) (xy 430.458798 -102.925714) (xy 430.415195 -102.890368)
			(xy 430.377243 -102.849014) (xy 430.36109 -102.826058) (xy 430.352756 -102.814578) (xy 430.331012 -102.796374)
			(xy 430.305099 -102.784856) (xy 430.277016 -102.780916) (xy 430.248933 -102.784856) (xy 430.22302 -102.796374)
			(xy 430.201276 -102.814578) (xy 430.192942 -102.826058) (xy 430.177632 -102.847817) (xy 430.141968 -102.887297)
			(xy 430.101167 -102.921441) (xy 430.05602 -102.949588) (xy 430.007401 -102.971192) (xy 429.956253 -102.985835)
			(xy 429.903567 -102.993232) (xy 429.876966 -102.993698) (xy 429.849716 -102.99323) (xy 429.79577 -102.985469)
			(xy 429.743478 -102.970111) (xy 429.693904 -102.947467) (xy 429.648057 -102.917999) (xy 429.606869 -102.882307)
			(xy 429.57118 -102.841116) (xy 429.541717 -102.795266) (xy 429.519077 -102.74569) (xy 429.503724 -102.693397)
			(xy 429.495968 -102.63945) (xy 414.74644 -102.63945) (xy 414.74644 -104.501188) (xy 418.035232 -104.501188)
			(xy 418.035683 -104.473817) (xy 418.043503 -104.419637) (xy 418.058996 -104.367134) (xy 418.081841 -104.317387)
			(xy 418.111569 -104.271421) (xy 418.129212 -104.25049) (xy 418.138459 -104.239171) (xy 418.150634 -104.21261)
			(xy 418.154804 -104.183691) (xy 418.150629 -104.154773) (xy 418.13845 -104.128214) (xy 418.129212 -104.116886)
			(xy 418.111602 -104.095931) (xy 418.081885 -104.049965) (xy 418.059043 -104.000223) (xy 418.043546 -103.947727)
			(xy 418.03571 -103.893556) (xy 418.035232 -103.866188) (xy 418.035644 -103.838933) (xy 418.043403 -103.784978)
			(xy 418.058763 -103.732677) (xy 418.08141 -103.683094) (xy 418.110883 -103.637239) (xy 418.146582 -103.596045)
			(xy 418.187781 -103.560352) (xy 418.23364 -103.530885) (xy 418.283226 -103.508245) (xy 418.335529 -103.492892)
			(xy 418.389485 -103.48514) (xy 418.41674 -103.48468) (xy 418.442319 -103.485084) (xy 418.493018 -103.491932)
			(xy 418.542348 -103.505486) (xy 418.589428 -103.525504) (xy 418.633414 -103.551628) (xy 418.673519 -103.583389)
			(xy 418.691568 -103.60152) (xy 418.701199 -103.61092) (xy 418.724293 -103.624724) (xy 418.750189 -103.632019)
			(xy 418.777092 -103.6323) (xy 418.803136 -103.625548) (xy 418.826513 -103.612231) (xy 418.836348 -103.603044)
			(xy 418.857913 -103.582417) (xy 418.906289 -103.547481) (xy 418.959517 -103.520507) (xy 419.016298 -103.502155)
			(xy 419.075244 -103.492872) (xy 419.10508 -103.4923) (xy 419.132333 -103.492774) (xy 419.186284 -103.500528)
			(xy 419.238582 -103.515882) (xy 419.288162 -103.538523) (xy 419.334016 -103.56799) (xy 419.375209 -103.603682)
			(xy 419.410903 -103.644874) (xy 419.440371 -103.690727) (xy 419.463013 -103.740307) (xy 419.478369 -103.792605)
			(xy 419.486125 -103.846555) (xy 419.486588 -103.873808) (xy 419.48613 -103.901179) (xy 419.47831 -103.955358)
			(xy 419.46282 -104.007861) (xy 419.439976 -104.057608) (xy 419.41025 -104.103575) (xy 419.392608 -104.124506)
			(xy 419.383363 -104.135827) (xy 419.371185 -104.162387) (xy 419.367014 -104.191306) (xy 419.371189 -104.220225)
			(xy 419.383369 -104.246783) (xy 419.392608 -104.25811) (xy 419.410266 -104.279026) (xy 419.439975 -104.325004)
			(xy 419.462807 -104.374755) (xy 419.478294 -104.427259) (xy 419.486117 -104.481438) (xy 419.486588 -104.508808)
			(xy 419.486152 -104.536062) (xy 419.478393 -104.590015) (xy 419.463035 -104.642314) (xy 419.440391 -104.691896)
			(xy 419.41092 -104.73775) (xy 419.375223 -104.778943) (xy 419.334028 -104.814637) (xy 419.288171 -104.844104)
			(xy 419.238588 -104.866745) (xy 419.186287 -104.882099) (xy 419.132334 -104.889854) (xy 419.10508 -104.890316)
			(xy 419.079501 -104.8899) (xy 419.028803 -104.883055) (xy 418.979473 -104.869503) (xy 418.932393 -104.849487)
			(xy 418.888407 -104.823365) (xy 418.848301 -104.791606) (xy 418.830252 -104.773476) (xy 418.820603 -104.764096)
			(xy 418.797514 -104.750292) (xy 418.771623 -104.742994) (xy 418.744724 -104.742709) (xy 418.718683 -104.749456)
			(xy 418.695307 -104.762768) (xy 418.685472 -104.771952) (xy 418.663898 -104.792569) (xy 418.615524 -104.827506)
			(xy 418.562298 -104.854482) (xy 418.50552 -104.872837) (xy 418.446576 -104.882123) (xy 418.41674 -104.882696)
			(xy 418.389488 -104.882207) (xy 418.335537 -104.874456) (xy 418.283239 -104.859104) (xy 418.233658 -104.836465)
			(xy 418.187804 -104.807) (xy 418.146611 -104.771309) (xy 418.110916 -104.730118) (xy 418.081448 -104.684267)
			(xy 418.058806 -104.634687) (xy 418.04345 -104.58239) (xy 418.035695 -104.52844) (xy 418.035232 -104.501188)
			(xy 414.74644 -104.501188) (xy 414.74644 -105.827322) (xy 429.906682 -105.827322) (xy 429.910753 -105.7717)
			(xy 429.922879 -105.717263) (xy 429.942802 -105.665172) (xy 429.970098 -105.616537) (xy 430.004184 -105.572394)
			(xy 430.044333 -105.533685) (xy 430.089691 -105.501234) (xy 430.139291 -105.475733) (xy 430.192075 -105.457726)
			(xy 430.246918 -105.447596) (xy 430.302652 -105.445559) (xy 430.358089 -105.451659) (xy 430.412046 -105.465765)
			(xy 430.463375 -105.487577) (xy 430.510981 -105.516631) (xy 430.553849 -105.552306) (xy 430.591066 -105.593843)
			(xy 430.614291 -105.628948) (xy 433.069492 -105.628948) (xy 433.069988 -105.601579) (xy 433.077799 -105.547401)
			(xy 433.093281 -105.494898) (xy 433.116116 -105.445151) (xy 433.145834 -105.399183) (xy 433.163472 -105.37825)
			(xy 433.172664 -105.366889) (xy 433.184851 -105.340344) (xy 433.189034 -105.311436) (xy 433.184871 -105.282526)
			(xy 433.172704 -105.255972) (xy 433.163472 -105.244646) (xy 433.145837 -105.223711) (xy 433.116125 -105.177739)
			(xy 433.093289 -105.127992) (xy 433.077797 -105.075492) (xy 433.069967 -105.021317) (xy 433.069492 -104.993948)
			(xy 433.069991 -104.965775) (xy 433.078298 -104.910045) (xy 433.094709 -104.856142) (xy 433.118868 -104.805238)
			(xy 433.150249 -104.75844) (xy 433.188171 -104.716765) (xy 433.231808 -104.681118) (xy 433.280212 -104.652276)
			(xy 433.332331 -104.630864) (xy 433.35956 -104.623616) (xy 433.373871 -104.619591) (xy 433.399467 -104.604497)
			(xy 433.419628 -104.582668) (xy 433.432644 -104.555955) (xy 433.437411 -104.526624) (xy 433.433523 -104.497164)
			(xy 433.427886 -104.483408) (xy 433.417375 -104.458766) (xy 433.402561 -104.407283) (xy 433.395071 -104.354238)
			(xy 433.394612 -104.327452) (xy 433.395098 -104.300201) (xy 433.402854 -104.246253) (xy 433.418209 -104.193958)
			(xy 433.440851 -104.144381) (xy 433.470317 -104.098531) (xy 433.506008 -104.05734) (xy 433.547199 -104.021649)
			(xy 433.593049 -103.992183) (xy 433.642626 -103.969541) (xy 433.694921 -103.954186) (xy 433.748869 -103.94643)
			(xy 433.803371 -103.94643) (xy 433.857319 -103.954186) (xy 433.909614 -103.969541) (xy 433.959191 -103.992183)
			(xy 434.005041 -104.021649) (xy 434.046232 -104.05734) (xy 434.081923 -104.098531) (xy 434.111389 -104.144381)
			(xy 434.134031 -104.193958) (xy 434.149386 -104.246253) (xy 434.157142 -104.300201) (xy 434.157628 -104.327452)
			(xy 434.157175 -104.354753) (xy 434.149421 -104.4088) (xy 434.134021 -104.461184) (xy 434.123084 -104.486202)
			(xy 434.117403 -104.499723) (xy 434.113306 -104.528754) (xy 434.117603 -104.557756) (xy 434.129943 -104.584351)
			(xy 434.149314 -104.606359) (xy 434.174127 -104.621976) (xy 434.188108 -104.62641) (xy 434.214542 -104.634228)
			(xy 434.264983 -104.656465) (xy 434.311697 -104.685732) (xy 434.353711 -104.721419) (xy 434.390149 -104.762783)
			(xy 434.420254 -104.808961) (xy 434.443397 -104.858992) (xy 434.459097 -104.911834) (xy 434.467026 -104.966386)
			(xy 434.467508 -104.993948) (xy 434.467009 -105.021317) (xy 434.459199 -105.075495) (xy 434.443718 -105.127997)
			(xy 434.420883 -105.177745) (xy 434.391166 -105.223713) (xy 434.373528 -105.244646) (xy 434.364243 -105.255938)
			(xy 434.352068 -105.282508) (xy 434.347903 -105.311436) (xy 434.352088 -105.340362) (xy 434.364282 -105.366923)
			(xy 434.373528 -105.37825) (xy 434.391161 -105.399187) (xy 434.420873 -105.445159) (xy 434.44371 -105.494905)
			(xy 434.459202 -105.547404) (xy 434.467033 -105.601579) (xy 434.467508 -105.628948) (xy 434.467067 -105.6562)
			(xy 434.459304 -105.71015) (xy 434.443943 -105.762445) (xy 434.421296 -105.812023) (xy 434.391825 -105.857873)
			(xy 434.356129 -105.899063) (xy 434.314934 -105.934753) (xy 434.269081 -105.964219) (xy 434.2195 -105.986859)
			(xy 434.167203 -106.002214) (xy 434.113252 -106.00997) (xy 434.086 -106.010456) (xy 434.058629 -106.010001)
			(xy 434.004449 -106.002182) (xy 433.951946 -105.986691) (xy 433.902199 -105.963847) (xy 433.856233 -105.934119)
			(xy 433.835302 -105.916476) (xy 433.823974 -105.90724) (xy 433.797417 -105.895064) (xy 433.7685 -105.890891)
			(xy 433.739583 -105.895064) (xy 433.713026 -105.90724) (xy 433.701698 -105.916476) (xy 433.680774 -105.934126)
			(xy 433.6348 -105.963837) (xy 433.58505 -105.986671) (xy 433.532547 -106.00216) (xy 433.47837 -106.009984)
			(xy 433.451 -106.010456) (xy 433.423751 -106.009922) (xy 433.369807 -106.002167) (xy 433.317516 -105.986814)
			(xy 433.267942 -105.964177) (xy 433.222094 -105.934715) (xy 433.180905 -105.899029) (xy 433.145214 -105.857844)
			(xy 433.115746 -105.812) (xy 433.093102 -105.762429) (xy 433.077743 -105.71014) (xy 433.069981 -105.656197)
			(xy 433.069492 -105.628948) (xy 430.614291 -105.628948) (xy 430.621839 -105.640356) (xy 430.645511 -105.690853)
			(xy 430.661579 -105.74426) (xy 430.669699 -105.799436) (xy 430.670208 -105.827322) (xy 430.669699 -105.855208)
			(xy 430.661579 -105.910384) (xy 430.645511 -105.963791) (xy 430.621839 -106.014288) (xy 430.591066 -106.060801)
			(xy 430.553849 -106.102338) (xy 430.510981 -106.138013) (xy 430.463375 -106.167067) (xy 430.412046 -106.188879)
			(xy 430.358089 -106.202985) (xy 430.302652 -106.209085) (xy 430.246918 -106.207048) (xy 430.192075 -106.196918)
			(xy 430.139291 -106.178911) (xy 430.089691 -106.15341) (xy 430.044333 -106.120959) (xy 430.004184 -106.08225)
			(xy 429.970098 -106.038107) (xy 429.942802 -105.989472) (xy 429.922879 -105.937381) (xy 429.910753 -105.882944)
			(xy 429.906682 -105.827322) (xy 414.74644 -105.827322) (xy 414.74644 -107.15117) (xy 428.930814 -107.15117)
			(xy 428.934885 -107.095548) (xy 428.947011 -107.041111) (xy 428.966934 -106.98902) (xy 428.99423 -106.940385)
			(xy 429.028316 -106.896242) (xy 429.068465 -106.857533) (xy 429.113823 -106.825082) (xy 429.163423 -106.799581)
			(xy 429.216207 -106.781574) (xy 429.27105 -106.771444) (xy 429.326784 -106.769407) (xy 429.368344 -106.77398)
			(xy 433.340254 -106.77398) (xy 433.344325 -106.718358) (xy 433.356451 -106.663921) (xy 433.376374 -106.61183)
			(xy 433.40367 -106.563195) (xy 433.437756 -106.519052) (xy 433.477905 -106.480343) (xy 433.523263 -106.447892)
			(xy 433.572863 -106.422391) (xy 433.625647 -106.404384) (xy 433.68049 -106.394254) (xy 433.736224 -106.392217)
			(xy 433.791661 -106.398317) (xy 433.845618 -106.412423) (xy 433.896947 -106.434235) (xy 433.944553 -106.463289)
			(xy 433.987421 -106.498964) (xy 434.024638 -106.540501) (xy 434.055411 -106.587014) (xy 434.079083 -106.637511)
			(xy 434.095151 -106.690918) (xy 434.103271 -106.746094) (xy 434.10378 -106.77398) (xy 434.103271 -106.801866)
			(xy 434.095151 -106.857042) (xy 434.079083 -106.910449) (xy 434.055411 -106.960946) (xy 434.024638 -107.007459)
			(xy 433.987421 -107.048996) (xy 433.944553 -107.084671) (xy 433.896947 -107.113725) (xy 433.845618 -107.135537)
			(xy 433.791661 -107.149643) (xy 433.736224 -107.155743) (xy 433.68049 -107.153706) (xy 433.625647 -107.143576)
			(xy 433.572863 -107.125569) (xy 433.523263 -107.100068) (xy 433.477905 -107.067617) (xy 433.437756 -107.028908)
			(xy 433.40367 -106.984765) (xy 433.376374 -106.93613) (xy 433.356451 -106.884039) (xy 433.344325 -106.829602)
			(xy 433.340254 -106.77398) (xy 429.368344 -106.77398) (xy 429.382221 -106.775507) (xy 429.436178 -106.789613)
			(xy 429.487507 -106.811425) (xy 429.535113 -106.840479) (xy 429.577981 -106.876154) (xy 429.615198 -106.917691)
			(xy 429.645971 -106.964204) (xy 429.669643 -107.014701) (xy 429.685711 -107.068108) (xy 429.693831 -107.123284)
			(xy 429.69434 -107.15117) (xy 429.693831 -107.179056) (xy 429.685711 -107.234232) (xy 429.677688 -107.260898)
			(xy 430.263552 -107.260898) (xy 430.267623 -107.205276) (xy 430.279749 -107.150839) (xy 430.299672 -107.098748)
			(xy 430.326968 -107.050113) (xy 430.361054 -107.00597) (xy 430.401203 -106.967261) (xy 430.446561 -106.93481)
			(xy 430.496161 -106.909309) (xy 430.548945 -106.891302) (xy 430.603788 -106.881172) (xy 430.659522 -106.879135)
			(xy 430.714959 -106.885235) (xy 430.768916 -106.899341) (xy 430.820245 -106.921153) (xy 430.867851 -106.950207)
			(xy 430.910719 -106.985882) (xy 430.947936 -107.027419) (xy 430.978709 -107.073932) (xy 431.002381 -107.124429)
			(xy 431.018449 -107.177836) (xy 431.026569 -107.233012) (xy 431.027078 -107.260898) (xy 431.026569 -107.288784)
			(xy 431.018449 -107.34396) (xy 431.002381 -107.397367) (xy 430.978709 -107.447864) (xy 430.947936 -107.494377)
			(xy 430.910719 -107.535914) (xy 430.867851 -107.571589) (xy 430.820245 -107.600643) (xy 430.768916 -107.622455)
			(xy 430.714959 -107.636561) (xy 430.659522 -107.642661) (xy 430.603788 -107.640624) (xy 430.548945 -107.630494)
			(xy 430.496161 -107.612487) (xy 430.446561 -107.586986) (xy 430.401203 -107.554535) (xy 430.361054 -107.515826)
			(xy 430.326968 -107.471683) (xy 430.299672 -107.423048) (xy 430.279749 -107.370957) (xy 430.267623 -107.31652)
			(xy 430.263552 -107.260898) (xy 429.677688 -107.260898) (xy 429.669643 -107.287639) (xy 429.645971 -107.338136)
			(xy 429.615198 -107.384649) (xy 429.577981 -107.426186) (xy 429.535113 -107.461861) (xy 429.487507 -107.490915)
			(xy 429.436178 -107.512727) (xy 429.382221 -107.526833) (xy 429.326784 -107.532933) (xy 429.27105 -107.530896)
			(xy 429.216207 -107.520766) (xy 429.163423 -107.502759) (xy 429.113823 -107.477258) (xy 429.068465 -107.444807)
			(xy 429.028316 -107.406098) (xy 428.99423 -107.361955) (xy 428.966934 -107.31332) (xy 428.947011 -107.261229)
			(xy 428.934885 -107.206792) (xy 428.930814 -107.15117) (xy 414.74644 -107.15117) (xy 414.74644 -107.645708)
			(xy 431.703478 -107.645708) (xy 431.707549 -107.590086) (xy 431.719675 -107.535649) (xy 431.739598 -107.483558)
			(xy 431.766894 -107.434923) (xy 431.80098 -107.39078) (xy 431.841129 -107.352071) (xy 431.886487 -107.31962)
			(xy 431.936087 -107.294119) (xy 431.988871 -107.276112) (xy 432.043714 -107.265982) (xy 432.099448 -107.263945)
			(xy 432.154885 -107.270045) (xy 432.208842 -107.284151) (xy 432.260171 -107.305963) (xy 432.307777 -107.335017)
			(xy 432.350645 -107.370692) (xy 432.387862 -107.412229) (xy 432.418635 -107.458742) (xy 432.442307 -107.509239)
			(xy 432.458375 -107.562646) (xy 432.466495 -107.617822) (xy 432.467004 -107.645708) (xy 432.466495 -107.673594)
			(xy 432.458375 -107.72877) (xy 432.442307 -107.782177) (xy 432.418635 -107.832674) (xy 432.387862 -107.879187)
			(xy 432.350645 -107.920724) (xy 432.307777 -107.956399) (xy 432.260171 -107.985453) (xy 432.208842 -108.007265)
			(xy 432.154885 -108.021371) (xy 432.099448 -108.027471) (xy 432.043714 -108.025434) (xy 431.988871 -108.015304)
			(xy 431.936087 -107.997297) (xy 431.886487 -107.971796) (xy 431.841129 -107.939345) (xy 431.80098 -107.900636)
			(xy 431.766894 -107.856493) (xy 431.739598 -107.807858) (xy 431.719675 -107.755767) (xy 431.707549 -107.70133)
			(xy 431.703478 -107.645708) (xy 414.74644 -107.645708) (xy 414.74644 -110.739417) (xy 415.365214 -110.739417)
			(xy 415.368942 -110.686169) (xy 415.380055 -110.63396) (xy 415.398338 -110.58381) (xy 415.423433 -110.536698)
			(xy 415.454851 -110.493544) (xy 415.491977 -110.455192) (xy 415.512758 -110.438438) (xy 415.524538 -110.428512)
			(xy 415.542061 -110.403197) (xy 415.551243 -110.373811) (xy 415.551248 -110.343023) (xy 415.542076 -110.313634)
			(xy 415.524562 -110.288314) (xy 415.512758 -110.278418) (xy 415.492003 -110.261631) (xy 415.454873 -110.223282)
			(xy 415.423452 -110.180131) (xy 415.398352 -110.133022) (xy 415.380065 -110.082873) (xy 415.368946 -110.030665)
			(xy 415.365214 -109.977417) (xy 415.368942 -109.924169) (xy 415.380055 -109.87196) (xy 415.398338 -109.82181)
			(xy 415.423433 -109.774698) (xy 415.454851 -109.731544) (xy 415.491977 -109.693192) (xy 415.512758 -109.676438)
			(xy 415.524538 -109.666512) (xy 415.542061 -109.641197) (xy 415.551243 -109.611811) (xy 415.551248 -109.581023)
			(xy 415.542076 -109.551634) (xy 415.524562 -109.526314) (xy 415.512758 -109.516418) (xy 415.492003 -109.499631)
			(xy 415.454873 -109.461282) (xy 415.423452 -109.418131) (xy 415.398352 -109.371022) (xy 415.380065 -109.320873)
			(xy 415.368946 -109.268665) (xy 415.365214 -109.215417) (xy 415.368942 -109.162169) (xy 415.380055 -109.10996)
			(xy 415.398338 -109.05981) (xy 415.423433 -109.012698) (xy 415.454851 -108.969544) (xy 415.491977 -108.931192)
			(xy 415.512758 -108.914438) (xy 415.524538 -108.904512) (xy 415.542061 -108.879197) (xy 415.551243 -108.849811)
			(xy 415.551248 -108.819023) (xy 415.542076 -108.789634) (xy 415.524562 -108.764314) (xy 415.512758 -108.754418)
			(xy 415.490274 -108.736227) (xy 415.450541 -108.694206) (xy 415.417603 -108.646671) (xy 415.392215 -108.59471)
			(xy 415.374959 -108.539513) (xy 415.366228 -108.482344) (xy 415.365692 -108.453428) (xy 415.366181 -108.426176)
			(xy 415.373935 -108.372226) (xy 415.389287 -108.319928) (xy 415.411926 -108.270348) (xy 415.441391 -108.224495)
			(xy 415.477082 -108.183302) (xy 415.518273 -108.147608) (xy 415.564124 -108.11814) (xy 415.613702 -108.095497)
			(xy 415.665998 -108.08014) (xy 415.719948 -108.072383) (xy 415.7472 -108.07192) (xy 415.776117 -108.072431)
			(xy 415.833289 -108.08116) (xy 415.888488 -108.098419) (xy 415.94045 -108.123812) (xy 415.987984 -108.156758)
			(xy 416.03 -108.1965) (xy 416.04819 -108.218986) (xy 416.058087 -108.230791) (xy 416.083411 -108.24831)
			(xy 416.112804 -108.257486) (xy 416.143596 -108.257486) (xy 416.172989 -108.24831) (xy 416.198313 -108.230791)
			(xy 416.20821 -108.218986) (xy 416.226392 -108.196495) (xy 416.268414 -108.156761) (xy 416.315951 -108.123823)
			(xy 416.367914 -108.098436) (xy 416.423113 -108.081181) (xy 416.480284 -108.072454) (xy 416.5092 -108.07192)
			(xy 416.536454 -108.072355) (xy 416.590408 -108.080113) (xy 416.642708 -108.095471) (xy 416.69229 -108.118115)
			(xy 416.738144 -108.147586) (xy 416.779337 -108.183282) (xy 416.815031 -108.224478) (xy 416.844498 -108.270335)
			(xy 416.867139 -108.319919) (xy 416.882493 -108.37222) (xy 416.890247 -108.426174) (xy 416.890708 -108.453428)
			(xy 416.890173 -108.482345) (xy 416.881452 -108.539517) (xy 416.8642 -108.594717) (xy 416.838812 -108.646679)
			(xy 416.805869 -108.694213) (xy 416.766128 -108.736229) (xy 416.743642 -108.754418) (xy 416.731806 -108.764283)
			(xy 416.714284 -108.789614) (xy 416.705109 -108.819017) (xy 416.705114 -108.849818) (xy 416.714299 -108.879217)
			(xy 416.73183 -108.904542) (xy 416.743642 -108.914438) (xy 416.764453 -108.931158) (xy 416.801583 -108.969516)
			(xy 416.833005 -109.012674) (xy 416.858103 -109.059791) (xy 416.876388 -109.109947) (xy 416.887503 -109.162163)
			(xy 416.89123 -109.215417) (xy 416.887498 -109.268672) (xy 416.876378 -109.320886) (xy 416.858089 -109.37104)
			(xy 416.832986 -109.418155) (xy 416.801561 -109.461311) (xy 416.764427 -109.499665) (xy 416.743642 -109.516418)
			(xy 416.731806 -109.526283) (xy 416.714284 -109.551614) (xy 416.705109 -109.581017) (xy 416.705114 -109.611818)
			(xy 416.714299 -109.641217) (xy 416.729537 -109.66323) (xy 433.334158 -109.66323) (xy 433.338229 -109.607608)
			(xy 433.350355 -109.553171) (xy 433.370278 -109.50108) (xy 433.397574 -109.452445) (xy 433.43166 -109.408302)
			(xy 433.471809 -109.369593) (xy 433.517167 -109.337142) (xy 433.566767 -109.311641) (xy 433.619551 -109.293634)
			(xy 433.674394 -109.283504) (xy 433.730128 -109.281467) (xy 433.785565 -109.287567) (xy 433.839522 -109.301673)
			(xy 433.890851 -109.323485) (xy 433.938457 -109.352539) (xy 433.981325 -109.388214) (xy 434.018542 -109.429751)
			(xy 434.049315 -109.476264) (xy 434.072987 -109.526761) (xy 434.089055 -109.580168) (xy 434.097175 -109.635344)
			(xy 434.097684 -109.66323) (xy 434.097175 -109.691116) (xy 434.089055 -109.746292) (xy 434.072987 -109.799699)
			(xy 434.049315 -109.850196) (xy 434.018542 -109.896709) (xy 433.981325 -109.938246) (xy 433.938457 -109.973921)
			(xy 433.890851 -110.002975) (xy 433.839522 -110.024787) (xy 433.785565 -110.038893) (xy 433.730128 -110.044993)
			(xy 433.674394 -110.042956) (xy 433.619551 -110.032826) (xy 433.566767 -110.014819) (xy 433.517167 -109.989318)
			(xy 433.471809 -109.956867) (xy 433.43166 -109.918158) (xy 433.397574 -109.874015) (xy 433.370278 -109.82538)
			(xy 433.350355 -109.773289) (xy 433.338229 -109.718852) (xy 433.334158 -109.66323) (xy 416.729537 -109.66323)
			(xy 416.73183 -109.666542) (xy 416.743642 -109.676438) (xy 416.764453 -109.693158) (xy 416.801583 -109.731516)
			(xy 416.833005 -109.774674) (xy 416.858103 -109.821791) (xy 416.876388 -109.871947) (xy 416.887503 -109.924163)
			(xy 416.89123 -109.977417) (xy 416.887498 -110.030672) (xy 416.876378 -110.082886) (xy 416.858089 -110.13304)
			(xy 416.832986 -110.180155) (xy 416.801561 -110.223311) (xy 416.764427 -110.261665) (xy 416.743642 -110.278418)
			(xy 416.740595 -110.280958) (xy 419.761922 -110.280958) (xy 419.765993 -110.225336) (xy 419.778119 -110.170899)
			(xy 419.798042 -110.118808) (xy 419.825338 -110.070173) (xy 419.859424 -110.02603) (xy 419.899573 -109.987321)
			(xy 419.944931 -109.95487) (xy 419.994531 -109.929369) (xy 420.047315 -109.911362) (xy 420.102158 -109.901232)
			(xy 420.157892 -109.899195) (xy 420.213329 -109.905295) (xy 420.267286 -109.919401) (xy 420.318615 -109.941213)
			(xy 420.366221 -109.970267) (xy 420.409089 -110.005942) (xy 420.446306 -110.047479) (xy 420.477079 -110.093992)
			(xy 420.500751 -110.144489) (xy 420.516819 -110.197896) (xy 420.524939 -110.253072) (xy 420.525369 -110.27664)
			(xy 428.913542 -110.27664) (xy 428.917613 -110.221018) (xy 428.929739 -110.166581) (xy 428.949662 -110.11449)
			(xy 428.976958 -110.065855) (xy 429.011044 -110.021712) (xy 429.051193 -109.983003) (xy 429.096551 -109.950552)
			(xy 429.146151 -109.925051) (xy 429.198935 -109.907044) (xy 429.253778 -109.896914) (xy 429.309512 -109.894877)
			(xy 429.364949 -109.900977) (xy 429.418906 -109.915083) (xy 429.470235 -109.936895) (xy 429.517841 -109.965949)
			(xy 429.560709 -110.001624) (xy 429.597926 -110.043161) (xy 429.628699 -110.089674) (xy 429.652371 -110.140171)
			(xy 429.668439 -110.193578) (xy 429.676559 -110.248754) (xy 429.677068 -110.27664) (xy 429.676559 -110.304526)
			(xy 429.668439 -110.359702) (xy 429.652371 -110.413109) (xy 429.628699 -110.463606) (xy 429.597926 -110.510119)
			(xy 429.560709 -110.551656) (xy 429.517841 -110.587331) (xy 429.470235 -110.616385) (xy 429.418906 -110.638197)
			(xy 429.364949 -110.652303) (xy 429.309512 -110.658403) (xy 429.253778 -110.656366) (xy 429.198935 -110.646236)
			(xy 429.146151 -110.628229) (xy 429.096551 -110.602728) (xy 429.051193 -110.570277) (xy 429.011044 -110.531568)
			(xy 428.976958 -110.487425) (xy 428.949662 -110.43879) (xy 428.929739 -110.386699) (xy 428.917613 -110.332262)
			(xy 428.913542 -110.27664) (xy 420.525369 -110.27664) (xy 420.525448 -110.280958) (xy 420.524939 -110.308844)
			(xy 420.516819 -110.36402) (xy 420.500751 -110.417427) (xy 420.477079 -110.467924) (xy 420.446306 -110.514437)
			(xy 420.409089 -110.555974) (xy 420.366221 -110.591649) (xy 420.318615 -110.620703) (xy 420.267286 -110.642515)
			(xy 420.213329 -110.656621) (xy 420.157892 -110.662721) (xy 420.102158 -110.660684) (xy 420.047315 -110.650554)
			(xy 419.994531 -110.632547) (xy 419.944931 -110.607046) (xy 419.899573 -110.574595) (xy 419.859424 -110.535886)
			(xy 419.825338 -110.491743) (xy 419.798042 -110.443108) (xy 419.778119 -110.391017) (xy 419.765993 -110.33658)
			(xy 419.761922 -110.280958) (xy 416.740595 -110.280958) (xy 416.731806 -110.288283) (xy 416.714284 -110.313614)
			(xy 416.705109 -110.343017) (xy 416.705114 -110.373818) (xy 416.714299 -110.403217) (xy 416.73183 -110.428542)
			(xy 416.743642 -110.438438) (xy 416.764453 -110.455158) (xy 416.801583 -110.493516) (xy 416.833005 -110.536674)
			(xy 416.858103 -110.583791) (xy 416.876388 -110.633947) (xy 416.887503 -110.686163) (xy 416.89123 -110.739417)
			(xy 416.887498 -110.792672) (xy 416.876378 -110.844886) (xy 416.858089 -110.89504) (xy 416.832986 -110.942155)
			(xy 416.801561 -110.985311) (xy 416.764427 -111.023665) (xy 416.743642 -111.040418) (xy 416.731806 -111.050283)
			(xy 416.714284 -111.075614) (xy 416.705109 -111.105017) (xy 416.705114 -111.135818) (xy 416.714299 -111.165217)
			(xy 416.73183 -111.190542) (xy 416.743642 -111.200438) (xy 416.766152 -111.218597) (xy 416.805884 -111.260625)
			(xy 416.838819 -111.308167) (xy 416.864202 -111.360134) (xy 416.881453 -111.415337) (xy 416.890176 -111.47251)
			(xy 416.890708 -111.501428) (xy 416.890248 -111.52868) (xy 416.882488 -111.582629) (xy 416.867129 -111.634924)
			(xy 416.844485 -111.684501) (xy 416.815016 -111.730351) (xy 416.779321 -111.771541) (xy 416.738129 -111.807232)
			(xy 416.692277 -111.836698) (xy 416.642698 -111.859339) (xy 416.590401 -111.874694) (xy 416.536452 -111.88245)
			(xy 416.5092 -111.882936) (xy 416.480282 -111.882442) (xy 416.423108 -111.873711) (xy 416.367908 -111.85645)
			(xy 416.315946 -111.831054) (xy 416.268413 -111.798105) (xy 416.226398 -111.758358) (xy 416.20821 -111.73587)
			(xy 416.198313 -111.724065) (xy 416.172989 -111.706546) (xy 416.143596 -111.69737) (xy 416.112804 -111.69737)
			(xy 416.083411 -111.706546) (xy 416.058087 -111.724065) (xy 416.04819 -111.73587) (xy 416.029997 -111.758352)
			(xy 415.987979 -111.798089) (xy 415.940444 -111.831029) (xy 415.888483 -111.856418) (xy 415.833286 -111.873674)
			(xy 415.776116 -111.882402) (xy 415.7472 -111.882936) (xy 415.71995 -111.882422) (xy 415.666005 -111.874667)
			(xy 415.613712 -111.859313) (xy 415.564137 -111.836674) (xy 415.518288 -111.80721) (xy 415.477098 -111.771522)
			(xy 415.441407 -111.730335) (xy 415.41194 -111.684488) (xy 415.389297 -111.634914) (xy 415.373939 -111.582623)
			(xy 415.36618 -111.528678) (xy 415.365692 -111.501428) (xy 415.366195 -111.47251) (xy 415.374923 -111.415337)
			(xy 415.392181 -111.360136) (xy 415.417575 -111.308173) (xy 415.450523 -111.26064) (xy 415.49027 -111.218626)
			(xy 415.512758 -111.200438) (xy 415.524538 -111.190512) (xy 415.542061 -111.165197) (xy 415.551243 -111.135811)
			(xy 415.551248 -111.105023) (xy 415.542076 -111.075634) (xy 415.524562 -111.050314) (xy 415.512758 -111.040418)
			(xy 415.492003 -111.023631) (xy 415.454873 -110.985282) (xy 415.423452 -110.942131) (xy 415.398352 -110.895022)
			(xy 415.380065 -110.844873) (xy 415.368946 -110.792665) (xy 415.365214 -110.739417) (xy 414.74644 -110.739417)
			(xy 414.74644 -111.478568) (xy 415.43732 -112.169448) (xy 430.229772 -112.169448)
		)
		(stroke
			(width 0)
			(type solid)
		)
		(fill yes)
		(layer "In15.Cu")
		(net "GND")
	)
	(gr_poly
		(pts
			(xy 278.5364 -78.682088) (xy 278.5364 -66.48704) (xy 277.711916 -65.662556) (xy 262.317738 -65.662556)
			(xy 261.880604 -65.749424) (xy 261.285228 -66.3448) (xy 263.172954 -66.3448) (xy 263.177025 -66.289178)
			(xy 263.189151 -66.234741) (xy 263.209074 -66.18265) (xy 263.23637 -66.134015) (xy 263.270456 -66.089872)
			(xy 263.310605 -66.051163) (xy 263.355963 -66.018712) (xy 263.405563 -65.993211) (xy 263.458347 -65.975204)
			(xy 263.51319 -65.965074) (xy 263.568924 -65.963037) (xy 263.624361 -65.969137) (xy 263.678318 -65.983243)
			(xy 263.729647 -66.005055) (xy 263.777253 -66.034109) (xy 263.820121 -66.069784) (xy 263.857338 -66.111321)
			(xy 263.888111 -66.157834) (xy 263.911783 -66.208331) (xy 263.927851 -66.261738) (xy 263.930708 -66.281153)
			(xy 273.401246 -66.281153) (xy 273.401246 -66.226647) (xy 273.409003 -66.172697) (xy 273.424358 -66.120399)
			(xy 273.447 -66.070819) (xy 273.476467 -66.024965) (xy 273.512159 -65.983772) (xy 273.553351 -65.948078)
			(xy 273.599203 -65.918608) (xy 273.648782 -65.895964) (xy 273.701079 -65.880606) (xy 273.755029 -65.872847)
			(xy 273.782282 -65.87236) (xy 273.8112 -65.872868) (xy 273.868372 -65.881596) (xy 273.923572 -65.898855)
			(xy 273.975534 -65.924248) (xy 274.023068 -65.957194) (xy 274.065083 -65.996939) (xy 274.083272 -66.019426)
			(xy 274.093169 -66.031231) (xy 274.118493 -66.04875) (xy 274.147886 -66.057926) (xy 274.178678 -66.057926)
			(xy 274.208071 -66.04875) (xy 274.233395 -66.031231) (xy 274.243292 -66.019426) (xy 274.260045 -65.998643)
			(xy 274.298399 -65.961513) (xy 274.341553 -65.930091) (xy 274.388667 -65.904992) (xy 274.438819 -65.886706)
			(xy 274.49103 -65.875589) (xy 274.544282 -65.871859) (xy 274.597534 -65.875589) (xy 274.649745 -65.886706)
			(xy 274.699897 -65.904992) (xy 274.747011 -65.930091) (xy 274.790165 -65.961513) (xy 274.828519 -65.998643)
			(xy 274.845272 -66.019426) (xy 274.855169 -66.031231) (xy 274.880493 -66.04875) (xy 274.909886 -66.057926)
			(xy 274.940678 -66.057926) (xy 274.970071 -66.04875) (xy 274.995395 -66.031231) (xy 275.005292 -66.019426)
			(xy 275.023494 -65.996952) (xy 275.065511 -65.957215) (xy 275.113043 -65.924274) (xy 275.165002 -65.898884)
			(xy 275.220198 -65.881626) (xy 275.277367 -65.872896) (xy 275.306282 -65.87236) (xy 275.333533 -65.872886)
			(xy 275.387482 -65.88064) (xy 275.439777 -65.895993) (xy 275.489356 -65.918633) (xy 275.535207 -65.948098)
			(xy 275.576399 -65.983789) (xy 275.612091 -66.024978) (xy 275.641558 -66.070829) (xy 275.6642 -66.120406)
			(xy 275.679556 -66.172701) (xy 275.687313 -66.226649) (xy 275.687313 -66.281151) (xy 275.679556 -66.335099)
			(xy 275.6642 -66.387394) (xy 275.641558 -66.436971) (xy 275.612091 -66.482822) (xy 275.576399 -66.524011)
			(xy 275.535207 -66.559702) (xy 275.489356 -66.589167) (xy 275.439777 -66.611807) (xy 275.387482 -66.62716)
			(xy 275.333533 -66.634914) (xy 275.306282 -66.635376) (xy 275.277367 -66.634808) (xy 275.220197 -66.626091)
			(xy 275.164999 -66.608843) (xy 275.113037 -66.583461) (xy 275.065502 -66.550526) (xy 275.023483 -66.510792)
			(xy 275.005292 -66.48831) (xy 274.995395 -66.476505) (xy 274.970071 -66.458986) (xy 274.940678 -66.44981)
			(xy 274.909886 -66.44981) (xy 274.880493 -66.458986) (xy 274.855169 -66.476505) (xy 274.845272 -66.48831)
			(xy 274.828519 -66.509093) (xy 274.790165 -66.546223) (xy 274.747011 -66.577645) (xy 274.699897 -66.602744)
			(xy 274.649745 -66.62103) (xy 274.597534 -66.632147) (xy 274.544282 -66.635877) (xy 274.49103 -66.632147)
			(xy 274.438819 -66.62103) (xy 274.388667 -66.602744) (xy 274.341553 -66.577645) (xy 274.298399 -66.546223)
			(xy 274.260045 -66.509093) (xy 274.243292 -66.48831) (xy 274.233395 -66.476505) (xy 274.208071 -66.458986)
			(xy 274.178678 -66.44981) (xy 274.147886 -66.44981) (xy 274.118493 -66.458986) (xy 274.093169 -66.476505)
			(xy 274.083272 -66.48831) (xy 274.065099 -66.510809) (xy 274.023075 -66.550543) (xy 273.975537 -66.58348)
			(xy 273.923572 -66.608865) (xy 273.868371 -66.626118) (xy 273.811199 -66.634843) (xy 273.782282 -66.635376)
			(xy 273.755029 -66.634953) (xy 273.701079 -66.627194) (xy 273.648782 -66.611836) (xy 273.599203 -66.589192)
			(xy 273.553351 -66.559722) (xy 273.512159 -66.524028) (xy 273.476467 -66.482835) (xy 273.447 -66.436981)
			(xy 273.424358 -66.387401) (xy 273.409003 -66.335103) (xy 273.401246 -66.281153) (xy 263.930708 -66.281153)
			(xy 263.935971 -66.316914) (xy 263.93648 -66.3448) (xy 263.935971 -66.372686) (xy 263.927851 -66.427862)
			(xy 263.911783 -66.481269) (xy 263.888111 -66.531766) (xy 263.857338 -66.578279) (xy 263.820121 -66.619816)
			(xy 263.777253 -66.655491) (xy 263.729647 -66.684545) (xy 263.678318 -66.706357) (xy 263.624361 -66.720463)
			(xy 263.568924 -66.726563) (xy 263.51319 -66.724526) (xy 263.458347 -66.714396) (xy 263.405563 -66.696389)
			(xy 263.355963 -66.670888) (xy 263.310605 -66.638437) (xy 263.270456 -66.599728) (xy 263.23637 -66.555585)
			(xy 263.209074 -66.50695) (xy 263.189151 -66.454859) (xy 263.177025 -66.400422) (xy 263.172954 -66.3448)
			(xy 261.285228 -66.3448) (xy 260.660388 -66.96964) (xy 260.674612 -67.001644) (xy 260.684543 -67.024743)
			(xy 260.698553 -67.073032) (xy 260.700834 -67.08902) (xy 261.67029 -67.08902) (xy 261.674361 -67.033398)
			(xy 261.686487 -66.978961) (xy 261.70641 -66.92687) (xy 261.733706 -66.878235) (xy 261.767792 -66.834092)
			(xy 261.807941 -66.795383) (xy 261.853299 -66.762932) (xy 261.902899 -66.737431) (xy 261.955683 -66.719424)
			(xy 262.010526 -66.709294) (xy 262.06626 -66.707257) (xy 262.121697 -66.713357) (xy 262.175654 -66.727463)
			(xy 262.226983 -66.749275) (xy 262.274589 -66.778329) (xy 262.317457 -66.814004) (xy 262.354674 -66.855541)
			(xy 262.385447 -66.902054) (xy 262.409119 -66.952551) (xy 262.425187 -67.005958) (xy 262.433307 -67.061134)
			(xy 262.433816 -67.08902) (xy 262.433307 -67.116906) (xy 262.425187 -67.172082) (xy 262.409119 -67.225489)
			(xy 262.385447 -67.275986) (xy 262.354674 -67.322499) (xy 262.317457 -67.364036) (xy 262.274589 -67.399711)
			(xy 262.239293 -67.421252) (xy 273.131024 -67.421252) (xy 273.135095 -67.36563) (xy 273.147221 -67.311193)
			(xy 273.167144 -67.259102) (xy 273.19444 -67.210467) (xy 273.228526 -67.166324) (xy 273.268675 -67.127615)
			(xy 273.314033 -67.095164) (xy 273.363633 -67.069663) (xy 273.416417 -67.051656) (xy 273.47126 -67.041526)
			(xy 273.526994 -67.039489) (xy 273.582431 -67.045589) (xy 273.636388 -67.059695) (xy 273.687717 -67.081507)
			(xy 273.735323 -67.110561) (xy 273.778191 -67.146236) (xy 273.815408 -67.187773) (xy 273.846181 -67.234286)
			(xy 273.869853 -67.284783) (xy 273.885921 -67.33819) (xy 273.894041 -67.393366) (xy 273.89455 -67.421252)
			(xy 274.020024 -67.421252) (xy 274.024095 -67.36563) (xy 274.036221 -67.311193) (xy 274.056144 -67.259102)
			(xy 274.08344 -67.210467) (xy 274.117526 -67.166324) (xy 274.157675 -67.127615) (xy 274.203033 -67.095164)
			(xy 274.252633 -67.069663) (xy 274.305417 -67.051656) (xy 274.36026 -67.041526) (xy 274.415994 -67.039489)
			(xy 274.471431 -67.045589) (xy 274.525388 -67.059695) (xy 274.576717 -67.081507) (xy 274.624323 -67.110561)
			(xy 274.667191 -67.146236) (xy 274.704408 -67.187773) (xy 274.735181 -67.234286) (xy 274.758853 -67.284783)
			(xy 274.774921 -67.33819) (xy 274.783041 -67.393366) (xy 274.78355 -67.421252) (xy 274.909024 -67.421252)
			(xy 274.913095 -67.36563) (xy 274.925221 -67.311193) (xy 274.945144 -67.259102) (xy 274.97244 -67.210467)
			(xy 275.006526 -67.166324) (xy 275.046675 -67.127615) (xy 275.092033 -67.095164) (xy 275.141633 -67.069663)
			(xy 275.194417 -67.051656) (xy 275.24926 -67.041526) (xy 275.304994 -67.039489) (xy 275.360431 -67.045589)
			(xy 275.414388 -67.059695) (xy 275.465717 -67.081507) (xy 275.513323 -67.110561) (xy 275.556191 -67.146236)
			(xy 275.593408 -67.187773) (xy 275.624181 -67.234286) (xy 275.647853 -67.284783) (xy 275.663921 -67.33819)
			(xy 275.672041 -67.393366) (xy 275.67255 -67.421252) (xy 275.672041 -67.449138) (xy 275.663921 -67.504314)
			(xy 275.647853 -67.557721) (xy 275.624181 -67.608218) (xy 275.593408 -67.654731) (xy 275.556191 -67.696268)
			(xy 275.513323 -67.731943) (xy 275.465717 -67.760997) (xy 275.414388 -67.782809) (xy 275.360431 -67.796915)
			(xy 275.304994 -67.803015) (xy 275.24926 -67.800978) (xy 275.194417 -67.790848) (xy 275.141633 -67.772841)
			(xy 275.092033 -67.74734) (xy 275.046675 -67.714889) (xy 275.006526 -67.67618) (xy 274.97244 -67.632037)
			(xy 274.945144 -67.583402) (xy 274.925221 -67.531311) (xy 274.913095 -67.476874) (xy 274.909024 -67.421252)
			(xy 274.78355 -67.421252) (xy 274.783041 -67.449138) (xy 274.774921 -67.504314) (xy 274.758853 -67.557721)
			(xy 274.735181 -67.608218) (xy 274.704408 -67.654731) (xy 274.667191 -67.696268) (xy 274.624323 -67.731943)
			(xy 274.576717 -67.760997) (xy 274.525388 -67.782809) (xy 274.471431 -67.796915) (xy 274.415994 -67.803015)
			(xy 274.36026 -67.800978) (xy 274.305417 -67.790848) (xy 274.252633 -67.772841) (xy 274.203033 -67.74734)
			(xy 274.157675 -67.714889) (xy 274.117526 -67.67618) (xy 274.08344 -67.632037) (xy 274.056144 -67.583402)
			(xy 274.036221 -67.531311) (xy 274.024095 -67.476874) (xy 274.020024 -67.421252) (xy 273.89455 -67.421252)
			(xy 273.894041 -67.449138) (xy 273.885921 -67.504314) (xy 273.869853 -67.557721) (xy 273.846181 -67.608218)
			(xy 273.815408 -67.654731) (xy 273.778191 -67.696268) (xy 273.735323 -67.731943) (xy 273.687717 -67.760997)
			(xy 273.636388 -67.782809) (xy 273.582431 -67.796915) (xy 273.526994 -67.803015) (xy 273.47126 -67.800978)
			(xy 273.416417 -67.790848) (xy 273.363633 -67.772841) (xy 273.314033 -67.74734) (xy 273.268675 -67.714889)
			(xy 273.228526 -67.67618) (xy 273.19444 -67.632037) (xy 273.167144 -67.583402) (xy 273.147221 -67.531311)
			(xy 273.135095 -67.476874) (xy 273.131024 -67.421252) (xy 262.239293 -67.421252) (xy 262.226983 -67.428765)
			(xy 262.175654 -67.450577) (xy 262.121697 -67.464683) (xy 262.06626 -67.470783) (xy 262.010526 -67.468746)
			(xy 261.955683 -67.458616) (xy 261.902899 -67.440609) (xy 261.853299 -67.415108) (xy 261.807941 -67.382657)
			(xy 261.767792 -67.343948) (xy 261.733706 -67.299805) (xy 261.70641 -67.25117) (xy 261.686487 -67.199079)
			(xy 261.674361 -67.144642) (xy 261.67029 -67.08902) (xy 260.700834 -67.08902) (xy 260.705653 -67.122808)
			(xy 260.706108 -67.147948) (xy 260.705555 -67.175929) (xy 260.696794 -67.2312) (xy 260.679496 -67.284421)
			(xy 260.654085 -67.33428) (xy 260.621188 -67.379551) (xy 260.581615 -67.419119) (xy 260.536339 -67.45201)
			(xy 260.486476 -67.477414) (xy 260.433253 -67.494706) (xy 260.377981 -67.503459) (xy 260.35 -67.504056)
			(xy 260.323326 -67.503575) (xy 260.270576 -67.495608) (xy 260.219603 -67.479866) (xy 260.171547 -67.456702)
			(xy 260.12748 -67.426634) (xy 260.088387 -67.390332) (xy 260.055143 -67.348608) (xy 260.04139 -67.325748)
			(xy 259.89661 -67.325748) (xy 259.88288 -67.348627) (xy 259.849645 -67.39037) (xy 259.810555 -67.426687)
			(xy 259.766485 -67.456768) (xy 259.718421 -67.479937) (xy 259.667439 -67.495678) (xy 259.614679 -67.503637)
			(xy 259.561321 -67.503637) (xy 259.508561 -67.495678) (xy 259.457579 -67.479937) (xy 259.409515 -67.456768)
			(xy 259.365445 -67.426687) (xy 259.326355 -67.39037) (xy 259.29312 -67.348627) (xy 259.27939 -67.325748)
			(xy 258.75615 -67.325748) (xy 258.732202 -67.339605) (xy 258.680992 -67.360547) (xy 258.62716 -67.373317)
			(xy 258.572 -67.377609) (xy 258.51684 -67.373317) (xy 258.463008 -67.360547) (xy 258.411798 -67.339605)
			(xy 258.38785 -67.325748) (xy 257.86715 -67.325748) (xy 257.843202 -67.339605) (xy 257.791992 -67.360547)
			(xy 257.73816 -67.373317) (xy 257.683 -67.377609) (xy 257.62784 -67.373317) (xy 257.574008 -67.360547)
			(xy 257.522798 -67.339605) (xy 257.49885 -67.325748) (xy 256.85115 -67.325748) (xy 256.827202 -67.339605)
			(xy 256.775992 -67.360547) (xy 256.72216 -67.373317) (xy 256.667 -67.377609) (xy 256.61184 -67.373317)
			(xy 256.558008 -67.360547) (xy 256.506798 -67.339605) (xy 256.48285 -67.325748) (xy 253.955804 -67.325748)
			(xy 253.81839 -67.35318) (xy 252.693198 -68.478252) (xy 273.901646 -68.478252) (xy 273.901646 -68.423748)
			(xy 273.909402 -68.369799) (xy 273.924756 -68.317503) (xy 273.947397 -68.267924) (xy 273.976862 -68.222072)
			(xy 274.012552 -68.180879) (xy 274.053741 -68.145185) (xy 274.099591 -68.115715) (xy 274.149168 -68.09307)
			(xy 274.201462 -68.07771) (xy 274.25541 -68.069948) (xy 274.282662 -68.06946) (xy 274.311579 -68.069983)
			(xy 274.368751 -68.078708) (xy 274.423951 -68.095963) (xy 274.475913 -68.121354) (xy 274.523447 -68.154298)
			(xy 274.565463 -68.19404) (xy 274.583652 -68.216526) (xy 274.593549 -68.228331) (xy 274.618873 -68.24585)
			(xy 274.648266 -68.255026) (xy 274.679058 -68.255026) (xy 274.708451 -68.24585) (xy 274.733775 -68.228331)
			(xy 274.743672 -68.216526) (xy 274.761885 -68.194061) (xy 274.8039 -68.154324) (xy 274.85143 -68.121382)
			(xy 274.903387 -68.09599) (xy 274.958581 -68.07873) (xy 275.015747 -68.069997) (xy 275.044662 -68.06946)
			(xy 275.071914 -68.069985) (xy 275.125865 -68.077737) (xy 275.178163 -68.093088) (xy 275.227744 -68.115726)
			(xy 275.273598 -68.145191) (xy 275.314791 -68.180882) (xy 275.350486 -68.222072) (xy 275.379955 -68.267923)
			(xy 275.402599 -68.317501) (xy 275.417955 -68.369798) (xy 275.425713 -68.423748) (xy 275.425713 -68.478252)
			(xy 275.417955 -68.532202) (xy 275.402599 -68.584499) (xy 275.379955 -68.634077) (xy 275.350486 -68.679928)
			(xy 275.314791 -68.721118) (xy 275.273598 -68.756809) (xy 275.227744 -68.786274) (xy 275.178163 -68.808912)
			(xy 275.125865 -68.824263) (xy 275.071914 -68.832015) (xy 275.044662 -68.832476) (xy 275.015746 -68.831922)
			(xy 274.958576 -68.823202) (xy 274.903378 -68.805952) (xy 274.851416 -68.780567) (xy 274.803881 -68.747629)
			(xy 274.761863 -68.707893) (xy 274.743672 -68.68541) (xy 274.733775 -68.673605) (xy 274.708451 -68.656086)
			(xy 274.679058 -68.64691) (xy 274.648266 -68.64691) (xy 274.618873 -68.656086) (xy 274.593549 -68.673605)
			(xy 274.583652 -68.68541) (xy 274.565434 -68.707871) (xy 274.52342 -68.747607) (xy 274.47589 -68.780548)
			(xy 274.423934 -68.80594) (xy 274.368742 -68.823202) (xy 274.311576 -68.831937) (xy 274.282662 -68.832476)
			(xy 274.25541 -68.832052) (xy 274.201462 -68.82429) (xy 274.149168 -68.80893) (xy 274.099591 -68.786285)
			(xy 274.053741 -68.756815) (xy 274.012552 -68.721121) (xy 273.976862 -68.679928) (xy 273.947397 -68.634076)
			(xy 273.924756 -68.584497) (xy 273.909402 -68.532201) (xy 273.901646 -68.478252) (xy 252.693198 -68.478252)
			(xy 251.608586 -69.562748) (xy 272.770626 -69.562748) (xy 272.770626 -69.508252) (xy 272.778382 -69.454311)
			(xy 272.793735 -69.402023) (xy 272.816373 -69.352452) (xy 272.845836 -69.306608) (xy 272.881523 -69.265423)
			(xy 272.922708 -69.229736) (xy 272.968552 -69.200273) (xy 273.018123 -69.177635) (xy 273.070411 -69.162282)
			(xy 273.124352 -69.154526) (xy 273.1516 -69.15404) (xy 273.180518 -69.154543) (xy 273.23769 -69.163273)
			(xy 273.29289 -69.180533) (xy 273.344852 -69.205928) (xy 273.392385 -69.238875) (xy 273.434401 -69.278619)
			(xy 273.45259 -69.301106) (xy 273.462487 -69.312911) (xy 273.487811 -69.33043) (xy 273.517204 -69.339606)
			(xy 273.547996 -69.339606) (xy 273.577389 -69.33043) (xy 273.602713 -69.312911) (xy 273.61261 -69.301106)
			(xy 273.629363 -69.280323) (xy 273.667717 -69.243193) (xy 273.710871 -69.211771) (xy 273.757985 -69.186672)
			(xy 273.808137 -69.168386) (xy 273.860348 -69.157269) (xy 273.9136 -69.153539) (xy 273.966852 -69.157269)
			(xy 274.019063 -69.168386) (xy 274.069215 -69.186672) (xy 274.116329 -69.211771) (xy 274.159483 -69.243193)
			(xy 274.197837 -69.280323) (xy 274.21459 -69.301106) (xy 274.224487 -69.312911) (xy 274.249811 -69.33043)
			(xy 274.279204 -69.339606) (xy 274.309996 -69.339606) (xy 274.339389 -69.33043) (xy 274.364713 -69.312911)
			(xy 274.37461 -69.301106) (xy 274.391363 -69.280323) (xy 274.429717 -69.243193) (xy 274.472871 -69.211771)
			(xy 274.519985 -69.186672) (xy 274.570137 -69.168386) (xy 274.622348 -69.157269) (xy 274.6756 -69.153539)
			(xy 274.728852 -69.157269) (xy 274.781063 -69.168386) (xy 274.831215 -69.186672) (xy 274.878329 -69.211771)
			(xy 274.921483 -69.243193) (xy 274.959837 -69.280323) (xy 274.97659 -69.301106) (xy 274.986487 -69.312911)
			(xy 275.011811 -69.33043) (xy 275.041204 -69.339606) (xy 275.071996 -69.339606) (xy 275.101389 -69.33043)
			(xy 275.126713 -69.312911) (xy 275.13661 -69.301106) (xy 275.153363 -69.280323) (xy 275.191717 -69.243193)
			(xy 275.234871 -69.211771) (xy 275.281985 -69.186672) (xy 275.332137 -69.168386) (xy 275.384348 -69.157269)
			(xy 275.4376 -69.153539) (xy 275.490852 -69.157269) (xy 275.543063 -69.168386) (xy 275.593215 -69.186672)
			(xy 275.640329 -69.211771) (xy 275.683483 -69.243193) (xy 275.721837 -69.280323) (xy 275.73859 -69.301106)
			(xy 275.748487 -69.312911) (xy 275.773811 -69.33043) (xy 275.803204 -69.339606) (xy 275.833996 -69.339606)
			(xy 275.863389 -69.33043) (xy 275.888713 -69.312911) (xy 275.89861 -69.301106) (xy 275.916797 -69.278619)
			(xy 275.958817 -69.238884) (xy 276.006353 -69.205945) (xy 276.058315 -69.180557) (xy 276.113514 -69.163302)
			(xy 276.170684 -69.154574) (xy 276.1996 -69.15404) (xy 276.226855 -69.15443) (xy 276.280809 -69.162187)
			(xy 276.333111 -69.177544) (xy 276.382694 -69.200188) (xy 276.42855 -69.229658) (xy 276.469746 -69.265354)
			(xy 276.505442 -69.30655) (xy 276.534912 -69.352406) (xy 276.557556 -69.401989) (xy 276.572913 -69.454291)
			(xy 276.58067 -69.508245) (xy 276.58067 -69.562755) (xy 276.572913 -69.616709) (xy 276.557556 -69.669011)
			(xy 276.534912 -69.718594) (xy 276.505442 -69.76445) (xy 276.469746 -69.805646) (xy 276.42855 -69.841342)
			(xy 276.382694 -69.870812) (xy 276.333111 -69.893456) (xy 276.280809 -69.908813) (xy 276.226855 -69.91657)
			(xy 276.1996 -69.917056) (xy 276.170682 -69.916554) (xy 276.11351 -69.907824) (xy 276.05831 -69.890564)
			(xy 276.006348 -69.865169) (xy 275.958814 -69.832222) (xy 275.916799 -69.792477) (xy 275.89861 -69.76999)
			(xy 275.888713 -69.758185) (xy 275.863389 -69.740666) (xy 275.833996 -69.73149) (xy 275.803204 -69.73149)
			(xy 275.773811 -69.740666) (xy 275.748487 -69.758185) (xy 275.73859 -69.76999) (xy 275.721837 -69.790773)
			(xy 275.683483 -69.827903) (xy 275.640329 -69.859325) (xy 275.593215 -69.884424) (xy 275.543063 -69.90271)
			(xy 275.490852 -69.913827) (xy 275.4376 -69.917557) (xy 275.384348 -69.913827) (xy 275.332137 -69.90271)
			(xy 275.281985 -69.884424) (xy 275.234871 -69.859325) (xy 275.191717 -69.827903) (xy 275.153363 -69.790773)
			(xy 275.13661 -69.76999) (xy 275.126713 -69.758185) (xy 275.101389 -69.740666) (xy 275.071996 -69.73149)
			(xy 275.041204 -69.73149) (xy 275.011811 -69.740666) (xy 274.986487 -69.758185) (xy 274.97659 -69.76999)
			(xy 274.959837 -69.790773) (xy 274.921483 -69.827903) (xy 274.878329 -69.859325) (xy 274.831215 -69.884424)
			(xy 274.781063 -69.90271) (xy 274.728852 -69.913827) (xy 274.6756 -69.917557) (xy 274.622348 -69.913827)
			(xy 274.570137 -69.90271) (xy 274.519985 -69.884424) (xy 274.472871 -69.859325) (xy 274.429717 -69.827903)
			(xy 274.391363 -69.790773) (xy 274.37461 -69.76999) (xy 274.364713 -69.758185) (xy 274.339389 -69.740666)
			(xy 274.309996 -69.73149) (xy 274.279204 -69.73149) (xy 274.249811 -69.740666) (xy 274.224487 -69.758185)
			(xy 274.21459 -69.76999) (xy 274.197837 -69.790773) (xy 274.159483 -69.827903) (xy 274.116329 -69.859325)
			(xy 274.069215 -69.884424) (xy 274.019063 -69.90271) (xy 273.966852 -69.913827) (xy 273.9136 -69.917557)
			(xy 273.860348 -69.913827) (xy 273.808137 -69.90271) (xy 273.757985 -69.884424) (xy 273.710871 -69.859325)
			(xy 273.667717 -69.827903) (xy 273.629363 -69.790773) (xy 273.61261 -69.76999) (xy 273.602713 -69.758185)
			(xy 273.577389 -69.740666) (xy 273.547996 -69.73149) (xy 273.517204 -69.73149) (xy 273.487811 -69.740666)
			(xy 273.462487 -69.758185) (xy 273.45259 -69.76999) (xy 273.434402 -69.792476) (xy 273.392382 -69.832212)
			(xy 273.344847 -69.865151) (xy 273.292885 -69.890539) (xy 273.237686 -69.907794) (xy 273.180516 -69.916522)
			(xy 273.1516 -69.917056) (xy 273.124352 -69.916474) (xy 273.070411 -69.908718) (xy 273.018123 -69.893365)
			(xy 272.968552 -69.870727) (xy 272.922708 -69.841264) (xy 272.881523 -69.805577) (xy 272.845836 -69.764392)
			(xy 272.816373 -69.718548) (xy 272.793735 -69.668977) (xy 272.778382 -69.616689) (xy 272.770626 -69.562748)
			(xy 251.608586 -69.562748) (xy 251.441204 -69.730112) (xy 251.420354 -69.750238) (xy 251.373505 -69.784342)
			(xy 251.321896 -69.810696) (xy 251.2668 -69.82865) (xy 251.209573 -69.837763) (xy 251.1806 -69.838316)
			(xy 250.679966 -69.838316) (xy 250.52528 -69.992748) (xy 248.882916 -69.992748) (xy 248.867441 -69.993291)
			(xy 248.837909 -70.002553) (xy 248.812504 -70.020231) (xy 248.793558 -70.044704) (xy 248.782807 -70.073727)
			(xy 248.781239 -70.104637) (xy 248.784618 -70.119748) (xy 248.790188 -70.142972) (xy 248.796169 -70.190356)
			(xy 248.796556 -70.214236) (xy 248.796556 -70.214744) (xy 248.796114 -70.241419) (xy 248.788686 -70.294248)
			(xy 248.773968 -70.345526) (xy 248.752247 -70.394253) (xy 248.723946 -70.439477) (xy 248.689619 -70.480315)
			(xy 248.670064 -70.498462) (xy 248.659758 -70.508333) (xy 248.644598 -70.532496) (xy 248.636706 -70.559907)
			(xy 248.636697 -70.588432) (xy 248.644572 -70.615848) (xy 248.659718 -70.64002) (xy 248.670064 -70.649846)
			(xy 248.689604 -70.668008) (xy 248.723924 -70.70885) (xy 248.752219 -70.754075) (xy 248.77394 -70.8028)
			(xy 248.78866 -70.854076) (xy 248.796095 -70.906902) (xy 248.796098 -70.96025) (xy 248.78867 -71.013077)
			(xy 248.773956 -71.064355) (xy 248.752242 -71.113083) (xy 248.723952 -71.158311) (xy 248.689637 -71.199157)
			(xy 248.670064 -71.217282) (xy 248.659761 -71.227153) (xy 248.644606 -71.251314) (xy 248.636719 -71.278722)
			(xy 248.636714 -71.307243) (xy 248.644592 -71.334654) (xy 248.659739 -71.35882) (xy 248.670064 -71.368666)
			(xy 248.689603 -71.386829) (xy 248.723921 -71.42767) (xy 248.752219 -71.472892) (xy 248.773943 -71.521615)
			(xy 248.788671 -71.572887) (xy 248.796115 -71.625711) (xy 248.796556 -71.652384) (xy 248.796112 -71.679036)
			(xy 248.788688 -71.73182) (xy 248.773982 -71.783054) (xy 248.763536 -71.807578) (xy 248.757848 -71.821703)
			(xy 248.754175 -71.851913) (xy 248.759564 -71.881865) (xy 248.773536 -71.9089) (xy 248.794852 -71.930621)
			(xy 248.821619 -71.9451) (xy 248.851464 -71.951052) (xy 248.86666 -71.950072) (xy 248.90476 -71.94804)
			(xy 248.932013 -71.948501) (xy 248.985966 -71.956253) (xy 249.038266 -71.971606) (xy 249.087848 -71.994247)
			(xy 249.133703 -72.023715) (xy 249.174896 -72.059409) (xy 249.21059 -72.100604) (xy 249.240057 -72.146459)
			(xy 249.262696 -72.196041) (xy 249.278048 -72.248342) (xy 249.2858 -72.302295) (xy 249.286268 -72.329548)
			(xy 249.285793 -72.356917) (xy 249.277962 -72.411091) (xy 249.262469 -72.46359) (xy 249.239631 -72.513335)
			(xy 249.209917 -72.559306) (xy 249.192288 -72.580246) (xy 249.183059 -72.591573) (xy 249.170896 -72.618127)
			(xy 249.166736 -72.647036) (xy 249.170917 -72.675943) (xy 249.183098 -72.702488) (xy 249.192288 -72.71385)
			(xy 249.209925 -72.734783) (xy 249.239641 -72.78075) (xy 249.262479 -72.830494) (xy 249.277969 -72.882993)
			(xy 249.285791 -72.937168) (xy 249.285786 -72.991904) (xy 249.277953 -73.046077) (xy 249.262454 -73.098573)
			(xy 249.239607 -73.148313) (xy 249.209881 -73.194275) (xy 249.192288 -73.215246) (xy 249.183059 -73.226573)
			(xy 249.170896 -73.253127) (xy 249.166736 -73.282036) (xy 249.170917 -73.310943) (xy 249.183098 -73.337488)
			(xy 249.192288 -73.34885) (xy 249.209925 -73.369783) (xy 249.239641 -73.41575) (xy 249.262479 -73.465494)
			(xy 249.277969 -73.517993) (xy 249.285791 -73.572168) (xy 249.285787 -73.620122) (xy 252.28245 -73.620122)
			(xy 252.286523 -73.564463) (xy 252.298658 -73.50999) (xy 252.318594 -73.457864) (xy 252.345908 -73.409196)
			(xy 252.380016 -73.365024) (xy 252.420193 -73.326289) (xy 252.465581 -73.293817) (xy 252.515213 -73.268299)
			(xy 252.568033 -73.25028) (xy 252.622912 -73.240143) (xy 252.678683 -73.238105) (xy 252.734157 -73.244208)
			(xy 252.78815 -73.258324) (xy 252.839513 -73.280151) (xy 252.887151 -73.309224) (xy 252.930047 -73.344923)
			(xy 252.967289 -73.386487) (xy 252.998083 -73.433031) (xy 253.021771 -73.483562) (xy 253.037201 -73.53485)
			(xy 272.927578 -73.53485) (xy 272.927578 -73.48035) (xy 272.935333 -73.426405) (xy 272.950687 -73.374112)
			(xy 272.973326 -73.324537) (xy 273.00279 -73.278688) (xy 273.038478 -73.237498) (xy 273.079665 -73.201807)
			(xy 273.125512 -73.17234) (xy 273.175086 -73.149697) (xy 273.227377 -73.134339) (xy 273.281322 -73.12658)
			(xy 273.308572 -73.126092) (xy 273.33749 -73.126595) (xy 273.394663 -73.135323) (xy 273.449864 -73.152581)
			(xy 273.501827 -73.177975) (xy 273.54936 -73.210923) (xy 273.591374 -73.25067) (xy 273.609562 -73.273158)
			(xy 273.619459 -73.284963) (xy 273.644783 -73.302482) (xy 273.674176 -73.311658) (xy 273.704968 -73.311658)
			(xy 273.734361 -73.302482) (xy 273.759685 -73.284963) (xy 273.769582 -73.273158) (xy 273.786335 -73.252375)
			(xy 273.824689 -73.215245) (xy 273.867843 -73.183823) (xy 273.914957 -73.158724) (xy 273.965109 -73.140438)
			(xy 274.01732 -73.129321) (xy 274.070572 -73.125591) (xy 274.123824 -73.129321) (xy 274.176035 -73.140438)
			(xy 274.226187 -73.158724) (xy 274.273301 -73.183823) (xy 274.316455 -73.215245) (xy 274.354809 -73.252375)
			(xy 274.371562 -73.273158) (xy 274.381459 -73.284963) (xy 274.406783 -73.302482) (xy 274.436176 -73.311658)
			(xy 274.466968 -73.311658) (xy 274.496361 -73.302482) (xy 274.521685 -73.284963) (xy 274.531582 -73.273158)
			(xy 274.548335 -73.252375) (xy 274.586689 -73.215245) (xy 274.629843 -73.183823) (xy 274.676957 -73.158724)
			(xy 274.727109 -73.140438) (xy 274.77932 -73.129321) (xy 274.832572 -73.125591) (xy 274.885824 -73.129321)
			(xy 274.938035 -73.140438) (xy 274.988187 -73.158724) (xy 275.035301 -73.183823) (xy 275.078455 -73.215245)
			(xy 275.116809 -73.252375) (xy 275.133562 -73.273158) (xy 275.143459 -73.284963) (xy 275.168783 -73.302482)
			(xy 275.198176 -73.311658) (xy 275.228968 -73.311658) (xy 275.258361 -73.302482) (xy 275.283685 -73.284963)
			(xy 275.293582 -73.273158) (xy 275.310335 -73.252375) (xy 275.348689 -73.215245) (xy 275.391843 -73.183823)
			(xy 275.438957 -73.158724) (xy 275.489109 -73.140438) (xy 275.54132 -73.129321) (xy 275.594572 -73.125591)
			(xy 275.647824 -73.129321) (xy 275.700035 -73.140438) (xy 275.750187 -73.158724) (xy 275.797301 -73.183823)
			(xy 275.840455 -73.215245) (xy 275.878809 -73.252375) (xy 275.895562 -73.273158) (xy 275.905459 -73.284963)
			(xy 275.930783 -73.302482) (xy 275.960176 -73.311658) (xy 275.990968 -73.311658) (xy 276.020361 -73.302482)
			(xy 276.045685 -73.284963) (xy 276.055582 -73.273158) (xy 276.073773 -73.250674) (xy 276.115794 -73.210941)
			(xy 276.163329 -73.178003) (xy 276.21529 -73.152615) (xy 276.270487 -73.135359) (xy 276.327656 -73.126628)
			(xy 276.356572 -73.126092) (xy 276.383826 -73.126553) (xy 276.43778 -73.134307) (xy 276.490081 -73.149661)
			(xy 276.539665 -73.172302) (xy 276.585522 -73.201769) (xy 276.626718 -73.237463) (xy 276.662414 -73.278656)
			(xy 276.691885 -73.32451) (xy 276.714529 -73.374092) (xy 276.729887 -73.426392) (xy 276.737645 -73.480346)
			(xy 276.737645 -73.534854) (xy 276.729887 -73.588808) (xy 276.714529 -73.641108) (xy 276.691885 -73.69069)
			(xy 276.662414 -73.736544) (xy 276.626718 -73.777737) (xy 276.585522 -73.813431) (xy 276.539665 -73.842898)
			(xy 276.490081 -73.865539) (xy 276.43778 -73.880893) (xy 276.383826 -73.888647) (xy 276.356572 -73.889108)
			(xy 276.327655 -73.888573) (xy 276.270483 -73.879852) (xy 276.215283 -73.8626) (xy 276.163321 -73.837212)
			(xy 276.115787 -73.804269) (xy 276.073771 -73.764528) (xy 276.055582 -73.742042) (xy 276.045685 -73.730237)
			(xy 276.020361 -73.712718) (xy 275.990968 -73.703542) (xy 275.960176 -73.703542) (xy 275.930783 -73.712718)
			(xy 275.905459 -73.730237) (xy 275.895562 -73.742042) (xy 275.878809 -73.762825) (xy 275.840455 -73.799955)
			(xy 275.797301 -73.831377) (xy 275.750187 -73.856476) (xy 275.700035 -73.874762) (xy 275.647824 -73.885879)
			(xy 275.594572 -73.889609) (xy 275.54132 -73.885879) (xy 275.489109 -73.874762) (xy 275.438957 -73.856476)
			(xy 275.391843 -73.831377) (xy 275.348689 -73.799955) (xy 275.310335 -73.762825) (xy 275.293582 -73.742042)
			(xy 275.283685 -73.730237) (xy 275.258361 -73.712718) (xy 275.228968 -73.703542) (xy 275.198176 -73.703542)
			(xy 275.168783 -73.712718) (xy 275.143459 -73.730237) (xy 275.133562 -73.742042) (xy 275.116809 -73.762825)
			(xy 275.078455 -73.799955) (xy 275.035301 -73.831377) (xy 274.988187 -73.856476) (xy 274.938035 -73.874762)
			(xy 274.885824 -73.885879) (xy 274.832572 -73.889609) (xy 274.77932 -73.885879) (xy 274.727109 -73.874762)
			(xy 274.676957 -73.856476) (xy 274.629843 -73.831377) (xy 274.586689 -73.799955) (xy 274.548335 -73.762825)
			(xy 274.531582 -73.742042) (xy 274.521685 -73.730237) (xy 274.496361 -73.712718) (xy 274.466968 -73.703542)
			(xy 274.436176 -73.703542) (xy 274.406783 -73.712718) (xy 274.381459 -73.730237) (xy 274.371562 -73.742042)
			(xy 274.354809 -73.762825) (xy 274.316455 -73.799955) (xy 274.273301 -73.831377) (xy 274.226187 -73.856476)
			(xy 274.176035 -73.874762) (xy 274.123824 -73.885879) (xy 274.070572 -73.889609) (xy 274.01732 -73.885879)
			(xy 273.965109 -73.874762) (xy 273.914957 -73.856476) (xy 273.867843 -73.831377) (xy 273.824689 -73.799955)
			(xy 273.786335 -73.762825) (xy 273.769582 -73.742042) (xy 273.759685 -73.730237) (xy 273.734361 -73.712718)
			(xy 273.704968 -73.703542) (xy 273.674176 -73.703542) (xy 273.644783 -73.712718) (xy 273.619459 -73.730237)
			(xy 273.609562 -73.742042) (xy 273.591403 -73.764552) (xy 273.549375 -73.804284) (xy 273.501833 -73.837219)
			(xy 273.449866 -73.862602) (xy 273.394663 -73.879853) (xy 273.33749 -73.888576) (xy 273.308572 -73.889108)
			(xy 273.281322 -73.88862) (xy 273.227377 -73.880861) (xy 273.175086 -73.865503) (xy 273.125512 -73.84286)
			(xy 273.079665 -73.813393) (xy 273.038478 -73.777702) (xy 273.00279 -73.736512) (xy 272.973326 -73.690663)
			(xy 272.950687 -73.641088) (xy 272.935333 -73.588795) (xy 272.927578 -73.53485) (xy 253.037201 -73.53485)
			(xy 253.037849 -73.537004) (xy 253.045975 -73.592218) (xy 253.046484 -73.620122) (xy 253.045975 -73.648026)
			(xy 253.037849 -73.70324) (xy 253.021771 -73.756682) (xy 252.998083 -73.807213) (xy 252.967289 -73.853757)
			(xy 252.930047 -73.895321) (xy 252.887151 -73.93102) (xy 252.839513 -73.960093) (xy 252.78815 -73.98192)
			(xy 252.734157 -73.996036) (xy 252.678683 -74.002139) (xy 252.622912 -74.000101) (xy 252.568033 -73.989964)
			(xy 252.515213 -73.971945) (xy 252.465581 -73.946427) (xy 252.420193 -73.913955) (xy 252.380016 -73.87522)
			(xy 252.345908 -73.831048) (xy 252.318594 -73.78238) (xy 252.298658 -73.730254) (xy 252.286523 -73.675781)
			(xy 252.28245 -73.620122) (xy 249.285787 -73.620122) (xy 249.285786 -73.626904) (xy 249.277953 -73.681077)
			(xy 249.262454 -73.733573) (xy 249.239607 -73.783313) (xy 249.209881 -73.829275) (xy 249.192288 -73.850246)
			(xy 249.183059 -73.861573) (xy 249.170896 -73.888127) (xy 249.166736 -73.917036) (xy 249.170917 -73.945943)
			(xy 249.183098 -73.972488) (xy 249.192288 -73.98385) (xy 249.209928 -74.004782) (xy 249.239649 -74.050749)
			(xy 249.261642 -74.098658) (xy 260.18693 -74.098658) (xy 260.191001 -74.043036) (xy 260.203127 -73.988599)
			(xy 260.22305 -73.936508) (xy 260.250346 -73.887873) (xy 260.284432 -73.84373) (xy 260.324581 -73.805021)
			(xy 260.369939 -73.77257) (xy 260.419539 -73.747069) (xy 260.472323 -73.729062) (xy 260.527166 -73.718932)
			(xy 260.5829 -73.716895) (xy 260.638337 -73.722995) (xy 260.692294 -73.737101) (xy 260.743623 -73.758913)
			(xy 260.791229 -73.787967) (xy 260.834097 -73.823642) (xy 260.871314 -73.865179) (xy 260.902087 -73.911692)
			(xy 260.925759 -73.962189) (xy 260.932964 -73.986136) (xy 261.8265 -73.986136) (xy 261.830571 -73.930514)
			(xy 261.842697 -73.876077) (xy 261.86262 -73.823986) (xy 261.889916 -73.775351) (xy 261.924002 -73.731208)
			(xy 261.964151 -73.692499) (xy 262.009509 -73.660048) (xy 262.059109 -73.634547) (xy 262.111893 -73.61654)
			(xy 262.166736 -73.60641) (xy 262.22247 -73.604373) (xy 262.277907 -73.610473) (xy 262.331864 -73.624579)
			(xy 262.383193 -73.646391) (xy 262.430799 -73.675445) (xy 262.473667 -73.71112) (xy 262.510884 -73.752657)
			(xy 262.541657 -73.79917) (xy 262.565329 -73.849667) (xy 262.581397 -73.903074) (xy 262.589517 -73.95825)
			(xy 262.590026 -73.986136) (xy 262.589517 -74.014022) (xy 262.581397 -74.069198) (xy 262.565329 -74.122605)
			(xy 262.541657 -74.173102) (xy 262.510884 -74.219615) (xy 262.473667 -74.261152) (xy 262.430799 -74.296827)
			(xy 262.383193 -74.325881) (xy 262.331864 -74.347693) (xy 262.277907 -74.361799) (xy 262.22247 -74.367899)
			(xy 262.166736 -74.365862) (xy 262.111893 -74.355732) (xy 262.059109 -74.337725) (xy 262.009509 -74.312224)
			(xy 261.964151 -74.279773) (xy 261.924002 -74.241064) (xy 261.889916 -74.196921) (xy 261.86262 -74.148286)
			(xy 261.842697 -74.096195) (xy 261.830571 -74.041758) (xy 261.8265 -73.986136) (xy 260.932964 -73.986136)
			(xy 260.941827 -74.015596) (xy 260.949947 -74.070772) (xy 260.950456 -74.098658) (xy 260.949947 -74.126544)
			(xy 260.941827 -74.18172) (xy 260.925759 -74.235127) (xy 260.902087 -74.285624) (xy 260.871314 -74.332137)
			(xy 260.834097 -74.373674) (xy 260.791229 -74.409349) (xy 260.743623 -74.438403) (xy 260.692294 -74.460215)
			(xy 260.638337 -74.474321) (xy 260.5829 -74.480421) (xy 260.527166 -74.478384) (xy 260.472323 -74.468254)
			(xy 260.419539 -74.450247) (xy 260.369939 -74.424746) (xy 260.324581 -74.392295) (xy 260.284432 -74.353586)
			(xy 260.250346 -74.309443) (xy 260.22305 -74.260808) (xy 260.203127 -74.208717) (xy 260.191001 -74.15428)
			(xy 260.18693 -74.098658) (xy 249.261642 -74.098658) (xy 249.262486 -74.100497) (xy 249.27797 -74.153)
			(xy 249.285782 -74.207178) (xy 249.286268 -74.234548) (xy 249.285778 -74.261796) (xy 249.278016 -74.315736)
			(xy 249.262656 -74.368023) (xy 249.240012 -74.417591) (xy 249.210544 -74.463433) (xy 249.174852 -74.504614)
			(xy 249.133662 -74.540297) (xy 249.087814 -74.569754) (xy 249.03824 -74.592387) (xy 248.98595 -74.607735)
			(xy 248.932008 -74.615485) (xy 248.90476 -74.616056) (xy 248.893495 -74.616004) (xy 248.871001 -74.614735)
			(xy 248.859802 -74.613516) (xy 248.846196 -74.612339) (xy 248.819204 -74.616423) (xy 248.794265 -74.627527)
			(xy 248.773171 -74.644856) (xy 248.757435 -74.667164) (xy 248.748189 -74.692849) (xy 248.746096 -74.720068)
			(xy 248.751306 -74.746866) (xy 248.752569 -74.74966) (xy 258.981954 -74.74966) (xy 258.986025 -74.694038)
			(xy 258.998151 -74.639601) (xy 259.018074 -74.58751) (xy 259.04537 -74.538875) (xy 259.079456 -74.494732)
			(xy 259.119605 -74.456023) (xy 259.164963 -74.423572) (xy 259.214563 -74.398071) (xy 259.267347 -74.380064)
			(xy 259.32219 -74.369934) (xy 259.377924 -74.367897) (xy 259.433361 -74.373997) (xy 259.487318 -74.388103)
			(xy 259.538647 -74.409915) (xy 259.586253 -74.438969) (xy 259.629121 -74.474644) (xy 259.666338 -74.516181)
			(xy 259.697111 -74.562694) (xy 259.720783 -74.613191) (xy 259.736851 -74.666598) (xy 259.744971 -74.721774)
			(xy 259.74548 -74.74966) (xy 259.744971 -74.777546) (xy 259.736851 -74.832722) (xy 259.720783 -74.886129)
			(xy 259.697111 -74.936626) (xy 259.666338 -74.983139) (xy 259.629121 -75.024676) (xy 259.586253 -75.060351)
			(xy 259.538647 -75.089405) (xy 259.487318 -75.111217) (xy 259.433361 -75.125323) (xy 259.377924 -75.131423)
			(xy 259.32219 -75.129386) (xy 259.267347 -75.119256) (xy 259.214563 -75.101249) (xy 259.164963 -75.075748)
			(xy 259.119605 -75.043297) (xy 259.079456 -75.004588) (xy 259.04537 -74.960445) (xy 259.018074 -74.91181)
			(xy 258.998151 -74.859719) (xy 258.986025 -74.805282) (xy 258.981954 -74.74966) (xy 248.752569 -74.74966)
			(xy 248.756932 -74.759312) (xy 248.769426 -74.785697) (xy 248.787073 -74.841344) (xy 248.796015 -74.899033)
			(xy 248.796556 -74.928222) (xy 248.796556 -74.928984) (xy 248.796071 -74.956237) (xy 248.788317 -75.010189)
			(xy 248.772964 -75.062489) (xy 248.750324 -75.112071) (xy 248.720859 -75.157927) (xy 248.685168 -75.199123)
			(xy 248.643978 -75.234821) (xy 248.598127 -75.264293) (xy 248.548549 -75.286941) (xy 248.496252 -75.302303)
			(xy 248.442301 -75.310067) (xy 248.415048 -75.310492) (xy 248.387679 -75.310017) (xy 248.333505 -75.302186)
			(xy 248.281006 -75.286693) (xy 248.23126 -75.263856) (xy 248.185289 -75.234143) (xy 248.16435 -75.216512)
			(xy 248.153022 -75.207276) (xy 248.126465 -75.1951) (xy 248.097548 -75.190927) (xy 248.068631 -75.1951)
			(xy 248.042074 -75.207276) (xy 248.030746 -75.216512) (xy 248.009813 -75.23415) (xy 247.963845 -75.263869)
			(xy 247.914098 -75.286704) (xy 247.861595 -75.302187) (xy 247.807417 -75.309997) (xy 247.780048 -75.310492)
			(xy 247.752794 -75.310032) (xy 247.69884 -75.302281) (xy 247.646539 -75.28693) (xy 247.596955 -75.264291)
			(xy 247.551097 -75.234825) (xy 247.509901 -75.199133) (xy 247.474203 -75.157941) (xy 247.444732 -75.112087)
			(xy 247.422087 -75.062506) (xy 247.406729 -75.010207) (xy 247.398971 -74.956254) (xy 247.398971 -74.901746)
			(xy 247.406729 -74.847793) (xy 247.422087 -74.795494) (xy 247.444732 -74.745913) (xy 247.474203 -74.700059)
			(xy 247.509901 -74.658867) (xy 247.551097 -74.623175) (xy 247.596955 -74.593709) (xy 247.646539 -74.57107)
			(xy 247.69884 -74.555719) (xy 247.752794 -74.547968) (xy 247.780048 -74.547476) (xy 247.807417 -74.547951)
			(xy 247.861592 -74.55578) (xy 247.914093 -74.571272) (xy 247.96384 -74.594107) (xy 248.009813 -74.623818)
			(xy 248.030746 -74.641456) (xy 248.042074 -74.650692) (xy 248.068631 -74.662868) (xy 248.097548 -74.667041)
			(xy 248.126465 -74.662868) (xy 248.153022 -74.650692) (xy 248.16435 -74.641456) (xy 248.185281 -74.623814)
			(xy 248.231248 -74.59409) (xy 248.280995 -74.57125) (xy 248.333498 -74.555764) (xy 248.387678 -74.547952)
			(xy 248.415048 -74.547476) (xy 248.426313 -74.547528) (xy 248.448807 -74.548798) (xy 248.460006 -74.550016)
			(xy 248.473614 -74.551192) (xy 248.500608 -74.547107) (xy 248.52555 -74.536001) (xy 248.546647 -74.518671)
			(xy 248.562386 -74.496362) (xy 248.571638 -74.470675) (xy 248.573737 -74.443454) (xy 248.568533 -74.416652)
			(xy 248.562876 -74.40422) (xy 248.55038 -74.377835) (xy 248.532728 -74.322189) (xy 248.523781 -74.264499)
			(xy 248.523252 -74.23531) (xy 248.523252 -74.234548) (xy 248.523728 -74.20718) (xy 248.531559 -74.153006)
			(xy 248.547053 -74.100508) (xy 248.569893 -74.050763) (xy 248.599608 -74.004794) (xy 248.617232 -73.98385)
			(xy 248.626473 -73.972521) (xy 248.63866 -73.94596) (xy 248.642842 -73.917036) (xy 248.63868 -73.88811)
			(xy 248.626513 -73.86154) (xy 248.617232 -73.850246) (xy 248.599588 -73.829313) (xy 248.569856 -73.783345)
			(xy 248.547003 -73.733596) (xy 248.531501 -73.681091) (xy 248.523666 -73.626909) (xy 248.523661 -73.572163)
			(xy 248.531485 -73.517979) (xy 248.546978 -73.465471) (xy 248.569821 -73.415719) (xy 248.599544 -73.369745)
			(xy 248.617232 -73.34885) (xy 248.626473 -73.337521) (xy 248.63866 -73.31096) (xy 248.642842 -73.282036)
			(xy 248.63868 -73.25311) (xy 248.626513 -73.22654) (xy 248.617232 -73.215246) (xy 248.599588 -73.194313)
			(xy 248.569856 -73.148345) (xy 248.547003 -73.098596) (xy 248.531501 -73.046091) (xy 248.523666 -72.991909)
			(xy 248.523661 -72.937163) (xy 248.531485 -72.882979) (xy 248.546978 -72.830471) (xy 248.569821 -72.780719)
			(xy 248.599544 -72.734745) (xy 248.617232 -72.71385) (xy 248.626473 -72.702521) (xy 248.63866 -72.67596)
			(xy 248.642842 -72.647036) (xy 248.63868 -72.61811) (xy 248.626513 -72.59154) (xy 248.617232 -72.580246)
			(xy 248.599592 -72.559314) (xy 248.56987 -72.513347) (xy 248.547032 -72.4636) (xy 248.531547 -72.411097)
			(xy 248.523736 -72.356918) (xy 248.523252 -72.329548) (xy 248.523693 -72.302896) (xy 248.531112 -72.250109)
			(xy 248.545811 -72.198871) (xy 248.556272 -72.174354) (xy 248.561965 -72.160226) (xy 248.565645 -72.130008)
			(xy 248.560261 -72.100046) (xy 248.546289 -72.073) (xy 248.52497 -72.05127) (xy 248.498196 -72.036784)
			(xy 248.468343 -72.030828) (xy 248.453148 -72.03186) (xy 248.415048 -72.033892) (xy 248.387679 -72.033417)
			(xy 248.333505 -72.025586) (xy 248.281006 -72.010093) (xy 248.23126 -71.987256) (xy 248.185289 -71.957543)
			(xy 248.16435 -71.939912) (xy 248.153022 -71.930676) (xy 248.126465 -71.9185) (xy 248.097548 -71.914327)
			(xy 248.068631 -71.9185) (xy 248.042074 -71.930676) (xy 248.030746 -71.939912) (xy 248.009813 -71.95755)
			(xy 247.963845 -71.987269) (xy 247.914098 -72.010104) (xy 247.861595 -72.025587) (xy 247.807417 -72.033397)
			(xy 247.780048 -72.033892) (xy 247.752793 -72.033432) (xy 247.698838 -72.02568) (xy 247.646535 -72.010328)
			(xy 247.59695 -71.987688) (xy 247.551092 -71.958221) (xy 247.509895 -71.922528) (xy 247.474198 -71.881333)
			(xy 247.444727 -71.835478) (xy 247.422083 -71.785895) (xy 247.406726 -71.733593) (xy 247.39897 -71.679639)
			(xy 247.39854 -71.652384) (xy 247.398987 -71.625711) (xy 247.406423 -71.572887) (xy 247.421149 -71.521615)
			(xy 247.442876 -71.472895) (xy 247.471181 -71.427679) (xy 247.505511 -71.386848) (xy 247.525032 -71.368666)
			(xy 247.535328 -71.358795) (xy 247.55047 -71.334639) (xy 247.558345 -71.307238) (xy 247.55834 -71.278728)
			(xy 247.550455 -71.25133) (xy 247.535305 -71.227178) (xy 247.525032 -71.217282) (xy 247.505496 -71.199118)
			(xy 247.471183 -71.158275) (xy 247.442893 -71.113052) (xy 247.421175 -71.06433) (xy 247.406454 -71.013058)
			(xy 247.399017 -70.960236) (xy 247.39854 -70.933564) (xy 247.399006 -70.906314) (xy 247.406767 -70.85237)
			(xy 247.422127 -70.800079) (xy 247.444772 -70.750506) (xy 247.474242 -70.704661) (xy 247.509936 -70.663477)
			(xy 247.551128 -70.627791) (xy 247.59698 -70.598332) (xy 247.646558 -70.575697) (xy 247.698852 -70.560349)
			(xy 247.752798 -70.5526) (xy 247.780048 -70.552056) (xy 247.807417 -70.552531) (xy 247.861591 -70.560362)
			(xy 247.914089 -70.575856) (xy 247.963834 -70.598695) (xy 248.009803 -70.628411) (xy 248.030746 -70.646036)
			(xy 248.042074 -70.655272) (xy 248.068631 -70.667448) (xy 248.097548 -70.671621) (xy 248.126465 -70.667448)
			(xy 248.153022 -70.655272) (xy 248.16435 -70.646036) (xy 248.173578 -70.638071) (xy 248.192896 -70.623199)
			(xy 248.202958 -70.616318) (xy 248.225564 -70.574154) (xy 248.202958 -70.53199) (xy 248.180968 -70.516731)
			(xy 248.14108 -70.481041) (xy 248.106567 -70.44013) (xy 248.078108 -70.3948) (xy 248.056258 -70.345938)
			(xy 248.041447 -70.294504) (xy 248.033966 -70.241506) (xy 248.03354 -70.214744) (xy 248.03354 -70.214236)
			(xy 248.033924 -70.190356) (xy 248.039907 -70.142972) (xy 248.045478 -70.119748) (xy 248.04881 -70.104639)
			(xy 248.047217 -70.073754) (xy 248.036461 -70.044758) (xy 248.017527 -70.020306) (xy 247.992146 -70.002636)
			(xy 247.962643 -69.993364) (xy 247.94718 -69.992748) (xy 246.89308 -69.992748) (xy 246.61368 -70.272148)
			(xy 246.61368 -75.377548) (xy 247.042288 -75.806156) (xy 274.987923 -75.806156) (xy 274.987923 -75.751644)
			(xy 274.995681 -75.697687) (xy 275.011039 -75.645383) (xy 275.033685 -75.595797) (xy 275.063158 -75.549939)
			(xy 275.098857 -75.508742) (xy 275.140055 -75.473046) (xy 275.185915 -75.443576) (xy 275.235502 -75.420932)
			(xy 275.287806 -75.405577) (xy 275.341764 -75.397822) (xy 275.36902 -75.39736) (xy 275.396391 -75.3978)
			(xy 275.450572 -75.405622) (xy 275.503076 -75.421116) (xy 275.552823 -75.443964) (xy 275.598788 -75.473695)
			(xy 275.619718 -75.49134) (xy 275.631046 -75.500576) (xy 275.657603 -75.512752) (xy 275.68652 -75.516925)
			(xy 275.715437 -75.512752) (xy 275.741994 -75.500576) (xy 275.753322 -75.49134) (xy 275.774255 -75.473699)
			(xy 275.820223 -75.443975) (xy 275.869969 -75.421129) (xy 275.922471 -75.405633) (xy 275.976649 -75.397804)
			(xy 276.031391 -75.397804) (xy 276.085569 -75.405633) (xy 276.138071 -75.421129) (xy 276.187817 -75.443975)
			(xy 276.233785 -75.473699) (xy 276.254718 -75.49134) (xy 276.266046 -75.500576) (xy 276.292603 -75.512752)
			(xy 276.32152 -75.516925) (xy 276.350437 -75.512752) (xy 276.376994 -75.500576) (xy 276.388322 -75.49134)
			(xy 276.409255 -75.473699) (xy 276.455223 -75.443975) (xy 276.504969 -75.421129) (xy 276.557471 -75.405633)
			(xy 276.611649 -75.397804) (xy 276.666391 -75.397804) (xy 276.720569 -75.405633) (xy 276.773071 -75.421129)
			(xy 276.822817 -75.443975) (xy 276.868785 -75.473699) (xy 276.889718 -75.49134) (xy 276.901046 -75.500576)
			(xy 276.927603 -75.512752) (xy 276.95652 -75.516925) (xy 276.985437 -75.512752) (xy 277.011994 -75.500576)
			(xy 277.023322 -75.49134) (xy 277.044255 -75.473699) (xy 277.090223 -75.443975) (xy 277.139969 -75.421129)
			(xy 277.192471 -75.405633) (xy 277.246649 -75.397804) (xy 277.301391 -75.397804) (xy 277.355569 -75.405633)
			(xy 277.408071 -75.421129) (xy 277.457817 -75.443975) (xy 277.503785 -75.473699) (xy 277.524718 -75.49134)
			(xy 277.536046 -75.500576) (xy 277.562603 -75.512752) (xy 277.59152 -75.516925) (xy 277.620437 -75.512752)
			(xy 277.646994 -75.500576) (xy 277.658322 -75.49134) (xy 277.679278 -75.47373) (xy 277.725243 -75.444013)
			(xy 277.774985 -75.42117) (xy 277.827481 -75.405673) (xy 277.881652 -75.397837) (xy 277.90902 -75.39736)
			(xy 277.936268 -75.397912) (xy 277.990209 -75.40567) (xy 278.042497 -75.421025) (xy 278.092067 -75.443666)
			(xy 278.137911 -75.47313) (xy 278.179096 -75.508818) (xy 278.214782 -75.550005) (xy 278.244244 -75.59585)
			(xy 278.266882 -75.645422) (xy 278.282235 -75.697711) (xy 278.28999 -75.751652) (xy 278.28999 -75.806148)
			(xy 278.282235 -75.860089) (xy 278.266882 -75.912378) (xy 278.244244 -75.96195) (xy 278.214782 -76.007795)
			(xy 278.179096 -76.048982) (xy 278.137911 -76.08467) (xy 278.092067 -76.114134) (xy 278.042497 -76.136775)
			(xy 277.990209 -76.15213) (xy 277.936268 -76.159888) (xy 277.90902 -76.160376) (xy 277.88165 -76.159904)
			(xy 277.827471 -76.152089) (xy 277.774968 -76.136601) (xy 277.725221 -76.113761) (xy 277.679254 -76.084037)
			(xy 277.658322 -76.066396) (xy 277.646994 -76.05716) (xy 277.620437 -76.044984) (xy 277.59152 -76.040811)
			(xy 277.562603 -76.044984) (xy 277.536046 -76.05716) (xy 277.524718 -76.066396) (xy 277.503785 -76.084037)
			(xy 277.457817 -76.113761) (xy 277.408071 -76.136607) (xy 277.355569 -76.152103) (xy 277.301391 -76.159932)
			(xy 277.246649 -76.159932) (xy 277.192471 -76.152103) (xy 277.139969 -76.136607) (xy 277.090223 -76.113761)
			(xy 277.044255 -76.084037) (xy 277.023322 -76.066396) (xy 277.011994 -76.05716) (xy 276.985437 -76.044984)
			(xy 276.95652 -76.040811) (xy 276.927603 -76.044984) (xy 276.901046 -76.05716) (xy 276.889718 -76.066396)
			(xy 276.868785 -76.084037) (xy 276.822817 -76.113761) (xy 276.773071 -76.136607) (xy 276.720569 -76.152103)
			(xy 276.666391 -76.159932) (xy 276.611649 -76.159932) (xy 276.557471 -76.152103) (xy 276.504969 -76.136607)
			(xy 276.455223 -76.113761) (xy 276.409255 -76.084037) (xy 276.388322 -76.066396) (xy 276.376994 -76.05716)
			(xy 276.350437 -76.044984) (xy 276.32152 -76.040811) (xy 276.292603 -76.044984) (xy 276.266046 -76.05716)
			(xy 276.254718 -76.066396) (xy 276.233785 -76.084037) (xy 276.187817 -76.113761) (xy 276.138071 -76.136607)
			(xy 276.085569 -76.152103) (xy 276.031391 -76.159932) (xy 275.976649 -76.159932) (xy 275.922471 -76.152103)
			(xy 275.869969 -76.136607) (xy 275.820223 -76.113761) (xy 275.774255 -76.084037) (xy 275.753322 -76.066396)
			(xy 275.741994 -76.05716) (xy 275.715437 -76.044984) (xy 275.68652 -76.040811) (xy 275.657603 -76.044984)
			(xy 275.631046 -76.05716) (xy 275.619718 -76.066396) (xy 275.598789 -76.084039) (xy 275.552816 -76.113751)
			(xy 275.503067 -76.136586) (xy 275.450566 -76.152076) (xy 275.396389 -76.159903) (xy 275.36902 -76.160376)
			(xy 275.341764 -76.159978) (xy 275.287806 -76.152223) (xy 275.235502 -76.136868) (xy 275.185915 -76.114224)
			(xy 275.140055 -76.084754) (xy 275.098857 -76.049058) (xy 275.063158 -76.007861) (xy 275.033685 -75.962003)
			(xy 275.011039 -75.912417) (xy 274.995681 -75.860113) (xy 274.987923 -75.806156) (xy 247.042288 -75.806156)
			(xy 248.16308 -76.926948) (xy 257.560062 -76.926948) (xy 257.564133 -76.871326) (xy 257.576259 -76.816889)
			(xy 257.596182 -76.764798) (xy 257.623478 -76.716163) (xy 257.657564 -76.67202) (xy 257.697713 -76.633311)
			(xy 257.743071 -76.60086) (xy 257.792671 -76.575359) (xy 257.845455 -76.557352) (xy 257.900298 -76.547222)
			(xy 257.956032 -76.545185) (xy 258.011469 -76.551285) (xy 258.065426 -76.565391) (xy 258.116755 -76.587203)
			(xy 258.164361 -76.616257) (xy 258.207229 -76.651932) (xy 258.244446 -76.693469) (xy 258.275219 -76.739982)
			(xy 258.298891 -76.790479) (xy 258.314959 -76.843886) (xy 258.323079 -76.899062) (xy 258.323588 -76.926948)
			(xy 258.323079 -76.954834) (xy 258.314959 -77.01001) (xy 258.298891 -77.063417) (xy 258.275219 -77.113914)
			(xy 258.244446 -77.160427) (xy 258.207229 -77.201964) (xy 258.164361 -77.237639) (xy 258.116755 -77.266693)
			(xy 258.065426 -77.288505) (xy 258.011469 -77.302611) (xy 257.956032 -77.308711) (xy 257.900298 -77.306674)
			(xy 257.845455 -77.296544) (xy 257.792671 -77.278537) (xy 257.743071 -77.253036) (xy 257.697713 -77.220585)
			(xy 257.657564 -77.181876) (xy 257.623478 -77.137733) (xy 257.596182 -77.089098) (xy 257.576259 -77.037007)
			(xy 257.564133 -76.98257) (xy 257.560062 -76.926948) (xy 248.16308 -76.926948) (xy 249.313954 -78.077822)
			(xy 262.833104 -78.077822) (xy 262.833509 -78.051441) (xy 262.840772 -77.999182) (xy 262.855163 -77.948421)
			(xy 262.876408 -77.900125) (xy 262.904101 -77.855216) (xy 262.937715 -77.814548) (xy 262.97661 -77.778897)
			(xy 263.020043 -77.748942) (xy 263.043416 -77.7367) (xy 263.05576 -77.72997) (xy 263.076497 -77.711003)
			(xy 263.091265 -77.687094) (xy 263.098943 -77.660061) (xy 263.098945 -77.631959) (xy 263.091273 -77.604924)
			(xy 263.076509 -77.581012) (xy 263.055777 -77.562042) (xy 263.043416 -77.555344) (xy 263.020059 -77.543078)
			(xy 262.976634 -77.513121) (xy 262.937747 -77.477469) (xy 262.90414 -77.436803) (xy 262.876451 -77.391898)
			(xy 262.855209 -77.343608) (xy 262.840817 -77.292853) (xy 262.833551 -77.2406) (xy 262.833104 -77.214222)
			(xy 262.83359 -77.186971) (xy 262.841346 -77.133023) (xy 262.856701 -77.080728) (xy 262.879343 -77.031151)
			(xy 262.908809 -76.985301) (xy 262.9445 -76.94411) (xy 262.985691 -76.908419) (xy 263.031541 -76.878953)
			(xy 263.081118 -76.856311) (xy 263.133413 -76.840956) (xy 263.187361 -76.8332) (xy 263.241863 -76.8332)
			(xy 263.295811 -76.840956) (xy 263.348106 -76.856311) (xy 263.397683 -76.878953) (xy 263.443533 -76.908419)
			(xy 263.484724 -76.94411) (xy 263.520415 -76.985301) (xy 263.549881 -77.031151) (xy 263.572523 -77.080728)
			(xy 263.587878 -77.133023) (xy 263.595634 -77.186971) (xy 263.59612 -77.214222) (xy 263.595656 -77.240601)
			(xy 263.588401 -77.292857) (xy 263.574018 -77.343616) (xy 263.552782 -77.39191) (xy 263.525097 -77.43682)
			(xy 263.491491 -77.477489) (xy 263.452604 -77.513142) (xy 263.409177 -77.5431) (xy 263.385808 -77.555344)
			(xy 263.373433 -77.562015) (xy 263.352707 -77.580998) (xy 263.337949 -77.604918) (xy 263.330281 -77.631957)
			(xy 263.330283 -77.660063) (xy 263.337957 -77.6871) (xy 263.352719 -77.711017) (xy 263.373449 -77.729996)
			(xy 263.385808 -77.7367) (xy 263.409189 -77.748922) (xy 263.452614 -77.778887) (xy 263.491499 -77.814545)
			(xy 263.525104 -77.855217) (xy 263.55279 -77.900129) (xy 263.574029 -77.948425) (xy 263.588415 -77.999185)
			(xy 263.595676 -78.051442) (xy 263.59612 -78.077822) (xy 263.595634 -78.105073) (xy 263.587878 -78.159021)
			(xy 263.572523 -78.211316) (xy 263.549881 -78.260893) (xy 263.520415 -78.306743) (xy 263.484724 -78.347934)
			(xy 263.443533 -78.383625) (xy 263.397683 -78.413091) (xy 263.348106 -78.435733) (xy 263.295811 -78.451088)
			(xy 263.241863 -78.458844) (xy 263.187361 -78.458844) (xy 263.133413 -78.451088) (xy 263.081118 -78.435733)
			(xy 263.031541 -78.413091) (xy 262.985691 -78.383625) (xy 262.9445 -78.347934) (xy 262.908809 -78.306743)
			(xy 262.879343 -78.260893) (xy 262.856701 -78.211316) (xy 262.841346 -78.159021) (xy 262.83359 -78.105073)
			(xy 262.833104 -78.077822) (xy 249.313954 -78.077822) (xy 250.21413 -78.977998) (xy 258.880862 -78.977998)
			(xy 258.884933 -78.922376) (xy 258.897059 -78.867939) (xy 258.916982 -78.815848) (xy 258.944278 -78.767213)
			(xy 258.978364 -78.72307) (xy 259.018513 -78.684361) (xy 259.063871 -78.65191) (xy 259.113471 -78.626409)
			(xy 259.166255 -78.608402) (xy 259.221098 -78.598272) (xy 259.276832 -78.596235) (xy 259.332269 -78.602335)
			(xy 259.386226 -78.616441) (xy 259.437555 -78.638253) (xy 259.485161 -78.667307) (xy 259.528029 -78.702982)
			(xy 259.565246 -78.744519) (xy 259.596019 -78.791032) (xy 259.619691 -78.841529) (xy 259.635759 -78.894936)
			(xy 259.643879 -78.950112) (xy 259.644388 -78.977998) (xy 259.643879 -79.005884) (xy 259.635759 -79.06106)
			(xy 259.619691 -79.114467) (xy 259.596019 -79.164964) (xy 259.565246 -79.211477) (xy 259.528029 -79.253014)
			(xy 259.485161 -79.288689) (xy 259.437555 -79.317743) (xy 259.386226 -79.339555) (xy 259.332269 -79.353661)
			(xy 259.276832 -79.359761) (xy 259.221098 -79.357724) (xy 259.166255 -79.347594) (xy 259.113471 -79.329587)
			(xy 259.063871 -79.304086) (xy 259.018513 -79.271635) (xy 258.978364 -79.232926) (xy 258.944278 -79.188783)
			(xy 258.916982 -79.140148) (xy 258.897059 -79.088057) (xy 258.884933 -79.03362) (xy 258.880862 -78.977998)
			(xy 250.21413 -78.977998) (xy 250.77928 -79.543148) (xy 277.67534 -79.543148)
		)
		(stroke
			(width 0)
			(type solid)
		)
		(fill yes)
		(layer "In15.Cu")
		(net "GND")
	)
	(gr_poly
		(pts
			(xy 436.78475 -34.635948) (xy 436.798648 -34.635469) (xy 436.825412 -34.62796) (xy 436.849159 -34.613513)
			(xy 436.868131 -34.593198) (xy 436.880923 -34.568519) (xy 436.886586 -34.541305) (xy 436.8847 -34.513572)
			(xy 436.880508 -34.500312) (xy 436.870296 -34.469496) (xy 436.859313 -34.405516) (xy 436.858664 -34.373058)
			(xy 436.85915 -34.345807) (xy 436.866906 -34.291859) (xy 436.882261 -34.239564) (xy 436.904903 -34.189987)
			(xy 436.934369 -34.144137) (xy 436.97006 -34.102946) (xy 437.011251 -34.067255) (xy 437.057101 -34.037789)
			(xy 437.106678 -34.015147) (xy 437.158973 -33.999792) (xy 437.212921 -33.992036) (xy 437.267423 -33.992036)
			(xy 437.321371 -33.999792) (xy 437.373666 -34.015147) (xy 437.423243 -34.037789) (xy 437.469093 -34.067255)
			(xy 437.510284 -34.102946) (xy 437.545975 -34.144137) (xy 437.575441 -34.189987) (xy 437.598083 -34.239564)
			(xy 437.613438 -34.291859) (xy 437.621194 -34.345807) (xy 437.62168 -34.373058) (xy 437.621024 -34.405515)
			(xy 437.610035 -34.469492) (xy 437.599836 -34.500312) (xy 437.595574 -34.513566) (xy 437.593663 -34.541332)
			(xy 437.599315 -34.568583) (xy 437.612112 -34.593298) (xy 437.631103 -34.613643) (xy 437.65488 -34.628108)
			(xy 437.681678 -34.63562) (xy 437.695594 -34.635948) (xy 452.1835 -34.635948) (xy 453.56272 -33.256728)
			(xy 453.56272 -29.331158) (xy 453.562283 -29.317231) (xy 453.554746 -29.290414) (xy 453.540245 -29.266631)
			(xy 453.519858 -29.24765) (xy 453.495101 -29.234883) (xy 453.467816 -29.229279) (xy 453.440031 -29.231254)
			(xy 453.413813 -29.240663) (xy 453.402192 -29.248354) (xy 453.377843 -29.264982) (xy 453.325104 -29.291342)
			(xy 453.268943 -29.309293) (xy 453.210691 -29.318408) (xy 453.181212 -29.318966) (xy 453.15396 -29.318503)
			(xy 453.10001 -29.310748) (xy 453.047713 -29.295392) (xy 452.998134 -29.27275) (xy 452.952282 -29.243281)
			(xy 452.911092 -29.207587) (xy 452.875401 -29.166394) (xy 452.845936 -29.12054) (xy 452.823297 -29.070959)
			(xy 452.807946 -29.018661) (xy 452.800194 -28.96471) (xy 452.799704 -28.937458) (xy 452.800122 -28.911137)
			(xy 452.807317 -28.858991) (xy 452.821617 -28.808331) (xy 452.842753 -28.76012) (xy 452.870321 -28.715275)
			(xy 452.903797 -28.674651) (xy 452.922894 -28.656534) (xy 452.932909 -28.646722) (xy 452.947596 -28.622853)
			(xy 452.955224 -28.595885) (xy 452.955216 -28.567859) (xy 452.947573 -28.540895) (xy 452.932872 -28.517034)
			(xy 452.922894 -28.507182) (xy 452.903832 -28.489033) (xy 452.870375 -28.448402) (xy 452.842816 -28.40356)
			(xy 452.821678 -28.355358) (xy 452.807361 -28.30471) (xy 452.800137 -28.252575) (xy 452.799704 -28.226258)
			(xy 452.800187 -28.198682) (xy 452.808122 -28.144105) (xy 452.823835 -28.09124) (xy 452.846999 -28.04119)
			(xy 452.877131 -27.994997) (xy 452.913601 -27.953626) (xy 452.934324 -27.935428) (xy 452.945213 -27.925528)
			(xy 452.961269 -27.900881) (xy 452.96964 -27.872681) (xy 452.969632 -27.843265) (xy 452.961246 -27.81507)
			(xy 452.945176 -27.790431) (xy 452.934324 -27.780488) (xy 452.913619 -27.762271) (xy 452.877156 -27.720899)
			(xy 452.847028 -27.674709) (xy 452.823863 -27.624663) (xy 452.808144 -27.571803) (xy 452.800197 -27.517232)
			(xy 452.799704 -27.489658) (xy 452.800193 -27.462409) (xy 452.807955 -27.408467) (xy 452.823313 -27.356178)
			(xy 452.845957 -27.306607) (xy 452.875425 -27.260762) (xy 452.911116 -27.219578) (xy 452.952306 -27.183892)
			(xy 452.998154 -27.154431) (xy 453.047728 -27.131795) (xy 453.100019 -27.116443) (xy 453.153963 -27.108689)
			(xy 453.181212 -27.10815) (xy 453.210694 -27.108696) (xy 453.268955 -27.117775) (xy 453.325119 -27.135729)
			(xy 453.377843 -27.162129) (xy 453.402192 -27.178762) (xy 453.413792 -27.186488) (xy 453.440014 -27.195908)
			(xy 453.467806 -27.197888) (xy 453.495099 -27.192282) (xy 453.51986 -27.179507) (xy 453.540246 -27.160514)
			(xy 453.554739 -27.136718) (xy 453.562259 -27.109889) (xy 453.56272 -27.095958) (xy 453.56272 -19.793966)
			(xy 453.562282 -19.780027) (xy 453.554735 -19.753188) (xy 453.540212 -19.72939) (xy 453.519795 -19.710406)
			(xy 453.495006 -19.697649) (xy 453.46769 -19.69207) (xy 453.453754 -19.69262) (xy 453.426068 -19.693636)
			(xy 453.398816 -19.693148) (xy 453.344868 -19.685387) (xy 453.292573 -19.670028) (xy 453.242996 -19.647384)
			(xy 453.197147 -19.617914) (xy 453.155957 -19.58222) (xy 453.120267 -19.541028) (xy 453.090801 -19.495175)
			(xy 453.068161 -19.445597) (xy 453.052806 -19.393301) (xy 453.04505 -19.339352) (xy 453.04505 -19.284848)
			(xy 453.052806 -19.230899) (xy 453.068161 -19.178603) (xy 453.090801 -19.129025) (xy 453.120267 -19.083172)
			(xy 453.155957 -19.04198) (xy 453.197147 -19.006286) (xy 453.242996 -18.976816) (xy 453.292573 -18.954172)
			(xy 453.344868 -18.938813) (xy 453.398816 -18.931052) (xy 453.426068 -18.93062) (xy 453.453754 -18.931636)
			(xy 453.46769 -18.932212) (xy 453.495008 -18.926631) (xy 453.519798 -18.91387) (xy 453.540213 -18.894879)
			(xy 453.554731 -18.871075) (xy 453.56227 -18.844231) (xy 453.56272 -18.83029) (xy 453.56272 -13.741908)
			(xy 453.24776 -13.426948) (xy 452.9455 -13.426948) (xy 452.93117 -13.427435) (xy 452.903638 -13.435395)
			(xy 452.8794 -13.450687) (xy 452.860362 -13.47211) (xy 452.848023 -13.497977) (xy 452.843352 -13.526253)
			(xy 452.846719 -13.554714) (xy 452.857857 -13.581121) (xy 452.866506 -13.592556) (xy 452.882614 -13.613058)
			(xy 452.909707 -13.657604) (xy 452.930483 -13.705424) (xy 452.944555 -13.755627) (xy 452.951661 -13.807279)
			(xy 452.952104 -13.833348) (xy 452.951618 -13.860599) (xy 452.943862 -13.914547) (xy 452.928507 -13.966842)
			(xy 452.905865 -14.016419) (xy 452.876399 -14.062269) (xy 452.840708 -14.10346) (xy 452.799517 -14.139151)
			(xy 452.753667 -14.168617) (xy 452.70409 -14.191259) (xy 452.651795 -14.206614) (xy 452.597847 -14.21437)
			(xy 452.543345 -14.21437) (xy 452.489397 -14.206614) (xy 452.437102 -14.191259) (xy 452.387525 -14.168617)
			(xy 452.341675 -14.139151) (xy 452.300484 -14.10346) (xy 452.264793 -14.062269) (xy 452.235327 -14.016419)
			(xy 452.212685 -13.966842) (xy 452.19733 -13.914547) (xy 452.189574 -13.860599) (xy 452.189088 -13.833348)
			(xy 452.18951 -13.807277) (xy 452.196607 -13.755619) (xy 452.210674 -13.70541) (xy 452.23145 -13.657585)
			(xy 452.258548 -13.613036) (xy 452.274686 -13.592556) (xy 452.283329 -13.581119) (xy 452.294477 -13.554723)
			(xy 452.29785 -13.526268) (xy 452.293181 -13.497997) (xy 452.280839 -13.472138) (xy 452.261796 -13.450727)
			(xy 452.237553 -13.435453) (xy 452.21002 -13.427518) (xy 452.195692 -13.426948) (xy 451.761352 -13.426948)
			(xy 451.74669 -13.42744) (xy 451.718577 -13.435786) (xy 451.693996 -13.451778) (xy 451.674972 -13.474096)
			(xy 451.663075 -13.500899) (xy 451.659285 -13.529979) (xy 451.661022 -13.54455) (xy 451.66327 -13.559498)
			(xy 451.665684 -13.589633) (xy 451.665848 -13.604748) (xy 451.665362 -13.631999) (xy 451.657606 -13.685947)
			(xy 451.642251 -13.738242) (xy 451.619609 -13.787819) (xy 451.590143 -13.833669) (xy 451.554452 -13.87486)
			(xy 451.513261 -13.910551) (xy 451.467411 -13.940017) (xy 451.417834 -13.962659) (xy 451.365539 -13.978014)
			(xy 451.311591 -13.98577) (xy 451.257089 -13.98577) (xy 451.203141 -13.978014) (xy 451.150846 -13.962659)
			(xy 451.101269 -13.940017) (xy 451.055419 -13.910551) (xy 451.014228 -13.87486) (xy 450.978537 -13.833669)
			(xy 450.949071 -13.787819) (xy 450.926429 -13.738242) (xy 450.911074 -13.685947) (xy 450.903318 -13.631999)
			(xy 450.902832 -13.604748) (xy 450.902992 -13.589633) (xy 450.90541 -13.559498) (xy 450.907658 -13.54455)
			(xy 450.909497 -13.529981) (xy 450.905703 -13.500875) (xy 450.893794 -13.474047) (xy 450.87475 -13.45171)
			(xy 450.850144 -13.435706) (xy 450.822004 -13.427356) (xy 450.807328 -13.426948) (xy 450.501766 -13.426948)
			(xy 450.486555 -13.427504) (xy 450.457477 -13.436446) (xy 450.432324 -13.453556) (xy 450.413326 -13.477317)
			(xy 450.402171 -13.505619) (xy 450.399847 -13.535952) (xy 450.402706 -13.5509) (xy 450.407104 -13.571704)
			(xy 450.41181 -13.613966) (xy 450.412104 -13.635228) (xy 450.411618 -13.662479) (xy 450.403862 -13.716427)
			(xy 450.388507 -13.768722) (xy 450.365865 -13.818299) (xy 450.336399 -13.864149) (xy 450.300708 -13.90534)
			(xy 450.259517 -13.941031) (xy 450.213667 -13.970497) (xy 450.16409 -13.993139) (xy 450.111795 -14.008494)
			(xy 450.057847 -14.01625) (xy 450.003345 -14.01625) (xy 449.949397 -14.008494) (xy 449.897102 -13.993139)
			(xy 449.847525 -13.970497) (xy 449.801675 -13.941031) (xy 449.760484 -13.90534) (xy 449.724793 -13.864149)
			(xy 449.695327 -13.818299) (xy 449.672685 -13.768722) (xy 449.65733 -13.716427) (xy 449.649574 -13.662479)
			(xy 449.649088 -13.635228) (xy 449.649365 -13.613965) (xy 449.654076 -13.571702) (xy 449.658486 -13.5509)
			(xy 449.661273 -13.535952) (xy 449.658927 -13.505652) (xy 449.647769 -13.477384) (xy 449.628788 -13.45365)
			(xy 449.603664 -13.436552) (xy 449.574621 -13.427603) (xy 449.559426 -13.426948) (xy 449.35648 -13.426948)
			(xy 449.342803 -13.427383) (xy 449.31643 -13.434644) (xy 449.292942 -13.448663) (xy 449.274032 -13.468428)
			(xy 449.261067 -13.492514) (xy 449.254981 -13.519182) (xy 449.255134 -13.532866) (xy 449.255388 -13.548868)
			(xy 449.254902 -13.576119) (xy 449.247146 -13.630067) (xy 449.231791 -13.682362) (xy 449.209149 -13.731939)
			(xy 449.179683 -13.777789) (xy 449.143992 -13.81898) (xy 449.102801 -13.854671) (xy 449.056951 -13.884137)
			(xy 449.007374 -13.906779) (xy 448.955079 -13.922134) (xy 448.901131 -13.92989) (xy 448.846629 -13.92989)
			(xy 448.792681 -13.922134) (xy 448.740386 -13.906779) (xy 448.690809 -13.884137) (xy 448.644959 -13.854671)
			(xy 448.603768 -13.81898) (xy 448.568077 -13.777789) (xy 448.538611 -13.731939) (xy 448.515969 -13.682362)
			(xy 448.500614 -13.630067) (xy 448.492858 -13.576119) (xy 448.492372 -13.548868) (xy 448.492626 -13.532866)
			(xy 448.492759 -13.51919) (xy 448.486623 -13.492548) (xy 448.473643 -13.468486) (xy 448.454748 -13.448727)
			(xy 448.43129 -13.434684) (xy 448.404949 -13.427363) (xy 448.39128 -13.426948) (xy 448.21856 -13.426948)
			(xy 448.205242 -13.427349) (xy 448.179516 -13.434253) (xy 448.156454 -13.447581) (xy 448.137627 -13.466424)
			(xy 448.124319 -13.489498) (xy 448.117437 -13.51523) (xy 448.11696 -13.528548) (xy 448.116474 -13.555799)
			(xy 448.108718 -13.609747) (xy 448.093363 -13.662042) (xy 448.070721 -13.711619) (xy 448.041255 -13.757469)
			(xy 448.005564 -13.79866) (xy 447.964373 -13.834351) (xy 447.918523 -13.863817) (xy 447.868946 -13.886459)
			(xy 447.816651 -13.901814) (xy 447.762703 -13.90957) (xy 447.708201 -13.90957) (xy 447.654253 -13.901814)
			(xy 447.601958 -13.886459) (xy 447.552381 -13.863817) (xy 447.506531 -13.834351) (xy 447.46534 -13.79866)
			(xy 447.429649 -13.757469) (xy 447.400183 -13.711619) (xy 447.377541 -13.662042) (xy 447.362186 -13.609747)
			(xy 447.35443 -13.555799) (xy 447.353944 -13.528548) (xy 447.353555 -13.515218) (xy 447.346667 -13.489463)
			(xy 447.333347 -13.466369) (xy 447.314504 -13.447509) (xy 447.291422 -13.434169) (xy 447.265674 -13.427257)
			(xy 447.252344 -13.426948) (xy 445.71412 -13.426948) (xy 445.11468 -14.026388) (xy 445.11468 -15.998698)
			(xy 450.297804 -15.998698) (xy 450.298267 -15.971123) (xy 450.30622 -15.91655) (xy 450.321945 -15.86369)
			(xy 450.345116 -15.813644) (xy 450.375249 -15.767455) (xy 450.411717 -15.726084) (xy 450.432424 -15.707868)
			(xy 450.443321 -15.69797) (xy 450.459389 -15.673319) (xy 450.46777 -15.645112) (xy 450.467769 -15.615686)
			(xy 450.459388 -15.587479) (xy 450.443319 -15.562828) (xy 450.432424 -15.552928) (xy 450.411728 -15.5347)
			(xy 450.375256 -15.493336) (xy 450.345121 -15.447149) (xy 450.321952 -15.397105) (xy 450.306233 -15.344245)
			(xy 450.298291 -15.289672) (xy 450.297804 -15.262098) (xy 450.29829 -15.234847) (xy 450.306046 -15.180899)
			(xy 450.321401 -15.128604) (xy 450.344043 -15.079027) (xy 450.373509 -15.033177) (xy 450.4092 -14.991986)
			(xy 450.450391 -14.956295) (xy 450.496241 -14.926829) (xy 450.545818 -14.904187) (xy 450.598113 -14.888832)
			(xy 450.652061 -14.881076) (xy 450.706563 -14.881076) (xy 450.760511 -14.888832) (xy 450.812806 -14.904187)
			(xy 450.862383 -14.926829) (xy 450.908233 -14.956295) (xy 450.949424 -14.991986) (xy 450.985115 -15.033177)
			(xy 451.014581 -15.079027) (xy 451.037223 -15.128604) (xy 451.052578 -15.180899) (xy 451.060334 -15.234847)
			(xy 451.06082 -15.262098) (xy 451.060346 -15.289672) (xy 451.052394 -15.344244) (xy 451.03667 -15.397104)
			(xy 451.013502 -15.44715) (xy 450.983371 -15.493339) (xy 450.946906 -15.534711) (xy 450.9262 -15.552928)
			(xy 450.915305 -15.562829) (xy 450.899233 -15.587479) (xy 450.890849 -15.615685) (xy 450.890849 -15.645112)
			(xy 450.899232 -15.673319) (xy 450.915304 -15.697969) (xy 450.9262 -15.707868) (xy 450.946899 -15.726092)
			(xy 450.98337 -15.767458) (xy 451.013504 -15.813646) (xy 451.036672 -15.863691) (xy 451.052391 -15.916551)
			(xy 451.060333 -15.971124) (xy 451.06082 -15.998698) (xy 451.060334 -16.025949) (xy 451.052578 -16.079897)
			(xy 451.037223 -16.132192) (xy 451.014581 -16.181769) (xy 450.985115 -16.227619) (xy 450.949424 -16.26881)
			(xy 450.908233 -16.304501) (xy 450.862383 -16.333967) (xy 450.812806 -16.356609) (xy 450.760511 -16.371964)
			(xy 450.706563 -16.37972) (xy 450.652061 -16.37972) (xy 450.598113 -16.371964) (xy 450.545818 -16.356609)
			(xy 450.496241 -16.333967) (xy 450.450391 -16.304501) (xy 450.4092 -16.26881) (xy 450.373509 -16.227619)
			(xy 450.344043 -16.181769) (xy 450.321401 -16.132192) (xy 450.306046 -16.079897) (xy 450.29829 -16.025949)
			(xy 450.297804 -15.998698) (xy 445.11468 -15.998698) (xy 445.11468 -18.446242) (xy 446.165984 -18.446242)
			(xy 446.170055 -18.39062) (xy 446.182181 -18.336183) (xy 446.202104 -18.284092) (xy 446.2294 -18.235457)
			(xy 446.263486 -18.191314) (xy 446.303635 -18.152605) (xy 446.348993 -18.120154) (xy 446.398593 -18.094653)
			(xy 446.451377 -18.076646) (xy 446.50622 -18.066516) (xy 446.561954 -18.064479) (xy 446.617391 -18.070579)
			(xy 446.671348 -18.084685) (xy 446.722677 -18.106497) (xy 446.770283 -18.135551) (xy 446.813151 -18.171226)
			(xy 446.850368 -18.212763) (xy 446.881141 -18.259276) (xy 446.904813 -18.309773) (xy 446.920881 -18.36318)
			(xy 446.929001 -18.418356) (xy 446.92951 -18.446242) (xy 446.929195 -18.463514) (xy 449.291454 -18.463514)
			(xy 449.295525 -18.407892) (xy 449.307651 -18.353455) (xy 449.327574 -18.301364) (xy 449.35487 -18.252729)
			(xy 449.388956 -18.208586) (xy 449.429105 -18.169877) (xy 449.474463 -18.137426) (xy 449.524063 -18.111925)
			(xy 449.576847 -18.093918) (xy 449.63169 -18.083788) (xy 449.687424 -18.081751) (xy 449.742861 -18.087851)
			(xy 449.796818 -18.101957) (xy 449.848147 -18.123769) (xy 449.895753 -18.152823) (xy 449.938621 -18.188498)
			(xy 449.975838 -18.230035) (xy 450.006611 -18.276548) (xy 450.030283 -18.327045) (xy 450.046351 -18.380452)
			(xy 450.054471 -18.435628) (xy 450.05498 -18.463514) (xy 450.054471 -18.4914) (xy 450.046351 -18.546576)
			(xy 450.030283 -18.599983) (xy 450.018171 -18.62582) (xy 450.615302 -18.62582) (xy 450.619373 -18.570198)
			(xy 450.631499 -18.515761) (xy 450.651422 -18.46367) (xy 450.678718 -18.415035) (xy 450.712804 -18.370892)
			(xy 450.752953 -18.332183) (xy 450.798311 -18.299732) (xy 450.847911 -18.274231) (xy 450.900695 -18.256224)
			(xy 450.955538 -18.246094) (xy 451.011272 -18.244057) (xy 451.066709 -18.250157) (xy 451.120666 -18.264263)
			(xy 451.171995 -18.286075) (xy 451.219601 -18.315129) (xy 451.262469 -18.350804) (xy 451.299686 -18.392341)
			(xy 451.330459 -18.438854) (xy 451.354131 -18.489351) (xy 451.364392 -18.523458) (xy 451.682104 -18.523458)
			(xy 451.682608 -18.495885) (xy 451.690553 -18.441314) (xy 451.70627 -18.388454) (xy 451.729433 -18.338408)
			(xy 451.759559 -18.292218) (xy 451.79602 -18.250845) (xy 451.816724 -18.232628) (xy 451.827661 -18.222771)
			(xy 451.843728 -18.198108) (xy 451.852104 -18.16989) (xy 451.852096 -18.140456) (xy 451.843705 -18.112242)
			(xy 451.827625 -18.087588) (xy 451.816724 -18.077688) (xy 451.796009 -18.059481) (xy 451.759538 -18.018112)
			(xy 451.729405 -17.971922) (xy 451.70624 -17.921873) (xy 451.690525 -17.869009) (xy 451.682588 -17.814433)
			(xy 451.682104 -17.786858) (xy 451.68259 -17.759607) (xy 451.690346 -17.705659) (xy 451.705701 -17.653364)
			(xy 451.728343 -17.603787) (xy 451.757809 -17.557937) (xy 451.7935 -17.516746) (xy 451.834691 -17.481055)
			(xy 451.880541 -17.451589) (xy 451.930118 -17.428947) (xy 451.982413 -17.413592) (xy 452.036361 -17.405836)
			(xy 452.090863 -17.405836) (xy 452.144811 -17.413592) (xy 452.197106 -17.428947) (xy 452.246683 -17.451589)
			(xy 452.292533 -17.481055) (xy 452.333724 -17.516746) (xy 452.369415 -17.557937) (xy 452.398881 -17.603787)
			(xy 452.421523 -17.653364) (xy 452.436878 -17.705659) (xy 452.444634 -17.759607) (xy 452.44512 -17.786858)
			(xy 452.444618 -17.814431) (xy 452.436672 -17.869002) (xy 452.420954 -17.921861) (xy 452.39779 -17.971907)
			(xy 452.367665 -18.018098) (xy 452.331204 -18.059471) (xy 452.3105 -18.077688) (xy 452.299645 -18.087629)
			(xy 452.283572 -18.112268) (xy 452.275183 -18.140464) (xy 452.275176 -18.169882) (xy 452.283549 -18.198083)
			(xy 452.299609 -18.222729) (xy 452.3105 -18.232628) (xy 452.331228 -18.250821) (xy 452.367697 -18.292194)
			(xy 452.397827 -18.338387) (xy 452.42099 -18.388439) (xy 452.436703 -18.441305) (xy 452.444637 -18.495882)
			(xy 452.44512 -18.523458) (xy 452.444634 -18.550709) (xy 452.436878 -18.604657) (xy 452.421523 -18.656952)
			(xy 452.398881 -18.706529) (xy 452.369415 -18.752379) (xy 452.333724 -18.79357) (xy 452.292533 -18.829261)
			(xy 452.246683 -18.858727) (xy 452.197106 -18.881369) (xy 452.144811 -18.896724) (xy 452.090863 -18.90448)
			(xy 452.036361 -18.90448) (xy 451.982413 -18.896724) (xy 451.930118 -18.881369) (xy 451.880541 -18.858727)
			(xy 451.834691 -18.829261) (xy 451.7935 -18.79357) (xy 451.757809 -18.752379) (xy 451.728343 -18.706529)
			(xy 451.705701 -18.656952) (xy 451.690346 -18.604657) (xy 451.68259 -18.550709) (xy 451.682104 -18.523458)
			(xy 451.364392 -18.523458) (xy 451.370199 -18.542758) (xy 451.378319 -18.597934) (xy 451.378828 -18.62582)
			(xy 451.378319 -18.653706) (xy 451.370199 -18.708882) (xy 451.354131 -18.762289) (xy 451.330459 -18.812786)
			(xy 451.299686 -18.859299) (xy 451.262469 -18.900836) (xy 451.219601 -18.936511) (xy 451.171995 -18.965565)
			(xy 451.120666 -18.987377) (xy 451.066709 -19.001483) (xy 451.011272 -19.007583) (xy 450.955538 -19.005546)
			(xy 450.900695 -18.995416) (xy 450.847911 -18.977409) (xy 450.798311 -18.951908) (xy 450.752953 -18.919457)
			(xy 450.712804 -18.880748) (xy 450.678718 -18.836605) (xy 450.651422 -18.78797) (xy 450.631499 -18.735879)
			(xy 450.619373 -18.681442) (xy 450.615302 -18.62582) (xy 450.018171 -18.62582) (xy 450.006611 -18.65048)
			(xy 449.975838 -18.696993) (xy 449.938621 -18.73853) (xy 449.895753 -18.774205) (xy 449.848147 -18.803259)
			(xy 449.796818 -18.825071) (xy 449.742861 -18.839177) (xy 449.687424 -18.845277) (xy 449.63169 -18.84324)
			(xy 449.576847 -18.83311) (xy 449.524063 -18.815103) (xy 449.474463 -18.789602) (xy 449.429105 -18.757151)
			(xy 449.388956 -18.718442) (xy 449.35487 -18.674299) (xy 449.327574 -18.625664) (xy 449.307651 -18.573573)
			(xy 449.295525 -18.519136) (xy 449.291454 -18.463514) (xy 446.929195 -18.463514) (xy 446.929001 -18.474128)
			(xy 446.920881 -18.529304) (xy 446.904813 -18.582711) (xy 446.881141 -18.633208) (xy 446.850368 -18.679721)
			(xy 446.813151 -18.721258) (xy 446.770283 -18.756933) (xy 446.722677 -18.785987) (xy 446.671348 -18.807799)
			(xy 446.617391 -18.821905) (xy 446.561954 -18.828005) (xy 446.50622 -18.825968) (xy 446.451377 -18.815838)
			(xy 446.398593 -18.797831) (xy 446.348993 -18.77233) (xy 446.303635 -18.739879) (xy 446.263486 -18.70117)
			(xy 446.2294 -18.657027) (xy 446.202104 -18.608392) (xy 446.182181 -18.556301) (xy 446.170055 -18.501864)
			(xy 446.165984 -18.446242) (xy 445.11468 -18.446242) (xy 445.11468 -19.506438) (xy 448.687442 -19.506438)
			(xy 448.691513 -19.450816) (xy 448.703639 -19.396379) (xy 448.723562 -19.344288) (xy 448.750858 -19.295653)
			(xy 448.784944 -19.25151) (xy 448.825093 -19.212801) (xy 448.870451 -19.18035) (xy 448.920051 -19.154849)
			(xy 448.972835 -19.136842) (xy 449.027678 -19.126712) (xy 449.083412 -19.124675) (xy 449.138849 -19.130775)
			(xy 449.192806 -19.144881) (xy 449.244135 -19.166693) (xy 449.291741 -19.195747) (xy 449.334609 -19.231422)
			(xy 449.371826 -19.272959) (xy 449.402599 -19.319472) (xy 449.426271 -19.369969) (xy 449.442339 -19.423376)
			(xy 449.450459 -19.478552) (xy 449.450968 -19.506438) (xy 449.450459 -19.534324) (xy 449.442339 -19.5895)
			(xy 449.426271 -19.642907) (xy 449.402599 -19.693404) (xy 449.371826 -19.739917) (xy 449.334609 -19.781454)
			(xy 449.291741 -19.817129) (xy 449.244135 -19.846183) (xy 449.192806 -19.867995) (xy 449.138849 -19.882101)
			(xy 449.083412 -19.888201) (xy 449.027678 -19.886164) (xy 448.972835 -19.876034) (xy 448.920051 -19.858027)
			(xy 448.870451 -19.832526) (xy 448.825093 -19.800075) (xy 448.784944 -19.761366) (xy 448.750858 -19.717223)
			(xy 448.723562 -19.668588) (xy 448.703639 -19.616497) (xy 448.691513 -19.56206) (xy 448.687442 -19.506438)
			(xy 445.11468 -19.506438) (xy 445.11468 -21.236178) (xy 448.479162 -21.236178) (xy 448.483233 -21.180556)
			(xy 448.495359 -21.126119) (xy 448.515282 -21.074028) (xy 448.542578 -21.025393) (xy 448.576664 -20.98125)
			(xy 448.616813 -20.942541) (xy 448.662171 -20.91009) (xy 448.711771 -20.884589) (xy 448.764555 -20.866582)
			(xy 448.819398 -20.856452) (xy 448.875132 -20.854415) (xy 448.930569 -20.860515) (xy 448.984526 -20.874621)
			(xy 449.035855 -20.896433) (xy 449.083461 -20.925487) (xy 449.126329 -20.961162) (xy 449.163546 -21.002699)
			(xy 449.194319 -21.049212) (xy 449.217991 -21.099709) (xy 449.234059 -21.153116) (xy 449.242179 -21.208292)
			(xy 449.242688 -21.236178) (xy 449.242179 -21.264064) (xy 449.234059 -21.31924) (xy 449.217991 -21.372647)
			(xy 449.194319 -21.423144) (xy 449.163546 -21.469657) (xy 449.126329 -21.511194) (xy 449.083461 -21.546869)
			(xy 449.035855 -21.575923) (xy 448.984526 -21.597735) (xy 448.930569 -21.611841) (xy 448.875132 -21.617941)
			(xy 448.819398 -21.615904) (xy 448.764555 -21.605774) (xy 448.711771 -21.587767) (xy 448.662171 -21.562266)
			(xy 448.616813 -21.529815) (xy 448.576664 -21.491106) (xy 448.542578 -21.446963) (xy 448.515282 -21.398328)
			(xy 448.495359 -21.346237) (xy 448.483233 -21.2918) (xy 448.479162 -21.236178) (xy 445.11468 -21.236178)
			(xy 445.11468 -22.426422) (xy 450.115176 -22.426422) (xy 450.119247 -22.3708) (xy 450.131373 -22.316363)
			(xy 450.151296 -22.264272) (xy 450.178592 -22.215637) (xy 450.212678 -22.171494) (xy 450.252827 -22.132785)
			(xy 450.298185 -22.100334) (xy 450.347785 -22.074833) (xy 450.400569 -22.056826) (xy 450.455412 -22.046696)
			(xy 450.511146 -22.044659) (xy 450.566583 -22.050759) (xy 450.62054 -22.064865) (xy 450.671869 -22.086677)
			(xy 450.719475 -22.115731) (xy 450.762343 -22.151406) (xy 450.79956 -22.192943) (xy 450.830333 -22.239456)
			(xy 450.854005 -22.289953) (xy 450.870073 -22.34336) (xy 450.878193 -22.398536) (xy 450.878234 -22.400768)
			(xy 452.115172 -22.400768) (xy 452.119243 -22.345146) (xy 452.131369 -22.290709) (xy 452.151292 -22.238618)
			(xy 452.178588 -22.189983) (xy 452.212674 -22.14584) (xy 452.252823 -22.107131) (xy 452.298181 -22.07468)
			(xy 452.347781 -22.049179) (xy 452.400565 -22.031172) (xy 452.455408 -22.021042) (xy 452.511142 -22.019005)
			(xy 452.566579 -22.025105) (xy 452.620536 -22.039211) (xy 452.671865 -22.061023) (xy 452.719471 -22.090077)
			(xy 452.762339 -22.125752) (xy 452.799556 -22.167289) (xy 452.830329 -22.213802) (xy 452.854001 -22.264299)
			(xy 452.870069 -22.317706) (xy 452.878189 -22.372882) (xy 452.878698 -22.400768) (xy 452.878189 -22.428654)
			(xy 452.870069 -22.48383) (xy 452.854001 -22.537237) (xy 452.830329 -22.587734) (xy 452.799556 -22.634247)
			(xy 452.762339 -22.675784) (xy 452.719471 -22.711459) (xy 452.671865 -22.740513) (xy 452.620536 -22.762325)
			(xy 452.566579 -22.776431) (xy 452.511142 -22.782531) (xy 452.455408 -22.780494) (xy 452.400565 -22.770364)
			(xy 452.347781 -22.752357) (xy 452.298181 -22.726856) (xy 452.252823 -22.694405) (xy 452.212674 -22.655696)
			(xy 452.178588 -22.611553) (xy 452.151292 -22.562918) (xy 452.131369 -22.510827) (xy 452.119243 -22.45639)
			(xy 452.115172 -22.400768) (xy 450.878234 -22.400768) (xy 450.878702 -22.426422) (xy 450.878193 -22.454308)
			(xy 450.870073 -22.509484) (xy 450.854005 -22.562891) (xy 450.830333 -22.613388) (xy 450.79956 -22.659901)
			(xy 450.762343 -22.701438) (xy 450.719475 -22.737113) (xy 450.671869 -22.766167) (xy 450.62054 -22.787979)
			(xy 450.566583 -22.802085) (xy 450.511146 -22.808185) (xy 450.455412 -22.806148) (xy 450.400569 -22.796018)
			(xy 450.347785 -22.778011) (xy 450.298185 -22.75251) (xy 450.252827 -22.720059) (xy 450.212678 -22.68135)
			(xy 450.178592 -22.637207) (xy 450.151296 -22.588572) (xy 450.131373 -22.536481) (xy 450.119247 -22.482044)
			(xy 450.115176 -22.426422) (xy 445.11468 -22.426422) (xy 445.11468 -22.866858) (xy 446.779394 -22.866858)
			(xy 446.783465 -22.811236) (xy 446.795591 -22.756799) (xy 446.815514 -22.704708) (xy 446.84281 -22.656073)
			(xy 446.876896 -22.61193) (xy 446.917045 -22.573221) (xy 446.962403 -22.54077) (xy 447.012003 -22.515269)
			(xy 447.064787 -22.497262) (xy 447.11963 -22.487132) (xy 447.175364 -22.485095) (xy 447.230801 -22.491195)
			(xy 447.284758 -22.505301) (xy 447.336087 -22.527113) (xy 447.383693 -22.556167) (xy 447.426561 -22.591842)
			(xy 447.463778 -22.633379) (xy 447.494551 -22.679892) (xy 447.518223 -22.730389) (xy 447.534291 -22.783796)
			(xy 447.542411 -22.838972) (xy 447.54292 -22.866858) (xy 447.542411 -22.894744) (xy 447.534291 -22.94992)
			(xy 447.518223 -23.003327) (xy 447.510755 -23.019258) (xy 451.351394 -23.019258) (xy 451.355465 -22.963636)
			(xy 451.367591 -22.909199) (xy 451.387514 -22.857108) (xy 451.41481 -22.808473) (xy 451.448896 -22.76433)
			(xy 451.489045 -22.725621) (xy 451.534403 -22.69317) (xy 451.584003 -22.667669) (xy 451.636787 -22.649662)
			(xy 451.69163 -22.639532) (xy 451.747364 -22.637495) (xy 451.802801 -22.643595) (xy 451.856758 -22.657701)
			(xy 451.908087 -22.679513) (xy 451.955693 -22.708567) (xy 451.998561 -22.744242) (xy 452.035778 -22.785779)
			(xy 452.066551 -22.832292) (xy 452.090223 -22.882789) (xy 452.106291 -22.936196) (xy 452.114411 -22.991372)
			(xy 452.11492 -23.019258) (xy 452.114411 -23.047144) (xy 452.106291 -23.10232) (xy 452.090223 -23.155727)
			(xy 452.066551 -23.206224) (xy 452.035778 -23.252737) (xy 451.998561 -23.294274) (xy 451.955693 -23.329949)
			(xy 451.908087 -23.359003) (xy 451.856758 -23.380815) (xy 451.802801 -23.394921) (xy 451.747364 -23.401021)
			(xy 451.69163 -23.398984) (xy 451.636787 -23.388854) (xy 451.584003 -23.370847) (xy 451.534403 -23.345346)
			(xy 451.489045 -23.312895) (xy 451.448896 -23.274186) (xy 451.41481 -23.230043) (xy 451.387514 -23.181408)
			(xy 451.367591 -23.129317) (xy 451.355465 -23.07488) (xy 451.351394 -23.019258) (xy 447.510755 -23.019258)
			(xy 447.494551 -23.053824) (xy 447.463778 -23.100337) (xy 447.426561 -23.141874) (xy 447.383693 -23.177549)
			(xy 447.336087 -23.206603) (xy 447.284758 -23.228415) (xy 447.230801 -23.242521) (xy 447.175364 -23.248621)
			(xy 447.11963 -23.246584) (xy 447.064787 -23.236454) (xy 447.012003 -23.218447) (xy 446.962403 -23.192946)
			(xy 446.917045 -23.160495) (xy 446.876896 -23.121786) (xy 446.84281 -23.077643) (xy 446.815514 -23.029008)
			(xy 446.795591 -22.976917) (xy 446.783465 -22.92248) (xy 446.779394 -22.866858) (xy 445.11468 -22.866858)
			(xy 445.11468 -24.873458) (xy 451.376794 -24.873458) (xy 451.380865 -24.817836) (xy 451.392991 -24.763399)
			(xy 451.412914 -24.711308) (xy 451.44021 -24.662673) (xy 451.474296 -24.61853) (xy 451.514445 -24.579821)
			(xy 451.559803 -24.54737) (xy 451.609403 -24.521869) (xy 451.662187 -24.503862) (xy 451.71703 -24.493732)
			(xy 451.772764 -24.491695) (xy 451.828201 -24.497795) (xy 451.882158 -24.511901) (xy 451.933487 -24.533713)
			(xy 451.981093 -24.562767) (xy 452.023961 -24.598442) (xy 452.061178 -24.639979) (xy 452.091951 -24.686492)
			(xy 452.115623 -24.736989) (xy 452.131691 -24.790396) (xy 452.139811 -24.845572) (xy 452.14032 -24.873458)
			(xy 452.139811 -24.901344) (xy 452.131691 -24.95652) (xy 452.115623 -25.009927) (xy 452.091951 -25.060424)
			(xy 452.061178 -25.106937) (xy 452.023961 -25.148474) (xy 451.981093 -25.184149) (xy 451.933487 -25.213203)
			(xy 451.882158 -25.235015) (xy 451.828201 -25.249121) (xy 451.772764 -25.255221) (xy 451.71703 -25.253184)
			(xy 451.662187 -25.243054) (xy 451.609403 -25.225047) (xy 451.559803 -25.199546) (xy 451.514445 -25.167095)
			(xy 451.474296 -25.128386) (xy 451.44021 -25.084243) (xy 451.412914 -25.035608) (xy 451.392991 -24.983517)
			(xy 451.380865 -24.92908) (xy 451.376794 -24.873458) (xy 445.11468 -24.873458) (xy 445.11468 -26.360628)
			(xy 444.6016 -26.873708) (xy 435.0639 -26.873708) (xy 434.954052 -26.983556) (xy 446.780313 -26.983556)
			(xy 446.780313 -26.929044) (xy 446.788071 -26.875086) (xy 446.803429 -26.822781) (xy 446.826075 -26.773195)
			(xy 446.855548 -26.727336) (xy 446.891247 -26.686138) (xy 446.932445 -26.650441) (xy 446.978305 -26.62097)
			(xy 447.027892 -26.598325) (xy 447.080197 -26.582969) (xy 447.134156 -26.575212) (xy 447.161412 -26.57475)
			(xy 447.18867 -26.575219) (xy 447.24263 -26.582987) (xy 447.294937 -26.598351) (xy 447.344526 -26.620998)
			(xy 447.390392 -26.650466) (xy 447.4316 -26.686158) (xy 447.467313 -26.727348) (xy 447.482468 -26.75001)
			(xy 447.490749 -26.761937) (xy 447.512685 -26.780941) (xy 447.539085 -26.792996) (xy 447.567812 -26.797126)
			(xy 447.596539 -26.792996) (xy 447.622939 -26.780941) (xy 447.644875 -26.761937) (xy 447.653156 -26.75001)
			(xy 447.668315 -26.727351) (xy 447.704021 -26.686155) (xy 447.745226 -26.650459) (xy 447.791091 -26.620989)
			(xy 447.840683 -26.598347) (xy 447.892992 -26.582991) (xy 447.946954 -26.575235) (xy 447.974212 -26.57475)
			(xy 448.00146 -26.575321) (xy 448.0554 -26.583078) (xy 448.107688 -26.598432) (xy 448.157258 -26.621072)
			(xy 448.203102 -26.650535) (xy 448.244286 -26.686223) (xy 448.279972 -26.727408) (xy 448.309434 -26.773253)
			(xy 448.332072 -26.822824) (xy 448.347425 -26.875112) (xy 448.35518 -26.929052) (xy 448.35518 -26.983548)
			(xy 448.347425 -27.037488) (xy 448.332072 -27.089776) (xy 448.309434 -27.139347) (xy 448.279972 -27.185192)
			(xy 448.244286 -27.226377) (xy 448.203102 -27.262065) (xy 448.157258 -27.291528) (xy 448.107688 -27.314168)
			(xy 448.0554 -27.329522) (xy 448.00146 -27.337279) (xy 447.974212 -27.337766) (xy 447.946955 -27.337272)
			(xy 447.892997 -27.329506) (xy 447.840691 -27.314147) (xy 447.791101 -27.291504) (xy 447.745236 -27.26204)
			(xy 447.704027 -27.226352) (xy 447.668312 -27.185166) (xy 447.653156 -27.162506) (xy 447.644875 -27.150579)
			(xy 447.622939 -27.131575) (xy 447.596539 -27.11952) (xy 447.567812 -27.11539) (xy 447.539085 -27.11952)
			(xy 447.512685 -27.131575) (xy 447.490749 -27.150579) (xy 447.482468 -27.162506) (xy 447.467298 -27.185158)
			(xy 447.431593 -27.226353) (xy 447.39039 -27.262049) (xy 447.344527 -27.291519) (xy 447.294937 -27.314163)
			(xy 447.24263 -27.329521) (xy 447.18867 -27.337279) (xy 447.161412 -27.337766) (xy 447.134156 -27.337388)
			(xy 447.080197 -27.329631) (xy 447.027892 -27.314275) (xy 446.978305 -27.29163) (xy 446.932445 -27.262159)
			(xy 446.891247 -27.226462) (xy 446.855548 -27.185264) (xy 446.826075 -27.139405) (xy 446.803429 -27.089819)
			(xy 446.788071 -27.037514) (xy 446.780313 -26.983556) (xy 434.954052 -26.983556) (xy 434.90388 -27.033728)
			(xy 434.90388 -27.930602) (xy 434.904324 -27.944369) (xy 434.911669 -27.970903) (xy 434.925851 -27.994503)
			(xy 434.945832 -28.013444) (xy 434.970155 -28.026344) (xy 434.997044 -28.032262) (xy 435.010814 -28.031948)
			(xy 435.03088 -28.03144) (xy 435.05813 -28.031902) (xy 435.112077 -28.039656) (xy 435.16437 -28.055008)
			(xy 435.213947 -28.077646) (xy 435.259797 -28.10711) (xy 435.300986 -28.142799) (xy 435.336678 -28.183987)
			(xy 435.366144 -28.229836) (xy 435.388785 -28.279411) (xy 435.40414 -28.331704) (xy 435.411897 -28.38565)
			(xy 435.411897 -28.44015) (xy 435.40414 -28.494096) (xy 435.388785 -28.546389) (xy 435.366144 -28.595964)
			(xy 435.352356 -28.617418) (xy 436.483504 -28.617418) (xy 436.487575 -28.561796) (xy 436.499701 -28.507359)
			(xy 436.519624 -28.455268) (xy 436.54692 -28.406633) (xy 436.581006 -28.36249) (xy 436.621155 -28.323781)
			(xy 436.666513 -28.29133) (xy 436.716113 -28.265829) (xy 436.768897 -28.247822) (xy 436.82374 -28.237692)
			(xy 436.879474 -28.235655) (xy 436.934911 -28.241755) (xy 436.988868 -28.255861) (xy 437.040197 -28.277673)
			(xy 437.087803 -28.306727) (xy 437.130671 -28.342402) (xy 437.167888 -28.383939) (xy 437.198661 -28.430452)
			(xy 437.222333 -28.480949) (xy 437.238401 -28.534356) (xy 437.246521 -28.589532) (xy 437.24703 -28.617418)
			(xy 437.246521 -28.645304) (xy 437.242102 -28.67533) (xy 438.783728 -28.67533) (xy 438.787799 -28.619708)
			(xy 438.799925 -28.565271) (xy 438.819848 -28.51318) (xy 438.847144 -28.464545) (xy 438.88123 -28.420402)
			(xy 438.921379 -28.381693) (xy 438.966737 -28.349242) (xy 439.016337 -28.323741) (xy 439.069121 -28.305734)
			(xy 439.123964 -28.295604) (xy 439.179698 -28.293567) (xy 439.235135 -28.299667) (xy 439.289092 -28.313773)
			(xy 439.340421 -28.335585) (xy 439.388027 -28.364639) (xy 439.430895 -28.400314) (xy 439.468112 -28.441851)
			(xy 439.498885 -28.488364) (xy 439.501039 -28.492958) (xy 440.846972 -28.492958) (xy 440.847475 -28.465637)
			(xy 440.855819 -28.411635) (xy 440.872304 -28.359538) (xy 440.896546 -28.310567) (xy 440.927975 -28.265868)
			(xy 440.94654 -28.245816) (xy 440.956979 -28.234228) (xy 440.970801 -28.206283) (xy 440.975549 -28.17547)
			(xy 440.970782 -28.144659) (xy 440.956944 -28.116722) (xy 440.94654 -28.1051) (xy 440.927942 -28.085073)
			(xy 440.896482 -28.040385) (xy 440.872229 -27.991409) (xy 440.855754 -27.9393) (xy 440.847445 -27.885284)
			(xy 440.846972 -27.857958) (xy 440.84747 -27.831309) (xy 440.855413 -27.778605) (xy 440.871123 -27.727675)
			(xy 440.894249 -27.679654) (xy 440.924273 -27.635617) (xy 440.960525 -27.596546) (xy 441.002196 -27.563315)
			(xy 441.048354 -27.536666) (xy 441.097968 -27.517194) (xy 441.14993 -27.505334) (xy 441.20308 -27.501351)
			(xy 441.25623 -27.505334) (xy 441.308192 -27.517194) (xy 441.357806 -27.536666) (xy 441.403964 -27.563315)
			(xy 441.445635 -27.596546) (xy 441.481887 -27.635617) (xy 441.511911 -27.679654) (xy 441.535037 -27.727675)
			(xy 441.550747 -27.778605) (xy 441.55869 -27.831309) (xy 441.559188 -27.857958) (xy 441.558644 -27.885278)
			(xy 441.550312 -27.939278) (xy 441.533837 -27.991375) (xy 441.509604 -28.040347) (xy 441.478182 -28.085047)
			(xy 441.45962 -28.1051) (xy 441.449267 -28.116757) (xy 441.435442 -28.144679) (xy 441.43068 -28.17547)
			(xy 441.435424 -28.206263) (xy 441.449232 -28.234193) (xy 441.45962 -28.245816) (xy 441.478236 -28.265827)
			(xy 441.509691 -28.310521) (xy 441.533939 -28.3595) (xy 441.55041 -28.411612) (xy 441.558716 -28.465631)
			(xy 441.559188 -28.492958) (xy 441.746894 -28.492958) (xy 441.747391 -28.465636) (xy 441.755735 -28.411634)
			(xy 441.772222 -28.359537) (xy 441.796465 -28.310566) (xy 441.827896 -28.265868) (xy 441.846462 -28.245816)
			(xy 441.856899 -28.234227) (xy 441.870718 -28.206282) (xy 441.875465 -28.17547) (xy 441.8707 -28.14466)
			(xy 441.856864 -28.116723) (xy 441.846462 -28.1051) (xy 441.827868 -28.08507) (xy 441.796407 -28.040383)
			(xy 441.772153 -27.991408) (xy 441.755677 -27.9393) (xy 441.747368 -27.885284) (xy 441.746894 -27.857958)
			(xy 441.747392 -27.831309) (xy 441.755335 -27.778605) (xy 441.771045 -27.727675) (xy 441.794171 -27.679654)
			(xy 441.824195 -27.635617) (xy 441.860447 -27.596546) (xy 441.902118 -27.563315) (xy 441.948276 -27.536666)
			(xy 441.99789 -27.517194) (xy 442.049852 -27.505334) (xy 442.103002 -27.501351) (xy 442.156152 -27.505334)
			(xy 442.208114 -27.517194) (xy 442.257728 -27.536666) (xy 442.303886 -27.563315) (xy 442.345557 -27.596546)
			(xy 442.381809 -27.635617) (xy 442.411833 -27.679654) (xy 442.434959 -27.727675) (xy 442.450669 -27.778605)
			(xy 442.458612 -27.831309) (xy 442.45911 -27.857958) (xy 442.45856 -27.885278) (xy 442.450229 -27.939278)
			(xy 442.433754 -27.991374) (xy 442.409523 -28.040346) (xy 442.378102 -28.085047) (xy 442.359542 -28.1051)
			(xy 442.349187 -28.116756) (xy 442.335359 -28.144678) (xy 442.330596 -28.17547) (xy 442.335341 -28.206264)
			(xy 442.349152 -28.234194) (xy 442.359542 -28.245816) (xy 442.378144 -28.265839) (xy 442.409604 -28.310528)
			(xy 442.433857 -28.359504) (xy 442.450331 -28.411614) (xy 442.458638 -28.465631) (xy 442.45911 -28.492958)
			(xy 442.646816 -28.492958) (xy 442.647307 -28.465636) (xy 442.655652 -28.411633) (xy 442.672139 -28.359536)
			(xy 442.696384 -28.310565) (xy 442.727817 -28.265867) (xy 442.746384 -28.245816) (xy 442.756819 -28.234226)
			(xy 442.770635 -28.206281) (xy 442.775381 -28.17547) (xy 442.770617 -28.144661) (xy 442.756784 -28.116724)
			(xy 442.746384 -28.1051) (xy 442.727777 -28.085082) (xy 442.69632 -28.04039) (xy 442.67207 -27.991412)
			(xy 442.655597 -27.939302) (xy 442.647289 -27.885285) (xy 442.646816 -27.857958) (xy 442.647314 -27.831309)
			(xy 442.655257 -27.778605) (xy 442.670967 -27.727675) (xy 442.694093 -27.679654) (xy 442.724117 -27.635617)
			(xy 442.760369 -27.596546) (xy 442.80204 -27.563315) (xy 442.848198 -27.536666) (xy 442.897812 -27.517194)
			(xy 442.949774 -27.505334) (xy 443.002924 -27.501351) (xy 443.056074 -27.505334) (xy 443.108036 -27.517194)
			(xy 443.15765 -27.536666) (xy 443.203808 -27.563315) (xy 443.245479 -27.596546) (xy 443.281731 -27.635617)
			(xy 443.311755 -27.679654) (xy 443.334881 -27.727675) (xy 443.350591 -27.778605) (xy 443.358534 -27.831309)
			(xy 443.359032 -27.857958) (xy 443.358476 -27.885277) (xy 443.350145 -27.939277) (xy 443.333672 -27.991373)
			(xy 443.309442 -28.040345) (xy 443.278023 -28.085046) (xy 443.259464 -28.1051) (xy 443.249107 -28.116755)
			(xy 443.235276 -28.144677) (xy 443.230512 -28.17547) (xy 443.235258 -28.206265) (xy 443.249072 -28.234195)
			(xy 443.259464 -28.245816) (xy 443.27807 -28.265836) (xy 443.309529 -28.310526) (xy 443.33378 -28.359503)
			(xy 443.350253 -28.411614) (xy 443.35856 -28.465631) (xy 443.359032 -28.492958) (xy 443.546992 -28.492958)
			(xy 443.547489 -28.465636) (xy 443.555834 -28.411634) (xy 443.57232 -28.359537) (xy 443.596563 -28.310566)
			(xy 443.627995 -28.265868) (xy 443.64656 -28.245816) (xy 443.656998 -28.234228) (xy 443.670816 -28.206282)
			(xy 443.675564 -28.17547) (xy 443.670798 -28.14466) (xy 443.656963 -28.116723) (xy 443.64656 -28.1051)
			(xy 443.627966 -28.08507) (xy 443.596504 -28.040383) (xy 443.57225 -27.991408) (xy 443.555775 -27.9393)
			(xy 443.547466 -27.885284) (xy 443.546992 -27.857958) (xy 443.54749 -27.831309) (xy 443.555433 -27.778605)
			(xy 443.571143 -27.727675) (xy 443.594269 -27.679654) (xy 443.624293 -27.635617) (xy 443.660545 -27.596546)
			(xy 443.702216 -27.563315) (xy 443.748374 -27.536666) (xy 443.797988 -27.517194) (xy 443.84995 -27.505334)
			(xy 443.9031 -27.501351) (xy 443.95625 -27.505334) (xy 444.008212 -27.517194) (xy 444.057826 -27.536666)
			(xy 444.103984 -27.563315) (xy 444.145655 -27.596546) (xy 444.181907 -27.635617) (xy 444.211931 -27.679654)
			(xy 444.235057 -27.727675) (xy 444.250767 -27.778605) (xy 444.25871 -27.831309) (xy 444.259208 -27.857958)
			(xy 444.258659 -27.885278) (xy 444.250327 -27.939278) (xy 444.233853 -27.991374) (xy 444.209621 -28.040346)
			(xy 444.178201 -28.085047) (xy 444.15964 -28.1051) (xy 444.149285 -28.116756) (xy 444.135458 -28.144678)
			(xy 444.130695 -28.17547) (xy 444.134607 -28.200858) (xy 445.636904 -28.200858) (xy 445.637401 -28.172118)
			(xy 445.64603 -28.11529) (xy 445.663086 -28.060398) (xy 445.688184 -28.008687) (xy 445.720755 -27.961326)
			(xy 445.740028 -27.94) (xy 445.750145 -27.928501) (xy 445.763488 -27.900943) (xy 445.768067 -27.870669)
			(xy 445.76347 -27.840398) (xy 445.75011 -27.812849) (xy 445.740028 -27.801316) (xy 445.720736 -27.780008)
			(xy 445.688173 -27.73264) (xy 445.663085 -27.680924) (xy 445.646039 -27.626029) (xy 445.637422 -27.569198)
			(xy 445.636904 -27.540458) (xy 445.63739 -27.513207) (xy 445.645146 -27.459259) (xy 445.660501 -27.406964)
			(xy 445.683143 -27.357387) (xy 445.712609 -27.311537) (xy 445.7483 -27.270346) (xy 445.789491 -27.234655)
			(xy 445.835341 -27.205189) (xy 445.884918 -27.182547) (xy 445.937213 -27.167192) (xy 445.991161 -27.159436)
			(xy 446.045663 -27.159436) (xy 446.099611 -27.167192) (xy 446.151906 -27.182547) (xy 446.201483 -27.205189)
			(xy 446.247333 -27.234655) (xy 446.288524 -27.270346) (xy 446.324215 -27.311537) (xy 446.353681 -27.357387)
			(xy 446.376323 -27.406964) (xy 446.391678 -27.459259) (xy 446.399434 -27.513207) (xy 446.39992 -27.540458)
			(xy 446.399426 -27.569198) (xy 446.390795 -27.626026) (xy 446.373738 -27.680917) (xy 446.34864 -27.732628)
			(xy 446.316069 -27.77999) (xy 446.296796 -27.801316) (xy 446.286768 -27.812884) (xy 446.273426 -27.840419)
			(xy 446.268835 -27.870669) (xy 446.273408 -27.900922) (xy 446.286733 -27.928465) (xy 446.296796 -27.94)
			(xy 446.316083 -27.961313) (xy 446.348649 -28.008678) (xy 446.37374 -28.060393) (xy 446.390786 -28.115287)
			(xy 446.399403 -28.172118) (xy 446.39992 -28.200858) (xy 446.399434 -28.228109) (xy 446.391678 -28.282057)
			(xy 446.376323 -28.334352) (xy 446.353681 -28.383929) (xy 446.324215 -28.429779) (xy 446.288524 -28.47097)
			(xy 446.247333 -28.506661) (xy 446.201483 -28.536127) (xy 446.151906 -28.558769) (xy 446.099611 -28.574124)
			(xy 446.045663 -28.58188) (xy 445.991161 -28.58188) (xy 445.937213 -28.574124) (xy 445.884918 -28.558769)
			(xy 445.835341 -28.536127) (xy 445.789491 -28.506661) (xy 445.7483 -28.47097) (xy 445.712609 -28.429779)
			(xy 445.683143 -28.383929) (xy 445.660501 -28.334352) (xy 445.645146 -28.282057) (xy 445.63739 -28.228109)
			(xy 445.636904 -28.200858) (xy 444.134607 -28.200858) (xy 444.13544 -28.206264) (xy 444.14925 -28.234194)
			(xy 444.15964 -28.245816) (xy 444.178242 -28.265839) (xy 444.209702 -28.310528) (xy 444.233955 -28.359504)
			(xy 444.250428 -28.411614) (xy 444.258736 -28.465631) (xy 444.259208 -28.492958) (xy 444.25871 -28.519607)
			(xy 444.250767 -28.572311) (xy 444.235057 -28.623241) (xy 444.211931 -28.671262) (xy 444.181907 -28.715299)
			(xy 444.145655 -28.75437) (xy 444.103984 -28.787601) (xy 444.057826 -28.81425) (xy 444.008212 -28.833722)
			(xy 443.95625 -28.845582) (xy 443.9031 -28.849566) (xy 443.84995 -28.845582) (xy 443.797988 -28.833722)
			(xy 443.748374 -28.81425) (xy 443.702216 -28.787601) (xy 443.660545 -28.75437) (xy 443.624293 -28.715299)
			(xy 443.594269 -28.671262) (xy 443.571143 -28.623241) (xy 443.555433 -28.572311) (xy 443.54749 -28.519607)
			(xy 443.546992 -28.492958) (xy 443.359032 -28.492958) (xy 443.358534 -28.519607) (xy 443.350591 -28.572311)
			(xy 443.334881 -28.623241) (xy 443.311755 -28.671262) (xy 443.281731 -28.715299) (xy 443.245479 -28.75437)
			(xy 443.203808 -28.787601) (xy 443.15765 -28.81425) (xy 443.108036 -28.833722) (xy 443.056074 -28.845582)
			(xy 443.002924 -28.849566) (xy 442.949774 -28.845582) (xy 442.897812 -28.833722) (xy 442.848198 -28.81425)
			(xy 442.80204 -28.787601) (xy 442.760369 -28.75437) (xy 442.724117 -28.715299) (xy 442.694093 -28.671262)
			(xy 442.670967 -28.623241) (xy 442.655257 -28.572311) (xy 442.647314 -28.519607) (xy 442.646816 -28.492958)
			(xy 442.45911 -28.492958) (xy 442.458612 -28.519607) (xy 442.450669 -28.572311) (xy 442.434959 -28.623241)
			(xy 442.411833 -28.671262) (xy 442.381809 -28.715299) (xy 442.345557 -28.75437) (xy 442.303886 -28.787601)
			(xy 442.257728 -28.81425) (xy 442.208114 -28.833722) (xy 442.156152 -28.845582) (xy 442.103002 -28.849566)
			(xy 442.049852 -28.845582) (xy 441.99789 -28.833722) (xy 441.948276 -28.81425) (xy 441.902118 -28.787601)
			(xy 441.860447 -28.75437) (xy 441.824195 -28.715299) (xy 441.794171 -28.671262) (xy 441.771045 -28.623241)
			(xy 441.755335 -28.572311) (xy 441.747392 -28.519607) (xy 441.746894 -28.492958) (xy 441.559188 -28.492958)
			(xy 441.55869 -28.519607) (xy 441.550747 -28.572311) (xy 441.535037 -28.623241) (xy 441.511911 -28.671262)
			(xy 441.481887 -28.715299) (xy 441.445635 -28.75437) (xy 441.403964 -28.787601) (xy 441.357806 -28.81425)
			(xy 441.308192 -28.833722) (xy 441.25623 -28.845582) (xy 441.20308 -28.849566) (xy 441.14993 -28.845582)
			(xy 441.097968 -28.833722) (xy 441.048354 -28.81425) (xy 441.002196 -28.787601) (xy 440.960525 -28.75437)
			(xy 440.924273 -28.715299) (xy 440.894249 -28.671262) (xy 440.871123 -28.623241) (xy 440.855413 -28.572311)
			(xy 440.84747 -28.519607) (xy 440.846972 -28.492958) (xy 439.501039 -28.492958) (xy 439.522557 -28.538861)
			(xy 439.538625 -28.592268) (xy 439.546745 -28.647444) (xy 439.547254 -28.67533) (xy 439.546745 -28.703216)
			(xy 439.538625 -28.758392) (xy 439.522557 -28.811799) (xy 439.498885 -28.862296) (xy 439.482767 -28.886658)
			(xy 449.015104 -28.886658) (xy 449.015548 -28.860342) (xy 449.02277 -28.808207) (xy 449.037085 -28.757559)
			(xy 449.058221 -28.709357) (xy 449.085778 -28.664515) (xy 449.119233 -28.623884) (xy 449.138294 -28.605734)
			(xy 449.148357 -28.595962) (xy 449.163053 -28.572078) (xy 449.170686 -28.545093) (xy 449.170678 -28.51705)
			(xy 449.16303 -28.49007) (xy 449.148321 -28.466194) (xy 449.138294 -28.456382) (xy 449.119205 -28.438257)
			(xy 449.085728 -28.397635) (xy 449.058159 -28.352792) (xy 449.037022 -28.304583) (xy 449.02272 -28.253923)
			(xy 449.015523 -28.201778) (xy 449.015104 -28.175458) (xy 449.015608 -28.147885) (xy 449.023553 -28.093314)
			(xy 449.03927 -28.040454) (xy 449.062433 -27.990408) (xy 449.092559 -27.944218) (xy 449.12902 -27.902845)
			(xy 449.149724 -27.884628) (xy 449.160661 -27.874771) (xy 449.176728 -27.850108) (xy 449.185104 -27.82189)
			(xy 449.185096 -27.792456) (xy 449.176705 -27.764242) (xy 449.160625 -27.739588) (xy 449.149724 -27.729688)
			(xy 449.129009 -27.711481) (xy 449.092538 -27.670112) (xy 449.062405 -27.623922) (xy 449.03924 -27.573873)
			(xy 449.023525 -27.521009) (xy 449.015588 -27.466433) (xy 449.015104 -27.438858) (xy 449.01559 -27.411607)
			(xy 449.023346 -27.357659) (xy 449.038701 -27.305364) (xy 449.061343 -27.255787) (xy 449.090809 -27.209937)
			(xy 449.1265 -27.168746) (xy 449.167691 -27.133055) (xy 449.213541 -27.103589) (xy 449.263118 -27.080947)
			(xy 449.315413 -27.065592) (xy 449.369361 -27.057836) (xy 449.423863 -27.057836) (xy 449.477811 -27.065592)
			(xy 449.530106 -27.080947) (xy 449.579683 -27.103589) (xy 449.625533 -27.133055) (xy 449.666724 -27.168746)
			(xy 449.702415 -27.209937) (xy 449.731881 -27.255787) (xy 449.754523 -27.305364) (xy 449.769878 -27.357659)
			(xy 449.777634 -27.411607) (xy 449.77812 -27.438858) (xy 449.777618 -27.466431) (xy 449.769672 -27.521002)
			(xy 449.753954 -27.573861) (xy 449.73079 -27.623907) (xy 449.700665 -27.670098) (xy 449.664204 -27.711471)
			(xy 449.6435 -27.729688) (xy 449.632645 -27.739629) (xy 449.616572 -27.764268) (xy 449.608183 -27.792464)
			(xy 449.608176 -27.821882) (xy 449.616549 -27.850083) (xy 449.632609 -27.874729) (xy 449.6435 -27.884628)
			(xy 449.664228 -27.902821) (xy 449.700697 -27.944194) (xy 449.730827 -27.990387) (xy 449.75399 -28.040439)
			(xy 449.769703 -28.093305) (xy 449.777637 -28.147882) (xy 449.77812 -28.175458) (xy 449.777679 -28.201774)
			(xy 449.770455 -28.253909) (xy 449.75614 -28.304557) (xy 449.735003 -28.352759) (xy 449.707446 -28.3976)
			(xy 449.673991 -28.438232) (xy 449.65493 -28.456382) (xy 449.64495 -28.466233) (xy 449.630245 -28.490093)
			(xy 449.6226 -28.517058) (xy 449.622592 -28.545085) (xy 449.630222 -28.572054) (xy 449.644913 -28.595923)
			(xy 449.65493 -28.605734) (xy 449.674013 -28.623866) (xy 449.707493 -28.664485) (xy 449.735065 -28.709326)
			(xy 449.756203 -28.757534) (xy 449.770506 -28.808193) (xy 449.777701 -28.860338) (xy 449.77812 -28.886658)
			(xy 449.777634 -28.913909) (xy 449.769878 -28.967857) (xy 449.754523 -29.020152) (xy 449.731881 -29.069729)
			(xy 449.702415 -29.115579) (xy 449.666724 -29.15677) (xy 449.625533 -29.192461) (xy 449.579683 -29.221927)
			(xy 449.530106 -29.244569) (xy 449.477811 -29.259924) (xy 449.423863 -29.26768) (xy 449.369361 -29.26768)
			(xy 449.315413 -29.259924) (xy 449.263118 -29.244569) (xy 449.213541 -29.221927) (xy 449.167691 -29.192461)
			(xy 449.1265 -29.15677) (xy 449.090809 -29.115579) (xy 449.061343 -29.069729) (xy 449.038701 -29.020152)
			(xy 449.023346 -28.967857) (xy 449.01559 -28.913909) (xy 449.015104 -28.886658) (xy 439.482767 -28.886658)
			(xy 439.468112 -28.908809) (xy 439.430895 -28.950346) (xy 439.388027 -28.986021) (xy 439.340421 -29.015075)
			(xy 439.289092 -29.036887) (xy 439.235135 -29.050993) (xy 439.179698 -29.057093) (xy 439.123964 -29.055056)
			(xy 439.069121 -29.044926) (xy 439.016337 -29.026919) (xy 438.966737 -29.001418) (xy 438.921379 -28.968967)
			(xy 438.88123 -28.930258) (xy 438.847144 -28.886115) (xy 438.819848 -28.83748) (xy 438.799925 -28.785389)
			(xy 438.787799 -28.730952) (xy 438.783728 -28.67533) (xy 437.242102 -28.67533) (xy 437.238401 -28.70048)
			(xy 437.222333 -28.753887) (xy 437.198661 -28.804384) (xy 437.167888 -28.850897) (xy 437.130671 -28.892434)
			(xy 437.087803 -28.928109) (xy 437.040197 -28.957163) (xy 436.988868 -28.978975) (xy 436.934911 -28.993081)
			(xy 436.879474 -28.999181) (xy 436.82374 -28.997144) (xy 436.768897 -28.987014) (xy 436.716113 -28.969007)
			(xy 436.666513 -28.943506) (xy 436.621155 -28.911055) (xy 436.581006 -28.872346) (xy 436.54692 -28.828203)
			(xy 436.519624 -28.779568) (xy 436.499701 -28.727477) (xy 436.487575 -28.67304) (xy 436.483504 -28.617418)
			(xy 435.352356 -28.617418) (xy 435.336678 -28.641813) (xy 435.300986 -28.683001) (xy 435.259797 -28.71869)
			(xy 435.213947 -28.748154) (xy 435.16437 -28.770792) (xy 435.112077 -28.786144) (xy 435.05813 -28.793898)
			(xy 435.03088 -28.794456) (xy 435.010814 -28.793948) (xy 434.997049 -28.793681) (xy 434.97018 -28.79963)
			(xy 434.945874 -28.812535) (xy 434.925894 -28.831459) (xy 434.911689 -28.855029) (xy 434.90429 -28.881535)
			(xy 434.90388 -28.895294) (xy 434.90388 -29.454602) (xy 434.904411 -29.470064) (xy 434.913644 -29.499576)
			(xy 434.931293 -29.524968) (xy 434.955736 -29.543908) (xy 434.98473 -29.554658) (xy 435.000146 -29.555948)
			(xy 435.027675 -29.557885) (xy 435.081791 -29.568695) (xy 435.133784 -29.58719) (xy 435.18257 -29.612984)
			(xy 435.21054 -29.633418) (xy 436.483504 -29.633418) (xy 436.487575 -29.577796) (xy 436.499701 -29.523359)
			(xy 436.519624 -29.471268) (xy 436.54692 -29.422633) (xy 436.581006 -29.37849) (xy 436.621155 -29.339781)
			(xy 436.666513 -29.30733) (xy 436.716113 -29.281829) (xy 436.768897 -29.263822) (xy 436.82374 -29.253692)
			(xy 436.879474 -29.251655) (xy 436.934911 -29.257755) (xy 436.988868 -29.271861) (xy 437.040197 -29.293673)
			(xy 437.087803 -29.322727) (xy 437.130671 -29.358402) (xy 437.167888 -29.399939) (xy 437.198661 -29.446452)
			(xy 437.222333 -29.496949) (xy 437.238401 -29.550356) (xy 437.246521 -29.605532) (xy 437.24703 -29.633418)
			(xy 437.246521 -29.661304) (xy 437.238401 -29.71648) (xy 437.222333 -29.769887) (xy 437.198661 -29.820384)
			(xy 437.167888 -29.866897) (xy 437.130671 -29.908434) (xy 437.087803 -29.944109) (xy 437.040197 -29.973163)
			(xy 436.988868 -29.994975) (xy 436.948502 -30.005528) (xy 438.804302 -30.005528) (xy 438.808373 -29.949906)
			(xy 438.820499 -29.895469) (xy 438.840422 -29.843378) (xy 438.867718 -29.794743) (xy 438.901804 -29.7506)
			(xy 438.941953 -29.711891) (xy 438.987311 -29.67944) (xy 439.036911 -29.653939) (xy 439.089695 -29.635932)
			(xy 439.144538 -29.625802) (xy 439.200272 -29.623765) (xy 439.255709 -29.629865) (xy 439.309666 -29.643971)
			(xy 439.360995 -29.665783) (xy 439.377664 -29.675956) (xy 446.145313 -29.675956) (xy 446.145313 -29.621444)
			(xy 446.153071 -29.567486) (xy 446.168429 -29.515181) (xy 446.191075 -29.465595) (xy 446.220548 -29.419736)
			(xy 446.256247 -29.378538) (xy 446.297445 -29.342841) (xy 446.343305 -29.31337) (xy 446.392892 -29.290725)
			(xy 446.445197 -29.275369) (xy 446.499156 -29.267612) (xy 446.526412 -29.26715) (xy 446.555327 -29.267713)
			(xy 446.612497 -29.27643) (xy 446.667696 -29.293678) (xy 446.719659 -29.319061) (xy 446.767193 -29.351998)
			(xy 446.809211 -29.391733) (xy 446.827402 -29.414216) (xy 446.837299 -29.426021) (xy 446.862623 -29.44354)
			(xy 446.892016 -29.452716) (xy 446.922808 -29.452716) (xy 446.952201 -29.44354) (xy 446.977525 -29.426021)
			(xy 446.987422 -29.414216) (xy 447.005605 -29.391725) (xy 447.047626 -29.35199) (xy 447.095162 -29.319051)
			(xy 447.147125 -29.293664) (xy 447.202324 -29.27641) (xy 447.259495 -29.267683) (xy 447.288412 -29.26715)
			(xy 447.31566 -29.267721) (xy 447.3696 -29.275478) (xy 447.421888 -29.290832) (xy 447.471458 -29.313472)
			(xy 447.517302 -29.342935) (xy 447.558486 -29.378623) (xy 447.594172 -29.419808) (xy 447.623634 -29.465653)
			(xy 447.646272 -29.515224) (xy 447.661625 -29.567512) (xy 447.66938 -29.621452) (xy 447.66938 -29.675948)
			(xy 447.661625 -29.729888) (xy 447.646272 -29.782176) (xy 447.623634 -29.831747) (xy 447.594172 -29.877592)
			(xy 447.558486 -29.918777) (xy 447.517302 -29.954465) (xy 447.471458 -29.983928) (xy 447.421888 -30.006568)
			(xy 447.3696 -30.021922) (xy 447.31566 -30.029679) (xy 447.288412 -30.030166) (xy 447.259495 -30.029652)
			(xy 447.202323 -30.020924) (xy 447.147123 -30.003666) (xy 447.095161 -29.978273) (xy 447.047628 -29.945329)
			(xy 447.005612 -29.905586) (xy 446.987422 -29.8831) (xy 446.977525 -29.871295) (xy 446.952201 -29.853776)
			(xy 446.922808 -29.8446) (xy 446.892016 -29.8446) (xy 446.862623 -29.853776) (xy 446.837299 -29.871295)
			(xy 446.827402 -29.8831) (xy 446.80921 -29.905583) (xy 446.76719 -29.945318) (xy 446.719656 -29.978257)
			(xy 446.667695 -30.003645) (xy 446.612497 -30.020902) (xy 446.555328 -30.029631) (xy 446.526412 -30.030166)
			(xy 446.499156 -30.029788) (xy 446.445197 -30.022031) (xy 446.392892 -30.006675) (xy 446.343305 -29.98403)
			(xy 446.297445 -29.954559) (xy 446.256247 -29.918862) (xy 446.220548 -29.877664) (xy 446.191075 -29.831805)
			(xy 446.168429 -29.782219) (xy 446.153071 -29.729914) (xy 446.145313 -29.675956) (xy 439.377664 -29.675956)
			(xy 439.408601 -29.694837) (xy 439.451469 -29.730512) (xy 439.488686 -29.772049) (xy 439.519459 -29.818562)
			(xy 439.543131 -29.869059) (xy 439.559199 -29.922466) (xy 439.567319 -29.977642) (xy 439.567828 -30.005528)
			(xy 439.567319 -30.033414) (xy 439.559199 -30.08859) (xy 439.543131 -30.141997) (xy 439.519459 -30.192494)
			(xy 439.488686 -30.239007) (xy 439.451469 -30.280544) (xy 439.408601 -30.316219) (xy 439.360995 -30.345273)
			(xy 439.309666 -30.367085) (xy 439.255709 -30.381191) (xy 439.200272 -30.387291) (xy 439.144538 -30.385254)
			(xy 439.089695 -30.375124) (xy 439.036911 -30.357117) (xy 438.987311 -30.331616) (xy 438.941953 -30.299165)
			(xy 438.901804 -30.260456) (xy 438.867718 -30.216313) (xy 438.840422 -30.167678) (xy 438.820499 -30.115587)
			(xy 438.808373 -30.06115) (xy 438.804302 -30.005528) (xy 436.948502 -30.005528) (xy 436.934911 -30.009081)
			(xy 436.879474 -30.015181) (xy 436.82374 -30.013144) (xy 436.768897 -30.003014) (xy 436.716113 -29.985007)
			(xy 436.666513 -29.959506) (xy 436.621155 -29.927055) (xy 436.581006 -29.888346) (xy 436.54692 -29.844203)
			(xy 436.519624 -29.795568) (xy 436.499701 -29.743477) (xy 436.487575 -29.68904) (xy 436.483504 -29.633418)
			(xy 435.21054 -29.633418) (xy 435.22713 -29.645538) (xy 435.266535 -29.684173) (xy 435.299961 -29.728083)
			(xy 435.326712 -29.776351) (xy 435.346228 -29.82797) (xy 435.358103 -29.881862) (xy 435.362089 -29.936903)
			(xy 435.358102 -29.991943) (xy 435.346227 -30.045835) (xy 435.326709 -30.097454) (xy 435.299958 -30.145721)
			(xy 435.266531 -30.189631) (xy 435.227126 -30.228265) (xy 435.182566 -30.260819) (xy 435.133779 -30.286612)
			(xy 435.081786 -30.305106) (xy 435.02767 -30.315916) (xy 435.000146 -30.317948) (xy 434.984752 -30.319314)
			(xy 434.955805 -30.3301) (xy 434.931396 -30.349032) (xy 434.913749 -30.374385) (xy 434.904471 -30.40385)
			(xy 434.90388 -30.419294) (xy 434.90388 -30.706568) (xy 441.506862 -30.706568) (xy 441.510933 -30.650946)
			(xy 441.523059 -30.596509) (xy 441.542982 -30.544418) (xy 441.570278 -30.495783) (xy 441.604364 -30.45164)
			(xy 441.644513 -30.412931) (xy 441.689871 -30.38048) (xy 441.739471 -30.354979) (xy 441.792255 -30.336972)
			(xy 441.847098 -30.326842) (xy 441.902832 -30.324805) (xy 441.958269 -30.330905) (xy 442.012226 -30.345011)
			(xy 442.063555 -30.366823) (xy 442.111161 -30.395877) (xy 442.154029 -30.431552) (xy 442.191066 -30.472888)
			(xy 444.326262 -30.472888) (xy 444.330333 -30.417266) (xy 444.342459 -30.362829) (xy 444.362382 -30.310738)
			(xy 444.389678 -30.262103) (xy 444.423764 -30.21796) (xy 444.463913 -30.179251) (xy 444.509271 -30.1468)
			(xy 444.558871 -30.121299) (xy 444.611655 -30.103292) (xy 444.666498 -30.093162) (xy 444.722232 -30.091125)
			(xy 444.777669 -30.097225) (xy 444.831626 -30.111331) (xy 444.882955 -30.133143) (xy 444.930561 -30.162197)
			(xy 444.973429 -30.197872) (xy 445.010646 -30.239409) (xy 445.041419 -30.285922) (xy 445.065091 -30.336419)
			(xy 445.081159 -30.389826) (xy 445.089279 -30.445002) (xy 445.089788 -30.472888) (xy 445.089279 -30.500774)
			(xy 445.081159 -30.55595) (xy 445.065091 -30.609357) (xy 445.041419 -30.659854) (xy 445.010646 -30.706367)
			(xy 444.973429 -30.747904) (xy 444.930561 -30.783579) (xy 444.882955 -30.812633) (xy 444.831626 -30.834445)
			(xy 444.777669 -30.848551) (xy 444.722232 -30.854651) (xy 444.666498 -30.852614) (xy 444.611655 -30.842484)
			(xy 444.558871 -30.824477) (xy 444.509271 -30.798976) (xy 444.463913 -30.766525) (xy 444.423764 -30.727816)
			(xy 444.389678 -30.683673) (xy 444.362382 -30.635038) (xy 444.342459 -30.582947) (xy 444.330333 -30.52851)
			(xy 444.326262 -30.472888) (xy 442.191066 -30.472888) (xy 442.191246 -30.473089) (xy 442.222019 -30.519602)
			(xy 442.245691 -30.570099) (xy 442.261759 -30.623506) (xy 442.269879 -30.678682) (xy 442.270388 -30.706568)
			(xy 442.269879 -30.734454) (xy 442.261759 -30.78963) (xy 442.245691 -30.843037) (xy 442.222019 -30.893534)
			(xy 442.191246 -30.940047) (xy 442.154029 -30.981584) (xy 442.111161 -31.017259) (xy 442.063555 -31.046313)
			(xy 442.012226 -31.068125) (xy 441.958269 -31.082231) (xy 441.902832 -31.088331) (xy 441.847098 -31.086294)
			(xy 441.792255 -31.076164) (xy 441.739471 -31.058157) (xy 441.689871 -31.032656) (xy 441.644513 -31.000205)
			(xy 441.604364 -30.961496) (xy 441.570278 -30.917353) (xy 441.542982 -30.868718) (xy 441.523059 -30.816627)
			(xy 441.510933 -30.76219) (xy 441.506862 -30.706568) (xy 434.90388 -30.706568) (xy 434.90388 -31.229808)
			(xy 442.850522 -31.229808) (xy 442.854593 -31.174186) (xy 442.866719 -31.119749) (xy 442.886642 -31.067658)
			(xy 442.913938 -31.019023) (xy 442.948024 -30.97488) (xy 442.988173 -30.936171) (xy 443.033531 -30.90372)
			(xy 443.083131 -30.878219) (xy 443.135915 -30.860212) (xy 443.190758 -30.850082) (xy 443.246492 -30.848045)
			(xy 443.301929 -30.854145) (xy 443.355886 -30.868251) (xy 443.407215 -30.890063) (xy 443.454821 -30.919117)
			(xy 443.497689 -30.954792) (xy 443.534906 -30.996329) (xy 443.565679 -31.042842) (xy 443.589351 -31.093339)
			(xy 443.605419 -31.146746) (xy 443.613539 -31.201922) (xy 443.614048 -31.229808) (xy 443.613539 -31.257694)
			(xy 443.605419 -31.31287) (xy 443.589351 -31.366277) (xy 443.565679 -31.416774) (xy 443.534906 -31.463287)
			(xy 443.497689 -31.504824) (xy 443.454821 -31.540499) (xy 443.407215 -31.569553) (xy 443.355886 -31.591365)
			(xy 443.301929 -31.605471) (xy 443.246492 -31.611571) (xy 443.190758 -31.609534) (xy 443.135915 -31.599404)
			(xy 443.083131 -31.581397) (xy 443.033531 -31.555896) (xy 442.988173 -31.523445) (xy 442.948024 -31.484736)
			(xy 442.913938 -31.440593) (xy 442.886642 -31.391958) (xy 442.866719 -31.339867) (xy 442.854593 -31.28543)
			(xy 442.850522 -31.229808) (xy 434.90388 -31.229808) (xy 434.90388 -32.573468) (xy 446.226182 -32.573468)
			(xy 446.230253 -32.517846) (xy 446.242379 -32.463409) (xy 446.262302 -32.411318) (xy 446.289598 -32.362683)
			(xy 446.323684 -32.31854) (xy 446.363833 -32.279831) (xy 446.409191 -32.24738) (xy 446.458791 -32.221879)
			(xy 446.511575 -32.203872) (xy 446.566418 -32.193742) (xy 446.622152 -32.191705) (xy 446.677589 -32.197805)
			(xy 446.731546 -32.211911) (xy 446.782875 -32.233723) (xy 446.830481 -32.262777) (xy 446.873349 -32.298452)
			(xy 446.910566 -32.339989) (xy 446.941339 -32.386502) (xy 446.965011 -32.436999) (xy 446.981079 -32.490406)
			(xy 446.989199 -32.545582) (xy 446.989708 -32.573468) (xy 446.989199 -32.601354) (xy 446.981079 -32.65653)
			(xy 446.965011 -32.709937) (xy 446.941339 -32.760434) (xy 446.910566 -32.806947) (xy 446.873349 -32.848484)
			(xy 446.830481 -32.884159) (xy 446.782875 -32.913213) (xy 446.731546 -32.935025) (xy 446.677589 -32.949131)
			(xy 446.622152 -32.955231) (xy 446.566418 -32.953194) (xy 446.511575 -32.943064) (xy 446.458791 -32.925057)
			(xy 446.409191 -32.899556) (xy 446.363833 -32.867105) (xy 446.323684 -32.828396) (xy 446.289598 -32.784253)
			(xy 446.262302 -32.735618) (xy 446.242379 -32.683527) (xy 446.230253 -32.62909) (xy 446.226182 -32.573468)
			(xy 434.90388 -32.573468) (xy 434.90388 -32.800544) (xy 434.904357 -32.815118) (xy 434.912598 -32.843078)
			(xy 434.928398 -32.867574) (xy 434.95047 -32.886612) (xy 434.97702 -32.898645) (xy 435.005887 -32.902693)
			(xy 435.034722 -32.898427) (xy 435.048152 -32.892746) (xy 435.073346 -32.881615) (xy 435.126134 -32.8659)
			(xy 435.180633 -32.857936) (xy 435.208172 -32.85744) (xy 435.235425 -32.857901) (xy 435.289376 -32.865655)
			(xy 435.341675 -32.88101) (xy 435.391255 -32.903651) (xy 435.437109 -32.933119) (xy 435.478301 -32.968814)
			(xy 435.513993 -33.010007) (xy 435.543458 -33.055862) (xy 435.566097 -33.105444) (xy 435.581449 -33.157743)
			(xy 435.5892 -33.211695) (xy 435.58968 -33.238948) (xy 435.589227 -33.265488) (xy 435.581879 -33.318058)
			(xy 435.567317 -33.369102) (xy 435.545823 -33.417636) (xy 435.517812 -33.462724) (xy 435.483822 -33.503495)
			(xy 435.464458 -33.52165) (xy 435.45455 -33.531182) (xy 435.439786 -33.554361) (xy 435.431754 -33.580643)
			(xy 435.431041 -33.608115) (xy 435.437697 -33.634779) (xy 435.451238 -33.658693) (xy 435.460648 -33.668716)
			(xy 435.924198 -34.132266) (xy 435.960012 -34.097722) (xy 435.981469 -34.077926) (xy 436.029273 -34.044422)
			(xy 436.081619 -34.018585) (xy 436.137289 -34.001016) (xy 436.194984 -33.992126) (xy 436.224172 -33.99155)
			(xy 436.251426 -33.992034) (xy 436.305379 -33.999787) (xy 436.357679 -34.015139) (xy 436.407263 -34.037778)
			(xy 436.45312 -34.067243) (xy 436.494317 -34.102934) (xy 436.530015 -34.144124) (xy 436.559488 -34.189976)
			(xy 436.582136 -34.239555) (xy 436.597498 -34.291853) (xy 436.605261 -34.345804) (xy 436.60568 -34.373058)
			(xy 436.605024 -34.405515) (xy 436.594035 -34.469492) (xy 436.583836 -34.500312) (xy 436.579574 -34.513566)
			(xy 436.577663 -34.541332) (xy 436.583315 -34.568583) (xy 436.596112 -34.593298) (xy 436.615103 -34.613643)
			(xy 436.63888 -34.628108) (xy 436.665678 -34.63562) (xy 436.679594 -34.635948)
		)
		(stroke
			(width 0)
			(type solid)
		)
		(fill yes)
		(layer "In15.Cu")
		(net "GND")
	)
	(gr_poly
		(pts
			(xy 183.642 -35.677348) (xy 183.65756 -35.65678) (xy 183.693636 -35.619924) (xy 183.734651 -35.588656)
			(xy 183.779747 -35.563632) (xy 183.82798 -35.545374) (xy 183.878343 -35.534264) (xy 183.929782 -35.530534)
			(xy 183.981221 -35.534264) (xy 184.031584 -35.545374) (xy 184.079817 -35.563632) (xy 184.124913 -35.588656)
			(xy 184.165928 -35.619924) (xy 184.202004 -35.65678) (xy 184.217564 -35.677348) (xy 185.22188 -35.677348)
			(xy 186.51728 -34.381948) (xy 186.51728 -32.888936) (xy 185.653172 -32.024828) (xy 185.642138 -32.014561)
			(xy 185.615553 -32.000394) (xy 185.585993 -31.994591) (xy 185.556026 -31.997658) (xy 185.528253 -32.009326)
			(xy 185.505088 -32.028583) (xy 185.488542 -32.053756) (xy 185.480053 -32.08266) (xy 185.47969 -32.097726)
			(xy 185.47969 -32.102552) (xy 185.479207 -32.130127) (xy 185.47127 -32.184703) (xy 185.455555 -32.237567)
			(xy 185.43239 -32.287617) (xy 185.402258 -32.333808) (xy 185.365787 -32.375177) (xy 185.34507 -32.393382)
			(xy 185.334169 -32.403282) (xy 185.318088 -32.427937) (xy 185.309696 -32.456151) (xy 185.309687 -32.485587)
			(xy 185.318062 -32.513806) (xy 185.334127 -32.538471) (xy 185.34507 -32.548322) (xy 185.365775 -32.566539)
			(xy 185.402237 -32.607911) (xy 185.432364 -32.654101) (xy 185.455528 -32.704148) (xy 185.471247 -32.757007)
			(xy 185.479192 -32.811579) (xy 185.47969 -32.839152) (xy 185.47969 -32.839406) (xy 185.479255 -32.865705)
			(xy 185.472036 -32.917804) (xy 185.457723 -32.968417) (xy 185.436588 -33.016581) (xy 185.409031 -33.061382)
			(xy 185.375576 -33.101968) (xy 185.3565 -33.120076) (xy 185.346473 -33.129888) (xy 185.331763 -33.153765)
			(xy 185.324114 -33.180746) (xy 185.324105 -33.20879) (xy 185.331737 -33.235776) (xy 185.346432 -33.259661)
			(xy 185.3565 -33.269428) (xy 185.375547 -33.287562) (xy 185.408981 -33.328157) (xy 185.436527 -33.372956)
			(xy 185.457663 -33.421112) (xy 185.47199 -33.471714) (xy 185.479236 -33.523803) (xy 185.47969 -33.550098)
			(xy 185.47969 -33.550352) (xy 185.479204 -33.577603) (xy 185.471448 -33.631551) (xy 185.456093 -33.683846)
			(xy 185.433451 -33.733423) (xy 185.403985 -33.779273) (xy 185.368294 -33.820464) (xy 185.327103 -33.856155)
			(xy 185.281253 -33.885621) (xy 185.231676 -33.908263) (xy 185.179381 -33.923618) (xy 185.125433 -33.931374)
			(xy 185.070931 -33.931374) (xy 185.016983 -33.923618) (xy 184.964688 -33.908263) (xy 184.915111 -33.885621)
			(xy 184.869261 -33.856155) (xy 184.82807 -33.820464) (xy 184.792379 -33.779273) (xy 184.762913 -33.733423)
			(xy 184.740271 -33.683846) (xy 184.724916 -33.631551) (xy 184.71716 -33.577603) (xy 184.716674 -33.550352)
			(xy 184.716674 -33.550098) (xy 184.717109 -33.5238) (xy 184.724328 -33.471701) (xy 184.738642 -33.421089)
			(xy 184.75978 -33.372927) (xy 184.78734 -33.328129) (xy 184.820798 -33.287546) (xy 184.839864 -33.269428)
			(xy 184.849881 -33.259618) (xy 184.86457 -33.235749) (xy 184.8722 -33.208781) (xy 184.872191 -33.180754)
			(xy 184.864544 -33.153791) (xy 184.849839 -33.129932) (xy 184.839864 -33.120076) (xy 184.820818 -33.101941)
			(xy 184.787387 -33.061345) (xy 184.759843 -33.016546) (xy 184.738708 -32.96839) (xy 184.724383 -32.917789)
			(xy 184.717137 -32.865701) (xy 184.716674 -32.839406) (xy 184.716674 -32.839152) (xy 184.717157 -32.811576)
			(xy 184.725093 -32.756999) (xy 184.740806 -32.704134) (xy 184.763969 -32.654083) (xy 184.794099 -32.607889)
			(xy 184.830568 -32.566517) (xy 184.851294 -32.548322) (xy 184.862185 -32.538424) (xy 184.878244 -32.513778)
			(xy 184.886617 -32.485577) (xy 184.886608 -32.456161) (xy 184.878218 -32.427966) (xy 184.862143 -32.403329)
			(xy 184.851294 -32.393382) (xy 184.830591 -32.375164) (xy 184.794131 -32.333791) (xy 184.764007 -32.2876)
			(xy 184.740844 -32.237554) (xy 184.725127 -32.184696) (xy 184.717182 -32.130125) (xy 184.716674 -32.102552)
			(xy 184.717163 -32.075303) (xy 184.724925 -32.021359) (xy 184.740284 -31.969069) (xy 184.762928 -31.919497)
			(xy 184.792395 -31.873651) (xy 184.828086 -31.832465) (xy 184.869275 -31.796777) (xy 184.915123 -31.767313)
			(xy 184.964697 -31.744674) (xy 185.016988 -31.729319) (xy 185.070932 -31.721561) (xy 185.098182 -31.721044)
			(xy 185.103008 -31.721044) (xy 185.11807 -31.72065) (xy 185.146964 -31.712156) (xy 185.172128 -31.695611)
			(xy 185.191379 -31.672452) (xy 185.203046 -31.644688) (xy 185.206116 -31.614729) (xy 185.200323 -31.585175)
			(xy 185.18617 -31.558592) (xy 185.175906 -31.547562) (xy 181.111652 -27.483308) (xy 181.083458 -27.452828)
			(xy 181.05801 -27.464181) (xy 181.004647 -27.480228) (xy 180.949521 -27.488363) (xy 180.92166 -27.488896)
			(xy 180.894411 -27.488407) (xy 180.840468 -27.480646) (xy 180.788179 -27.465287) (xy 180.738608 -27.442644)
			(xy 180.692763 -27.413176) (xy 180.651579 -27.377484) (xy 180.615893 -27.336295) (xy 180.586432 -27.290447)
			(xy 180.563795 -27.240872) (xy 180.548443 -27.188581) (xy 180.540689 -27.134637) (xy 180.540152 -27.107388)
			(xy 180.540673 -27.078652) (xy 180.549293 -27.021829) (xy 180.566335 -26.966941) (xy 180.591415 -26.915229)
			(xy 180.623965 -26.867863) (xy 180.663249 -26.825912) (xy 180.70838 -26.790326) (xy 180.758336 -26.76191)
			(xy 180.811988 -26.741305) (xy 180.868123 -26.728978) (xy 180.896768 -26.726642) (xy 180.944012 -26.676096)
			(xy 180.944012 -26.596086) (xy 180.916767 -26.594493) (xy 180.863201 -26.584056) (xy 180.811854 -26.56557)
			(xy 180.763929 -26.539467) (xy 180.720546 -26.506358) (xy 180.682723 -26.467018) (xy 180.651343 -26.422369)
			(xy 180.627142 -26.373455) (xy 180.610686 -26.321422) (xy 180.602361 -26.267488) (xy 180.60236 -26.212915)
			(xy 180.610685 -26.15898) (xy 180.627141 -26.106947) (xy 180.651342 -26.058033) (xy 180.682721 -26.013384)
			(xy 180.720545 -25.974044) (xy 180.763927 -25.940935) (xy 180.811852 -25.914831) (xy 180.863199 -25.896344)
			(xy 180.916764 -25.885907) (xy 180.944012 -25.884378) (xy 180.944012 -22.957028) (xy 179.723796 -21.736558)
			(xy 179.713007 -21.726465) (xy 179.687032 -21.712415) (xy 179.658125 -21.706378) (xy 179.628698 -21.708856)
			(xy 179.601208 -21.719644) (xy 179.577949 -21.737841) (xy 179.560863 -21.761928) (xy 179.551377 -21.789894)
			(xy 179.550314 -21.80463) (xy 179.548913 -21.831237) (xy 179.539647 -21.883706) (xy 179.523171 -21.934375)
			(xy 179.499807 -21.982259) (xy 179.470007 -22.026427) (xy 179.434351 -22.066018) (xy 179.393535 -22.100264)
			(xy 179.34835 -22.128498) (xy 179.299677 -22.150171) (xy 179.248461 -22.164861) (xy 179.1957 -22.172282)
			(xy 179.16906 -22.172676) (xy 179.142564 -22.17222) (xy 179.090082 -22.164883) (xy 179.039119 -22.150357)
			(xy 178.990656 -22.12892) (xy 178.945624 -22.100986) (xy 178.90489 -22.06709) (xy 178.869236 -22.027885)
			(xy 178.839349 -21.984124) (xy 178.827176 -21.960586) (xy 178.820023 -21.94729) (xy 178.799368 -21.925293)
			(xy 178.773183 -21.910296) (xy 178.743758 -21.90361) (xy 178.713664 -21.905818) (xy 178.699414 -21.910802)
			(xy 178.677421 -21.91891) (xy 178.631956 -21.930321) (xy 178.585437 -21.936093) (xy 178.562 -21.936456)
			(xy 178.534745 -21.93597) (xy 178.480791 -21.928213) (xy 178.428489 -21.912856) (xy 178.378906 -21.890212)
			(xy 178.33305 -21.860742) (xy 178.291854 -21.825046) (xy 178.256158 -21.78385) (xy 178.226688 -21.737994)
			(xy 178.204044 -21.688411) (xy 178.188687 -21.636109) (xy 178.18093 -21.582155) (xy 178.18093 -21.527645)
			(xy 178.188687 -21.473691) (xy 178.204044 -21.421389) (xy 178.226688 -21.371806) (xy 178.256158 -21.32595)
			(xy 178.291854 -21.284754) (xy 178.33305 -21.249058) (xy 178.378906 -21.219588) (xy 178.428489 -21.196944)
			(xy 178.480791 -21.181587) (xy 178.534745 -21.17383) (xy 178.562 -21.17344) (xy 178.588497 -21.173894)
			(xy 178.640983 -21.181226) (xy 178.691949 -21.195748) (xy 178.740415 -21.217183) (xy 178.785451 -21.245116)
			(xy 178.826188 -21.279011) (xy 178.861845 -21.318217) (xy 178.891734 -21.361979) (xy 178.903884 -21.38553)
			(xy 178.911039 -21.398817) (xy 178.931696 -21.420797) (xy 178.957877 -21.435776) (xy 178.987293 -21.442447)
			(xy 179.017374 -21.440225) (xy 179.031646 -21.435314) (xy 179.06154 -21.424456) (xy 179.123843 -21.411695)
			(xy 179.155598 -21.409914) (xy 179.17035 -21.408902) (xy 179.198357 -21.399461) (xy 179.222484 -21.38239)
			(xy 179.240707 -21.359121) (xy 179.251497 -21.331606) (xy 179.25395 -21.302152) (xy 179.247859 -21.273231)
			(xy 179.233735 -21.247268) (xy 179.22367 -21.236432) (xy 178.858672 -20.871434) (xy 178.836275 -20.848441)
			(xy 178.796234 -20.798269) (xy 178.762064 -20.743929) (xy 178.734193 -20.686105) (xy 178.712972 -20.625523)
			(xy 178.698668 -20.562946) (xy 178.691462 -20.499161) (xy 178.691032 -20.467066) (xy 178.691032 -20.002754)
			(xy 178.06162 -19.373088) (xy 178.032918 -19.38147) (xy 178.007002 -19.388481) (xy 177.953844 -19.396005)
			(xy 177.927 -19.396456) (xy 177.899748 -19.39597) (xy 177.845797 -19.388214) (xy 177.7935 -19.372859)
			(xy 177.743919 -19.350219) (xy 177.698066 -19.320753) (xy 177.656871 -19.285063) (xy 177.621175 -19.243873)
			(xy 177.591704 -19.198023) (xy 177.569057 -19.148445) (xy 177.553696 -19.09615) (xy 177.545933 -19.0422)
			(xy 177.545492 -19.014948) (xy 177.545945 -18.988104) (xy 177.553459 -18.934944) (xy 177.560478 -18.90903)
			(xy 177.56886 -18.880328) (xy 177.52568 -18.837148) (xy 175.945292 -18.837148) (xy 175.940466 -18.838164)
			(xy 175.922236 -18.841515) (xy 175.88534 -18.845077) (xy 175.866806 -18.845276) (xy 175.848272 -18.845069)
			(xy 175.811376 -18.84151) (xy 175.793146 -18.838164) (xy 175.78832 -18.837148) (xy 174.960026 -18.837148)
			(xy 174.941816 -18.858297) (xy 174.90027 -18.895561) (xy 174.853738 -18.926374) (xy 174.803213 -18.950077)
			(xy 174.749774 -18.966167) (xy 174.69456 -18.974298) (xy 174.638752 -18.974298) (xy 174.583538 -18.966167)
			(xy 174.530099 -18.950077) (xy 174.479574 -18.926374) (xy 174.433042 -18.895561) (xy 174.391496 -18.858297)
			(xy 174.373286 -18.837148) (xy 173.15688 -18.837148) (xy 173.120558 -18.87347) (xy 173.111206 -18.883493)
			(xy 173.09773 -18.907353) (xy 173.091083 -18.933936) (xy 173.091741 -18.96133) (xy 173.099659 -18.987563)
			(xy 173.114266 -19.010748) (xy 173.124114 -19.020282) (xy 173.143318 -19.03843) (xy 173.177042 -19.079107)
			(xy 173.20483 -19.124047) (xy 173.226151 -19.172393) (xy 173.240598 -19.223217) (xy 173.247893 -19.275549)
			(xy 173.24832 -19.301968) (xy 173.247859 -19.329223) (xy 173.240106 -19.383178) (xy 173.224753 -19.43548)
			(xy 173.202112 -19.485065) (xy 173.172645 -19.530923) (xy 173.136952 -19.572121) (xy 173.095759 -19.607819)
			(xy 173.049904 -19.637291) (xy 173.000321 -19.659938) (xy 172.948021 -19.675297) (xy 172.894067 -19.683056)
			(xy 172.866812 -19.683476) (xy 172.840393 -19.683028) (xy 172.78806 -19.67574) (xy 172.737234 -19.6613)
			(xy 172.688885 -19.639986) (xy 172.64394 -19.612206) (xy 172.603258 -19.578489) (xy 172.585126 -19.55927)
			(xy 172.575582 -19.549416) (xy 172.552412 -19.534752) (xy 172.52617 -19.526797) (xy 172.498757 -19.526128)
			(xy 172.472158 -19.532793) (xy 172.4483 -19.54631) (xy 172.438314 -19.555714) (xy 172.05198 -19.942048)
			(xy 176.496472 -19.942048) (xy 176.496958 -19.914797) (xy 176.504714 -19.860849) (xy 176.520069 -19.808554)
			(xy 176.542711 -19.758977) (xy 176.572177 -19.713127) (xy 176.607868 -19.671936) (xy 176.649059 -19.636245)
			(xy 176.694909 -19.606779) (xy 176.744486 -19.584137) (xy 176.796781 -19.568782) (xy 176.850729 -19.561026)
			(xy 176.905231 -19.561026) (xy 176.959179 -19.568782) (xy 177.011474 -19.584137) (xy 177.061051 -19.606779)
			(xy 177.106901 -19.636245) (xy 177.148092 -19.671936) (xy 177.183783 -19.713127) (xy 177.213249 -19.758977)
			(xy 177.235891 -19.808554) (xy 177.251246 -19.860849) (xy 177.259002 -19.914797) (xy 177.259488 -19.942048)
			(xy 177.25908 -19.968062) (xy 177.252003 -20.019606) (xy 177.237988 -20.06971) (xy 177.217293 -20.117445)
			(xy 177.190304 -20.161925) (xy 177.157521 -20.202325) (xy 177.138838 -20.220432) (xy 177.12914 -20.230009)
			(xy 177.114828 -20.253195) (xy 177.107164 -20.279342) (xy 177.106696 -20.306585) (xy 177.113457 -20.332981)
			(xy 177.126965 -20.356644) (xy 177.146255 -20.375887) (xy 177.157888 -20.382992) (xy 177.182525 -20.397672)
			(xy 177.227509 -20.433241) (xy 177.266661 -20.475145) (xy 177.299097 -20.522439) (xy 177.324086 -20.574056)
			(xy 177.341064 -20.628833) (xy 177.34965 -20.685534) (xy 177.350166 -20.714208) (xy 177.349713 -20.741579)
			(xy 177.341893 -20.795759) (xy 177.326402 -20.848262) (xy 177.303557 -20.898009) (xy 177.273829 -20.943975)
			(xy 177.256186 -20.964906) (xy 177.246943 -20.976228) (xy 177.234768 -21.002788) (xy 177.230597 -21.031706)
			(xy 177.234771 -21.060624) (xy 177.246949 -21.087182) (xy 177.256186 -21.09851) (xy 177.273841 -21.119429)
			(xy 177.303551 -21.165405) (xy 177.326384 -21.215156) (xy 177.341871 -21.26766) (xy 177.349695 -21.321838)
			(xy 177.350166 -21.349208) (xy 177.349912 -21.365718) (xy 177.349784 -21.379791) (xy 177.356241 -21.407169)
			(xy 177.369933 -21.431741) (xy 177.389819 -21.451637) (xy 177.414384 -21.465341) (xy 177.441759 -21.471811)
			(xy 177.45583 -21.471636) (xy 177.47234 -21.471382) (xy 177.499588 -21.471921) (xy 177.553528 -21.479682)
			(xy 177.605815 -21.495041) (xy 177.655384 -21.517684) (xy 177.701226 -21.547151) (xy 177.742408 -21.582842)
			(xy 177.778091 -21.62403) (xy 177.80755 -21.669878) (xy 177.830184 -21.719451) (xy 177.845533 -21.77174)
			(xy 177.853284 -21.825682) (xy 177.85328 -21.880178) (xy 177.84552 -21.934118) (xy 177.830163 -21.986406)
			(xy 177.807521 -22.035975) (xy 177.778055 -22.081818) (xy 177.742365 -22.123001) (xy 177.701178 -22.158685)
			(xy 177.655331 -22.188145) (xy 177.605759 -22.21078) (xy 177.553469 -22.226131) (xy 177.499528 -22.233883)
			(xy 177.445032 -22.23388) (xy 177.391091 -22.226122) (xy 177.338804 -22.210766) (xy 177.289234 -22.188126)
			(xy 177.24339 -22.158661) (xy 177.202206 -22.122972) (xy 177.166521 -22.081786) (xy 177.13706 -22.03594)
			(xy 177.114423 -21.986368) (xy 177.099071 -21.934079) (xy 177.091317 -21.880138) (xy 177.090832 -21.85289)
			(xy 177.091086 -21.83638) (xy 177.091218 -21.822307) (xy 177.08476 -21.794928) (xy 177.071067 -21.770356)
			(xy 177.051181 -21.750461) (xy 177.026615 -21.736756) (xy 176.999239 -21.730286) (xy 176.985168 -21.730462)
			(xy 176.968658 -21.730716) (xy 176.941406 -21.730261) (xy 176.887458 -21.722499) (xy 176.835163 -21.707139)
			(xy 176.785586 -21.684494) (xy 176.739736 -21.655024) (xy 176.698547 -21.619329) (xy 176.662856 -21.578137)
			(xy 176.63339 -21.532284) (xy 176.610749 -21.482705) (xy 176.595394 -21.430409) (xy 176.587636 -21.37646)
			(xy 176.58715 -21.349208) (xy 176.587609 -21.321837) (xy 176.595426 -21.267657) (xy 176.610916 -21.215154)
			(xy 176.63376 -21.165407) (xy 176.663487 -21.119441) (xy 176.68113 -21.09851) (xy 176.690357 -21.087176)
			(xy 176.702531 -21.06062) (xy 176.706704 -21.031706) (xy 176.702535 -21.002792) (xy 176.690363 -20.976234)
			(xy 176.68113 -20.964906) (xy 176.663485 -20.943979) (xy 176.633773 -20.898005) (xy 176.610938 -20.848256)
			(xy 176.595448 -20.795754) (xy 176.587622 -20.741578) (xy 176.58715 -20.714208) (xy 176.587614 -20.688196)
			(xy 176.594682 -20.636655) (xy 176.608688 -20.586553) (xy 176.629372 -20.538818) (xy 176.65635 -20.494336)
			(xy 176.689122 -20.453933) (xy 176.7078 -20.435824) (xy 176.717428 -20.426183) (xy 176.731736 -20.403013)
			(xy 176.739402 -20.376882) (xy 176.739878 -20.349654) (xy 176.733131 -20.32327) (xy 176.719642 -20.299614)
			(xy 176.700372 -20.280371) (xy 176.68875 -20.273264) (xy 176.664102 -20.258601) (xy 176.619116 -20.22303)
			(xy 176.579964 -20.181124) (xy 176.547528 -20.133828) (xy 176.522541 -20.082208) (xy 176.505566 -20.027428)
			(xy 176.496985 -19.970723) (xy 176.496472 -19.942048) (xy 172.05198 -19.942048) (xy 171.677076 -20.316952)
			(xy 171.689014 -20.34794) (xy 171.697119 -20.369934) (xy 171.708522 -20.415399) (xy 171.714289 -20.461917)
			(xy 171.714668 -20.485354) (xy 171.714668 -20.485608) (xy 171.714204 -20.512859) (xy 171.706446 -20.566807)
			(xy 171.691089 -20.619102) (xy 171.668445 -20.668679) (xy 171.638976 -20.714528) (xy 171.603282 -20.755716)
			(xy 171.562089 -20.791405) (xy 171.516236 -20.820868) (xy 171.466657 -20.843506) (xy 171.41436 -20.858856)
			(xy 171.360412 -20.866608) (xy 171.33316 -20.867116) (xy 171.332906 -20.867116) (xy 171.309466 -20.866776)
			(xy 171.262942 -20.861026) (xy 171.217476 -20.849599) (xy 171.195492 -20.841462) (xy 171.164504 -20.829524)
			(xy 170.84548 -21.148548) (xy 170.84548 -21.85035) (xy 170.846032 -21.865638) (xy 170.855137 -21.894831)
			(xy 170.87246 -21.920031) (xy 170.896454 -21.938989) (xy 170.924977 -21.950013) (xy 170.955484 -21.952119)
			(xy 170.985252 -21.945118) (xy 170.998642 -21.937726) (xy 171.020772 -21.925132) (xy 171.06766 -21.905279)
			(xy 171.116774 -21.891845) (xy 171.167239 -21.885067) (xy 171.192698 -21.88464) (xy 171.219948 -21.885103)
			(xy 171.273892 -21.892859) (xy 171.326183 -21.908213) (xy 171.375758 -21.930852) (xy 171.421605 -21.960317)
			(xy 171.462793 -21.996006) (xy 171.498482 -22.037193) (xy 171.527947 -22.083041) (xy 171.550587 -22.132615)
			(xy 171.565941 -22.184906) (xy 171.573697 -22.23885) (xy 171.573697 -22.29335) (xy 171.565941 -22.347294)
			(xy 171.550587 -22.399585) (xy 171.527947 -22.449159) (xy 171.498482 -22.495007) (xy 171.462793 -22.536194)
			(xy 171.421605 -22.571883) (xy 171.375758 -22.601348) (xy 171.326183 -22.623987) (xy 171.273892 -22.639341)
			(xy 171.219948 -22.647097) (xy 171.192698 -22.647656) (xy 171.167239 -22.647232) (xy 171.116775 -22.640453)
			(xy 171.067662 -22.627015) (xy 171.020776 -22.607157) (xy 170.998642 -22.59457) (xy 170.985209 -22.587259)
			(xy 170.955458 -22.580231) (xy 170.92496 -22.582316) (xy 170.896442 -22.593326) (xy 170.872455 -22.612277)
			(xy 170.855146 -22.637474) (xy 170.846062 -22.666662) (xy 170.84548 -22.681946) (xy 170.84548 -22.723348)
			(xy 171.784262 -22.723348) (xy 171.788333 -22.667726) (xy 171.800459 -22.613289) (xy 171.820382 -22.561198)
			(xy 171.847678 -22.512563) (xy 171.881764 -22.46842) (xy 171.921913 -22.429711) (xy 171.967271 -22.39726)
			(xy 172.016871 -22.371759) (xy 172.069655 -22.353752) (xy 172.124498 -22.343622) (xy 172.180232 -22.341585)
			(xy 172.235669 -22.347685) (xy 172.289626 -22.361791) (xy 172.340955 -22.383603) (xy 172.388561 -22.412657)
			(xy 172.431429 -22.448332) (xy 172.468646 -22.489869) (xy 172.499419 -22.536382) (xy 172.523091 -22.586879)
			(xy 172.539159 -22.640286) (xy 172.547279 -22.695462) (xy 172.547788 -22.723348) (xy 172.547279 -22.751234)
			(xy 172.539159 -22.80641) (xy 172.523091 -22.859817) (xy 172.499419 -22.910314) (xy 172.468646 -22.956827)
			(xy 172.431429 -22.998364) (xy 172.388561 -23.034039) (xy 172.340955 -23.063093) (xy 172.289626 -23.084905)
			(xy 172.235669 -23.099011) (xy 172.180232 -23.105111) (xy 172.124498 -23.103074) (xy 172.069655 -23.092944)
			(xy 172.016871 -23.074937) (xy 171.967271 -23.049436) (xy 171.921913 -23.016985) (xy 171.881764 -22.978276)
			(xy 171.847678 -22.934133) (xy 171.820382 -22.885498) (xy 171.800459 -22.833407) (xy 171.788333 -22.77897)
			(xy 171.784262 -22.723348) (xy 170.84548 -22.723348) (xy 170.84548 -22.97176) (xy 170.859366 -22.996765)
			(xy 170.880307 -23.049987) (xy 170.893065 -23.105739) (xy 170.897352 -23.162772) (xy 170.893073 -23.219806)
			(xy 170.880324 -23.27556) (xy 170.85939 -23.328785) (xy 170.84548 -23.353776) (xy 170.84548 -25.517348)
			(xy 179.124862 -25.517348) (xy 179.128933 -25.461726) (xy 179.141059 -25.407289) (xy 179.160982 -25.355198)
			(xy 179.188278 -25.306563) (xy 179.222364 -25.26242) (xy 179.262513 -25.223711) (xy 179.307871 -25.19126)
			(xy 179.357471 -25.165759) (xy 179.410255 -25.147752) (xy 179.465098 -25.137622) (xy 179.520832 -25.135585)
			(xy 179.576269 -25.141685) (xy 179.630226 -25.155791) (xy 179.681555 -25.177603) (xy 179.729161 -25.206657)
			(xy 179.772029 -25.242332) (xy 179.809246 -25.283869) (xy 179.840019 -25.330382) (xy 179.863691 -25.380879)
			(xy 179.879759 -25.434286) (xy 179.887879 -25.489462) (xy 179.888388 -25.517348) (xy 179.887879 -25.545234)
			(xy 179.879759 -25.60041) (xy 179.863691 -25.653817) (xy 179.840019 -25.704314) (xy 179.809246 -25.750827)
			(xy 179.772029 -25.792364) (xy 179.729161 -25.828039) (xy 179.681555 -25.857093) (xy 179.630226 -25.878905)
			(xy 179.576269 -25.893011) (xy 179.520832 -25.899111) (xy 179.465098 -25.897074) (xy 179.410255 -25.886944)
			(xy 179.357471 -25.868937) (xy 179.307871 -25.843436) (xy 179.262513 -25.810985) (xy 179.222364 -25.772276)
			(xy 179.188278 -25.728133) (xy 179.160982 -25.679498) (xy 179.141059 -25.627407) (xy 179.128933 -25.57297)
			(xy 179.124862 -25.517348) (xy 170.84548 -25.517348) (xy 170.84548 -26.321512) (xy 171.947586 -26.321512)
			(xy 171.971108 -26.306497) (xy 172.021616 -26.282768) (xy 172.075044 -26.266658) (xy 172.13025 -26.258512)
			(xy 172.158152 -26.258012) (xy 172.15866 -26.258012) (xy 172.185093 -26.258464) (xy 172.237452 -26.265765)
			(xy 172.288303 -26.280217) (xy 172.336676 -26.301545) (xy 172.381644 -26.329342) (xy 172.422348 -26.363075)
			(xy 172.45801 -26.4021) (xy 172.473366 -26.42362) (xy 172.482304 -26.435735) (xy 172.505789 -26.454547)
			(xy 172.533737 -26.465698) (xy 172.563722 -26.468222) (xy 172.59314 -26.461897) (xy 172.619439 -26.447274)
			(xy 172.640335 -26.425622) (xy 172.64761 -26.412444) (xy 172.659909 -26.38928) (xy 172.689906 -26.34626)
			(xy 172.72551 -26.307752) (xy 172.766053 -26.274483) (xy 172.810769 -26.247079) (xy 172.858817 -26.226055)
			(xy 172.90929 -26.211809) (xy 172.961239 -26.204609) (xy 172.987462 -26.204164) (xy 173.014719 -26.204624)
			(xy 173.068678 -26.212377) (xy 173.120984 -26.227731) (xy 173.170573 -26.250373) (xy 173.216434 -26.279843)
			(xy 173.257634 -26.315539) (xy 173.293335 -26.356736) (xy 173.322808 -26.402594) (xy 173.345455 -26.45218)
			(xy 173.360814 -26.504485) (xy 173.368573 -26.558443) (xy 173.368573 -26.612957) (xy 173.365411 -26.634948)
			(xy 175.950372 -26.634948) (xy 175.950906 -26.607186) (xy 175.958947 -26.552249) (xy 175.974868 -26.499058)
			(xy 175.998332 -26.448736) (xy 176.028842 -26.402347) (xy 176.065755 -26.360872) (xy 176.10829 -26.325185)
			(xy 176.155549 -26.296041) (xy 176.206534 -26.274056) (xy 176.260168 -26.259694) (xy 176.287684 -26.25598)
			(xy 176.301308 -26.253896) (xy 176.326816 -26.243495) (xy 176.348612 -26.226649) (xy 176.365105 -26.204584)
			(xy 176.375093 -26.178912) (xy 176.377847 -26.151502) (xy 176.373168 -26.124356) (xy 176.367694 -26.111708)
			(xy 176.356227 -26.086205) (xy 176.340069 -26.032674) (xy 176.33188 -25.97736) (xy 176.331372 -25.949402)
			(xy 176.331372 -25.949148) (xy 176.331858 -25.921897) (xy 176.339614 -25.867949) (xy 176.354969 -25.815654)
			(xy 176.377611 -25.766077) (xy 176.407077 -25.720227) (xy 176.442768 -25.679036) (xy 176.483959 -25.643345)
			(xy 176.529809 -25.613879) (xy 176.579386 -25.591237) (xy 176.631681 -25.575882) (xy 176.685629 -25.568126)
			(xy 176.740131 -25.568126) (xy 176.794079 -25.575882) (xy 176.846374 -25.591237) (xy 176.895951 -25.613879)
			(xy 176.941801 -25.643345) (xy 176.982992 -25.679036) (xy 177.018683 -25.720227) (xy 177.048149 -25.766077)
			(xy 177.070791 -25.815654) (xy 177.086146 -25.867949) (xy 177.093902 -25.921897) (xy 177.094388 -25.949148)
			(xy 177.094388 -25.949656) (xy 177.093874 -25.977897) (xy 177.085507 -26.033757) (xy 177.068993 -26.087772)
			(xy 177.057304 -26.113486) (xy 177.051815 -26.126112) (xy 177.047046 -26.153215) (xy 177.049687 -26.180608)
			(xy 177.059546 -26.206301) (xy 177.075906 -26.228429) (xy 177.097581 -26.245385) (xy 177.122996 -26.255939)
			(xy 177.150306 -26.259324) (xy 177.163984 -26.257758) (xy 177.176684 -26.25598) (xy 177.190308 -26.253896)
			(xy 177.215816 -26.243495) (xy 177.237612 -26.226649) (xy 177.254105 -26.204584) (xy 177.264093 -26.178912)
			(xy 177.266847 -26.151502) (xy 177.262168 -26.124356) (xy 177.256694 -26.111708) (xy 177.245227 -26.086205)
			(xy 177.229069 -26.032674) (xy 177.22088 -25.97736) (xy 177.220372 -25.949402) (xy 177.220372 -25.949148)
			(xy 177.220858 -25.921897) (xy 177.228614 -25.867949) (xy 177.243969 -25.815654) (xy 177.266611 -25.766077)
			(xy 177.296077 -25.720227) (xy 177.331768 -25.679036) (xy 177.372959 -25.643345) (xy 177.418809 -25.613879)
			(xy 177.468386 -25.591237) (xy 177.520681 -25.575882) (xy 177.574629 -25.568126) (xy 177.629131 -25.568126)
			(xy 177.683079 -25.575882) (xy 177.735374 -25.591237) (xy 177.784951 -25.613879) (xy 177.830801 -25.643345)
			(xy 177.871992 -25.679036) (xy 177.907683 -25.720227) (xy 177.937149 -25.766077) (xy 177.959791 -25.815654)
			(xy 177.975146 -25.867949) (xy 177.982902 -25.921897) (xy 177.983388 -25.949148) (xy 177.983388 -25.949656)
			(xy 177.982874 -25.977897) (xy 177.974507 -26.033757) (xy 177.957993 -26.087772) (xy 177.946304 -26.113486)
			(xy 177.940815 -26.126112) (xy 177.936046 -26.153215) (xy 177.938687 -26.180608) (xy 177.948546 -26.206301)
			(xy 177.964906 -26.228429) (xy 177.986581 -26.245385) (xy 178.011996 -26.255939) (xy 178.039306 -26.259324)
			(xy 178.052984 -26.257758) (xy 178.065684 -26.25598) (xy 178.079308 -26.253896) (xy 178.104816 -26.243495)
			(xy 178.126612 -26.226649) (xy 178.143105 -26.204584) (xy 178.153093 -26.178912) (xy 178.155847 -26.151502)
			(xy 178.151168 -26.124356) (xy 178.145694 -26.111708) (xy 178.134227 -26.086205) (xy 178.118069 -26.032674)
			(xy 178.10988 -25.97736) (xy 178.109372 -25.949402) (xy 178.109372 -25.949148) (xy 178.109858 -25.921897)
			(xy 178.117614 -25.867949) (xy 178.132969 -25.815654) (xy 178.155611 -25.766077) (xy 178.185077 -25.720227)
			(xy 178.220768 -25.679036) (xy 178.261959 -25.643345) (xy 178.307809 -25.613879) (xy 178.357386 -25.591237)
			(xy 178.409681 -25.575882) (xy 178.463629 -25.568126) (xy 178.518131 -25.568126) (xy 178.572079 -25.575882)
			(xy 178.624374 -25.591237) (xy 178.673951 -25.613879) (xy 178.719801 -25.643345) (xy 178.760992 -25.679036)
			(xy 178.796683 -25.720227) (xy 178.826149 -25.766077) (xy 178.848791 -25.815654) (xy 178.864146 -25.867949)
			(xy 178.871902 -25.921897) (xy 178.872388 -25.949148) (xy 178.871886 -25.976911) (xy 178.863844 -26.031852)
			(xy 178.847921 -26.085046) (xy 178.824455 -26.135369) (xy 178.793942 -26.18176) (xy 178.757025 -26.223236)
			(xy 178.714485 -26.258922) (xy 178.667221 -26.288064) (xy 178.616232 -26.310046) (xy 178.562594 -26.324404)
			(xy 178.535076 -26.328116) (xy 178.521432 -26.330108) (xy 178.495903 -26.340509) (xy 178.474092 -26.357367)
			(xy 178.457592 -26.37945) (xy 178.447608 -26.405145) (xy 178.444869 -26.432575) (xy 178.449576 -26.459737)
			(xy 178.455066 -26.472388) (xy 178.466529 -26.497892) (xy 178.48269 -26.551423) (xy 178.490879 -26.606736)
			(xy 178.491388 -26.634694) (xy 178.491388 -26.634948) (xy 178.490902 -26.662199) (xy 178.483146 -26.716147)
			(xy 178.467791 -26.768442) (xy 178.445149 -26.818019) (xy 178.415683 -26.863869) (xy 178.379992 -26.90506)
			(xy 178.338801 -26.940751) (xy 178.292951 -26.970217) (xy 178.243374 -26.992859) (xy 178.191079 -27.008214)
			(xy 178.137131 -27.01597) (xy 178.082629 -27.01597) (xy 178.028681 -27.008214) (xy 177.976386 -26.992859)
			(xy 177.926809 -26.970217) (xy 177.880959 -26.940751) (xy 177.839768 -26.90506) (xy 177.804077 -26.863869)
			(xy 177.774611 -26.818019) (xy 177.751969 -26.768442) (xy 177.736614 -26.716147) (xy 177.728858 -26.662199)
			(xy 177.728372 -26.634948) (xy 177.728372 -26.63444) (xy 177.728887 -26.606199) (xy 177.737255 -26.550339)
			(xy 177.753768 -26.496324) (xy 177.765456 -26.47061) (xy 177.770991 -26.458001) (xy 177.775763 -26.430889)
			(xy 177.773122 -26.403487) (xy 177.763258 -26.377786) (xy 177.74689 -26.355653) (xy 177.725205 -26.338695)
			(xy 177.699778 -26.328144) (xy 177.672458 -26.324766) (xy 177.658776 -26.326338) (xy 177.646076 -26.328116)
			(xy 177.632432 -26.330108) (xy 177.606903 -26.340509) (xy 177.585092 -26.357367) (xy 177.568592 -26.37945)
			(xy 177.558608 -26.405145) (xy 177.555869 -26.432575) (xy 177.560576 -26.459737) (xy 177.566066 -26.472388)
			(xy 177.577529 -26.497892) (xy 177.59369 -26.551423) (xy 177.601879 -26.606736) (xy 177.602388 -26.634694)
			(xy 177.602388 -26.634948) (xy 177.601902 -26.662199) (xy 177.594146 -26.716147) (xy 177.578791 -26.768442)
			(xy 177.556149 -26.818019) (xy 177.526683 -26.863869) (xy 177.490992 -26.90506) (xy 177.449801 -26.940751)
			(xy 177.403951 -26.970217) (xy 177.354374 -26.992859) (xy 177.302079 -27.008214) (xy 177.248131 -27.01597)
			(xy 177.193629 -27.01597) (xy 177.139681 -27.008214) (xy 177.087386 -26.992859) (xy 177.037809 -26.970217)
			(xy 176.991959 -26.940751) (xy 176.950768 -26.90506) (xy 176.915077 -26.863869) (xy 176.885611 -26.818019)
			(xy 176.862969 -26.768442) (xy 176.847614 -26.716147) (xy 176.839858 -26.662199) (xy 176.839372 -26.634948)
			(xy 176.839372 -26.63444) (xy 176.839887 -26.606199) (xy 176.848255 -26.550339) (xy 176.864768 -26.496324)
			(xy 176.876456 -26.47061) (xy 176.881991 -26.458001) (xy 176.886763 -26.430889) (xy 176.884122 -26.403487)
			(xy 176.874258 -26.377786) (xy 176.85789 -26.355653) (xy 176.836205 -26.338695) (xy 176.810778 -26.328144)
			(xy 176.783458 -26.324766) (xy 176.769776 -26.326338) (xy 176.757076 -26.328116) (xy 176.743432 -26.330108)
			(xy 176.717903 -26.340509) (xy 176.696092 -26.357367) (xy 176.679592 -26.37945) (xy 176.669608 -26.405145)
			(xy 176.666869 -26.432575) (xy 176.671576 -26.459737) (xy 176.677066 -26.472388) (xy 176.688529 -26.497892)
			(xy 176.70469 -26.551423) (xy 176.712879 -26.606736) (xy 176.713388 -26.634694) (xy 176.713388 -26.634948)
			(xy 176.712902 -26.662199) (xy 176.705146 -26.716147) (xy 176.689791 -26.768442) (xy 176.667149 -26.818019)
			(xy 176.637683 -26.863869) (xy 176.601992 -26.90506) (xy 176.560801 -26.940751) (xy 176.514951 -26.970217)
			(xy 176.465374 -26.992859) (xy 176.413079 -27.008214) (xy 176.359131 -27.01597) (xy 176.304629 -27.01597)
			(xy 176.250681 -27.008214) (xy 176.198386 -26.992859) (xy 176.148809 -26.970217) (xy 176.102959 -26.940751)
			(xy 176.061768 -26.90506) (xy 176.026077 -26.863869) (xy 175.996611 -26.818019) (xy 175.973969 -26.768442)
			(xy 175.958614 -26.716147) (xy 175.950858 -26.662199) (xy 175.950372 -26.634948) (xy 173.365411 -26.634948)
			(xy 173.360814 -26.666915) (xy 173.345455 -26.71922) (xy 173.322808 -26.768806) (xy 173.293335 -26.814664)
			(xy 173.257634 -26.855861) (xy 173.216434 -26.891557) (xy 173.170573 -26.921027) (xy 173.120984 -26.943669)
			(xy 173.068678 -26.959023) (xy 173.014719 -26.966776) (xy 172.987462 -26.96718) (xy 172.961029 -26.966729)
			(xy 172.908668 -26.959431) (xy 172.857815 -26.944981) (xy 172.80944 -26.923654) (xy 172.764471 -26.895859)
			(xy 172.723765 -26.862126) (xy 172.688101 -26.8231) (xy 172.672756 -26.801572) (xy 172.663818 -26.78947)
			(xy 172.64034 -26.770682) (xy 172.612407 -26.759551) (xy 172.582442 -26.757041) (xy 172.553047 -26.763372)
			(xy 172.526772 -26.777994) (xy 172.505897 -26.799637) (xy 172.498512 -26.812748) (xy 172.486214 -26.835913)
			(xy 172.456218 -26.878936) (xy 172.420614 -26.917446) (xy 172.380072 -26.950719) (xy 172.335356 -26.978126)
			(xy 172.287308 -26.999153) (xy 172.236834 -27.013402) (xy 172.184883 -27.020605) (xy 172.15866 -27.021028)
			(xy 172.158152 -27.021028) (xy 172.130254 -27.020495) (xy 172.075059 -27.012326) (xy 172.02164 -26.996212)
			(xy 171.971134 -26.972497) (xy 171.947586 -26.957528) (xy 170.84548 -26.957528) (xy 170.84548 -27.582876)
			(xy 170.845979 -27.597013) (xy 170.853806 -27.624186) (xy 170.868783 -27.648172) (xy 170.889763 -27.667132)
			(xy 170.915137 -27.679613) (xy 170.942961 -27.684659) (xy 170.971102 -27.681883) (xy 170.984418 -27.67711)
			(xy 171.006776 -27.668673) (xy 171.053066 -27.656803) (xy 171.100478 -27.65082) (xy 171.124372 -27.65044)
			(xy 171.12488 -27.65044) (xy 171.152133 -27.650902) (xy 171.206083 -27.658657) (xy 171.258381 -27.674012)
			(xy 171.30796 -27.696654) (xy 171.353812 -27.726122) (xy 171.395003 -27.761816) (xy 171.430695 -27.80301)
			(xy 171.46016 -27.848864) (xy 171.482798 -27.898446) (xy 171.498149 -27.950744) (xy 171.5059 -28.004695)
			(xy 171.506388 -28.031948) (xy 171.505938 -28.058744) (xy 171.498447 -28.111809) (xy 171.483605 -28.163304)
			(xy 171.461704 -28.212216) (xy 171.433174 -28.257582) (xy 171.398577 -28.29851) (xy 171.37888 -28.316682)
			(xy 171.368607 -28.3265) (xy 171.353463 -28.350531) (xy 171.345514 -28.377801) (xy 171.345375 -28.406206)
			(xy 171.353056 -28.433553) (xy 171.367964 -28.457732) (xy 171.388948 -28.476876) (xy 171.401486 -28.48356)
			(xy 171.425087 -28.495709) (xy 171.46898 -28.525559) (xy 171.508312 -28.561204) (xy 171.542324 -28.601956)
			(xy 171.570359 -28.64703) (xy 171.591878 -28.695553) (xy 171.600253 -28.72486) (xy 174.124112 -28.72486)
			(xy 174.124575 -28.698208) (xy 174.132012 -28.645427) (xy 174.146724 -28.594193) (xy 174.168422 -28.545506)
			(xy 174.196685 -28.500313) (xy 174.230963 -28.459493) (xy 174.270589 -28.423841) (xy 174.31479 -28.39405)
			(xy 174.362708 -28.370701) (xy 174.413408 -28.354249) (xy 174.43958 -28.349194) (xy 174.453331 -28.346366)
			(xy 174.47862 -28.334198) (xy 174.499643 -28.315607) (xy 174.514814 -28.291997) (xy 174.522988 -28.265149)
			(xy 174.523549 -28.237091) (xy 174.516453 -28.209938) (xy 174.502236 -28.185742) (xy 174.492412 -28.175712)
			(xy 174.474221 -28.157679) (xy 174.442384 -28.117553) (xy 174.416201 -28.073528) (xy 174.396143 -28.026396)
			(xy 174.38257 -27.977005) (xy 174.375727 -27.926241) (xy 174.375318 -27.90063) (xy 174.375804 -27.873379)
			(xy 174.38356 -27.819431) (xy 174.398915 -27.767136) (xy 174.421557 -27.717559) (xy 174.451023 -27.671709)
			(xy 174.486714 -27.630518) (xy 174.527905 -27.594827) (xy 174.573755 -27.565361) (xy 174.623332 -27.542719)
			(xy 174.675627 -27.527364) (xy 174.729575 -27.519608) (xy 174.784077 -27.519608) (xy 174.838025 -27.527364)
			(xy 174.89032 -27.542719) (xy 174.939897 -27.565361) (xy 174.985747 -27.594827) (xy 175.026938 -27.630518)
			(xy 175.062629 -27.671709) (xy 175.092095 -27.717559) (xy 175.114737 -27.767136) (xy 175.130092 -27.819431)
			(xy 175.137848 -27.873379) (xy 175.138334 -27.90063) (xy 175.137803 -27.927278) (xy 175.130368 -27.980053)
			(xy 175.115661 -28.03128) (xy 175.093968 -28.079962) (xy 175.065711 -28.125152) (xy 175.031441 -28.165969)
			(xy 174.991824 -28.20162) (xy 174.947631 -28.231411) (xy 174.899722 -28.254761) (xy 174.84903 -28.271218)
			(xy 174.822866 -28.276296) (xy 174.809122 -28.279158) (xy 174.78383 -28.291316) (xy 174.762802 -28.3099)
			(xy 174.747628 -28.333506) (xy 174.739451 -28.360351) (xy 174.738891 -28.388408) (xy 174.745988 -28.415558)
			(xy 174.760208 -28.439751) (xy 174.770034 -28.449778) (xy 174.78821 -28.467826) (xy 174.820051 -28.507948)
			(xy 174.846237 -28.551969) (xy 174.866298 -28.599098) (xy 174.879873 -28.648488) (xy 174.886718 -28.699249)
			(xy 174.887128 -28.72486) (xy 174.887128 -28.725114) (xy 174.886648 -28.751439) (xy 174.879396 -28.803587)
			(xy 174.865046 -28.854244) (xy 174.843869 -28.902447) (xy 174.816269 -28.947283) (xy 174.782768 -28.987899)
			(xy 174.763684 -29.006038) (xy 174.753683 -29.01594) (xy 174.738953 -29.039903) (xy 174.731317 -29.066975)
			(xy 174.731356 -29.095103) (xy 174.739065 -29.122154) (xy 174.753862 -29.146076) (xy 174.763938 -29.155898)
			(xy 174.783138 -29.17405) (xy 174.816857 -29.214727) (xy 174.841886 -29.255212) (xy 176.187862 -29.255212)
			(xy 176.187862 -29.254958) (xy 176.188418 -29.227664) (xy 176.196777 -29.173719) (xy 176.213261 -29.121678)
			(xy 176.237486 -29.072759) (xy 176.268885 -29.028104) (xy 176.28743 -29.00807) (xy 176.297817 -28.996439)
			(xy 176.311645 -28.968509) (xy 176.316404 -28.937709) (xy 176.311651 -28.906908) (xy 176.297827 -28.878975)
			(xy 176.28743 -28.867354) (xy 176.268825 -28.847368) (xy 176.237391 -28.802719) (xy 176.213152 -28.753791)
			(xy 176.196675 -28.701733) (xy 176.18835 -28.647768) (xy 176.187862 -28.620466) (xy 176.187862 -28.620212)
			(xy 176.18836 -28.593563) (xy 176.196303 -28.540859) (xy 176.212013 -28.489929) (xy 176.235139 -28.441908)
			(xy 176.265163 -28.397871) (xy 176.301415 -28.3588) (xy 176.343086 -28.325569) (xy 176.389244 -28.29892)
			(xy 176.438858 -28.279448) (xy 176.49082 -28.267588) (xy 176.54397 -28.263605) (xy 176.59712 -28.267588)
			(xy 176.649082 -28.279448) (xy 176.698696 -28.29892) (xy 176.744854 -28.325569) (xy 176.786525 -28.3588)
			(xy 176.822777 -28.397871) (xy 176.852801 -28.441908) (xy 176.875927 -28.489929) (xy 176.891637 -28.540859)
			(xy 176.89958 -28.593563) (xy 176.900078 -28.620212) (xy 176.900078 -28.620466) (xy 176.899553 -28.647762)
			(xy 176.891189 -28.701709) (xy 176.874699 -28.753751) (xy 176.850466 -28.80267) (xy 176.819059 -28.847322)
			(xy 176.80051 -28.867354) (xy 176.790105 -28.878968) (xy 176.776287 -28.906905) (xy 176.771535 -28.937709)
			(xy 176.776292 -28.968511) (xy 176.790115 -28.996446) (xy 176.80051 -29.00807) (xy 176.819086 -29.028082)
			(xy 176.850522 -29.072724) (xy 176.874766 -29.121646) (xy 176.89125 -29.173698) (xy 176.899585 -29.227658)
			(xy 176.900078 -29.254958) (xy 176.900078 -29.255212) (xy 177.087784 -29.255212) (xy 177.087784 -29.254958)
			(xy 177.088334 -29.227664) (xy 177.096693 -29.173718) (xy 177.113179 -29.121677) (xy 177.137405 -29.072757)
			(xy 177.168806 -29.028103) (xy 177.187352 -29.00807) (xy 177.197737 -28.996438) (xy 177.211562 -28.968508)
			(xy 177.21632 -28.937709) (xy 177.211568 -28.906909) (xy 177.197747 -28.878976) (xy 177.187352 -28.867354)
			(xy 177.168751 -28.847364) (xy 177.137316 -28.802717) (xy 177.113075 -28.75379) (xy 177.096598 -28.701732)
			(xy 177.088272 -28.647768) (xy 177.087784 -28.620466) (xy 177.087784 -28.620212) (xy 177.088282 -28.593563)
			(xy 177.096225 -28.540859) (xy 177.111935 -28.489929) (xy 177.135061 -28.441908) (xy 177.165085 -28.397871)
			(xy 177.201337 -28.3588) (xy 177.243008 -28.325569) (xy 177.289166 -28.29892) (xy 177.33878 -28.279448)
			(xy 177.390742 -28.267588) (xy 177.443892 -28.263605) (xy 177.497042 -28.267588) (xy 177.549004 -28.279448)
			(xy 177.598618 -28.29892) (xy 177.644776 -28.325569) (xy 177.686447 -28.3588) (xy 177.722699 -28.397871)
			(xy 177.752723 -28.441908) (xy 177.775849 -28.489929) (xy 177.791559 -28.540859) (xy 177.799502 -28.593563)
			(xy 177.8 -28.620212) (xy 177.8 -28.620466) (xy 177.799469 -28.647761) (xy 177.791106 -28.701708)
			(xy 177.774616 -28.753749) (xy 177.750385 -28.802668) (xy 177.71898 -28.847322) (xy 177.700432 -28.867354)
			(xy 177.690025 -28.878967) (xy 177.676204 -28.906904) (xy 177.671452 -28.937709) (xy 177.676209 -28.968512)
			(xy 177.690035 -28.996447) (xy 177.700432 -29.00807) (xy 177.719011 -29.028079) (xy 177.750446 -29.072722)
			(xy 177.774689 -29.121645) (xy 177.791172 -29.173698) (xy 177.799507 -29.227658) (xy 177.8 -29.254958)
			(xy 177.8 -29.255212) (xy 177.987706 -29.255212) (xy 177.987706 -29.254958) (xy 177.98825 -29.227663)
			(xy 177.99661 -29.173717) (xy 178.013096 -29.121676) (xy 178.037324 -29.072756) (xy 178.068727 -29.028103)
			(xy 178.087274 -29.00807) (xy 178.097657 -28.996437) (xy 178.111479 -28.968507) (xy 178.116236 -28.937709)
			(xy 178.111485 -28.90691) (xy 178.097667 -28.878977) (xy 178.087274 -28.867354) (xy 178.068659 -28.847376)
			(xy 178.037229 -28.802725) (xy 178.012992 -28.753794) (xy 177.996518 -28.701734) (xy 177.988193 -28.647768)
			(xy 177.987706 -28.620466) (xy 177.987706 -28.620212) (xy 177.988204 -28.593563) (xy 177.996147 -28.540859)
			(xy 178.011857 -28.489929) (xy 178.034983 -28.441908) (xy 178.065007 -28.397871) (xy 178.101259 -28.3588)
			(xy 178.14293 -28.325569) (xy 178.189088 -28.29892) (xy 178.238702 -28.279448) (xy 178.290664 -28.267588)
			(xy 178.343814 -28.263605) (xy 178.396964 -28.267588) (xy 178.448926 -28.279448) (xy 178.49854 -28.29892)
			(xy 178.544698 -28.325569) (xy 178.586369 -28.3588) (xy 178.622621 -28.397871) (xy 178.652645 -28.441908)
			(xy 178.675771 -28.489929) (xy 178.691481 -28.540859) (xy 178.699424 -28.593563) (xy 178.699922 -28.620212)
			(xy 178.699922 -28.620466) (xy 178.699385 -28.647761) (xy 178.691022 -28.701707) (xy 178.674534 -28.753748)
			(xy 178.650305 -28.802667) (xy 178.618901 -28.847321) (xy 178.600354 -28.867354) (xy 178.589945 -28.878966)
			(xy 178.576121 -28.906903) (xy 178.571367 -28.937709) (xy 178.576126 -28.968513) (xy 178.589955 -28.996448)
			(xy 178.600354 -29.00807) (xy 178.61892 -29.028091) (xy 178.65036 -29.07273) (xy 178.674607 -29.121649)
			(xy 178.691092 -29.1737) (xy 178.699429 -29.227658) (xy 178.699922 -29.254958) (xy 178.699922 -29.255212)
			(xy 178.887882 -29.255212) (xy 178.887882 -29.254958) (xy 178.888433 -29.227664) (xy 178.896792 -29.173718)
			(xy 178.913277 -29.121677) (xy 178.937503 -29.072758) (xy 178.968904 -29.028103) (xy 178.98745 -29.00807)
			(xy 178.997835 -28.996438) (xy 179.011661 -28.968508) (xy 179.016419 -28.937709) (xy 179.011666 -28.906908)
			(xy 178.997845 -28.878976) (xy 178.98745 -28.867354) (xy 178.968848 -28.847364) (xy 178.937414 -28.802717)
			(xy 178.913173 -28.75379) (xy 178.896696 -28.701732) (xy 178.88837 -28.647768) (xy 178.887882 -28.620466)
			(xy 178.887882 -28.620212) (xy 178.88838 -28.593563) (xy 178.896323 -28.540859) (xy 178.912033 -28.489929)
			(xy 178.935159 -28.441908) (xy 178.965183 -28.397871) (xy 179.001435 -28.3588) (xy 179.043106 -28.325569)
			(xy 179.089264 -28.29892) (xy 179.138878 -28.279448) (xy 179.19084 -28.267588) (xy 179.24399 -28.263605)
			(xy 179.29714 -28.267588) (xy 179.349102 -28.279448) (xy 179.398716 -28.29892) (xy 179.444874 -28.325569)
			(xy 179.486545 -28.3588) (xy 179.522797 -28.397871) (xy 179.552821 -28.441908) (xy 179.575947 -28.489929)
			(xy 179.591657 -28.540859) (xy 179.5996 -28.593563) (xy 179.600098 -28.620212) (xy 179.600098 -28.620466)
			(xy 179.599567 -28.647761) (xy 179.591204 -28.701708) (xy 179.574715 -28.75375) (xy 179.550484 -28.802669)
			(xy 179.519078 -28.847322) (xy 179.50053 -28.867354) (xy 179.490123 -28.878967) (xy 179.476303 -28.906904)
			(xy 179.47155 -28.937709) (xy 179.476308 -28.968512) (xy 179.490133 -28.996447) (xy 179.50053 -29.00807)
			(xy 179.519109 -29.028079) (xy 179.550544 -29.072723) (xy 179.574787 -29.121645) (xy 179.59127 -29.173698)
			(xy 179.599605 -29.227658) (xy 179.600098 -29.254958) (xy 179.600098 -29.255212) (xy 179.5996 -29.281861)
			(xy 179.591657 -29.334565) (xy 179.575947 -29.385495) (xy 179.552821 -29.433516) (xy 179.522797 -29.477553)
			(xy 179.486545 -29.516624) (xy 179.444874 -29.549855) (xy 179.398716 -29.576504) (xy 179.349102 -29.595976)
			(xy 179.29714 -29.607836) (xy 179.24399 -29.61182) (xy 179.19084 -29.607836) (xy 179.138878 -29.595976)
			(xy 179.089264 -29.576504) (xy 179.043106 -29.549855) (xy 179.001435 -29.516624) (xy 178.965183 -29.477553)
			(xy 178.935159 -29.433516) (xy 178.912033 -29.385495) (xy 178.896323 -29.334565) (xy 178.88838 -29.281861)
			(xy 178.887882 -29.255212) (xy 178.699922 -29.255212) (xy 178.699424 -29.281861) (xy 178.691481 -29.334565)
			(xy 178.675771 -29.385495) (xy 178.652645 -29.433516) (xy 178.622621 -29.477553) (xy 178.586369 -29.516624)
			(xy 178.544698 -29.549855) (xy 178.49854 -29.576504) (xy 178.448926 -29.595976) (xy 178.396964 -29.607836)
			(xy 178.343814 -29.61182) (xy 178.290664 -29.607836) (xy 178.238702 -29.595976) (xy 178.189088 -29.576504)
			(xy 178.14293 -29.549855) (xy 178.101259 -29.516624) (xy 178.065007 -29.477553) (xy 178.034983 -29.433516)
			(xy 178.011857 -29.385495) (xy 177.996147 -29.334565) (xy 177.988204 -29.281861) (xy 177.987706 -29.255212)
			(xy 177.8 -29.255212) (xy 177.799502 -29.281861) (xy 177.791559 -29.334565) (xy 177.775849 -29.385495)
			(xy 177.752723 -29.433516) (xy 177.722699 -29.477553) (xy 177.686447 -29.516624) (xy 177.644776 -29.549855)
			(xy 177.598618 -29.576504) (xy 177.549004 -29.595976) (xy 177.497042 -29.607836) (xy 177.443892 -29.61182)
			(xy 177.390742 -29.607836) (xy 177.33878 -29.595976) (xy 177.289166 -29.576504) (xy 177.243008 -29.549855)
			(xy 177.201337 -29.516624) (xy 177.165085 -29.477553) (xy 177.135061 -29.433516) (xy 177.111935 -29.385495)
			(xy 177.096225 -29.334565) (xy 177.088282 -29.281861) (xy 177.087784 -29.255212) (xy 176.900078 -29.255212)
			(xy 176.89958 -29.281861) (xy 176.891637 -29.334565) (xy 176.875927 -29.385495) (xy 176.852801 -29.433516)
			(xy 176.822777 -29.477553) (xy 176.786525 -29.516624) (xy 176.744854 -29.549855) (xy 176.698696 -29.576504)
			(xy 176.649082 -29.595976) (xy 176.59712 -29.607836) (xy 176.54397 -29.61182) (xy 176.49082 -29.607836)
			(xy 176.438858 -29.595976) (xy 176.389244 -29.576504) (xy 176.343086 -29.549855) (xy 176.301415 -29.516624)
			(xy 176.265163 -29.477553) (xy 176.235139 -29.433516) (xy 176.212013 -29.385495) (xy 176.196303 -29.334565)
			(xy 176.18836 -29.281861) (xy 176.187862 -29.255212) (xy 174.841886 -29.255212) (xy 174.844641 -29.259668)
			(xy 174.865959 -29.308012) (xy 174.880402 -29.358836) (xy 174.887694 -29.411166) (xy 174.888144 -29.437584)
			(xy 174.887658 -29.464835) (xy 174.879902 -29.518783) (xy 174.864547 -29.571078) (xy 174.841905 -29.620655)
			(xy 174.812439 -29.666505) (xy 174.776748 -29.707696) (xy 174.735557 -29.743387) (xy 174.689707 -29.772853)
			(xy 174.64013 -29.795495) (xy 174.587835 -29.81085) (xy 174.533887 -29.818606) (xy 174.479385 -29.818606)
			(xy 174.425437 -29.81085) (xy 174.373142 -29.795495) (xy 174.323565 -29.772853) (xy 174.277715 -29.743387)
			(xy 174.236524 -29.707696) (xy 174.200833 -29.666505) (xy 174.171367 -29.620655) (xy 174.148725 -29.571078)
			(xy 174.13337 -29.518783) (xy 174.125614 -29.464835) (xy 174.125128 -29.437584) (xy 174.125128 -29.43733)
			(xy 174.125553 -29.411003) (xy 174.132813 -29.358852) (xy 174.147173 -29.308193) (xy 174.16836 -29.25999)
			(xy 174.195971 -29.215156) (xy 174.229483 -29.174542) (xy 174.248572 -29.156406) (xy 174.258625 -29.146554)
			(xy 174.273344 -29.122575) (xy 174.280968 -29.095492) (xy 174.280919 -29.067355) (xy 174.2732 -29.040298)
			(xy 174.258397 -29.016371) (xy 174.248318 -29.006546) (xy 174.229102 -28.98841) (xy 174.195382 -28.947731)
			(xy 174.167599 -28.902787) (xy 174.146283 -28.854439) (xy 174.131844 -28.803612) (xy 174.124558 -28.751279)
			(xy 174.124112 -28.72486) (xy 171.600253 -28.72486) (xy 171.606463 -28.746591) (xy 171.613834 -28.799158)
			(xy 171.614338 -28.825698) (xy 171.613852 -28.85295) (xy 171.606096 -28.9069) (xy 171.590742 -28.959196)
			(xy 171.568101 -29.008776) (xy 171.538635 -29.054629) (xy 171.502944 -29.095821) (xy 171.461754 -29.131516)
			(xy 171.415904 -29.160986) (xy 171.366326 -29.18363) (xy 171.314031 -29.198989) (xy 171.260082 -29.20675)
			(xy 171.23283 -29.207206) (xy 171.20264 -29.206639) (xy 171.143015 -29.197129) (xy 171.085638 -29.178326)
			(xy 171.031948 -29.150703) (xy 171.007278 -29.133292) (xy 170.995719 -29.125342) (xy 170.969458 -29.115499)
			(xy 170.94151 -29.113174) (xy 170.913984 -29.118541) (xy 170.888958 -29.131197) (xy 170.86832 -29.150185)
			(xy 170.853628 -29.174073) (xy 170.845991 -29.201058) (xy 170.84548 -29.21508) (xy 170.84548 -29.775756)
			(xy 171.211135 -29.775756) (xy 171.211135 -29.721244) (xy 171.218893 -29.667287) (xy 171.234252 -29.614983)
			(xy 171.256899 -29.565397) (xy 171.286372 -29.51954) (xy 171.322072 -29.478344) (xy 171.363272 -29.442648)
			(xy 171.409132 -29.41318) (xy 171.45872 -29.390538) (xy 171.511026 -29.375185) (xy 171.564984 -29.367432)
			(xy 171.59224 -29.366972) (xy 171.620347 -29.367487) (xy 171.675947 -29.375781) (xy 171.702984 -29.383482)
			(xy 171.716683 -29.387092) (xy 171.744997 -29.387472) (xy 171.772331 -29.380074) (xy 171.796588 -29.365464)
			(xy 171.815909 -29.344763) (xy 171.828814 -29.319557) (xy 171.832016 -29.305758) (xy 171.837518 -29.280075)
			(xy 171.854669 -29.230431) (xy 171.878468 -29.183608) (xy 171.908465 -29.140493) (xy 171.944093 -29.1019)
			(xy 171.984677 -29.068559) (xy 172.029452 -29.0411) (xy 172.077569 -29.020042) (xy 172.128121 -29.005784)
			(xy 172.18015 -28.998594) (xy 172.206412 -28.998164) (xy 172.233661 -28.998707) (xy 172.287603 -29.006464)
			(xy 172.339892 -29.021819) (xy 172.389464 -29.04446) (xy 172.43531 -29.073924) (xy 172.476496 -29.109613)
			(xy 172.512183 -29.1508) (xy 172.541646 -29.196646) (xy 172.564285 -29.246219) (xy 172.579638 -29.298509)
			(xy 172.587394 -29.352451) (xy 172.587394 -29.406949) (xy 172.579638 -29.460891) (xy 172.564285 -29.513181)
			(xy 172.541646 -29.562754) (xy 172.512183 -29.6086) (xy 172.476496 -29.649787) (xy 172.43531 -29.685476)
			(xy 172.389464 -29.71494) (xy 172.339892 -29.737581) (xy 172.287603 -29.752936) (xy 172.233661 -29.760693)
			(xy 172.206412 -29.76118) (xy 172.178305 -29.760652) (xy 172.122705 -29.752367) (xy 172.095668 -29.74467)
			(xy 172.081963 -29.741077) (xy 172.053649 -29.740684) (xy 172.026312 -29.748074) (xy 172.002053 -29.762682)
			(xy 171.982732 -29.783384) (xy 171.969833 -29.808593) (xy 171.966636 -29.822394) (xy 171.962389 -29.841952)
			(xy 180.652674 -29.841952) (xy 180.653185 -29.814379) (xy 180.661129 -29.759809) (xy 180.676846 -29.70695)
			(xy 180.700008 -29.656904) (xy 180.730132 -29.610713) (xy 180.766591 -29.56934) (xy 180.787294 -29.551122)
			(xy 180.798239 -29.541272) (xy 180.814311 -29.516608) (xy 180.822689 -29.488388) (xy 180.82268 -29.45895)
			(xy 180.814284 -29.430735) (xy 180.798198 -29.406081) (xy 180.787294 -29.396182) (xy 180.76657 -29.377985)
			(xy 180.730101 -29.336613) (xy 180.69997 -29.29042) (xy 180.676807 -29.24037) (xy 180.661093 -29.187504)
			(xy 180.653157 -29.132928) (xy 180.652674 -29.105352) (xy 180.653133 -29.0781) (xy 180.660896 -29.024153)
			(xy 180.676256 -28.971859) (xy 180.698901 -28.922282) (xy 180.728371 -28.876433) (xy 180.764065 -28.835244)
			(xy 180.805257 -28.799553) (xy 180.851109 -28.770087) (xy 180.900687 -28.747445) (xy 180.952982 -28.732089)
			(xy 181.00693 -28.724331) (xy 181.034182 -28.723844) (xy 181.061439 -28.724338) (xy 181.115398 -28.732103)
			(xy 181.167704 -28.747462) (xy 181.217293 -28.770105) (xy 181.263159 -28.799569) (xy 181.304368 -28.835257)
			(xy 181.340083 -28.876443) (xy 181.355238 -28.899104) (xy 181.363519 -28.911031) (xy 181.385455 -28.930035)
			(xy 181.411855 -28.94209) (xy 181.440582 -28.94622) (xy 181.469309 -28.94209) (xy 181.495709 -28.930035)
			(xy 181.517645 -28.911031) (xy 181.525926 -28.899104) (xy 181.541103 -28.876457) (xy 181.576806 -28.835261)
			(xy 181.618008 -28.799565) (xy 181.66387 -28.770094) (xy 181.713459 -28.747449) (xy 181.765765 -28.732091)
			(xy 181.819725 -28.724331) (xy 181.846982 -28.723844) (xy 181.874231 -28.724395) (xy 181.928173 -28.732148)
			(xy 181.980464 -28.747498) (xy 182.030038 -28.770134) (xy 182.075886 -28.799593) (xy 182.117075 -28.835278)
			(xy 182.152767 -28.876461) (xy 182.182235 -28.922304) (xy 182.204879 -28.971874) (xy 182.220238 -29.024162)
			(xy 182.228 -29.078103) (xy 182.22849 -29.105352) (xy 182.227995 -29.132926) (xy 182.220049 -29.187497)
			(xy 182.20433 -29.240357) (xy 182.181165 -29.290403) (xy 182.151038 -29.336593) (xy 182.114575 -29.377965)
			(xy 182.09387 -29.396182) (xy 182.083024 -29.406131) (xy 182.066955 -29.430768) (xy 182.058569 -29.458962)
			(xy 182.05856 -29.488376) (xy 182.066929 -29.516575) (xy 182.082983 -29.541222) (xy 182.09387 -29.551122)
			(xy 182.114589 -29.569325) (xy 182.15106 -29.610695) (xy 182.181192 -29.656886) (xy 182.204357 -29.706936)
			(xy 182.220071 -29.7598) (xy 182.228007 -29.814377) (xy 182.22849 -29.841952) (xy 182.228 -29.869204)
			(xy 182.220249 -29.923155) (xy 182.204898 -29.975454) (xy 182.18226 -30.025035) (xy 182.152795 -30.070889)
			(xy 182.117104 -30.112083) (xy 182.075913 -30.147777) (xy 182.030061 -30.177246) (xy 181.980482 -30.199888)
			(xy 181.928185 -30.215243) (xy 181.874234 -30.222998) (xy 181.846982 -30.22346) (xy 181.819724 -30.222991)
			(xy 181.765764 -30.215222) (xy 181.713458 -30.199858) (xy 181.663868 -30.177211) (xy 181.618003 -30.147743)
			(xy 181.576795 -30.112051) (xy 181.541081 -30.070862) (xy 181.525926 -30.0482) (xy 181.517645 -30.036273)
			(xy 181.495709 -30.017269) (xy 181.469309 -30.005214) (xy 181.440582 -30.001084) (xy 181.411855 -30.005214)
			(xy 181.385455 -30.017269) (xy 181.363519 -30.036273) (xy 181.355238 -30.0482) (xy 181.340086 -30.070864)
			(xy 181.304378 -30.11206) (xy 181.263172 -30.147755) (xy 181.217306 -30.177224) (xy 181.167713 -30.199866)
			(xy 181.115403 -30.21522) (xy 181.061441 -30.222975) (xy 181.034182 -30.22346) (xy 181.006926 -30.223062)
			(xy 180.952971 -30.215301) (xy 180.900669 -30.19994) (xy 180.851085 -30.177292) (xy 180.80523 -30.147818)
			(xy 180.764036 -30.112117) (xy 180.728343 -30.070917) (xy 180.698876 -30.025057) (xy 180.676237 -29.975469)
			(xy 180.660885 -29.923165) (xy 180.653134 -29.869208) (xy 180.652674 -29.841952) (xy 171.962389 -29.841952)
			(xy 171.960443 -29.850915) (xy 171.940539 -29.905777) (xy 171.912514 -29.956969) (xy 171.877021 -30.003297)
			(xy 171.834887 -30.043679) (xy 171.787095 -30.077175) (xy 171.73476 -30.103003) (xy 171.679103 -30.120561)
			(xy 171.621421 -30.129438) (xy 171.59224 -30.129988) (xy 171.564984 -30.129568) (xy 171.511026 -30.121815)
			(xy 171.45872 -30.106462) (xy 171.409132 -30.08382) (xy 171.363272 -30.054352) (xy 171.322072 -30.018656)
			(xy 171.286372 -29.97746) (xy 171.256899 -29.931603) (xy 171.234252 -29.882017) (xy 171.218893 -29.829713)
			(xy 171.211135 -29.775756) (xy 170.84548 -29.775756) (xy 170.84548 -30.395672) (xy 171.824394 -30.395672)
			(xy 171.828465 -30.34005) (xy 171.840591 -30.285613) (xy 171.860514 -30.233522) (xy 171.88781 -30.184887)
			(xy 171.921896 -30.140744) (xy 171.962045 -30.102035) (xy 172.007403 -30.069584) (xy 172.057003 -30.044083)
			(xy 172.109787 -30.026076) (xy 172.16463 -30.015946) (xy 172.220364 -30.013909) (xy 172.275801 -30.020009)
			(xy 172.329758 -30.034115) (xy 172.381087 -30.055927) (xy 172.428693 -30.084981) (xy 172.471561 -30.120656)
			(xy 172.508778 -30.162193) (xy 172.539551 -30.208706) (xy 172.563223 -30.259203) (xy 172.579291 -30.31261)
			(xy 172.587411 -30.367786) (xy 172.58792 -30.395672) (xy 172.587411 -30.423558) (xy 172.579291 -30.478734)
			(xy 172.563223 -30.532141) (xy 172.539551 -30.582638) (xy 172.508778 -30.629151) (xy 172.471561 -30.670688)
			(xy 172.428693 -30.706363) (xy 172.381087 -30.735417) (xy 172.329758 -30.757229) (xy 172.275801 -30.771335)
			(xy 172.220364 -30.777435) (xy 172.16463 -30.775398) (xy 172.109787 -30.765268) (xy 172.057003 -30.747261)
			(xy 172.007403 -30.72176) (xy 171.962045 -30.689309) (xy 171.921896 -30.6506) (xy 171.88781 -30.606457)
			(xy 171.860514 -30.557822) (xy 171.840591 -30.505731) (xy 171.828465 -30.451294) (xy 171.824394 -30.395672)
			(xy 170.84548 -30.395672) (xy 170.84548 -31.446248) (xy 176.813144 -31.446248) (xy 176.813145 -31.39174)
			(xy 176.820904 -31.337786) (xy 176.836262 -31.285486) (xy 176.858907 -31.235903) (xy 176.888378 -31.190049)
			(xy 176.924075 -31.148855) (xy 176.965271 -31.113161) (xy 177.011128 -31.083693) (xy 177.060712 -31.061052)
			(xy 177.113013 -31.045698) (xy 177.166968 -31.037943) (xy 177.221476 -31.037946) (xy 177.27543 -31.045707)
			(xy 177.327729 -31.061067) (xy 177.377311 -31.083715) (xy 177.423164 -31.113188) (xy 177.464356 -31.148886)
			(xy 177.500048 -31.190084) (xy 177.529514 -31.235942) (xy 177.552154 -31.285527) (xy 177.567506 -31.337829)
			(xy 177.575258 -31.391784) (xy 177.575718 -31.419038) (xy 177.575718 -31.428944) (xy 177.575825 -31.44294)
			(xy 177.582765 -31.470045) (xy 177.5968 -31.49425) (xy 177.616878 -31.513737) (xy 177.64149 -31.527045)
			(xy 177.66879 -31.533174) (xy 177.696728 -31.531664) (xy 177.723209 -31.522629) (xy 177.734976 -31.51505)
			(xy 177.759047 -31.498984) (xy 177.811029 -31.473548) (xy 177.866258 -31.45626) (xy 177.923464 -31.447515)
			(xy 177.9524 -31.446978) (xy 177.979653 -31.447455) (xy 178.033604 -31.455212) (xy 178.085903 -31.470569)
			(xy 178.135483 -31.493212) (xy 178.181336 -31.52268) (xy 178.222529 -31.558374) (xy 178.258223 -31.599567)
			(xy 178.287691 -31.645421) (xy 178.310333 -31.695002) (xy 178.325689 -31.7473) (xy 178.333445 -31.801252)
			(xy 178.333444 -31.855758) (xy 178.325687 -31.909709) (xy 178.312618 -31.954216) (xy 179.198014 -31.954216)
			(xy 179.202085 -31.898594) (xy 179.214211 -31.844157) (xy 179.234134 -31.792066) (xy 179.26143 -31.743431)
			(xy 179.295516 -31.699288) (xy 179.335665 -31.660579) (xy 179.381023 -31.628128) (xy 179.430623 -31.602627)
			(xy 179.483407 -31.58462) (xy 179.53825 -31.57449) (xy 179.593984 -31.572453) (xy 179.649421 -31.578553)
			(xy 179.703378 -31.592659) (xy 179.754707 -31.614471) (xy 179.802313 -31.643525) (xy 179.806794 -31.647254)
			(xy 182.48193 -31.647254) (xy 182.48193 -31.592746) (xy 182.489687 -31.538793) (xy 182.505043 -31.486493)
			(xy 182.527686 -31.436911) (xy 182.557154 -31.391056) (xy 182.592848 -31.349861) (xy 182.634041 -31.314165)
			(xy 182.679895 -31.284694) (xy 182.729476 -31.262049) (xy 182.781776 -31.246691) (xy 182.835728 -31.238931)
			(xy 182.862982 -31.238444) (xy 182.890239 -31.238938) (xy 182.944198 -31.246703) (xy 182.996504 -31.262062)
			(xy 183.046093 -31.284705) (xy 183.091959 -31.314169) (xy 183.133168 -31.349857) (xy 183.168883 -31.391043)
			(xy 183.184038 -31.413704) (xy 183.192319 -31.425631) (xy 183.214255 -31.444635) (xy 183.240655 -31.45669)
			(xy 183.269382 -31.46082) (xy 183.298109 -31.45669) (xy 183.324509 -31.444635) (xy 183.346445 -31.425631)
			(xy 183.354726 -31.413704) (xy 183.369903 -31.391057) (xy 183.405606 -31.349861) (xy 183.446808 -31.314165)
			(xy 183.49267 -31.284694) (xy 183.542259 -31.262049) (xy 183.594565 -31.246691) (xy 183.648525 -31.238931)
			(xy 183.675782 -31.238444) (xy 183.703032 -31.239002) (xy 183.756978 -31.246756) (xy 183.809272 -31.262108)
			(xy 183.858848 -31.284747) (xy 183.904698 -31.314211) (xy 183.945887 -31.3499) (xy 183.981578 -31.391088)
			(xy 184.011044 -31.436936) (xy 184.033685 -31.486511) (xy 184.04904 -31.538804) (xy 184.056797 -31.59275)
			(xy 184.056797 -31.64725) (xy 184.04904 -31.701196) (xy 184.033685 -31.753489) (xy 184.011044 -31.803064)
			(xy 183.981578 -31.848912) (xy 183.945887 -31.8901) (xy 183.904698 -31.925789) (xy 183.858848 -31.955253)
			(xy 183.809272 -31.977892) (xy 183.756978 -31.993244) (xy 183.703032 -32.000998) (xy 183.675782 -32.00146)
			(xy 183.648524 -32.000991) (xy 183.594564 -31.993222) (xy 183.542258 -31.977858) (xy 183.492668 -31.955211)
			(xy 183.446803 -31.925743) (xy 183.405595 -31.890051) (xy 183.369881 -31.848862) (xy 183.354726 -31.8262)
			(xy 183.346445 -31.814273) (xy 183.324509 -31.795269) (xy 183.298109 -31.783214) (xy 183.269382 -31.779084)
			(xy 183.240655 -31.783214) (xy 183.214255 -31.795269) (xy 183.192319 -31.814273) (xy 183.184038 -31.8262)
			(xy 183.168886 -31.848864) (xy 183.133178 -31.89006) (xy 183.091972 -31.925755) (xy 183.046106 -31.955224)
			(xy 182.996513 -31.977866) (xy 182.944203 -31.99322) (xy 182.890241 -32.000975) (xy 182.862982 -32.00146)
			(xy 182.835728 -32.001069) (xy 182.781776 -31.993309) (xy 182.729476 -31.977951) (xy 182.679895 -31.955306)
			(xy 182.634041 -31.925835) (xy 182.592848 -31.890139) (xy 182.557154 -31.848944) (xy 182.527686 -31.803089)
			(xy 182.505043 -31.753507) (xy 182.489687 -31.701207) (xy 182.48193 -31.647254) (xy 179.806794 -31.647254)
			(xy 179.845181 -31.6792) (xy 179.882398 -31.720737) (xy 179.913171 -31.76725) (xy 179.936843 -31.817747)
			(xy 179.952911 -31.871154) (xy 179.961031 -31.92633) (xy 179.96154 -31.954216) (xy 179.961031 -31.982102)
			(xy 179.952911 -32.037278) (xy 179.936843 -32.090685) (xy 179.913171 -32.141182) (xy 179.882398 -32.187695)
			(xy 179.845181 -32.229232) (xy 179.802313 -32.264907) (xy 179.754707 -32.293961) (xy 179.703378 -32.315773)
			(xy 179.649421 -32.329879) (xy 179.593984 -32.335979) (xy 179.53825 -32.333942) (xy 179.483407 -32.323812)
			(xy 179.430623 -32.305805) (xy 179.381023 -32.280304) (xy 179.335665 -32.247853) (xy 179.295516 -32.209144)
			(xy 179.26143 -32.165001) (xy 179.234134 -32.116366) (xy 179.214211 -32.064275) (xy 179.202085 -32.009838)
			(xy 179.198014 -31.954216) (xy 178.312618 -31.954216) (xy 178.31033 -31.962007) (xy 178.287686 -32.011587)
			(xy 178.258217 -32.05744) (xy 178.222523 -32.098632) (xy 178.181329 -32.134326) (xy 178.135475 -32.163793)
			(xy 178.085894 -32.186435) (xy 178.033595 -32.20179) (xy 177.979644 -32.209545) (xy 177.925138 -32.209544)
			(xy 177.871186 -32.201786) (xy 177.818889 -32.186428) (xy 177.769309 -32.163784) (xy 177.723456 -32.134314)
			(xy 177.682264 -32.098619) (xy 177.646572 -32.057425) (xy 177.617105 -32.011571) (xy 177.594464 -31.961989)
			(xy 177.579109 -31.909691) (xy 177.571354 -31.855739) (xy 177.570892 -31.828486) (xy 177.570892 -31.81858)
			(xy 177.570823 -31.804585) (xy 177.563868 -31.777484) (xy 177.549822 -31.753286) (xy 177.52974 -31.733805)
			(xy 177.505126 -31.7205) (xy 177.477827 -31.714371) (xy 177.449888 -31.715875) (xy 177.423405 -31.724901)
			(xy 177.411634 -31.732474) (xy 177.387554 -31.748527) (xy 177.335576 -31.773968) (xy 177.28035 -31.791261)
			(xy 177.223145 -31.800008) (xy 177.19421 -31.800546) (xy 177.166956 -31.800056) (xy 177.113002 -31.7923)
			(xy 177.060701 -31.776944) (xy 177.011118 -31.754301) (xy 176.965262 -31.724832) (xy 176.924066 -31.689136)
			(xy 176.888371 -31.647942) (xy 176.858901 -31.602086) (xy 176.836258 -31.552503) (xy 176.820901 -31.500202)
			(xy 176.813144 -31.446248) (xy 170.84548 -31.446248) (xy 170.84548 -32.535622) (xy 180.552342 -32.535622)
			(xy 180.556413 -32.48) (xy 180.568539 -32.425563) (xy 180.588462 -32.373472) (xy 180.615758 -32.324837)
			(xy 180.649844 -32.280694) (xy 180.689993 -32.241985) (xy 180.735351 -32.209534) (xy 180.784951 -32.184033)
			(xy 180.837735 -32.166026) (xy 180.892578 -32.155896) (xy 180.948312 -32.153859) (xy 181.003749 -32.159959)
			(xy 181.057706 -32.174065) (xy 181.109035 -32.195877) (xy 181.156641 -32.224931) (xy 181.199509 -32.260606)
			(xy 181.236726 -32.302143) (xy 181.267499 -32.348656) (xy 181.291171 -32.399153) (xy 181.307239 -32.45256)
			(xy 181.315359 -32.507736) (xy 181.315868 -32.535622) (xy 181.315359 -32.563508) (xy 181.307239 -32.618684)
			(xy 181.291171 -32.672091) (xy 181.267499 -32.722588) (xy 181.236726 -32.769101) (xy 181.199509 -32.810638)
			(xy 181.156641 -32.846313) (xy 181.109035 -32.875367) (xy 181.057706 -32.897179) (xy 181.003749 -32.911285)
			(xy 180.948312 -32.917385) (xy 180.892578 -32.915348) (xy 180.837735 -32.905218) (xy 180.784951 -32.887211)
			(xy 180.735351 -32.86171) (xy 180.689993 -32.829259) (xy 180.649844 -32.79055) (xy 180.615758 -32.746407)
			(xy 180.588462 -32.697772) (xy 180.568539 -32.645681) (xy 180.556413 -32.591244) (xy 180.552342 -32.535622)
			(xy 170.84548 -32.535622) (xy 170.84548 -34.339654) (xy 181.84693 -34.339654) (xy 181.84693 -34.285146)
			(xy 181.854687 -34.231193) (xy 181.870043 -34.178893) (xy 181.892686 -34.129311) (xy 181.922154 -34.083456)
			(xy 181.957848 -34.042261) (xy 181.999041 -34.006565) (xy 182.044895 -33.977094) (xy 182.094476 -33.954449)
			(xy 182.146776 -33.939091) (xy 182.200728 -33.931331) (xy 182.227982 -33.930844) (xy 182.256899 -33.931359)
			(xy 182.314071 -33.940086) (xy 182.369271 -33.957344) (xy 182.421233 -33.982736) (xy 182.468767 -34.015681)
			(xy 182.510783 -34.055424) (xy 182.528972 -34.07791) (xy 182.538869 -34.089715) (xy 182.564193 -34.107234)
			(xy 182.593586 -34.11641) (xy 182.624378 -34.11641) (xy 182.653771 -34.107234) (xy 182.679095 -34.089715)
			(xy 182.688992 -34.07791) (xy 182.70719 -34.055432) (xy 182.749208 -34.015696) (xy 182.796741 -33.982756)
			(xy 182.848701 -33.957367) (xy 182.903898 -33.94011) (xy 182.961066 -33.931379) (xy 182.989982 -33.930844)
			(xy 183.017232 -33.931402) (xy 183.071178 -33.939156) (xy 183.123472 -33.954508) (xy 183.173048 -33.977147)
			(xy 183.218898 -34.006611) (xy 183.260087 -34.0423) (xy 183.295778 -34.083488) (xy 183.325244 -34.129336)
			(xy 183.347885 -34.178911) (xy 183.36324 -34.231204) (xy 183.370997 -34.28515) (xy 183.370997 -34.33965)
			(xy 183.36324 -34.393596) (xy 183.347885 -34.445889) (xy 183.325244 -34.495464) (xy 183.295778 -34.541312)
			(xy 183.260087 -34.5825) (xy 183.218898 -34.618189) (xy 183.173048 -34.647653) (xy 183.123472 -34.670292)
			(xy 183.071178 -34.685644) (xy 183.017232 -34.693398) (xy 182.989982 -34.69386) (xy 182.961067 -34.693298)
			(xy 182.903897 -34.68458) (xy 182.848698 -34.667332) (xy 182.796736 -34.641948) (xy 182.749201 -34.609012)
			(xy 182.707183 -34.569277) (xy 182.688992 -34.546794) (xy 182.679095 -34.534989) (xy 182.653771 -34.51747)
			(xy 182.624378 -34.508294) (xy 182.593586 -34.508294) (xy 182.564193 -34.51747) (xy 182.538869 -34.534989)
			(xy 182.528972 -34.546794) (xy 182.510795 -34.56929) (xy 182.468773 -34.609024) (xy 182.421235 -34.641962)
			(xy 182.369271 -34.667348) (xy 182.314071 -34.684602) (xy 182.256899 -34.693327) (xy 182.227982 -34.69386)
			(xy 182.200728 -34.693469) (xy 182.146776 -34.685709) (xy 182.094476 -34.670351) (xy 182.044895 -34.647706)
			(xy 181.999041 -34.618235) (xy 181.957848 -34.582539) (xy 181.922154 -34.541344) (xy 181.892686 -34.495489)
			(xy 181.870043 -34.445907) (xy 181.854687 -34.393607) (xy 181.84693 -34.339654) (xy 170.84548 -34.339654)
			(xy 170.84548 -34.508948) (xy 172.01388 -35.677348)
		)
		(stroke
			(width 0)
			(type solid)
		)
		(fill yes)
		(layer "In15.Cu")
		(net "GND")
	)
	(gr_poly
		(pts
			(xy 435.17185 -152.620218) (xy 435.182815 -152.630438) (xy 435.209231 -152.644572) (xy 435.238612 -152.650435)
			(xy 435.26843 -152.647524) (xy 435.296121 -152.636088) (xy 435.319304 -152.61711) (xy 435.335985 -152.592224)
			(xy 435.34473 -152.563569) (xy 435.345332 -152.54859) (xy 435.345332 -142.215616) (xy 436.5498 -141.011148)
			(xy 441.6806 -141.011148) (xy 441.7314 -141.061948) (xy 444.785242 -141.061948) (xy 446.715642 -139.131548)
			(xy 446.715642 -124.342906) (xy 439.88101 -117.508274) (xy 429.414686 -117.508274) (xy 429.409606 -117.553486)
			(xy 429.405957 -117.581096) (xy 429.391691 -117.634928) (xy 429.369758 -117.686118) (xy 429.340623 -117.733579)
			(xy 429.304905 -117.776306) (xy 429.263359 -117.813392) (xy 429.216868 -117.844052) (xy 429.166416 -117.867634)
			(xy 429.113075 -117.883639) (xy 429.057975 -117.891727) (xy 429.002285 -117.891727) (xy 428.947185 -117.883639)
			(xy 428.893844 -117.867634) (xy 428.843392 -117.844052) (xy 428.796901 -117.813392) (xy 428.755355 -117.776306)
			(xy 428.719637 -117.733579) (xy 428.690502 -117.686118) (xy 428.668569 -117.634928) (xy 428.654303 -117.581096)
			(xy 428.650654 -117.553486) (xy 428.645574 -117.508274) (xy 428.43704 -117.508274) (xy 428.356522 -117.588792)
			(xy 428.356522 -117.609874) (xy 428.356018 -117.637132) (xy 428.348227 -117.691088) (xy 428.33284 -117.743387)
			(xy 428.310169 -117.792965) (xy 428.280676 -117.838814) (xy 428.244961 -117.880001) (xy 428.20375 -117.915689)
			(xy 428.157882 -117.945151) (xy 428.108288 -117.967789) (xy 428.055979 -117.983141) (xy 428.002018 -117.990896)
			(xy 427.947502 -117.990896) (xy 427.893541 -117.983141) (xy 427.841232 -117.967789) (xy 427.791638 -117.945151)
			(xy 427.74577 -117.915689) (xy 427.704559 -117.880001) (xy 427.668844 -117.838814) (xy 427.639351 -117.792965)
			(xy 427.61668 -117.743387) (xy 427.601293 -117.691088) (xy 427.593502 -117.637132) (xy 427.592998 -117.609874)
			(xy 427.592998 -117.588792) (xy 427.51248 -117.508274) (xy 416.742118 -117.508274) (xy 415.195766 -119.054626)
			(xy 431.95824 -119.054626) (xy 431.962311 -118.999004) (xy 431.974437 -118.944567) (xy 431.99436 -118.892476)
			(xy 432.021656 -118.843841) (xy 432.055742 -118.799698) (xy 432.095891 -118.760989) (xy 432.141249 -118.728538)
			(xy 432.190849 -118.703037) (xy 432.243633 -118.68503) (xy 432.298476 -118.6749) (xy 432.35421 -118.672863)
			(xy 432.409647 -118.678963) (xy 432.463604 -118.693069) (xy 432.514933 -118.714881) (xy 432.562539 -118.743935)
			(xy 432.605407 -118.77961) (xy 432.642624 -118.821147) (xy 432.673397 -118.86766) (xy 432.697069 -118.918157)
			(xy 432.713137 -118.971564) (xy 432.721257 -119.02674) (xy 432.721766 -119.054626) (xy 432.721257 -119.082512)
			(xy 432.713137 -119.137688) (xy 432.697069 -119.191095) (xy 432.696269 -119.192802) (xy 436.989726 -119.192802)
			(xy 436.993797 -119.13718) (xy 437.005923 -119.082743) (xy 437.025846 -119.030652) (xy 437.053142 -118.982017)
			(xy 437.087228 -118.937874) (xy 437.127377 -118.899165) (xy 437.172735 -118.866714) (xy 437.222335 -118.841213)
			(xy 437.275119 -118.823206) (xy 437.329962 -118.813076) (xy 437.385696 -118.811039) (xy 437.441133 -118.817139)
			(xy 437.49509 -118.831245) (xy 437.546419 -118.853057) (xy 437.594025 -118.882111) (xy 437.636893 -118.917786)
			(xy 437.67411 -118.959323) (xy 437.704883 -119.005836) (xy 437.728555 -119.056333) (xy 437.744623 -119.10974)
			(xy 437.752743 -119.164916) (xy 437.753252 -119.192802) (xy 437.752743 -119.220688) (xy 437.744623 -119.275864)
			(xy 437.728555 -119.329271) (xy 437.704883 -119.379768) (xy 437.67411 -119.426281) (xy 437.636893 -119.467818)
			(xy 437.594025 -119.503493) (xy 437.546419 -119.532547) (xy 437.49509 -119.554359) (xy 437.441133 -119.568465)
			(xy 437.385696 -119.574565) (xy 437.329962 -119.572528) (xy 437.275119 -119.562398) (xy 437.222335 -119.544391)
			(xy 437.172735 -119.51889) (xy 437.127377 -119.486439) (xy 437.087228 -119.44773) (xy 437.053142 -119.403587)
			(xy 437.025846 -119.354952) (xy 437.005923 -119.302861) (xy 436.993797 -119.248424) (xy 436.989726 -119.192802)
			(xy 432.696269 -119.192802) (xy 432.673397 -119.241592) (xy 432.642624 -119.288105) (xy 432.605407 -119.329642)
			(xy 432.562539 -119.365317) (xy 432.514933 -119.394371) (xy 432.463604 -119.416183) (xy 432.409647 -119.430289)
			(xy 432.35421 -119.436389) (xy 432.298476 -119.434352) (xy 432.243633 -119.424222) (xy 432.190849 -119.406215)
			(xy 432.141249 -119.380714) (xy 432.095891 -119.348263) (xy 432.055742 -119.309554) (xy 432.021656 -119.265411)
			(xy 431.99436 -119.216776) (xy 431.974437 -119.164685) (xy 431.962311 -119.110248) (xy 431.95824 -119.054626)
			(xy 415.195766 -119.054626) (xy 414.333944 -119.916448) (xy 422.520362 -119.916448) (xy 422.524433 -119.860826)
			(xy 422.536559 -119.806389) (xy 422.556482 -119.754298) (xy 422.583778 -119.705663) (xy 422.617864 -119.66152)
			(xy 422.658013 -119.622811) (xy 422.703371 -119.59036) (xy 422.752971 -119.564859) (xy 422.805755 -119.546852)
			(xy 422.860598 -119.536722) (xy 422.916332 -119.534685) (xy 422.971769 -119.540785) (xy 423.025726 -119.554891)
			(xy 423.077055 -119.576703) (xy 423.089365 -119.584216) (xy 433.69814 -119.584216) (xy 433.702211 -119.528594)
			(xy 433.714337 -119.474157) (xy 433.73426 -119.422066) (xy 433.761556 -119.373431) (xy 433.795642 -119.329288)
			(xy 433.835791 -119.290579) (xy 433.881149 -119.258128) (xy 433.930749 -119.232627) (xy 433.983533 -119.21462)
			(xy 434.038376 -119.20449) (xy 434.09411 -119.202453) (xy 434.149547 -119.208553) (xy 434.203504 -119.222659)
			(xy 434.254833 -119.244471) (xy 434.302439 -119.273525) (xy 434.345307 -119.3092) (xy 434.382524 -119.350737)
			(xy 434.413297 -119.39725) (xy 434.436969 -119.447747) (xy 434.453037 -119.501154) (xy 434.461157 -119.55633)
			(xy 434.461666 -119.584216) (xy 434.96814 -119.584216) (xy 434.972211 -119.528594) (xy 434.984337 -119.474157)
			(xy 435.00426 -119.422066) (xy 435.031556 -119.373431) (xy 435.065642 -119.329288) (xy 435.105791 -119.290579)
			(xy 435.151149 -119.258128) (xy 435.200749 -119.232627) (xy 435.253533 -119.21462) (xy 435.308376 -119.20449)
			(xy 435.36411 -119.202453) (xy 435.419547 -119.208553) (xy 435.473504 -119.222659) (xy 435.524833 -119.244471)
			(xy 435.572439 -119.273525) (xy 435.615307 -119.3092) (xy 435.652524 -119.350737) (xy 435.683297 -119.39725)
			(xy 435.706969 -119.447747) (xy 435.723037 -119.501154) (xy 435.731157 -119.55633) (xy 435.731666 -119.584216)
			(xy 435.731157 -119.612102) (xy 435.723037 -119.667278) (xy 435.706969 -119.720685) (xy 435.683297 -119.771182)
			(xy 435.652524 -119.817695) (xy 435.615307 -119.859232) (xy 435.572439 -119.894907) (xy 435.524833 -119.923961)
			(xy 435.473504 -119.945773) (xy 435.419547 -119.959879) (xy 435.36411 -119.965979) (xy 435.308376 -119.963942)
			(xy 435.253533 -119.953812) (xy 435.200749 -119.935805) (xy 435.151149 -119.910304) (xy 435.105791 -119.877853)
			(xy 435.065642 -119.839144) (xy 435.031556 -119.795001) (xy 435.00426 -119.746366) (xy 434.984337 -119.694275)
			(xy 434.972211 -119.639838) (xy 434.96814 -119.584216) (xy 434.461666 -119.584216) (xy 434.461157 -119.612102)
			(xy 434.453037 -119.667278) (xy 434.436969 -119.720685) (xy 434.413297 -119.771182) (xy 434.382524 -119.817695)
			(xy 434.345307 -119.859232) (xy 434.302439 -119.894907) (xy 434.254833 -119.923961) (xy 434.203504 -119.945773)
			(xy 434.149547 -119.959879) (xy 434.09411 -119.965979) (xy 434.038376 -119.963942) (xy 433.983533 -119.953812)
			(xy 433.930749 -119.935805) (xy 433.881149 -119.910304) (xy 433.835791 -119.877853) (xy 433.795642 -119.839144)
			(xy 433.761556 -119.795001) (xy 433.73426 -119.746366) (xy 433.714337 -119.694275) (xy 433.702211 -119.639838)
			(xy 433.69814 -119.584216) (xy 423.089365 -119.584216) (xy 423.124661 -119.605757) (xy 423.167529 -119.641432)
			(xy 423.204746 -119.682969) (xy 423.235519 -119.729482) (xy 423.259191 -119.779979) (xy 423.275259 -119.833386)
			(xy 423.283379 -119.888562) (xy 423.283888 -119.916448) (xy 423.283379 -119.944334) (xy 423.275259 -119.99951)
			(xy 423.259191 -120.052917) (xy 423.259105 -120.0531) (xy 429.699926 -120.0531) (xy 429.703997 -119.997478)
			(xy 429.716123 -119.943041) (xy 429.736046 -119.89095) (xy 429.763342 -119.842315) (xy 429.797428 -119.798172)
			(xy 429.837577 -119.759463) (xy 429.882935 -119.727012) (xy 429.932535 -119.701511) (xy 429.985319 -119.683504)
			(xy 430.040162 -119.673374) (xy 430.095896 -119.671337) (xy 430.151333 -119.677437) (xy 430.20529 -119.691543)
			(xy 430.256619 -119.713355) (xy 430.304225 -119.742409) (xy 430.347093 -119.778084) (xy 430.38431 -119.819621)
			(xy 430.415083 -119.866134) (xy 430.438755 -119.916631) (xy 430.454823 -119.970038) (xy 430.462943 -120.025214)
			(xy 430.463452 -120.0531) (xy 430.462943 -120.080986) (xy 430.454823 -120.136162) (xy 430.438755 -120.189569)
			(xy 430.415083 -120.240066) (xy 430.38431 -120.286579) (xy 430.347093 -120.328116) (xy 430.304225 -120.363791)
			(xy 430.256619 -120.392845) (xy 430.20529 -120.414657) (xy 430.151333 -120.428763) (xy 430.095896 -120.434863)
			(xy 430.040162 -120.432826) (xy 429.985319 -120.422696) (xy 429.932535 -120.404689) (xy 429.882935 -120.379188)
			(xy 429.837577 -120.346737) (xy 429.797428 -120.308028) (xy 429.763342 -120.263885) (xy 429.736046 -120.21525)
			(xy 429.716123 -120.163159) (xy 429.703997 -120.108722) (xy 429.699926 -120.0531) (xy 423.259105 -120.0531)
			(xy 423.235519 -120.103414) (xy 423.204746 -120.149927) (xy 423.167529 -120.191464) (xy 423.124661 -120.227139)
			(xy 423.077055 -120.256193) (xy 423.025726 -120.278005) (xy 422.971769 -120.292111) (xy 422.916332 -120.298211)
			(xy 422.860598 -120.296174) (xy 422.805755 -120.286044) (xy 422.752971 -120.268037) (xy 422.703371 -120.242536)
			(xy 422.658013 -120.210085) (xy 422.617864 -120.171376) (xy 422.583778 -120.127233) (xy 422.556482 -120.078598)
			(xy 422.536559 -120.026507) (xy 422.524433 -119.97207) (xy 422.520362 -119.916448) (xy 414.333944 -119.916448)
			(xy 413.753046 -120.497346) (xy 435.408576 -120.497346) (xy 435.412647 -120.441724) (xy 435.424773 -120.387287)
			(xy 435.444696 -120.335196) (xy 435.471992 -120.286561) (xy 435.506078 -120.242418) (xy 435.546227 -120.203709)
			(xy 435.591585 -120.171258) (xy 435.641185 -120.145757) (xy 435.693969 -120.12775) (xy 435.748812 -120.11762)
			(xy 435.804546 -120.115583) (xy 435.859983 -120.121683) (xy 435.91394 -120.135789) (xy 435.965269 -120.157601)
			(xy 436.012875 -120.186655) (xy 436.055743 -120.22233) (xy 436.09296 -120.263867) (xy 436.123733 -120.31038)
			(xy 436.147405 -120.360877) (xy 436.163473 -120.414284) (xy 436.171593 -120.46946) (xy 436.172102 -120.497346)
			(xy 436.171593 -120.525232) (xy 436.163473 -120.580408) (xy 436.147405 -120.633815) (xy 436.123733 -120.684312)
			(xy 436.09296 -120.730825) (xy 436.055743 -120.772362) (xy 436.012875 -120.808037) (xy 435.965269 -120.837091)
			(xy 435.91394 -120.858903) (xy 435.859983 -120.873009) (xy 435.804546 -120.879109) (xy 435.748812 -120.877072)
			(xy 435.693969 -120.866942) (xy 435.641185 -120.848935) (xy 435.591585 -120.823434) (xy 435.546227 -120.790983)
			(xy 435.506078 -120.752274) (xy 435.471992 -120.708131) (xy 435.444696 -120.659496) (xy 435.424773 -120.607405)
			(xy 435.412647 -120.552968) (xy 435.408576 -120.497346) (xy 413.753046 -120.497346) (xy 412.173166 -122.077226)
			(xy 421.87952 -122.077226) (xy 421.883591 -122.021604) (xy 421.895717 -121.967167) (xy 421.91564 -121.915076)
			(xy 421.942936 -121.866441) (xy 421.977022 -121.822298) (xy 422.017171 -121.783589) (xy 422.062529 -121.751138)
			(xy 422.112129 -121.725637) (xy 422.164913 -121.70763) (xy 422.219756 -121.6975) (xy 422.27549 -121.695463)
			(xy 422.330927 -121.701563) (xy 422.384884 -121.715669) (xy 422.436213 -121.737481) (xy 422.44561 -121.743216)
			(xy 428.864014 -121.743216) (xy 428.8645 -121.715965) (xy 428.872256 -121.662017) (xy 428.887611 -121.609722)
			(xy 428.910253 -121.560145) (xy 428.939719 -121.514295) (xy 428.97541 -121.473104) (xy 429.016601 -121.437413)
			(xy 429.062451 -121.407947) (xy 429.112028 -121.385305) (xy 429.164323 -121.36995) (xy 429.218271 -121.362194)
			(xy 429.272773 -121.362194) (xy 429.326721 -121.36995) (xy 429.379016 -121.385305) (xy 429.428593 -121.407947)
			(xy 429.474443 -121.437413) (xy 429.515634 -121.473104) (xy 429.551325 -121.514295) (xy 429.557897 -121.524522)
			(xy 435.516018 -121.524522) (xy 435.520089 -121.4689) (xy 435.532215 -121.414463) (xy 435.552138 -121.362372)
			(xy 435.579434 -121.313737) (xy 435.61352 -121.269594) (xy 435.653669 -121.230885) (xy 435.699027 -121.198434)
			(xy 435.748627 -121.172933) (xy 435.801411 -121.154926) (xy 435.856254 -121.144796) (xy 435.911988 -121.142759)
			(xy 435.967425 -121.148859) (xy 436.021382 -121.162965) (xy 436.072711 -121.184777) (xy 436.120317 -121.213831)
			(xy 436.163185 -121.249506) (xy 436.200402 -121.291043) (xy 436.231175 -121.337556) (xy 436.254847 -121.388053)
			(xy 436.26679 -121.427748) (xy 439.280298 -121.427748) (xy 439.284369 -121.372126) (xy 439.296495 -121.317689)
			(xy 439.316418 -121.265598) (xy 439.343714 -121.216963) (xy 439.3778 -121.17282) (xy 439.417949 -121.134111)
			(xy 439.463307 -121.10166) (xy 439.512907 -121.076159) (xy 439.565691 -121.058152) (xy 439.620534 -121.048022)
			(xy 439.676268 -121.045985) (xy 439.731705 -121.052085) (xy 439.785662 -121.066191) (xy 439.836991 -121.088003)
			(xy 439.884597 -121.117057) (xy 439.927465 -121.152732) (xy 439.964682 -121.194269) (xy 439.995455 -121.240782)
			(xy 440.019127 -121.291279) (xy 440.035195 -121.344686) (xy 440.043315 -121.399862) (xy 440.043824 -121.427748)
			(xy 440.043315 -121.455634) (xy 440.035195 -121.51081) (xy 440.019127 -121.564217) (xy 439.995455 -121.614714)
			(xy 439.964682 -121.661227) (xy 439.927465 -121.702764) (xy 439.884597 -121.738439) (xy 439.836991 -121.767493)
			(xy 439.785662 -121.789305) (xy 439.731705 -121.803411) (xy 439.676268 -121.809511) (xy 439.620534 -121.807474)
			(xy 439.565691 -121.797344) (xy 439.512907 -121.779337) (xy 439.463307 -121.753836) (xy 439.417949 -121.721385)
			(xy 439.3778 -121.682676) (xy 439.343714 -121.638533) (xy 439.316418 -121.589898) (xy 439.296495 -121.537807)
			(xy 439.284369 -121.48337) (xy 439.280298 -121.427748) (xy 436.26679 -121.427748) (xy 436.270915 -121.44146)
			(xy 436.279035 -121.496636) (xy 436.279544 -121.524522) (xy 436.279035 -121.552408) (xy 436.270915 -121.607584)
			(xy 436.254847 -121.660991) (xy 436.231175 -121.711488) (xy 436.200402 -121.758001) (xy 436.163185 -121.799538)
			(xy 436.120317 -121.835213) (xy 436.072711 -121.864267) (xy 436.021382 -121.886079) (xy 435.967425 -121.900185)
			(xy 435.911988 -121.906285) (xy 435.856254 -121.904248) (xy 435.801411 -121.894118) (xy 435.748627 -121.876111)
			(xy 435.699027 -121.85061) (xy 435.653669 -121.818159) (xy 435.61352 -121.77945) (xy 435.579434 -121.735307)
			(xy 435.552138 -121.686672) (xy 435.532215 -121.634581) (xy 435.520089 -121.580144) (xy 435.516018 -121.524522)
			(xy 429.557897 -121.524522) (xy 429.580791 -121.560145) (xy 429.603433 -121.609722) (xy 429.618788 -121.662017)
			(xy 429.626544 -121.715965) (xy 429.62703 -121.743216) (xy 429.626439 -121.773043) (xy 429.617165 -121.831972)
			(xy 429.598829 -121.888738) (xy 429.57188 -121.941957) (xy 429.554894 -121.966482) (xy 429.546539 -121.97895)
			(xy 429.536807 -122.007326) (xy 429.535742 -122.037306) (xy 429.543437 -122.066301) (xy 429.559226 -122.091808)
			(xy 429.570134 -122.102118) (xy 429.590087 -122.120342) (xy 429.622741 -122.158506) (xy 441.404246 -122.158506)
			(xy 441.408317 -122.102884) (xy 441.420443 -122.048447) (xy 441.440366 -121.996356) (xy 441.467662 -121.947721)
			(xy 441.501748 -121.903578) (xy 441.541897 -121.864869) (xy 441.587255 -121.832418) (xy 441.636855 -121.806917)
			(xy 441.689639 -121.78891) (xy 441.744482 -121.77878) (xy 441.800216 -121.776743) (xy 441.855653 -121.782843)
			(xy 441.90961 -121.796949) (xy 441.960939 -121.818761) (xy 442.008545 -121.847815) (xy 442.051413 -121.88349)
			(xy 442.08863 -121.925027) (xy 442.119403 -121.97154) (xy 442.143075 -122.022037) (xy 442.159143 -122.075444)
			(xy 442.167263 -122.13062) (xy 442.167772 -122.158506) (xy 442.167263 -122.186392) (xy 442.159143 -122.241568)
			(xy 442.143075 -122.294975) (xy 442.119403 -122.345472) (xy 442.08863 -122.391985) (xy 442.051413 -122.433522)
			(xy 442.008545 -122.469197) (xy 441.960939 -122.498251) (xy 441.90961 -122.520063) (xy 441.855653 -122.534169)
			(xy 441.800216 -122.540269) (xy 441.744482 -122.538232) (xy 441.689639 -122.528102) (xy 441.636855 -122.510095)
			(xy 441.587255 -122.484594) (xy 441.541897 -122.452143) (xy 441.501748 -122.413434) (xy 441.467662 -122.369291)
			(xy 441.440366 -122.320656) (xy 441.420443 -122.268565) (xy 441.408317 -122.214128) (xy 441.404246 -122.158506)
			(xy 429.622741 -122.158506) (xy 429.625216 -122.161399) (xy 429.654204 -122.207001) (xy 429.67647 -122.256236)
			(xy 429.691569 -122.308119) (xy 429.6992 -122.361612) (xy 429.699674 -122.38863) (xy 429.699188 -122.415881)
			(xy 429.691432 -122.469829) (xy 429.676077 -122.522124) (xy 429.653435 -122.571701) (xy 429.623969 -122.617551)
			(xy 429.588278 -122.658742) (xy 429.547087 -122.694433) (xy 429.501237 -122.723899) (xy 429.45166 -122.746541)
			(xy 429.399365 -122.761896) (xy 429.345417 -122.769652) (xy 429.290915 -122.769652) (xy 429.236967 -122.761896)
			(xy 429.184672 -122.746541) (xy 429.135095 -122.723899) (xy 429.089245 -122.694433) (xy 429.048054 -122.658742)
			(xy 429.012363 -122.617551) (xy 428.982897 -122.571701) (xy 428.960255 -122.522124) (xy 428.9449 -122.469829)
			(xy 428.937144 -122.415881) (xy 428.936658 -122.38863) (xy 428.937205 -122.358801) (xy 428.94649 -122.29987)
			(xy 428.964838 -122.243103) (xy 428.991801 -122.189886) (xy 429.008794 -122.165364) (xy 429.017104 -122.152868)
			(xy 429.026844 -122.124503) (xy 429.027919 -122.094532) (xy 429.020235 -122.065542) (xy 429.004456 -122.040038)
			(xy 428.993554 -122.029728) (xy 428.973573 -122.011534) (xy 428.938446 -121.97047) (xy 428.909463 -121.924862)
			(xy 428.887201 -121.875621) (xy 428.872108 -121.823733) (xy 428.864484 -121.770235) (xy 428.864014 -121.743216)
			(xy 422.44561 -121.743216) (xy 422.483819 -121.766535) (xy 422.526687 -121.80221) (xy 422.563904 -121.843747)
			(xy 422.594677 -121.89026) (xy 422.618349 -121.940757) (xy 422.634417 -121.994164) (xy 422.642537 -122.04934)
			(xy 422.643046 -122.077226) (xy 422.642537 -122.105112) (xy 422.634417 -122.160288) (xy 422.618349 -122.213695)
			(xy 422.594677 -122.264192) (xy 422.563904 -122.310705) (xy 422.526687 -122.352242) (xy 422.483819 -122.387917)
			(xy 422.436213 -122.416971) (xy 422.384884 -122.438783) (xy 422.330927 -122.452889) (xy 422.27549 -122.458989)
			(xy 422.219756 -122.456952) (xy 422.164913 -122.446822) (xy 422.112129 -122.428815) (xy 422.062529 -122.403314)
			(xy 422.017171 -122.370863) (xy 421.977022 -122.332154) (xy 421.942936 -122.288011) (xy 421.91564 -122.239376)
			(xy 421.895717 -122.187285) (xy 421.883591 -122.132848) (xy 421.87952 -122.077226) (xy 412.173166 -122.077226)
			(xy 411.385512 -122.86488) (xy 435.519574 -122.86488) (xy 435.523645 -122.809258) (xy 435.535771 -122.754821)
			(xy 435.555694 -122.70273) (xy 435.58299 -122.654095) (xy 435.617076 -122.609952) (xy 435.657225 -122.571243)
			(xy 435.702583 -122.538792) (xy 435.752183 -122.513291) (xy 435.804967 -122.495284) (xy 435.85981 -122.485154)
			(xy 435.915544 -122.483117) (xy 435.970981 -122.489217) (xy 436.024938 -122.503323) (xy 436.076267 -122.525135)
			(xy 436.123873 -122.554189) (xy 436.166741 -122.589864) (xy 436.203958 -122.631401) (xy 436.21542 -122.648726)
			(xy 437.90057 -122.648726) (xy 437.904641 -122.593104) (xy 437.916767 -122.538667) (xy 437.93669 -122.486576)
			(xy 437.963986 -122.437941) (xy 437.998072 -122.393798) (xy 438.038221 -122.355089) (xy 438.083579 -122.322638)
			(xy 438.133179 -122.297137) (xy 438.185963 -122.27913) (xy 438.240806 -122.269) (xy 438.29654 -122.266963)
			(xy 438.351977 -122.273063) (xy 438.405934 -122.287169) (xy 438.457263 -122.308981) (xy 438.504869 -122.338035)
			(xy 438.547737 -122.37371) (xy 438.584954 -122.415247) (xy 438.615727 -122.46176) (xy 438.639399 -122.512257)
			(xy 438.655467 -122.565664) (xy 438.663587 -122.62084) (xy 438.664096 -122.648726) (xy 438.663587 -122.676612)
			(xy 438.655467 -122.731788) (xy 438.639399 -122.785195) (xy 438.615727 -122.835692) (xy 438.584954 -122.882205)
			(xy 438.547737 -122.923742) (xy 438.504869 -122.959417) (xy 438.457263 -122.988471) (xy 438.405934 -123.010283)
			(xy 438.351977 -123.024389) (xy 438.29654 -123.030489) (xy 438.240806 -123.028452) (xy 438.185963 -123.018322)
			(xy 438.133179 -123.000315) (xy 438.083579 -122.974814) (xy 438.038221 -122.942363) (xy 437.998072 -122.903654)
			(xy 437.963986 -122.859511) (xy 437.93669 -122.810876) (xy 437.916767 -122.758785) (xy 437.904641 -122.704348)
			(xy 437.90057 -122.648726) (xy 436.21542 -122.648726) (xy 436.234731 -122.677914) (xy 436.258403 -122.728411)
			(xy 436.274471 -122.781818) (xy 436.282591 -122.836994) (xy 436.2831 -122.86488) (xy 436.282591 -122.892766)
			(xy 436.274471 -122.947942) (xy 436.258403 -123.001349) (xy 436.234731 -123.051846) (xy 436.203958 -123.098359)
			(xy 436.166741 -123.139896) (xy 436.123873 -123.175571) (xy 436.076267 -123.204625) (xy 436.024938 -123.226437)
			(xy 435.970981 -123.240543) (xy 435.915544 -123.246643) (xy 435.85981 -123.244606) (xy 435.804967 -123.234476)
			(xy 435.752183 -123.216469) (xy 435.702583 -123.190968) (xy 435.657225 -123.158517) (xy 435.617076 -123.119808)
			(xy 435.58299 -123.075665) (xy 435.555694 -123.02703) (xy 435.535771 -122.974939) (xy 435.523645 -122.920502)
			(xy 435.519574 -122.86488) (xy 411.385512 -122.86488) (xy 410.934408 -123.315984) (xy 428.176434 -123.315984)
			(xy 428.180505 -123.260362) (xy 428.192631 -123.205925) (xy 428.212554 -123.153834) (xy 428.23985 -123.105199)
			(xy 428.273936 -123.061056) (xy 428.314085 -123.022347) (xy 428.359443 -122.989896) (xy 428.409043 -122.964395)
			(xy 428.461827 -122.946388) (xy 428.51667 -122.936258) (xy 428.572404 -122.934221) (xy 428.627841 -122.940321)
			(xy 428.681798 -122.954427) (xy 428.733127 -122.976239) (xy 428.780733 -123.005293) (xy 428.823601 -123.040968)
			(xy 428.860818 -123.082505) (xy 428.891591 -123.129018) (xy 428.915263 -123.179515) (xy 428.931331 -123.232922)
			(xy 428.939451 -123.288098) (xy 428.93996 -123.315984) (xy 428.939451 -123.34387) (xy 428.931331 -123.399046)
			(xy 428.915263 -123.452453) (xy 428.891591 -123.50295) (xy 428.860818 -123.549463) (xy 428.823601 -123.591)
			(xy 428.780733 -123.626675) (xy 428.733127 -123.655729) (xy 428.681798 -123.677541) (xy 428.627841 -123.691647)
			(xy 428.572404 -123.697747) (xy 428.51667 -123.69571) (xy 428.461827 -123.68558) (xy 428.409043 -123.667573)
			(xy 428.359443 -123.642072) (xy 428.314085 -123.609621) (xy 428.273936 -123.570912) (xy 428.23985 -123.526769)
			(xy 428.212554 -123.478134) (xy 428.192631 -123.426043) (xy 428.180505 -123.371606) (xy 428.176434 -123.315984)
			(xy 410.934408 -123.315984) (xy 410.420566 -123.829826) (xy 410.420566 -123.87199) (xy 435.521606 -123.87199)
			(xy 435.525677 -123.816368) (xy 435.537803 -123.761931) (xy 435.557726 -123.70984) (xy 435.585022 -123.661205)
			(xy 435.619108 -123.617062) (xy 435.659257 -123.578353) (xy 435.704615 -123.545902) (xy 435.754215 -123.520401)
			(xy 435.806999 -123.502394) (xy 435.861842 -123.492264) (xy 435.917576 -123.490227) (xy 435.973013 -123.496327)
			(xy 436.02697 -123.510433) (xy 436.078299 -123.532245) (xy 436.125905 -123.561299) (xy 436.168773 -123.596974)
			(xy 436.20599 -123.638511) (xy 436.223334 -123.664726) (xy 439.889898 -123.664726) (xy 439.893969 -123.609104)
			(xy 439.906095 -123.554667) (xy 439.926018 -123.502576) (xy 439.953314 -123.453941) (xy 439.9874 -123.409798)
			(xy 440.027549 -123.371089) (xy 440.072907 -123.338638) (xy 440.122507 -123.313137) (xy 440.175291 -123.29513)
			(xy 440.230134 -123.285) (xy 440.285868 -123.282963) (xy 440.341305 -123.289063) (xy 440.395262 -123.303169)
			(xy 440.446591 -123.324981) (xy 440.494197 -123.354035) (xy 440.537065 -123.38971) (xy 440.574282 -123.431247)
			(xy 440.605055 -123.47776) (xy 440.628727 -123.528257) (xy 440.644795 -123.581664) (xy 440.652915 -123.63684)
			(xy 440.653424 -123.664726) (xy 440.652915 -123.692612) (xy 440.644795 -123.747788) (xy 440.628727 -123.801195)
			(xy 440.605055 -123.851692) (xy 440.574282 -123.898205) (xy 440.537065 -123.939742) (xy 440.494197 -123.975417)
			(xy 440.446591 -124.004471) (xy 440.395262 -124.026283) (xy 440.341305 -124.040389) (xy 440.285868 -124.046489)
			(xy 440.230134 -124.044452) (xy 440.175291 -124.034322) (xy 440.122507 -124.016315) (xy 440.072907 -123.990814)
			(xy 440.027549 -123.958363) (xy 439.9874 -123.919654) (xy 439.953314 -123.875511) (xy 439.926018 -123.826876)
			(xy 439.906095 -123.774785) (xy 439.893969 -123.720348) (xy 439.889898 -123.664726) (xy 436.223334 -123.664726)
			(xy 436.236763 -123.685024) (xy 436.260435 -123.735521) (xy 436.276503 -123.788928) (xy 436.284623 -123.844104)
			(xy 436.285132 -123.87199) (xy 436.284623 -123.899876) (xy 436.276503 -123.955052) (xy 436.260435 -124.008459)
			(xy 436.236763 -124.058956) (xy 436.20599 -124.105469) (xy 436.168773 -124.147006) (xy 436.125905 -124.182681)
			(xy 436.078299 -124.211735) (xy 436.02697 -124.233547) (xy 435.973013 -124.247653) (xy 435.917576 -124.253753)
			(xy 435.861842 -124.251716) (xy 435.806999 -124.241586) (xy 435.754215 -124.223579) (xy 435.704615 -124.198078)
			(xy 435.659257 -124.165627) (xy 435.619108 -124.126918) (xy 435.585022 -124.082775) (xy 435.557726 -124.03414)
			(xy 435.537803 -123.982049) (xy 435.525677 -123.927612) (xy 435.521606 -123.87199) (xy 410.420566 -123.87199)
			(xy 410.420566 -124.29744) (xy 410.99994 -124.29744) (xy 411.028914 -124.297998) (xy 411.086143 -124.307104)
			(xy 411.141242 -124.325053) (xy 411.192853 -124.351404) (xy 411.239705 -124.385507) (xy 411.260544 -124.405644)
			(xy 411.62734 -124.77242) (xy 427.805848 -124.77242) (xy 427.809919 -124.716798) (xy 427.822045 -124.662361)
			(xy 427.841968 -124.61027) (xy 427.869264 -124.561635) (xy 427.90335 -124.517492) (xy 427.943499 -124.478783)
			(xy 427.988857 -124.446332) (xy 428.038457 -124.420831) (xy 428.091241 -124.402824) (xy 428.146084 -124.392694)
			(xy 428.201818 -124.390657) (xy 428.257255 -124.396757) (xy 428.311212 -124.410863) (xy 428.362541 -124.432675)
			(xy 428.410147 -124.461729) (xy 428.453015 -124.497404) (xy 428.490232 -124.538941) (xy 428.521005 -124.585454)
			(xy 428.544677 -124.635951) (xy 428.560745 -124.689358) (xy 428.568865 -124.744534) (xy 428.569374 -124.77242)
			(xy 428.568865 -124.800306) (xy 428.560745 -124.855482) (xy 428.551652 -124.885704) (xy 435.552594 -124.885704)
			(xy 435.556665 -124.830082) (xy 435.568791 -124.775645) (xy 435.588714 -124.723554) (xy 435.61601 -124.674919)
			(xy 435.650096 -124.630776) (xy 435.690245 -124.592067) (xy 435.735603 -124.559616) (xy 435.785203 -124.534115)
			(xy 435.837987 -124.516108) (xy 435.89283 -124.505978) (xy 435.948564 -124.503941) (xy 436.004001 -124.510041)
			(xy 436.057958 -124.524147) (xy 436.109287 -124.545959) (xy 436.156893 -124.575013) (xy 436.199761 -124.610688)
			(xy 436.236978 -124.652225) (xy 436.255834 -124.680726) (xy 439.889898 -124.680726) (xy 439.893969 -124.625104)
			(xy 439.906095 -124.570667) (xy 439.926018 -124.518576) (xy 439.953314 -124.469941) (xy 439.9874 -124.425798)
			(xy 440.027549 -124.387089) (xy 440.072907 -124.354638) (xy 440.122507 -124.329137) (xy 440.175291 -124.31113)
			(xy 440.230134 -124.301) (xy 440.285868 -124.298963) (xy 440.341305 -124.305063) (xy 440.395262 -124.319169)
			(xy 440.446591 -124.340981) (xy 440.494197 -124.370035) (xy 440.537065 -124.40571) (xy 440.574282 -124.447247)
			(xy 440.605055 -124.49376) (xy 440.628727 -124.544257) (xy 440.644795 -124.597664) (xy 440.652915 -124.65284)
			(xy 440.653424 -124.680726) (xy 440.652915 -124.708612) (xy 440.644795 -124.763788) (xy 440.628727 -124.817195)
			(xy 440.605055 -124.867692) (xy 440.574282 -124.914205) (xy 440.537065 -124.955742) (xy 440.494197 -124.991417)
			(xy 440.446591 -125.020471) (xy 440.395262 -125.042283) (xy 440.341305 -125.056389) (xy 440.285868 -125.062489)
			(xy 440.230134 -125.060452) (xy 440.175291 -125.050322) (xy 440.122507 -125.032315) (xy 440.072907 -125.006814)
			(xy 440.027549 -124.974363) (xy 439.9874 -124.935654) (xy 439.953314 -124.891511) (xy 439.926018 -124.842876)
			(xy 439.906095 -124.790785) (xy 439.893969 -124.736348) (xy 439.889898 -124.680726) (xy 436.255834 -124.680726)
			(xy 436.267751 -124.698738) (xy 436.291423 -124.749235) (xy 436.307491 -124.802642) (xy 436.315611 -124.857818)
			(xy 436.31612 -124.885704) (xy 436.315611 -124.91359) (xy 436.307491 -124.968766) (xy 436.291423 -125.022173)
			(xy 436.267751 -125.07267) (xy 436.236978 -125.119183) (xy 436.199761 -125.16072) (xy 436.156893 -125.196395)
			(xy 436.109287 -125.225449) (xy 436.057958 -125.247261) (xy 436.004001 -125.261367) (xy 435.948564 -125.267467)
			(xy 435.89283 -125.26543) (xy 435.837987 -125.2553) (xy 435.785203 -125.237293) (xy 435.735603 -125.211792)
			(xy 435.690245 -125.179341) (xy 435.650096 -125.140632) (xy 435.61601 -125.096489) (xy 435.588714 -125.047854)
			(xy 435.568791 -124.995763) (xy 435.556665 -124.941326) (xy 435.552594 -124.885704) (xy 428.551652 -124.885704)
			(xy 428.544677 -124.908889) (xy 428.521005 -124.959386) (xy 428.490232 -125.005899) (xy 428.453015 -125.047436)
			(xy 428.410147 -125.083111) (xy 428.362541 -125.112165) (xy 428.311212 -125.133977) (xy 428.257255 -125.148083)
			(xy 428.201818 -125.154183) (xy 428.146084 -125.152146) (xy 428.091241 -125.142016) (xy 428.038457 -125.124009)
			(xy 427.988857 -125.098508) (xy 427.943499 -125.066057) (xy 427.90335 -125.027348) (xy 427.869264 -124.983205)
			(xy 427.841968 -124.93457) (xy 427.822045 -124.882479) (xy 427.809919 -124.828042) (xy 427.805848 -124.77242)
			(xy 411.62734 -124.77242) (xy 412.249167 -125.394212) (xy 429.170336 -125.394212) (xy 429.174407 -125.33859)
			(xy 429.186533 -125.284153) (xy 429.206456 -125.232062) (xy 429.233752 -125.183427) (xy 429.267838 -125.139284)
			(xy 429.307987 -125.100575) (xy 429.353345 -125.068124) (xy 429.402945 -125.042623) (xy 429.455729 -125.024616)
			(xy 429.510572 -125.014486) (xy 429.566306 -125.012449) (xy 429.621743 -125.018549) (xy 429.6757 -125.032655)
			(xy 429.727029 -125.054467) (xy 429.774635 -125.083521) (xy 429.817503 -125.119196) (xy 429.85472 -125.160733)
			(xy 429.885493 -125.207246) (xy 429.909165 -125.257743) (xy 429.925233 -125.31115) (xy 429.933353 -125.366326)
			(xy 429.933862 -125.394212) (xy 429.933353 -125.422098) (xy 429.925233 -125.477274) (xy 429.909165 -125.530681)
			(xy 429.885493 -125.581178) (xy 429.85472 -125.627691) (xy 429.817503 -125.669228) (xy 429.774635 -125.704903)
			(xy 429.727029 -125.733957) (xy 429.6757 -125.755769) (xy 429.621743 -125.769875) (xy 429.566306 -125.775975)
			(xy 429.510572 -125.773938) (xy 429.455729 -125.763808) (xy 429.402945 -125.745801) (xy 429.353345 -125.7203)
			(xy 429.307987 -125.687849) (xy 429.267838 -125.64914) (xy 429.233752 -125.604997) (xy 429.206456 -125.556362)
			(xy 429.186533 -125.504271) (xy 429.174407 -125.449834) (xy 429.170336 -125.394212) (xy 412.249167 -125.394212)
			(xy 412.658638 -125.80366) (xy 426.7995 -125.80366) (xy 426.803571 -125.748038) (xy 426.815697 -125.693601)
			(xy 426.83562 -125.64151) (xy 426.862916 -125.592875) (xy 426.897002 -125.548732) (xy 426.937151 -125.510023)
			(xy 426.982509 -125.477572) (xy 427.032109 -125.452071) (xy 427.084893 -125.434064) (xy 427.139736 -125.423934)
			(xy 427.19547 -125.421897) (xy 427.250907 -125.427997) (xy 427.304864 -125.442103) (xy 427.356193 -125.463915)
			(xy 427.403799 -125.492969) (xy 427.446667 -125.528644) (xy 427.483884 -125.570181) (xy 427.514657 -125.616694)
			(xy 427.538329 -125.667191) (xy 427.554397 -125.720598) (xy 427.562517 -125.775774) (xy 427.563026 -125.80366)
			(xy 427.562517 -125.831546) (xy 427.554397 -125.886722) (xy 427.55073 -125.89891) (xy 435.50408 -125.89891)
			(xy 435.508151 -125.843288) (xy 435.520277 -125.788851) (xy 435.5402 -125.73676) (xy 435.567496 -125.688125)
			(xy 435.601582 -125.643982) (xy 435.641731 -125.605273) (xy 435.687089 -125.572822) (xy 435.736689 -125.547321)
			(xy 435.789473 -125.529314) (xy 435.844316 -125.519184) (xy 435.90005 -125.517147) (xy 435.955487 -125.523247)
			(xy 436.009444 -125.537353) (xy 436.060773 -125.559165) (xy 436.108379 -125.588219) (xy 436.151247 -125.623894)
			(xy 436.188464 -125.665431) (xy 436.219237 -125.711944) (xy 436.242909 -125.762441) (xy 436.258977 -125.815848)
			(xy 436.267097 -125.871024) (xy 436.267606 -125.89891) (xy 436.267097 -125.926796) (xy 436.258977 -125.981972)
			(xy 436.242909 -126.035379) (xy 436.219237 -126.085876) (xy 436.188464 -126.132389) (xy 436.151247 -126.173926)
			(xy 436.108379 -126.209601) (xy 436.060773 -126.238655) (xy 436.009444 -126.260467) (xy 435.955487 -126.274573)
			(xy 435.90005 -126.280673) (xy 435.844316 -126.278636) (xy 435.789473 -126.268506) (xy 435.736689 -126.250499)
			(xy 435.687089 -126.224998) (xy 435.641731 -126.192547) (xy 435.601582 -126.153838) (xy 435.567496 -126.109695)
			(xy 435.5402 -126.06106) (xy 435.520277 -126.008969) (xy 435.508151 -125.954532) (xy 435.50408 -125.89891)
			(xy 427.55073 -125.89891) (xy 427.538329 -125.940129) (xy 427.514657 -125.990626) (xy 427.483884 -126.037139)
			(xy 427.446667 -126.078676) (xy 427.403799 -126.114351) (xy 427.356193 -126.143405) (xy 427.304864 -126.165217)
			(xy 427.250907 -126.179323) (xy 427.19547 -126.185423) (xy 427.139736 -126.183386) (xy 427.084893 -126.173256)
			(xy 427.032109 -126.155249) (xy 426.982509 -126.129748) (xy 426.937151 -126.097297) (xy 426.897002 -126.058588)
			(xy 426.862916 -126.014445) (xy 426.83562 -125.96581) (xy 426.815697 -125.913719) (xy 426.803571 -125.859282)
			(xy 426.7995 -125.80366) (xy 412.658638 -125.80366) (xy 414.313317 -127.458247) (xy 429.165816 -127.458247)
			(xy 429.165816 -127.403753) (xy 429.173571 -127.349814) (xy 429.188923 -127.297527) (xy 429.211559 -127.247957)
			(xy 429.241019 -127.202113) (xy 429.276704 -127.160928) (xy 429.317886 -127.12524) (xy 429.363727 -127.095775)
			(xy 429.413295 -127.073135) (xy 429.46558 -127.057778) (xy 429.519519 -127.050019) (xy 429.546766 -127.04953)
			(xy 429.576816 -127.050124) (xy 429.636173 -127.059554) (xy 429.693318 -127.078172) (xy 429.746838 -127.105515)
			(xy 429.795411 -127.14091) (xy 429.817022 -127.161798) (xy 429.827948 -127.171991) (xy 429.85427 -127.186102)
			(xy 429.883548 -127.192005) (xy 429.913282 -127.189196) (xy 429.940936 -127.177914) (xy 429.96415 -127.159121)
			(xy 429.972978 -127.147066) (xy 429.986745 -127.127393) (xy 430.018464 -127.091344) (xy 430.036224 -127.075184)
			(xy 430.045506 -127.066504) (xy 430.059824 -127.045517) (xy 430.068508 -127.021642) (xy 430.07102 -126.996361)
			(xy 430.069498 -126.983744) (xy 430.042506 -126.973126) (xy 429.991838 -126.944899) (xy 429.94602 -126.909337)
			(xy 429.906104 -126.867256) (xy 429.87301 -126.819624) (xy 429.847497 -126.767536) (xy 429.830153 -126.71219)
			(xy 429.821375 -126.654858) (xy 429.820832 -126.625858) (xy 429.821285 -126.598588) (xy 429.829053 -126.544603)
			(xy 429.844423 -126.492274) (xy 429.867084 -126.442664) (xy 429.896573 -126.396783) (xy 429.932292 -126.355566)
			(xy 429.973512 -126.319852) (xy 430.019395 -126.290366) (xy 430.069007 -126.26771) (xy 430.121339 -126.252345)
			(xy 430.175324 -126.244583) (xy 430.202594 -126.244096) (xy 430.220543 -126.244286) (xy 430.256289 -126.247591)
			(xy 430.273968 -126.2507) (xy 430.28362 -126.2507) (xy 430.310872 -126.251159) (xy 430.364821 -126.258919)
			(xy 430.417117 -126.274277) (xy 430.466695 -126.296921) (xy 430.512545 -126.32639) (xy 430.553736 -126.362084)
			(xy 430.589427 -126.403277) (xy 430.618893 -126.44913) (xy 430.641533 -126.498709) (xy 430.656887 -126.551006)
			(xy 430.664643 -126.604956) (xy 430.665128 -126.632208) (xy 430.664654 -126.659166) (xy 430.657062 -126.712545)
			(xy 430.642031 -126.764323) (xy 430.61986 -126.813469) (xy 430.59099 -126.859005) (xy 430.555998 -126.900022)
			(xy 430.536096 -126.918212) (xy 430.525502 -126.928164) (xy 430.509944 -126.952701) (xy 430.501935 -126.980629)
			(xy 430.502124 -127.009682) (xy 430.510495 -127.037504) (xy 430.52637 -127.061838) (xy 430.537112 -127.071628)
			(xy 430.544805 -127.078327) (xy 430.559545 -127.092432) (xy 430.566576 -127.099822) (xy 430.577044 -127.110092)
			(xy 430.602417 -127.124763) (xy 430.63091 -127.131636) (xy 430.660182 -127.130146) (xy 430.687829 -127.120415)
			(xy 430.711582 -127.103243) (xy 430.729488 -127.080039) (xy 430.735232 -127.066548) (xy 430.746045 -127.039951)
			(xy 430.774487 -126.990078) (xy 430.810079 -126.945029) (xy 430.852019 -126.90582) (xy 430.899358 -126.873337)
			(xy 430.95103 -126.848312) (xy 431.005868 -126.83131) (xy 431.062634 -126.822715) (xy 431.09134 -126.8222)
			(xy 431.091848 -126.8222) (xy 431.10222 -126.822278) (xy 431.122932 -126.823423) (xy 431.13325 -126.824486)
			(xy 431.146494 -126.82561) (xy 431.172767 -126.821628) (xy 431.197115 -126.810984) (xy 431.21788 -126.794402)
			(xy 431.233649 -126.773013) (xy 431.243346 -126.748272) (xy 431.246312 -126.721864) (xy 431.244756 -126.708662)
			(xy 431.242843 -126.694707) (xy 431.240806 -126.666612) (xy 431.240692 -126.652528) (xy 431.241181 -126.625276)
			(xy 431.248935 -126.571326) (xy 431.264287 -126.519028) (xy 431.286926 -126.469448) (xy 431.316391 -126.423595)
			(xy 431.352082 -126.382402) (xy 431.393273 -126.346708) (xy 431.439124 -126.31724) (xy 431.488702 -126.294597)
			(xy 431.540998 -126.27924) (xy 431.594948 -126.271483) (xy 431.6222 -126.27102) (xy 431.646145 -126.271364)
			(xy 431.693659 -126.277356) (xy 431.716942 -126.282958) (xy 431.730331 -126.285959) (xy 431.757756 -126.285459)
			(xy 431.784058 -126.277672) (xy 431.807335 -126.263162) (xy 431.825907 -126.242975) (xy 431.838431 -126.218572)
			(xy 431.841656 -126.205234) (xy 431.848089 -126.176987) (xy 431.868334 -126.122708) (xy 431.896552 -126.072114)
			(xy 431.932094 -126.026367) (xy 431.974143 -125.986519) (xy 432.021733 -125.953486) (xy 432.07377 -125.928026)
			(xy 432.129057 -125.910725) (xy 432.186324 -125.901981) (xy 432.21529 -125.90145) (xy 432.24254 -125.901997)
			(xy 432.296486 -125.909752) (xy 432.34878 -125.925105) (xy 432.398356 -125.947744) (xy 432.444205 -125.977209)
			(xy 432.485394 -126.012899) (xy 432.521085 -126.054087) (xy 432.550551 -126.099936) (xy 432.573192 -126.149511)
			(xy 432.588546 -126.201804) (xy 432.596303 -126.25575) (xy 432.596303 -126.31025) (xy 432.588546 -126.364196)
			(xy 432.573192 -126.416489) (xy 432.550551 -126.466064) (xy 432.521085 -126.511913) (xy 432.485394 -126.553101)
			(xy 432.444205 -126.588791) (xy 432.398356 -126.618256) (xy 432.34878 -126.640895) (xy 432.296486 -126.656248)
			(xy 432.24254 -126.664003) (xy 432.21529 -126.664466) (xy 432.191346 -126.664106) (xy 432.143832 -126.658124)
			(xy 432.120548 -126.652528) (xy 432.107159 -126.649527) (xy 432.079735 -126.65003) (xy 432.053435 -126.657818)
			(xy 432.030158 -126.672328) (xy 432.011586 -126.692513) (xy 431.99906 -126.716915) (xy 431.995834 -126.730252)
			(xy 431.994462 -126.736348) (xy 433.246782 -126.736348) (xy 433.250853 -126.680726) (xy 433.262979 -126.626289)
			(xy 433.282902 -126.574198) (xy 433.310198 -126.525563) (xy 433.344284 -126.48142) (xy 433.384433 -126.442711)
			(xy 433.429791 -126.41026) (xy 433.479391 -126.384759) (xy 433.532175 -126.366752) (xy 433.587018 -126.356622)
			(xy 433.642752 -126.354585) (xy 433.698189 -126.360685) (xy 433.752146 -126.374791) (xy 433.803475 -126.396603)
			(xy 433.851081 -126.425657) (xy 433.893949 -126.461332) (xy 433.931166 -126.502869) (xy 433.961939 -126.549382)
			(xy 433.985611 -126.599879) (xy 434.001679 -126.653286) (xy 434.009799 -126.708462) (xy 434.010308 -126.736348)
			(xy 434.009799 -126.764234) (xy 434.001679 -126.81941) (xy 433.985611 -126.872817) (xy 433.961939 -126.923314)
			(xy 433.931166 -126.969827) (xy 433.893949 -127.011364) (xy 433.851081 -127.047039) (xy 433.803475 -127.076093)
			(xy 433.752146 -127.097905) (xy 433.698189 -127.112011) (xy 433.642752 -127.118111) (xy 433.587018 -127.116074)
			(xy 433.532175 -127.105944) (xy 433.479391 -127.087937) (xy 433.429791 -127.062436) (xy 433.384433 -127.029985)
			(xy 433.344284 -126.991276) (xy 433.310198 -126.947133) (xy 433.282902 -126.898498) (xy 433.262979 -126.846407)
			(xy 433.250853 -126.79197) (xy 433.246782 -126.736348) (xy 431.994462 -126.736348) (xy 431.989471 -126.758516)
			(xy 431.969213 -126.812795) (xy 431.940984 -126.863387) (xy 431.905432 -126.909132) (xy 431.863374 -126.948978)
			(xy 431.815776 -126.982009) (xy 431.763733 -127.007466) (xy 431.70844 -127.024764) (xy 431.651168 -127.033506)
			(xy 431.6222 -127.034036) (xy 431.621692 -127.034036) (xy 431.61132 -127.033955) (xy 431.590608 -127.032812)
			(xy 431.58029 -127.03175) (xy 431.567042 -127.030739) (xy 431.540783 -127.034709) (xy 431.516446 -127.045337)
			(xy 431.495687 -127.0619) (xy 431.479918 -127.083269) (xy 431.470215 -127.107989) (xy 431.467237 -127.134379)
			(xy 431.468784 -127.147574) (xy 431.470701 -127.161528) (xy 431.472736 -127.189623) (xy 431.472848 -127.203708)
			(xy 431.47233 -127.230958) (xy 431.464573 -127.284902) (xy 431.44993 -127.334772) (xy 431.877976 -127.334772)
			(xy 431.882047 -127.27915) (xy 431.894173 -127.224713) (xy 431.914096 -127.172622) (xy 431.941392 -127.123987)
			(xy 431.975478 -127.079844) (xy 432.015627 -127.041135) (xy 432.060985 -127.008684) (xy 432.110585 -126.983183)
			(xy 432.163369 -126.965176) (xy 432.218212 -126.955046) (xy 432.273946 -126.953009) (xy 432.329383 -126.959109)
			(xy 432.38334 -126.973215) (xy 432.434669 -126.995027) (xy 432.482275 -127.024081) (xy 432.525143 -127.059756)
			(xy 432.56236 -127.101293) (xy 432.593133 -127.147806) (xy 432.616805 -127.198303) (xy 432.632873 -127.25171)
			(xy 432.640993 -127.306886) (xy 432.641502 -127.334772) (xy 432.640993 -127.362658) (xy 432.632873 -127.417834)
			(xy 432.616805 -127.471241) (xy 432.593133 -127.521738) (xy 432.56236 -127.568251) (xy 432.525143 -127.609788)
			(xy 432.482275 -127.645463) (xy 432.434669 -127.674517) (xy 432.38334 -127.696329) (xy 432.329383 -127.710435)
			(xy 432.273946 -127.716535) (xy 432.218212 -127.714498) (xy 432.163369 -127.704368) (xy 432.110585 -127.686361)
			(xy 432.060985 -127.66086) (xy 432.015627 -127.628409) (xy 431.975478 -127.5897) (xy 431.941392 -127.545557)
			(xy 431.914096 -127.496922) (xy 431.894173 -127.444831) (xy 431.882047 -127.390394) (xy 431.877976 -127.334772)
			(xy 431.44993 -127.334772) (xy 431.449219 -127.337194) (xy 431.42658 -127.386768) (xy 431.397117 -127.432617)
			(xy 431.361429 -127.473806) (xy 431.320242 -127.509497) (xy 431.274397 -127.538965) (xy 431.224824 -127.561608)
			(xy 431.172533 -127.576966) (xy 431.11859 -127.584727) (xy 431.09134 -127.585216) (xy 431.065389 -127.584758)
			(xy 431.013967 -127.577715) (xy 430.963974 -127.563767) (xy 430.916333 -127.543172) (xy 430.871923 -127.51631)
			(xy 430.831564 -127.483676) (xy 430.813464 -127.465074) (xy 430.803058 -127.454737) (xy 430.777668 -127.440069)
			(xy 430.74916 -127.433203) (xy 430.719876 -127.434703) (xy 430.69222 -127.444446) (xy 430.668461 -127.461632)
			(xy 430.650552 -127.48485) (xy 430.644808 -127.498348) (xy 430.634042 -127.524966) (xy 430.605595 -127.574841)
			(xy 430.569997 -127.619891) (xy 430.528051 -127.659099) (xy 430.480704 -127.69158) (xy 430.429025 -127.716602)
			(xy 430.37418 -127.733598) (xy 430.317409 -127.742185) (xy 430.2887 -127.742696) (xy 430.258649 -127.742116)
			(xy 430.199292 -127.732681) (xy 430.142148 -127.71406) (xy 430.088628 -127.686714) (xy 430.040055 -127.651317)
			(xy 430.018444 -127.630428) (xy 430.007554 -127.620193) (xy 429.981221 -127.60608) (xy 429.951932 -127.60018)
			(xy 429.922189 -127.602997) (xy 429.894529 -127.614291) (xy 429.871314 -127.633097) (xy 429.862488 -127.64516)
			(xy 429.847183 -127.666891) (xy 429.811542 -127.706322) (xy 429.77077 -127.740421) (xy 429.725659 -127.768527)
			(xy 429.677081 -127.790097) (xy 429.625978 -127.804711) (xy 429.573342 -127.812088) (xy 429.546766 -127.812546)
			(xy 429.519519 -127.811981) (xy 429.46558 -127.804222) (xy 429.413295 -127.788865) (xy 429.363727 -127.766225)
			(xy 429.317886 -127.73676) (xy 429.276704 -127.701072) (xy 429.241019 -127.659887) (xy 429.211559 -127.614043)
			(xy 429.188923 -127.564473) (xy 429.173571 -127.512186) (xy 429.165816 -127.458247) (xy 414.313317 -127.458247)
			(xy 415.564814 -128.709674) (xy 433.3367 -128.709674) (xy 433.33715 -128.683295) (xy 433.344406 -128.631037)
			(xy 433.35879 -128.580278) (xy 433.380028 -128.531982) (xy 433.407715 -128.487073) (xy 433.441324 -128.446404)
			(xy 433.480213 -128.410752) (xy 433.523642 -128.380795) (xy 433.547012 -128.368552) (xy 433.559389 -128.361886)
			(xy 433.580112 -128.3429) (xy 433.594866 -128.31898) (xy 433.602533 -128.291941) (xy 433.60253 -128.263836)
			(xy 433.594857 -128.236799) (xy 433.580097 -128.212882) (xy 433.55937 -128.193901) (xy 433.547012 -128.187196)
			(xy 433.523634 -128.174968) (xy 433.480208 -128.145005) (xy 433.441322 -128.109349) (xy 433.407716 -128.068677)
			(xy 433.38003 -128.023766) (xy 433.358791 -127.975471) (xy 433.344404 -127.924711) (xy 433.337143 -127.872454)
			(xy 433.3367 -127.846074) (xy 433.337186 -127.818823) (xy 433.344942 -127.764875) (xy 433.360297 -127.71258)
			(xy 433.382939 -127.663003) (xy 433.412405 -127.617153) (xy 433.448096 -127.575962) (xy 433.489287 -127.540271)
			(xy 433.535137 -127.510805) (xy 433.584714 -127.488163) (xy 433.637009 -127.472808) (xy 433.690957 -127.465052)
			(xy 433.745459 -127.465052) (xy 433.799407 -127.472808) (xy 433.851702 -127.488163) (xy 433.901279 -127.510805)
			(xy 433.947129 -127.540271) (xy 433.98832 -127.575962) (xy 434.024011 -127.617153) (xy 434.053477 -127.663003)
			(xy 434.076119 -127.71258) (xy 434.091474 -127.764875) (xy 434.09923 -127.818823) (xy 434.099716 -127.846074)
			(xy 434.099297 -127.872454) (xy 434.092035 -127.924712) (xy 434.077645 -127.975473) (xy 434.056402 -128.023768)
			(xy 434.028711 -128.068677) (xy 433.995099 -128.109345) (xy 433.956207 -128.144997) (xy 433.912775 -128.174953)
			(xy 433.889404 -128.187196) (xy 433.877071 -128.193938) (xy 433.856351 -128.21291) (xy 433.841595 -128.236816)
			(xy 433.833924 -128.263842) (xy 433.833921 -128.291935) (xy 433.841586 -128.318963) (xy 433.856336 -128.342872)
			(xy 433.877052 -128.361848) (xy 433.889404 -128.368552) (xy 433.912764 -128.380812) (xy 433.956188 -128.410771)
			(xy 433.995074 -128.446424) (xy 434.028681 -128.487091) (xy 434.056369 -128.531997) (xy 434.077611 -128.580288)
			(xy 434.092002 -128.631043) (xy 434.099269 -128.683296) (xy 434.099716 -128.709674) (xy 434.09923 -128.736925)
			(xy 434.091474 -128.790873) (xy 434.076119 -128.843168) (xy 434.053477 -128.892745) (xy 434.024011 -128.938595)
			(xy 433.98832 -128.979786) (xy 433.947129 -129.015477) (xy 433.901279 -129.044943) (xy 433.851702 -129.067585)
			(xy 433.799407 -129.08294) (xy 433.745459 -129.090696) (xy 433.690957 -129.090696) (xy 433.637009 -129.08294)
			(xy 433.584714 -129.067585) (xy 433.535137 -129.044943) (xy 433.489287 -129.015477) (xy 433.448096 -128.979786)
			(xy 433.412405 -128.938595) (xy 433.382939 -128.892745) (xy 433.360297 -128.843168) (xy 433.344942 -128.790873)
			(xy 433.337186 -128.736925) (xy 433.3367 -128.709674) (xy 415.564814 -128.709674) (xy 415.813494 -128.95834)
			(xy 431.4444 -128.95834) (xy 431.473375 -128.958895) (xy 431.530607 -128.967995) (xy 431.58571 -128.98594)
			(xy 431.637326 -129.012287) (xy 431.684182 -129.046387) (xy 431.705004 -129.066544) (xy 433.207922 -130.569208)
			(xy 433.218105 -130.578723) (xy 433.242434 -130.592298) (xy 433.269524 -130.598798) (xy 433.297364 -130.59774)
			(xy 433.323883 -130.589203) (xy 433.347111 -130.573821) (xy 433.365323 -130.552738) (xy 433.377163 -130.52752)
			(xy 433.381753 -130.500041) (xy 433.380642 -130.48615) (xy 433.379579 -130.475832) (xy 433.378434 -130.45512)
			(xy 433.378356 -130.444748) (xy 433.378842 -130.417497) (xy 433.386598 -130.363549) (xy 433.401953 -130.311254)
			(xy 433.424595 -130.261677) (xy 433.454061 -130.215827) (xy 433.489752 -130.174636) (xy 433.530943 -130.138945)
			(xy 433.576793 -130.109479) (xy 433.62637 -130.086837) (xy 433.678665 -130.071482) (xy 433.732613 -130.063726)
			(xy 433.787115 -130.063726) (xy 433.841063 -130.071482) (xy 433.893358 -130.086837) (xy 433.942935 -130.109479)
			(xy 433.988785 -130.138945) (xy 434.029976 -130.174636) (xy 434.065667 -130.215827) (xy 434.095133 -130.261677)
			(xy 434.117775 -130.311254) (xy 434.13313 -130.363549) (xy 434.140886 -130.417497) (xy 434.141372 -130.444748)
			(xy 434.141004 -130.467822) (xy 434.13541 -130.513631) (xy 434.124343 -130.558434) (xy 434.11648 -130.58013)
			(xy 434.112081 -130.592882) (xy 434.109441 -130.619719) (xy 434.113925 -130.64631) (xy 434.125219 -130.670797)
			(xy 434.142534 -130.69147) (xy 434.164661 -130.706884) (xy 434.190054 -130.715962) (xy 434.216937 -130.718069)
			(xy 434.230272 -130.71602) (xy 434.247637 -130.712956) (xy 434.282745 -130.709647) (xy 434.300376 -130.709416)
			(xy 434.327629 -130.709878) (xy 434.381582 -130.717632) (xy 434.433881 -130.732986) (xy 434.483463 -130.755628)
			(xy 434.529317 -130.785095) (xy 434.570511 -130.820789) (xy 434.606205 -130.861983) (xy 434.635672 -130.907837)
			(xy 434.658314 -130.957419) (xy 434.673668 -131.009718) (xy 434.681422 -131.063671) (xy 434.681884 -131.090924)
			(xy 434.681346 -131.119874) (xy 434.672594 -131.177109) (xy 434.655297 -131.232365) (xy 434.62985 -131.284374)
			(xy 434.596837 -131.331941) (xy 434.557018 -131.373975) (xy 434.511304 -131.40951) (xy 434.460747 -131.437731)
			(xy 434.406507 -131.45799) (xy 434.349829 -131.469822) (xy 434.32095 -131.471924) (xy 434.306433 -131.473163)
			(xy 434.27897 -131.482857) (xy 434.255367 -131.499917) (xy 434.237547 -131.522952) (xy 434.226964 -131.550084)
			(xy 434.224481 -131.579102) (xy 434.2303 -131.607638) (xy 434.236622 -131.620768) (xy 434.250136 -131.647532)
			(xy 434.26927 -131.704349) (xy 434.278973 -131.763512) (xy 434.279548 -131.793488) (xy 434.279548 -133.154674)
			(xy 436.082948 -134.958328) (xy 436.088536 -134.96163) (xy 436.112327 -134.97652) (xy 436.155667 -135.012181)
			(xy 436.193317 -135.053804) (xy 436.224466 -135.100493) (xy 436.248441 -135.151239) (xy 436.264727 -135.204949)
			(xy 436.272971 -135.260466) (xy 436.273448 -135.288528) (xy 436.27296 -135.315779) (xy 436.265201 -135.369726)
			(xy 436.249844 -135.422019) (xy 436.227201 -135.471596) (xy 436.197735 -135.517445) (xy 436.162044 -135.558636)
			(xy 436.120855 -135.594328) (xy 436.075006 -135.623796) (xy 436.025431 -135.646439) (xy 435.973138 -135.661798)
			(xy 435.919191 -135.669559) (xy 435.89194 -135.670036) (xy 435.864316 -135.66954) (xy 435.809648 -135.661555)
			(xy 435.756707 -135.64576) (xy 435.7066 -135.622487) (xy 435.660378 -135.592223) (xy 435.619011 -135.555602)
			(xy 435.583364 -135.513393) (xy 435.568344 -135.490204) (xy 435.565042 -135.485124) (xy 435.56174 -135.47979)
			(xy 433.650136 -133.567932) (xy 433.630012 -133.547082) (xy 433.595913 -133.500232) (xy 433.569566 -133.448623)
			(xy 433.551619 -133.393526) (xy 433.542516 -133.3363) (xy 433.541932 -133.307328) (xy 433.541932 -131.946142)
			(xy 432.143916 -130.548126) (xy 432.133307 -130.538225) (xy 432.107868 -130.524294) (xy 432.079535 -130.518087)
			(xy 432.050601 -130.520108) (xy 432.023406 -130.530191) (xy 432.000149 -130.547523) (xy 431.991008 -130.558794)
			(xy 431.972875 -130.581958) (xy 431.930684 -130.622949) (xy 431.882696 -130.656972) (xy 431.830053 -130.683221)
			(xy 431.774002 -130.701072) (xy 431.715874 -130.710102) (xy 431.686462 -130.710686) (xy 431.659213 -130.710197)
			(xy 431.605271 -130.702436) (xy 431.552982 -130.687077) (xy 431.503411 -130.664434) (xy 431.457567 -130.634966)
			(xy 431.416383 -130.599274) (xy 431.380698 -130.558085) (xy 431.351237 -130.512236) (xy 431.328602 -130.462662)
			(xy 431.313251 -130.410371) (xy 431.305499 -130.356427) (xy 431.304954 -130.329178) (xy 431.305501 -130.299765)
			(xy 431.31454 -130.241637) (xy 431.332401 -130.185588) (xy 431.358659 -130.132947) (xy 431.392692 -130.084964)
			(xy 431.433691 -130.042778) (xy 431.456846 -130.024632) (xy 431.468101 -130.015483) (xy 431.485387 -129.99221)
			(xy 431.495446 -129.96502) (xy 431.497469 -129.936101) (xy 431.491292 -129.907776) (xy 431.477413 -129.882323)
			(xy 431.467514 -129.871724) (xy 431.291746 -129.695956) (xy 415.66084 -129.695956) (xy 415.631867 -129.695396)
			(xy 415.574639 -129.686288) (xy 415.519543 -129.668336) (xy 415.467934 -129.641983) (xy 415.421085 -129.607879)
			(xy 415.400236 -129.587752) (xy 410.847286 -125.035056) (xy 410.420566 -125.035056) (xy 410.420566 -125.176534)
			(xy 415.619438 -130.375406) (xy 421.537892 -130.375406) (xy 421.668194 -130.505708) (xy 425.236638 -130.505708)
			(xy 425.240709 -130.450086) (xy 425.252835 -130.395649) (xy 425.272758 -130.343558) (xy 425.300054 -130.294923)
			(xy 425.33414 -130.25078) (xy 425.374289 -130.212071) (xy 425.419647 -130.17962) (xy 425.469247 -130.154119)
			(xy 425.522031 -130.136112) (xy 425.576874 -130.125982) (xy 425.632608 -130.123945) (xy 425.688045 -130.130045)
			(xy 425.742002 -130.144151) (xy 425.793331 -130.165963) (xy 425.840937 -130.195017) (xy 425.883805 -130.230692)
			(xy 425.921022 -130.272229) (xy 425.951795 -130.318742) (xy 425.956687 -130.329178) (xy 429.131728 -130.329178)
			(xy 429.135799 -130.273556) (xy 429.147925 -130.219119) (xy 429.167848 -130.167028) (xy 429.195144 -130.118393)
			(xy 429.22923 -130.07425) (xy 429.269379 -130.035541) (xy 429.314737 -130.00309) (xy 429.364337 -129.977589)
			(xy 429.417121 -129.959582) (xy 429.471964 -129.949452) (xy 429.527698 -129.947415) (xy 429.583135 -129.953515)
			(xy 429.637092 -129.967621) (xy 429.688421 -129.989433) (xy 429.736027 -130.018487) (xy 429.778895 -130.054162)
			(xy 429.816112 -130.095699) (xy 429.846885 -130.142212) (xy 429.870557 -130.192709) (xy 429.886625 -130.246116)
			(xy 429.894745 -130.301292) (xy 429.895254 -130.329178) (xy 429.894745 -130.357064) (xy 429.886625 -130.41224)
			(xy 429.870557 -130.465647) (xy 429.846885 -130.516144) (xy 429.816112 -130.562657) (xy 429.778895 -130.604194)
			(xy 429.736027 -130.639869) (xy 429.688421 -130.668923) (xy 429.637092 -130.690735) (xy 429.583135 -130.704841)
			(xy 429.527698 -130.710941) (xy 429.471964 -130.708904) (xy 429.417121 -130.698774) (xy 429.364337 -130.680767)
			(xy 429.314737 -130.655266) (xy 429.269379 -130.622815) (xy 429.22923 -130.584106) (xy 429.195144 -130.539963)
			(xy 429.167848 -130.491328) (xy 429.147925 -130.439237) (xy 429.135799 -130.3848) (xy 429.131728 -130.329178)
			(xy 425.956687 -130.329178) (xy 425.975467 -130.369239) (xy 425.991535 -130.422646) (xy 425.999655 -130.477822)
			(xy 426.000164 -130.505708) (xy 425.999655 -130.533594) (xy 425.991535 -130.58877) (xy 425.975467 -130.642177)
			(xy 425.951795 -130.692674) (xy 425.926771 -130.730498) (xy 427.27829 -130.730498) (xy 427.282361 -130.674876)
			(xy 427.294487 -130.620439) (xy 427.31441 -130.568348) (xy 427.341706 -130.519713) (xy 427.375792 -130.47557)
			(xy 427.415941 -130.436861) (xy 427.461299 -130.40441) (xy 427.510899 -130.378909) (xy 427.563683 -130.360902)
			(xy 427.618526 -130.350772) (xy 427.67426 -130.348735) (xy 427.729697 -130.354835) (xy 427.783654 -130.368941)
			(xy 427.834983 -130.390753) (xy 427.882589 -130.419807) (xy 427.925457 -130.455482) (xy 427.962674 -130.497019)
			(xy 427.993447 -130.543532) (xy 428.017119 -130.594029) (xy 428.033187 -130.647436) (xy 428.041307 -130.702612)
			(xy 428.041816 -130.730498) (xy 428.041307 -130.758384) (xy 428.033187 -130.81356) (xy 428.017119 -130.866967)
			(xy 427.993447 -130.917464) (xy 427.962674 -130.963977) (xy 427.925457 -131.005514) (xy 427.882589 -131.041189)
			(xy 427.834983 -131.070243) (xy 427.783654 -131.092055) (xy 427.729697 -131.106161) (xy 427.67426 -131.112261)
			(xy 427.618526 -131.110224) (xy 427.563683 -131.100094) (xy 427.510899 -131.082087) (xy 427.461299 -131.056586)
			(xy 427.415941 -131.024135) (xy 427.375792 -130.985426) (xy 427.341706 -130.941283) (xy 427.31441 -130.892648)
			(xy 427.294487 -130.840557) (xy 427.282361 -130.78612) (xy 427.27829 -130.730498) (xy 425.926771 -130.730498)
			(xy 425.921022 -130.739187) (xy 425.883805 -130.780724) (xy 425.840937 -130.816399) (xy 425.793331 -130.845453)
			(xy 425.742002 -130.867265) (xy 425.688045 -130.881371) (xy 425.632608 -130.887471) (xy 425.576874 -130.885434)
			(xy 425.522031 -130.875304) (xy 425.469247 -130.857297) (xy 425.419647 -130.831796) (xy 425.374289 -130.799345)
			(xy 425.33414 -130.760636) (xy 425.300054 -130.716493) (xy 425.272758 -130.667858) (xy 425.252835 -130.615767)
			(xy 425.240709 -130.56133) (xy 425.236638 -130.505708) (xy 421.668194 -130.505708) (xy 422.432226 -131.26974)
			(xy 427.15688 -131.26974) (xy 427.168564 -131.269994) (xy 427.288452 -131.269994) (xy 427.375066 -131.356608)
			(xy 427.38167 -131.362958) (xy 427.61789 -131.599178) (xy 428.565054 -131.599178) (xy 428.569125 -131.543556)
			(xy 428.581251 -131.489119) (xy 428.601174 -131.437028) (xy 428.62847 -131.388393) (xy 428.662556 -131.34425)
			(xy 428.702705 -131.305541) (xy 428.748063 -131.27309) (xy 428.797663 -131.247589) (xy 428.850447 -131.229582)
			(xy 428.90529 -131.219452) (xy 428.961024 -131.217415) (xy 429.016461 -131.223515) (xy 429.070418 -131.237621)
			(xy 429.121747 -131.259433) (xy 429.169353 -131.288487) (xy 429.212221 -131.324162) (xy 429.249438 -131.365699)
			(xy 429.280211 -131.412212) (xy 429.303883 -131.462709) (xy 429.319951 -131.516116) (xy 429.328071 -131.571292)
			(xy 429.32858 -131.599178) (xy 431.856386 -131.599178) (xy 431.860457 -131.543556) (xy 431.872583 -131.489119)
			(xy 431.892506 -131.437028) (xy 431.919802 -131.388393) (xy 431.953888 -131.34425) (xy 431.994037 -131.305541)
			(xy 432.039395 -131.27309) (xy 432.088995 -131.247589) (xy 432.141779 -131.229582) (xy 432.196622 -131.219452)
			(xy 432.252356 -131.217415) (xy 432.307793 -131.223515) (xy 432.36175 -131.237621) (xy 432.413079 -131.259433)
			(xy 432.460685 -131.288487) (xy 432.503553 -131.324162) (xy 432.54077 -131.365699) (xy 432.571543 -131.412212)
			(xy 432.595215 -131.462709) (xy 432.611283 -131.516116) (xy 432.619403 -131.571292) (xy 432.619912 -131.599178)
			(xy 432.619403 -131.627064) (xy 432.611283 -131.68224) (xy 432.595215 -131.735647) (xy 432.571543 -131.786144)
			(xy 432.54077 -131.832657) (xy 432.503553 -131.874194) (xy 432.460685 -131.909869) (xy 432.413079 -131.938923)
			(xy 432.36175 -131.960735) (xy 432.307793 -131.974841) (xy 432.252356 -131.980941) (xy 432.196622 -131.978904)
			(xy 432.141779 -131.968774) (xy 432.088995 -131.950767) (xy 432.039395 -131.925266) (xy 431.994037 -131.892815)
			(xy 431.953888 -131.854106) (xy 431.919802 -131.809963) (xy 431.892506 -131.761328) (xy 431.872583 -131.709237)
			(xy 431.860457 -131.6548) (xy 431.856386 -131.599178) (xy 429.32858 -131.599178) (xy 429.328071 -131.627064)
			(xy 429.319951 -131.68224) (xy 429.303883 -131.735647) (xy 429.280211 -131.786144) (xy 429.249438 -131.832657)
			(xy 429.212221 -131.874194) (xy 429.169353 -131.909869) (xy 429.121747 -131.938923) (xy 429.070418 -131.960735)
			(xy 429.016461 -131.974841) (xy 428.961024 -131.980941) (xy 428.90529 -131.978904) (xy 428.850447 -131.968774)
			(xy 428.797663 -131.950767) (xy 428.748063 -131.925266) (xy 428.702705 -131.892815) (xy 428.662556 -131.854106)
			(xy 428.62847 -131.809963) (xy 428.601174 -131.761328) (xy 428.581251 -131.709237) (xy 428.569125 -131.6548)
			(xy 428.565054 -131.599178) (xy 427.61789 -131.599178) (xy 428.167546 -132.148834) (xy 428.341282 -132.322824)
			(xy 430.248822 -132.322824) (xy 430.33569 -132.409692) (xy 430.34204 -132.415788) (xy 430.38903 -132.462778)
			(xy 431.231292 -132.462778) (xy 431.235363 -132.407156) (xy 431.247489 -132.352719) (xy 431.267412 -132.300628)
			(xy 431.294708 -132.251993) (xy 431.328794 -132.20785) (xy 431.368943 -132.169141) (xy 431.414301 -132.13669)
			(xy 431.463901 -132.111189) (xy 431.516685 -132.093182) (xy 431.571528 -132.083052) (xy 431.627262 -132.081015)
			(xy 431.682699 -132.087115) (xy 431.736656 -132.101221) (xy 431.787985 -132.123033) (xy 431.835591 -132.152087)
			(xy 431.878459 -132.187762) (xy 431.915676 -132.229299) (xy 431.946449 -132.275812) (xy 431.970121 -132.326309)
			(xy 431.986189 -132.379716) (xy 431.994309 -132.434892) (xy 431.994818 -132.462778) (xy 431.994309 -132.490664)
			(xy 431.986189 -132.54584) (xy 431.970121 -132.599247) (xy 431.946449 -132.649744) (xy 431.915676 -132.696257)
			(xy 431.878459 -132.737794) (xy 431.835591 -132.773469) (xy 431.787985 -132.802523) (xy 431.736656 -132.824335)
			(xy 431.682699 -132.838441) (xy 431.627262 -132.844541) (xy 431.571528 -132.842504) (xy 431.516685 -132.832374)
			(xy 431.463901 -132.814367) (xy 431.414301 -132.788866) (xy 431.368943 -132.756415) (xy 431.328794 -132.717706)
			(xy 431.294708 -132.673563) (xy 431.267412 -132.624928) (xy 431.247489 -132.572837) (xy 431.235363 -132.5184)
			(xy 431.231292 -132.462778) (xy 430.38903 -132.462778) (xy 431.24247 -133.316218) (xy 431.24882 -133.322822)
			(xy 431.335434 -133.409436) (xy 431.335434 -133.529324) (xy 431.335688 -133.541008) (xy 431.335688 -133.629908)
			(xy 432.162202 -133.629908) (xy 432.166273 -133.574286) (xy 432.178399 -133.519849) (xy 432.198322 -133.467758)
			(xy 432.225618 -133.419123) (xy 432.259704 -133.37498) (xy 432.299853 -133.336271) (xy 432.345211 -133.30382)
			(xy 432.394811 -133.278319) (xy 432.447595 -133.260312) (xy 432.502438 -133.250182) (xy 432.558172 -133.248145)
			(xy 432.613609 -133.254245) (xy 432.667566 -133.268351) (xy 432.718895 -133.290163) (xy 432.766501 -133.319217)
			(xy 432.809369 -133.354892) (xy 432.846586 -133.396429) (xy 432.877359 -133.442942) (xy 432.901031 -133.493439)
			(xy 432.917099 -133.546846) (xy 432.925219 -133.602022) (xy 432.925728 -133.629908) (xy 432.925219 -133.657794)
			(xy 432.917099 -133.71297) (xy 432.901031 -133.766377) (xy 432.877359 -133.816874) (xy 432.846586 -133.863387)
			(xy 432.809369 -133.904924) (xy 432.766501 -133.940599) (xy 432.718895 -133.969653) (xy 432.667566 -133.991465)
			(xy 432.613609 -134.005571) (xy 432.558172 -134.011671) (xy 432.502438 -134.009634) (xy 432.447595 -133.999504)
			(xy 432.394811 -133.981497) (xy 432.345211 -133.955996) (xy 432.299853 -133.923545) (xy 432.259704 -133.884836)
			(xy 432.225618 -133.840693) (xy 432.198322 -133.792058) (xy 432.178399 -133.739967) (xy 432.166273 -133.68553)
			(xy 432.162202 -133.629908) (xy 431.335688 -133.629908) (xy 431.335688 -135.093964) (xy 431.336172 -135.108005)
			(xy 431.343891 -135.135007) (xy 431.358673 -135.158887) (xy 431.3794 -135.177837) (xy 431.404504 -135.190426)
			(xy 431.432089 -135.195702) (xy 431.460067 -135.193265) (xy 431.473356 -135.188706) (xy 431.495161 -135.180746)
			(xy 431.540214 -135.169562) (xy 431.58629 -135.163916) (xy 431.6095 -135.16356) (xy 431.609754 -135.16356)
			(xy 431.637011 -135.16402) (xy 431.690972 -135.171772) (xy 431.74328 -135.187125) (xy 431.79287 -135.209767)
			(xy 431.838733 -135.239237) (xy 431.879934 -135.274933) (xy 431.915636 -135.316131) (xy 431.945111 -135.36199)
			(xy 431.967758 -135.411577) (xy 431.983118 -135.463883) (xy 431.990877 -135.517843) (xy 431.990877 -135.572357)
			(xy 431.983118 -135.626317) (xy 431.967758 -135.678623) (xy 431.945111 -135.72821) (xy 431.915636 -135.774069)
			(xy 431.887481 -135.806558) (xy 432.659911 -135.806558) (xy 432.659911 -135.752042) (xy 432.66767 -135.698081)
			(xy 432.68303 -135.645773) (xy 432.705678 -135.596185) (xy 432.735154 -135.550324) (xy 432.770857 -135.509125)
			(xy 432.812059 -135.473428) (xy 432.857923 -135.443957) (xy 432.907515 -135.421315) (xy 432.959824 -135.405961)
			(xy 433.013786 -135.398208) (xy 433.041044 -135.397748) (xy 433.071983 -135.398373) (xy 433.133051 -135.408358)
			(xy 433.191705 -135.428075) (xy 433.246404 -135.457005) (xy 433.271422 -135.475218) (xy 433.282668 -135.48321)
			(xy 433.308295 -135.493405) (xy 433.335716 -135.496354) (xy 433.362924 -135.491841) (xy 433.387925 -135.480197)
			(xy 433.408887 -135.462274) (xy 433.416964 -135.451088) (xy 433.432273 -135.429314) (xy 433.467904 -135.389775)
			(xy 433.508688 -135.355577) (xy 433.553832 -135.327383) (xy 433.602458 -135.305741) (xy 433.653621 -135.291072)
			(xy 433.706328 -135.283661) (xy 433.73294 -135.283194) (xy 433.76019 -135.283679) (xy 433.814133 -135.29144)
			(xy 433.866423 -135.306798) (xy 433.915996 -135.329442) (xy 433.961842 -135.358909) (xy 434.003027 -135.394601)
			(xy 434.038715 -135.435791) (xy 434.068177 -135.481639) (xy 434.090816 -135.531214) (xy 434.106169 -135.583506)
			(xy 434.113924 -135.63745) (xy 434.113924 -135.69195) (xy 434.106169 -135.745894) (xy 434.090816 -135.798186)
			(xy 434.068177 -135.847761) (xy 434.038715 -135.893609) (xy 434.003027 -135.934799) (xy 433.961842 -135.970491)
			(xy 433.915996 -135.999958) (xy 433.866423 -136.022602) (xy 433.814133 -136.03796) (xy 433.76019 -136.045721)
			(xy 433.73294 -136.04621) (xy 433.702 -136.045601) (xy 433.640931 -136.035612) (xy 433.582277 -136.015891)
			(xy 433.527579 -135.986955) (xy 433.502562 -135.96874) (xy 433.491321 -135.960741) (xy 433.465693 -135.950554)
			(xy 433.438271 -135.94761) (xy 433.411064 -135.952124) (xy 433.386063 -135.963767) (xy 433.365099 -135.981685)
			(xy 433.35702 -135.99287) (xy 433.341708 -136.014642) (xy 433.306079 -136.054183) (xy 433.265296 -136.088383)
			(xy 433.220153 -136.116578) (xy 433.171527 -136.13822) (xy 433.120363 -136.152888) (xy 433.067656 -136.160298)
			(xy 433.041044 -136.160764) (xy 433.013786 -136.160392) (xy 432.959824 -136.152639) (xy 432.907515 -136.137285)
			(xy 432.857923 -136.114643) (xy 432.812059 -136.085172) (xy 432.770857 -136.049475) (xy 432.735154 -136.008276)
			(xy 432.705678 -135.962415) (xy 432.68303 -135.912827) (xy 432.66767 -135.860519) (xy 432.659911 -135.806558)
			(xy 431.887481 -135.806558) (xy 431.879934 -135.815267) (xy 431.838733 -135.850963) (xy 431.79287 -135.880433)
			(xy 431.74328 -135.903075) (xy 431.690972 -135.918428) (xy 431.637011 -135.92618) (xy 431.609754 -135.926576)
			(xy 431.6095 -135.926576) (xy 431.586288 -135.926237) (xy 431.540208 -135.920605) (xy 431.495154 -135.909413)
			(xy 431.473356 -135.90143) (xy 431.46007 -135.896865) (xy 431.432092 -135.894426) (xy 431.404509 -135.899702)
			(xy 431.379406 -135.912293) (xy 431.358683 -135.931246) (xy 431.343907 -135.955127) (xy 431.336195 -135.982131)
			(xy 431.335688 -135.996172) (xy 431.335688 -137.147808) (xy 431.336161 -137.161689) (xy 431.343649 -137.188421)
			(xy 431.358069 -137.212143) (xy 431.378352 -137.231098) (xy 431.402994 -137.243882) (xy 431.430171 -137.249547)
			(xy 431.457869 -137.247673) (xy 431.484036 -137.238399) (xy 431.495708 -137.230866) (xy 431.519928 -137.214456)
			(xy 431.572338 -137.188467) (xy 431.628103 -137.170786) (xy 431.685914 -137.161831) (xy 431.715164 -137.16127)
			(xy 431.74242 -137.16173) (xy 431.796378 -137.169484) (xy 431.848683 -137.184838) (xy 431.898271 -137.207479)
			(xy 431.944131 -137.236948) (xy 431.985331 -137.272644) (xy 432.02103 -137.31384) (xy 432.050503 -137.359697)
			(xy 432.07315 -137.409283) (xy 432.085276 -137.450576) (xy 433.794406 -137.450576) (xy 433.798477 -137.394954)
			(xy 433.810603 -137.340517) (xy 433.830526 -137.288426) (xy 433.857822 -137.239791) (xy 433.891908 -137.195648)
			(xy 433.932057 -137.156939) (xy 433.977415 -137.124488) (xy 434.027015 -137.098987) (xy 434.079799 -137.08098)
			(xy 434.134642 -137.07085) (xy 434.190376 -137.068813) (xy 434.245813 -137.074913) (xy 434.29977 -137.089019)
			(xy 434.351099 -137.110831) (xy 434.398705 -137.139885) (xy 434.441573 -137.17556) (xy 434.47879 -137.217097)
			(xy 434.509563 -137.26361) (xy 434.533235 -137.314107) (xy 434.549303 -137.367514) (xy 434.557423 -137.42269)
			(xy 434.557932 -137.450576) (xy 434.557423 -137.478462) (xy 434.549303 -137.533638) (xy 434.533235 -137.587045)
			(xy 434.509563 -137.637542) (xy 434.47879 -137.684055) (xy 434.441573 -137.725592) (xy 434.398705 -137.761267)
			(xy 434.351099 -137.790321) (xy 434.29977 -137.812133) (xy 434.245813 -137.826239) (xy 434.190376 -137.832339)
			(xy 434.134642 -137.830302) (xy 434.079799 -137.820172) (xy 434.027015 -137.802165) (xy 433.977415 -137.776664)
			(xy 433.932057 -137.744213) (xy 433.891908 -137.705504) (xy 433.857822 -137.661361) (xy 433.830526 -137.612726)
			(xy 433.810603 -137.560635) (xy 433.798477 -137.506198) (xy 433.794406 -137.450576) (xy 432.085276 -137.450576)
			(xy 432.088509 -137.461587) (xy 432.096267 -137.515544) (xy 432.096267 -137.570056) (xy 432.088509 -137.624013)
			(xy 432.07315 -137.676317) (xy 432.050503 -137.725903) (xy 432.02103 -137.77176) (xy 431.985331 -137.812956)
			(xy 431.944131 -137.848652) (xy 431.898271 -137.878121) (xy 431.848683 -137.900762) (xy 431.796378 -137.916116)
			(xy 431.74242 -137.92387) (xy 431.715164 -137.924286) (xy 431.685915 -137.923709) (xy 431.628108 -137.914747)
			(xy 431.572345 -137.897069) (xy 431.519933 -137.87109) (xy 431.495708 -137.85469) (xy 431.484081 -137.847094)
			(xy 431.457906 -137.837843) (xy 431.430207 -137.835988) (xy 431.403032 -137.841666) (xy 431.378393 -137.854457)
			(xy 431.358113 -137.873415) (xy 431.343692 -137.897137) (xy 431.336197 -137.923868) (xy 431.335688 -137.937748)
			(xy 431.335688 -139.038756) (xy 433.284894 -139.038756) (xy 433.292649 -138.984811) (xy 433.308002 -138.932519)
			(xy 433.330641 -138.882945) (xy 433.360104 -138.837096) (xy 433.395793 -138.795908) (xy 433.436979 -138.760217)
			(xy 433.482826 -138.730751) (xy 433.532399 -138.70811) (xy 433.58469 -138.692754) (xy 433.638634 -138.684995)
			(xy 433.665884 -138.684508) (xy 433.688455 -138.684839) (xy 433.733278 -138.690182) (xy 433.755292 -138.695176)
			(xy 433.769008 -138.697889) (xy 433.796927 -138.696765) (xy 433.823496 -138.688112) (xy 433.846722 -138.672579)
			(xy 433.864866 -138.651329) (xy 433.876567 -138.625955) (xy 433.880949 -138.598359) (xy 433.879752 -138.584432)
			(xy 433.878541 -138.573296) (xy 433.87727 -138.550929) (xy 433.877212 -138.539728) (xy 433.877625 -138.512473)
			(xy 433.885379 -138.458517) (xy 433.900732 -138.406214) (xy 433.923373 -138.356628) (xy 433.95284 -138.31077)
			(xy 433.988533 -138.269571) (xy 434.029727 -138.233872) (xy 434.075582 -138.204398) (xy 434.125164 -138.181751)
			(xy 434.177465 -138.16639) (xy 434.23142 -138.158629) (xy 434.28593 -138.158625) (xy 434.339885 -138.166379)
			(xy 434.392188 -138.181733) (xy 434.441774 -138.204374) (xy 434.487633 -138.233841) (xy 434.528831 -138.269535)
			(xy 434.56453 -138.310729) (xy 434.594003 -138.356584) (xy 434.61665 -138.406167) (xy 434.632011 -138.458468)
			(xy 434.639771 -138.512422) (xy 434.639775 -138.566932) (xy 434.63202 -138.620888) (xy 434.616666 -138.673191)
			(xy 434.594025 -138.722776) (xy 434.564557 -138.768635) (xy 434.528863 -138.809833) (xy 434.487669 -138.845531)
			(xy 434.441814 -138.875004) (xy 434.392231 -138.897651) (xy 434.33993 -138.913011) (xy 434.285975 -138.920772)
			(xy 434.25872 -138.921236) (xy 434.236149 -138.920903) (xy 434.191326 -138.915561) (xy 434.169312 -138.910568)
			(xy 434.155602 -138.90781) (xy 434.127674 -138.908933) (xy 434.101098 -138.91759) (xy 434.077866 -138.93313)
			(xy 434.059721 -138.95439) (xy 434.048023 -138.979775) (xy 434.043649 -139.007382) (xy 434.044852 -139.021312)
			(xy 434.046067 -139.032448) (xy 434.047335 -139.054814) (xy 434.047392 -139.066016) (xy 434.046905 -139.093266)
			(xy 434.039146 -139.14721) (xy 434.02379 -139.199501) (xy 434.001149 -139.249074) (xy 433.971683 -139.294921)
			(xy 433.935992 -139.336107) (xy 433.894804 -139.371796) (xy 433.848955 -139.401259) (xy 433.799381 -139.423898)
			(xy 433.747089 -139.439251) (xy 433.693144 -139.447006) (xy 433.638645 -139.447005) (xy 433.584701 -139.439249)
			(xy 433.532409 -139.423894) (xy 433.482835 -139.401254) (xy 433.436988 -139.371789) (xy 433.3958 -139.3361)
			(xy 433.360111 -139.294912) (xy 433.330646 -139.249065) (xy 433.308006 -139.199491) (xy 433.292651 -139.147199)
			(xy 433.284895 -139.093255) (xy 433.284894 -139.038756) (xy 431.335688 -139.038756) (xy 431.335688 -139.716256)
			(xy 432.257706 -139.716256) (xy 432.261777 -139.660634) (xy 432.273903 -139.606197) (xy 432.293826 -139.554106)
			(xy 432.321122 -139.505471) (xy 432.355208 -139.461328) (xy 432.395357 -139.422619) (xy 432.440715 -139.390168)
			(xy 432.490315 -139.364667) (xy 432.543099 -139.34666) (xy 432.597942 -139.33653) (xy 432.653676 -139.334493)
			(xy 432.709113 -139.340593) (xy 432.76307 -139.354699) (xy 432.814399 -139.376511) (xy 432.862005 -139.405565)
			(xy 432.904873 -139.44124) (xy 432.94209 -139.482777) (xy 432.972863 -139.52929) (xy 432.996535 -139.579787)
			(xy 433.012603 -139.633194) (xy 433.020723 -139.68837) (xy 433.021232 -139.716256) (xy 433.020723 -139.744142)
			(xy 433.012603 -139.799318) (xy 432.996535 -139.852725) (xy 432.972863 -139.903222) (xy 432.94209 -139.949735)
			(xy 432.904873 -139.991272) (xy 432.862005 -140.026947) (xy 432.814399 -140.056001) (xy 432.76307 -140.077813)
			(xy 432.709113 -140.091919) (xy 432.653676 -140.098019) (xy 432.597942 -140.095982) (xy 432.543099 -140.085852)
			(xy 432.490315 -140.067845) (xy 432.440715 -140.042344) (xy 432.395357 -140.009893) (xy 432.355208 -139.971184)
			(xy 432.321122 -139.927041) (xy 432.293826 -139.878406) (xy 432.273903 -139.826315) (xy 432.261777 -139.771878)
			(xy 432.257706 -139.716256) (xy 431.335688 -139.716256) (xy 431.335688 -140.705332) (xy 431.336109 -140.718812)
			(xy 431.343175 -140.744831) (xy 431.356806 -140.768093) (xy 431.376051 -140.786975) (xy 431.399568 -140.800161)
			(xy 431.425717 -140.80673) (xy 431.452673 -140.806225) (xy 431.465736 -140.802868) (xy 431.492003 -140.795621)
			(xy 431.545934 -140.787846) (xy 431.573178 -140.787374) (xy 431.600433 -140.787835) (xy 431.654389 -140.79559)
			(xy 431.706692 -140.810945) (xy 431.756277 -140.833587) (xy 431.802136 -140.863056) (xy 431.843333 -140.898752)
			(xy 431.879031 -140.939947) (xy 431.908502 -140.985803) (xy 431.931147 -141.035387) (xy 431.946505 -141.087689)
			(xy 431.954263 -141.141645) (xy 431.954263 -141.196155) (xy 431.946505 -141.250111) (xy 431.931147 -141.302413)
			(xy 431.908502 -141.351997) (xy 431.879031 -141.397853) (xy 431.843333 -141.439048) (xy 431.802136 -141.474744)
			(xy 431.756277 -141.504213) (xy 431.706692 -141.526855) (xy 431.654389 -141.54221) (xy 431.600433 -141.549965)
			(xy 431.573178 -141.55039) (xy 431.545936 -141.549886) (xy 431.49201 -141.542111) (xy 431.465736 -141.534896)
			(xy 431.452678 -141.531522) (xy 431.425722 -141.531016) (xy 431.399574 -141.537586) (xy 431.37606 -141.550776)
			(xy 431.356821 -141.569663) (xy 431.343199 -141.59293) (xy 431.336147 -141.618951) (xy 431.335688 -141.632432)
			(xy 431.335688 -148.784056)
		)
		(stroke
			(width 0)
			(type solid)
		)
		(fill yes)
		(layer "In15.Cu")
		(net "GND")
	)
	(gr_poly
		(pts
			(xy 101.531166 -261.185152) (xy 101.536039 -261.159309) (xy 101.552384 -261.109327) (xy 101.575903 -261.062291)
			(xy 101.606084 -261.019227) (xy 101.64227 -260.98107) (xy 101.683676 -260.94865) (xy 101.729399 -260.922673)
			(xy 101.778446 -260.903703) (xy 101.82975 -260.892154) (xy 101.882194 -260.888276) (xy 101.934638 -260.892154)
			(xy 101.985942 -260.903703) (xy 102.034989 -260.922673) (xy 102.080712 -260.94865) (xy 102.122118 -260.98107)
			(xy 102.158304 -261.019227) (xy 102.188485 -261.062291) (xy 102.212004 -261.109327) (xy 102.228349 -261.159309)
			(xy 102.233222 -261.185152) (xy 102.240588 -261.22757) (xy 102.53599 -261.22757) (xy 102.55079 -261.227067)
			(xy 102.579148 -261.218583) (xy 102.603883 -261.202323) (xy 102.622916 -261.179655) (xy 102.634651 -261.15248)
			(xy 102.638102 -261.123082) (xy 102.632978 -261.093929) (xy 102.61971 -261.067469) (xy 102.609904 -261.056374)
			(xy 102.591873 -261.036446) (xy 102.561397 -260.992182) (xy 102.53791 -260.943846) (xy 102.521943 -260.892533)
			(xy 102.513857 -260.839404) (xy 102.513384 -260.812534) (xy 102.513902 -260.784547) (xy 102.522653 -260.72926)
			(xy 102.539946 -260.676024) (xy 102.565354 -260.626148) (xy 102.598252 -260.580862) (xy 102.63783 -260.541279)
			(xy 102.683113 -260.508376) (xy 102.732985 -260.482962) (xy 102.786219 -260.465663) (xy 102.841505 -260.456905)
			(xy 102.869492 -260.456426) (xy 102.896873 -260.456935) (xy 102.950986 -260.465333) (xy 103.003177 -260.481917)
			(xy 103.052212 -260.506296) (xy 103.096937 -260.537895) (xy 103.136297 -260.575969) (xy 103.169364 -260.61962)
			(xy 103.195358 -260.667819) (xy 103.213666 -260.71943) (xy 103.21925 -260.74624) (xy 103.222298 -260.76148)
			(xy 103.269288 -260.80847) (xy 103.352346 -260.725412) (xy 103.352346 -258.048252) (xy 103.313738 -258.038854)
			(xy 103.28835 -258.032063) (xy 103.239762 -258.012037) (xy 103.194644 -257.985087) (xy 103.153977 -257.9518)
			(xy 103.118642 -257.912899) (xy 103.089408 -257.869228) (xy 103.066908 -257.821734) (xy 103.051632 -257.77145)
			(xy 103.04391 -257.719467) (xy 103.043912 -257.666914) (xy 103.051636 -257.614931) (xy 103.066915 -257.564648)
			(xy 103.089417 -257.517156) (xy 103.118654 -257.473486) (xy 103.153991 -257.434586) (xy 103.19466 -257.401302)
			(xy 103.239779 -257.374355) (xy 103.288368 -257.354331) (xy 103.313738 -257.347466) (xy 103.352346 -257.338068)
			(xy 103.352346 -256.141728) (xy 103.351819 -256.12675) (xy 103.343135 -256.09808) (xy 103.326504 -256.073163)
			(xy 103.303359 -256.054145) (xy 103.275692 -256.042661) (xy 103.245882 -256.039699) (xy 103.216496 -256.045515)
			(xy 103.190061 -256.059608) (xy 103.179118 -256.069846) (xy 103.158942 -256.089165) (xy 103.113696 -256.121918)
			(xy 103.063895 -256.147212) (xy 103.010758 -256.164431) (xy 102.955586 -256.173151) (xy 102.927658 -256.173732)
			(xy 102.900798 -256.17324) (xy 102.847688 -256.165168) (xy 102.796391 -256.149212) (xy 102.748073 -256.125735)
			(xy 102.703827 -256.095269) (xy 102.664657 -256.058505) (xy 102.631452 -256.016276) (xy 102.604964 -255.96954)
			(xy 102.594918 -255.944624) (xy 102.588839 -255.930201) (xy 102.569407 -255.905685) (xy 102.543455 -255.888218)
			(xy 102.513428 -255.879446) (xy 102.482154 -255.880194) (xy 102.467156 -255.88468) (xy 102.439285 -255.893551)
			(xy 102.38159 -255.903131) (xy 102.352348 -255.90373) (xy 102.325693 -255.90326) (xy 102.272977 -255.895321)
			(xy 102.222034 -255.879613) (xy 102.174001 -255.856487) (xy 102.129951 -255.82646) (xy 102.09087 -255.790203)
			(xy 102.057629 -255.748525) (xy 102.030972 -255.702359) (xy 102.011494 -255.652734) (xy 101.99963 -255.600761)
			(xy 101.995646 -255.5476) (xy 101.99963 -255.494439) (xy 102.011494 -255.442466) (xy 102.030972 -255.392841)
			(xy 102.057629 -255.346675) (xy 102.09087 -255.304997) (xy 102.129951 -255.26874) (xy 102.174001 -255.238713)
			(xy 102.222034 -255.215587) (xy 102.272977 -255.199879) (xy 102.325693 -255.19194) (xy 102.352348 -255.191514)
			(xy 102.352602 -255.191514) (xy 102.379172 -255.191978) (xy 102.43172 -255.199885) (xy 102.45725 -255.207262)
			(xy 102.470361 -255.210851) (xy 102.497522 -255.211725) (xy 102.523953 -255.205414) (xy 102.547788 -255.192363)
			(xy 102.567344 -255.173494) (xy 102.581238 -255.150141) (xy 102.585266 -255.137158) (xy 102.592532 -255.112408)
			(xy 102.613214 -255.065157) (xy 102.640497 -255.021383) (xy 102.673809 -254.982003) (xy 102.712454 -254.947841)
			(xy 102.755623 -254.919611) (xy 102.802413 -254.897904) (xy 102.851844 -254.883174) (xy 102.902884 -254.875729)
			(xy 102.928674 -254.875284) (xy 102.956497 -254.875818) (xy 103.011468 -254.884467) (xy 103.064425 -254.901559)
			(xy 103.114079 -254.926677) (xy 103.159224 -254.959212) (xy 103.179372 -254.978408) (xy 103.190369 -254.988546)
			(xy 103.216802 -255.002517) (xy 103.246146 -255.008235) (xy 103.27589 -255.005211) (xy 103.303484 -254.993705)
			(xy 103.326564 -254.974702) (xy 103.343154 -254.94983) (xy 103.351831 -254.92122) (xy 103.352346 -254.906272)
			(xy 103.352346 -253.087632) (xy 103.351921 -253.073726) (xy 103.344422 -253.046945) (xy 103.329973 -253.023183)
			(xy 103.309645 -253.004203) (xy 103.284949 -252.991414) (xy 103.257717 -252.985767) (xy 103.229972 -252.98768)
			(xy 103.203773 -252.997011) (xy 103.181066 -253.013068) (xy 103.172006 -253.023624) (xy 103.154988 -253.043768)
			(xy 103.116027 -253.079301) (xy 103.072253 -253.108702) (xy 103.024623 -253.131328) (xy 102.974178 -253.146685)
			(xy 102.92202 -253.154438) (xy 102.895654 -253.154942) (xy 102.867672 -253.15439) (xy 102.812399 -253.145629)
			(xy 102.759176 -253.128331) (xy 102.709313 -253.102921) (xy 102.664039 -253.070025) (xy 102.624468 -253.030452)
			(xy 102.591573 -252.985176) (xy 102.566164 -252.935313) (xy 102.548868 -252.88209) (xy 102.540109 -252.826816)
			(xy 102.539546 -252.798834) (xy 102.539971 -252.774167) (xy 102.546791 -252.725305) (xy 102.560291 -252.677854)
			(xy 102.580214 -252.63272) (xy 102.606177 -252.59077) (xy 102.621588 -252.571504) (xy 102.630223 -252.560375)
			(xy 102.641584 -252.534613) (xy 102.645475 -252.506726) (xy 102.641598 -252.478838) (xy 102.63025 -252.453069)
			(xy 102.621588 -252.441964) (xy 102.606155 -252.422715) (xy 102.580189 -252.380764) (xy 102.560272 -252.335626)
			(xy 102.546785 -252.288169) (xy 102.539988 -252.239303) (xy 102.539546 -252.214634) (xy 102.540092 -252.186648)
			(xy 102.548843 -252.131364) (xy 102.566134 -252.078129) (xy 102.591539 -252.028255) (xy 102.624434 -251.982969)
			(xy 102.664008 -251.943386) (xy 102.709287 -251.910481) (xy 102.759155 -251.885064) (xy 102.812386 -251.867762)
			(xy 102.867668 -251.858999) (xy 102.895654 -251.858526) (xy 102.922018 -251.859005) (xy 102.974171 -251.86678)
			(xy 103.024609 -251.882153) (xy 103.072233 -251.904788) (xy 103.116002 -251.934192) (xy 103.154963 -251.969722)
			(xy 103.172006 -251.989844) (xy 103.181142 -252.000318) (xy 103.20384 -252.016336) (xy 103.230016 -252.025641)
			(xy 103.257732 -252.027544) (xy 103.284935 -252.021903) (xy 103.309609 -252.009137) (xy 103.329927 -251.990191)
			(xy 103.344385 -251.966468) (xy 103.351911 -251.939726) (xy 103.352346 -251.925836) (xy 103.352346 -250.180856)
			(xy 104.893618 -248.639584) (xy 104.893618 -246.694706) (xy 104.892602 -246.66956) (xy 104.893618 -246.644414)
			(xy 104.893618 -245.01729) (xy 103.290878 -243.41455) (xy 103.290878 -241.289078) (xy 103.290403 -241.274849)
			(xy 103.28255 -241.247497) (xy 103.26746 -241.22337) (xy 103.246302 -241.204339) (xy 103.220717 -241.19188)
			(xy 103.192688 -241.186959) (xy 103.164389 -241.189956) (xy 103.138013 -241.200641) (xy 103.12654 -241.209068)
			(xy 103.102874 -241.226888) (xy 103.050859 -241.255235) (xy 102.994869 -241.274581) (xy 102.936449 -241.284392)
			(xy 102.90683 -241.285014) (xy 102.878843 -241.284496) (xy 102.823557 -241.275744) (xy 102.770322 -241.258451)
			(xy 102.720447 -241.233043) (xy 102.675161 -241.200144) (xy 102.635579 -241.160567) (xy 102.602676 -241.115284)
			(xy 102.577263 -241.065412) (xy 102.559964 -241.012178) (xy 102.551207 -240.956893) (xy 102.550722 -240.928906)
			(xy 102.551141 -240.904237) (xy 102.557952 -240.855371) (xy 102.571444 -240.807913) (xy 102.591359 -240.762772)
			(xy 102.617315 -240.720813) (xy 102.632764 -240.701576) (xy 102.64139 -240.690445) (xy 102.652735 -240.664684)
			(xy 102.656616 -240.636805) (xy 102.652737 -240.608925) (xy 102.641394 -240.583163) (xy 102.632764 -240.572036)
			(xy 102.617327 -240.552788) (xy 102.591355 -240.510838) (xy 102.57143 -240.465701) (xy 102.557934 -240.418243)
			(xy 102.551128 -240.369376) (xy 102.550722 -240.344706) (xy 102.551242 -240.316721) (xy 102.559997 -240.261441)
			(xy 102.577293 -240.20821) (xy 102.602703 -240.158342) (xy 102.635603 -240.113062) (xy 102.67518 -240.073487)
			(xy 102.720462 -240.040591) (xy 102.770333 -240.015184) (xy 102.823564 -239.997892) (xy 102.878845 -239.98914)
			(xy 102.90683 -239.988598) (xy 102.936452 -239.989183) (xy 102.99488 -239.998987) (xy 103.050876 -240.018336)
			(xy 103.102892 -240.046695) (xy 103.12654 -240.064544) (xy 103.138031 -240.072962) (xy 103.16441 -240.08368)
			(xy 103.192722 -240.086701) (xy 103.220769 -240.081791) (xy 103.246371 -240.069331) (xy 103.267539 -240.050288)
			(xy 103.28263 -240.026143) (xy 103.290471 -239.998771) (xy 103.290878 -239.984534) (xy 103.290878 -239.91189)
			(xy 103.059738 -239.68075) (xy 102.224586 -239.68075) (xy 102.209941 -239.681234) (xy 102.181857 -239.689552)
			(xy 102.157289 -239.705499) (xy 102.138258 -239.727764) (xy 102.126329 -239.754515) (xy 102.122484 -239.783552)
			(xy 102.124256 -239.798098) (xy 102.126278 -239.811788) (xy 102.128439 -239.839378) (xy 102.128574 -239.853216)
			(xy 102.128076 -239.879865) (xy 102.120133 -239.932569) (xy 102.104423 -239.983499) (xy 102.081297 -240.03152)
			(xy 102.051273 -240.075557) (xy 102.015021 -240.114628) (xy 101.97335 -240.147859) (xy 101.927192 -240.174508)
			(xy 101.877578 -240.19398) (xy 101.825616 -240.20584) (xy 101.772466 -240.209824) (xy 101.719316 -240.20584)
			(xy 101.667354 -240.19398) (xy 101.61774 -240.174508) (xy 101.571582 -240.147859) (xy 101.529911 -240.114628)
			(xy 101.493659 -240.075557) (xy 101.463635 -240.03152) (xy 101.440509 -239.983499) (xy 101.424799 -239.932569)
			(xy 101.416856 -239.879865) (xy 101.416358 -239.853216) (xy 101.416505 -239.839379) (xy 101.41867 -239.81179)
			(xy 101.420676 -239.798098) (xy 101.422464 -239.783559) (xy 101.418597 -239.754535) (xy 101.406657 -239.727799)
			(xy 101.387623 -239.705548) (xy 101.363061 -239.689609) (xy 101.334986 -239.681291) (xy 101.320346 -239.68075)
			(xy 101.284532 -239.68075) (xy 101.269882 -239.681228) (xy 101.241787 -239.689538) (xy 101.217207 -239.705483)
			(xy 101.198166 -239.727751) (xy 101.186231 -239.754509) (xy 101.182384 -239.783554) (xy 101.184202 -239.798098)
			(xy 101.186224 -239.811788) (xy 101.188384 -239.839378) (xy 101.18852 -239.853216) (xy 101.18797 -239.881199)
			(xy 101.179213 -239.936475) (xy 101.161917 -239.9897) (xy 101.136508 -240.039565) (xy 101.103612 -240.084842)
			(xy 101.064039 -240.124415) (xy 101.018762 -240.15731) (xy 100.968897 -240.182719) (xy 100.915671 -240.200014)
			(xy 100.860395 -240.20877) (xy 100.832412 -240.209324) (xy 100.806838 -240.20889) (xy 100.756214 -240.201589)
			(xy 100.707155 -240.18712) (xy 100.66067 -240.165782) (xy 100.617717 -240.138012) (xy 100.579178 -240.104384)
			(xy 100.545847 -240.065588) (xy 100.518409 -240.022422) (xy 100.507546 -239.999266) (xy 100.501385 -239.986637)
			(xy 100.483328 -239.965121) (xy 100.460085 -239.949349) (xy 100.433421 -239.940517) (xy 100.405358 -239.939297)
			(xy 100.378028 -239.945779) (xy 100.353503 -239.959473) (xy 100.343208 -239.96904) (xy 100.202238 -240.11001)
			(xy 100.202238 -240.213388) (xy 100.202748 -240.22779) (xy 100.210811 -240.255443) (xy 100.22627 -240.279748)
			(xy 100.247898 -240.298772) (xy 100.273976 -240.311005) (xy 100.302432 -240.315474) (xy 100.316792 -240.314226)
			(xy 100.328233 -240.312815) (xy 100.351238 -240.311292) (xy 100.362766 -240.311178) (xy 100.38942 -240.311649)
			(xy 100.442133 -240.319589) (xy 100.493073 -240.335298) (xy 100.541103 -240.358424) (xy 100.58515 -240.388451)
			(xy 100.624229 -240.424707) (xy 100.657467 -240.466383) (xy 100.684123 -240.512548) (xy 100.703599 -240.562171)
			(xy 100.715462 -240.614141) (xy 100.719446 -240.6673) (xy 100.71745 -240.693935) (xy 100.946956 -240.693935)
			(xy 100.946956 -240.640637) (xy 100.954899 -240.587933) (xy 100.970609 -240.537003) (xy 100.993735 -240.488982)
			(xy 101.023759 -240.444945) (xy 101.060011 -240.405874) (xy 101.101682 -240.372643) (xy 101.14784 -240.345994)
			(xy 101.197454 -240.326522) (xy 101.249416 -240.314662) (xy 101.302566 -240.310679) (xy 101.355716 -240.314662)
			(xy 101.407678 -240.326522) (xy 101.457292 -240.345994) (xy 101.50345 -240.372643) (xy 101.545121 -240.405874)
			(xy 101.581373 -240.444945) (xy 101.611397 -240.488982) (xy 101.634523 -240.537003) (xy 101.650233 -240.587933)
			(xy 101.658176 -240.640637) (xy 101.658674 -240.667286) (xy 101.658176 -240.693935) (xy 101.650233 -240.746639)
			(xy 101.634523 -240.797569) (xy 101.611397 -240.84559) (xy 101.581373 -240.889627) (xy 101.545121 -240.928698)
			(xy 101.50345 -240.961929) (xy 101.457292 -240.988578) (xy 101.407678 -241.00805) (xy 101.355716 -241.01991)
			(xy 101.302566 -241.023894) (xy 101.249416 -241.01991) (xy 101.197454 -241.00805) (xy 101.14784 -240.988578)
			(xy 101.101682 -240.961929) (xy 101.060011 -240.928698) (xy 101.023759 -240.889627) (xy 100.993735 -240.84559)
			(xy 100.970609 -240.797569) (xy 100.954899 -240.746639) (xy 100.946956 -240.693935) (xy 100.71745 -240.693935)
			(xy 100.715462 -240.720459) (xy 100.703599 -240.772429) (xy 100.684123 -240.822052) (xy 100.657467 -240.868217)
			(xy 100.624229 -240.909893) (xy 100.58515 -240.946149) (xy 100.541103 -240.976176) (xy 100.493073 -240.999302)
			(xy 100.442133 -241.015011) (xy 100.38942 -241.022951) (xy 100.362766 -241.023394) (xy 100.351238 -241.023285)
			(xy 100.328233 -241.021758) (xy 100.316792 -241.020346) (xy 100.30243 -241.018998) (xy 100.273944 -241.023452)
			(xy 100.247838 -241.03569) (xy 100.226194 -241.054739) (xy 100.210737 -241.079078) (xy 100.2027 -241.106767)
			(xy 100.202238 -241.121184) (xy 100.202238 -241.304826) (xy 100.20808 -241.315748) (xy 100.220857 -241.34142)
			(xy 100.238957 -241.395829) (xy 100.248124 -241.452432) (xy 100.24872 -241.481102) (xy 100.248241 -241.507751)
			(xy 100.477056 -241.507751) (xy 100.477056 -241.454453) (xy 100.484999 -241.401749) (xy 100.500709 -241.350819)
			(xy 100.523835 -241.302798) (xy 100.553859 -241.258761) (xy 100.590111 -241.21969) (xy 100.631782 -241.186459)
			(xy 100.67794 -241.15981) (xy 100.727554 -241.140338) (xy 100.779516 -241.128478) (xy 100.832666 -241.124495)
			(xy 100.885816 -241.128478) (xy 100.937778 -241.140338) (xy 100.987392 -241.15981) (xy 101.03355 -241.186459)
			(xy 101.075221 -241.21969) (xy 101.111473 -241.258761) (xy 101.141497 -241.302798) (xy 101.164623 -241.350819)
			(xy 101.180333 -241.401749) (xy 101.188276 -241.454453) (xy 101.188774 -241.481102) (xy 101.188276 -241.507751)
			(xy 101.180333 -241.560455) (xy 101.164623 -241.611385) (xy 101.141497 -241.659406) (xy 101.111473 -241.703443)
			(xy 101.075221 -241.742514) (xy 101.03355 -241.775745) (xy 100.987392 -241.802394) (xy 100.937778 -241.821866)
			(xy 100.885816 -241.833726) (xy 100.832666 -241.83771) (xy 100.779516 -241.833726) (xy 100.727554 -241.821866)
			(xy 100.67794 -241.802394) (xy 100.631782 -241.775745) (xy 100.590111 -241.742514) (xy 100.553859 -241.703443)
			(xy 100.523835 -241.659406) (xy 100.500709 -241.611385) (xy 100.484999 -241.560455) (xy 100.477056 -241.507751)
			(xy 100.248241 -241.507751) (xy 100.248204 -241.50978) (xy 100.239055 -241.566399) (xy 100.220932 -241.620815)
			(xy 100.20808 -241.646456) (xy 100.202238 -241.657378) (xy 100.202238 -241.84102) (xy 100.202739 -241.855429)
			(xy 100.21079 -241.883098) (xy 100.226247 -241.90742) (xy 100.247879 -241.926459) (xy 100.273966 -241.938702)
			(xy 100.302434 -241.943174) (xy 100.316792 -241.941858) (xy 100.328233 -241.940447) (xy 100.351238 -241.938924)
			(xy 100.362766 -241.93881) (xy 100.389417 -241.939281) (xy 100.442126 -241.947221) (xy 100.493062 -241.962928)
			(xy 100.541087 -241.986052) (xy 100.58513 -242.016076) (xy 100.624206 -242.052329) (xy 100.657441 -242.094001)
			(xy 100.684094 -242.140162) (xy 100.703569 -242.18978) (xy 100.71543 -242.241746) (xy 100.719414 -242.2949)
			(xy 100.71543 -242.348054) (xy 100.703569 -242.40002) (xy 100.684094 -242.449638) (xy 100.657441 -242.495799)
			(xy 100.624206 -242.537471) (xy 100.58513 -242.573724) (xy 100.541087 -242.603748) (xy 100.493062 -242.626872)
			(xy 100.442126 -242.642579) (xy 100.389417 -242.650519) (xy 100.362766 -242.651026) (xy 100.351238 -242.650917)
			(xy 100.328233 -242.64939) (xy 100.316792 -242.647978) (xy 100.302432 -242.646631) (xy 100.273948 -242.651084)
			(xy 100.247846 -242.663323) (xy 100.226207 -242.682372) (xy 100.210757 -242.706712) (xy 100.202728 -242.734401)
			(xy 100.202238 -242.748816) (xy 100.202238 -242.932712) (xy 100.20808 -242.943634) (xy 100.220858 -242.969306)
			(xy 100.23896 -243.023715) (xy 100.24813 -243.080318) (xy 100.24872 -243.108988) (xy 100.248234 -243.135637)
			(xy 100.476802 -243.135637) (xy 100.476802 -243.082339) (xy 100.484745 -243.029635) (xy 100.500455 -242.978705)
			(xy 100.523581 -242.930684) (xy 100.553605 -242.886647) (xy 100.589857 -242.847576) (xy 100.631528 -242.814345)
			(xy 100.677686 -242.787696) (xy 100.7273 -242.768224) (xy 100.779262 -242.756364) (xy 100.832412 -242.752381)
			(xy 100.885562 -242.756364) (xy 100.937524 -242.768224) (xy 100.987138 -242.787696) (xy 101.033296 -242.814345)
			(xy 101.074967 -242.847576) (xy 101.111219 -242.886647) (xy 101.141243 -242.930684) (xy 101.164369 -242.978705)
			(xy 101.180079 -243.029635) (xy 101.188022 -243.082339) (xy 101.18852 -243.108988) (xy 101.188022 -243.135637)
			(xy 101.416602 -243.135637) (xy 101.416602 -243.082339) (xy 101.424545 -243.029635) (xy 101.440255 -242.978705)
			(xy 101.463381 -242.930684) (xy 101.493405 -242.886647) (xy 101.529657 -242.847576) (xy 101.571328 -242.814345)
			(xy 101.617486 -242.787696) (xy 101.6671 -242.768224) (xy 101.719062 -242.756364) (xy 101.772212 -242.752381)
			(xy 101.825362 -242.756364) (xy 101.877324 -242.768224) (xy 101.926938 -242.787696) (xy 101.973096 -242.814345)
			(xy 102.014767 -242.847576) (xy 102.051019 -242.886647) (xy 102.081043 -242.930684) (xy 102.104169 -242.978705)
			(xy 102.119879 -243.029635) (xy 102.127822 -243.082339) (xy 102.12832 -243.108988) (xy 102.127822 -243.135637)
			(xy 102.119879 -243.188341) (xy 102.104169 -243.239271) (xy 102.081043 -243.287292) (xy 102.051019 -243.331329)
			(xy 102.014767 -243.3704) (xy 101.973096 -243.403631) (xy 101.926938 -243.43028) (xy 101.877324 -243.449752)
			(xy 101.825362 -243.461612) (xy 101.772212 -243.465596) (xy 101.719062 -243.461612) (xy 101.6671 -243.449752)
			(xy 101.617486 -243.43028) (xy 101.571328 -243.403631) (xy 101.529657 -243.3704) (xy 101.493405 -243.331329)
			(xy 101.463381 -243.287292) (xy 101.440255 -243.239271) (xy 101.424545 -243.188341) (xy 101.416602 -243.135637)
			(xy 101.188022 -243.135637) (xy 101.180079 -243.188341) (xy 101.164369 -243.239271) (xy 101.141243 -243.287292)
			(xy 101.111219 -243.331329) (xy 101.074967 -243.3704) (xy 101.033296 -243.403631) (xy 100.987138 -243.43028)
			(xy 100.937524 -243.449752) (xy 100.885562 -243.461612) (xy 100.832412 -243.465596) (xy 100.779262 -243.461612)
			(xy 100.7273 -243.449752) (xy 100.677686 -243.43028) (xy 100.631528 -243.403631) (xy 100.589857 -243.3704)
			(xy 100.553605 -243.331329) (xy 100.523581 -243.287292) (xy 100.500455 -243.239271) (xy 100.484745 -243.188341)
			(xy 100.476802 -243.135637) (xy 100.248234 -243.135637) (xy 100.248197 -243.137664) (xy 100.239036 -243.194278)
			(xy 100.220901 -243.248686) (xy 100.20808 -243.274342) (xy 100.202238 -243.285264) (xy 100.202238 -243.468906)
			(xy 100.202737 -243.483316) (xy 100.210786 -243.510989) (xy 100.226242 -243.535314) (xy 100.247875 -243.554357)
			(xy 100.273964 -243.566601) (xy 100.302435 -243.571074) (xy 100.316792 -243.569744) (xy 100.328233 -243.568333)
			(xy 100.351238 -243.566809) (xy 100.362766 -243.566696) (xy 100.389419 -243.567167) (xy 100.442129 -243.575107)
			(xy 100.493067 -243.590815) (xy 100.541094 -243.61394) (xy 100.585139 -243.643965) (xy 100.624216 -243.680219)
			(xy 100.657453 -243.721894) (xy 100.684107 -243.768056) (xy 100.703582 -243.817676) (xy 100.715444 -243.869644)
			(xy 100.719428 -243.9228) (xy 100.71743 -243.949453) (xy 100.946702 -243.949453) (xy 100.946702 -243.896155)
			(xy 100.954645 -243.843451) (xy 100.970355 -243.792521) (xy 100.993481 -243.7445) (xy 101.023505 -243.700463)
			(xy 101.059757 -243.661392) (xy 101.101428 -243.628161) (xy 101.147586 -243.601512) (xy 101.1972 -243.58204)
			(xy 101.249162 -243.57018) (xy 101.302312 -243.566197) (xy 101.355462 -243.57018) (xy 101.407424 -243.58204)
			(xy 101.457038 -243.601512) (xy 101.503196 -243.628161) (xy 101.544867 -243.661392) (xy 101.581119 -243.700463)
			(xy 101.611143 -243.7445) (xy 101.634269 -243.792521) (xy 101.649979 -243.843451) (xy 101.657922 -243.896155)
			(xy 101.65842 -243.922804) (xy 101.657922 -243.949453) (xy 101.886756 -243.949453) (xy 101.886756 -243.896155)
			(xy 101.894699 -243.843451) (xy 101.910409 -243.792521) (xy 101.933535 -243.7445) (xy 101.963559 -243.700463)
			(xy 101.999811 -243.661392) (xy 102.041482 -243.628161) (xy 102.08764 -243.601512) (xy 102.137254 -243.58204)
			(xy 102.189216 -243.57018) (xy 102.242366 -243.566197) (xy 102.295516 -243.57018) (xy 102.347478 -243.58204)
			(xy 102.397092 -243.601512) (xy 102.44325 -243.628161) (xy 102.484921 -243.661392) (xy 102.521173 -243.700463)
			(xy 102.551197 -243.7445) (xy 102.574323 -243.792521) (xy 102.590033 -243.843451) (xy 102.597976 -243.896155)
			(xy 102.598474 -243.922804) (xy 102.597976 -243.949453) (xy 102.590033 -244.002157) (xy 102.574323 -244.053087)
			(xy 102.551197 -244.101108) (xy 102.521173 -244.145145) (xy 102.484921 -244.184216) (xy 102.44325 -244.217447)
			(xy 102.397092 -244.244096) (xy 102.347478 -244.263568) (xy 102.295516 -244.275428) (xy 102.242366 -244.279412)
			(xy 102.189216 -244.275428) (xy 102.137254 -244.263568) (xy 102.08764 -244.244096) (xy 102.041482 -244.217447)
			(xy 101.999811 -244.184216) (xy 101.963559 -244.145145) (xy 101.933535 -244.101108) (xy 101.910409 -244.053087)
			(xy 101.894699 -244.002157) (xy 101.886756 -243.949453) (xy 101.657922 -243.949453) (xy 101.649979 -244.002157)
			(xy 101.634269 -244.053087) (xy 101.611143 -244.101108) (xy 101.581119 -244.145145) (xy 101.544867 -244.184216)
			(xy 101.503196 -244.217447) (xy 101.457038 -244.244096) (xy 101.407424 -244.263568) (xy 101.355462 -244.275428)
			(xy 101.302312 -244.279412) (xy 101.249162 -244.275428) (xy 101.1972 -244.263568) (xy 101.147586 -244.244096)
			(xy 101.101428 -244.217447) (xy 101.059757 -244.184216) (xy 101.023505 -244.145145) (xy 100.993481 -244.101108)
			(xy 100.970355 -244.053087) (xy 100.954645 -244.002157) (xy 100.946702 -243.949453) (xy 100.71743 -243.949453)
			(xy 100.715444 -243.975956) (xy 100.703582 -244.027924) (xy 100.684107 -244.077544) (xy 100.657453 -244.123706)
			(xy 100.624216 -244.165381) (xy 100.585139 -244.201635) (xy 100.541094 -244.23166) (xy 100.493067 -244.254785)
			(xy 100.442129 -244.270493) (xy 100.389419 -244.278433) (xy 100.362766 -244.278912) (xy 100.351238 -244.278803)
			(xy 100.328233 -244.277276) (xy 100.316792 -244.275864) (xy 100.302431 -244.274517) (xy 100.273946 -244.27897)
			(xy 100.247843 -244.291209) (xy 100.226201 -244.310258) (xy 100.210748 -244.334597) (xy 100.202716 -244.362286)
			(xy 100.202238 -244.376702) (xy 100.202238 -244.559582) (xy 100.206048 -244.56644) (xy 100.245164 -244.605556)
			(xy 100.245164 -244.683026) (xy 100.24706 -244.696344) (xy 100.249094 -244.723169) (xy 100.249228 -244.73662)
			(xy 100.249106 -244.750072) (xy 100.248105 -244.763269) (xy 100.476802 -244.763269) (xy 100.476802 -244.709971)
			(xy 100.484745 -244.657267) (xy 100.500455 -244.606337) (xy 100.523581 -244.558316) (xy 100.553605 -244.514279)
			(xy 100.589857 -244.475208) (xy 100.631528 -244.441977) (xy 100.677686 -244.415328) (xy 100.7273 -244.395856)
			(xy 100.779262 -244.383996) (xy 100.832412 -244.380013) (xy 100.885562 -244.383996) (xy 100.937524 -244.395856)
			(xy 100.987138 -244.415328) (xy 101.033296 -244.441977) (xy 101.074967 -244.475208) (xy 101.111219 -244.514279)
			(xy 101.141243 -244.558316) (xy 101.164369 -244.606337) (xy 101.180079 -244.657267) (xy 101.188022 -244.709971)
			(xy 101.18852 -244.73662) (xy 101.188022 -244.763269) (xy 101.416602 -244.763269) (xy 101.416602 -244.709971)
			(xy 101.424545 -244.657267) (xy 101.440255 -244.606337) (xy 101.463381 -244.558316) (xy 101.493405 -244.514279)
			(xy 101.529657 -244.475208) (xy 101.571328 -244.441977) (xy 101.617486 -244.415328) (xy 101.6671 -244.395856)
			(xy 101.719062 -244.383996) (xy 101.772212 -244.380013) (xy 101.825362 -244.383996) (xy 101.877324 -244.395856)
			(xy 101.926938 -244.415328) (xy 101.973096 -244.441977) (xy 102.014767 -244.475208) (xy 102.051019 -244.514279)
			(xy 102.081043 -244.558316) (xy 102.104169 -244.606337) (xy 102.119879 -244.657267) (xy 102.127822 -244.709971)
			(xy 102.12832 -244.73662) (xy 102.127822 -244.763269) (xy 102.119879 -244.815973) (xy 102.104169 -244.866903)
			(xy 102.081043 -244.914924) (xy 102.051019 -244.958961) (xy 102.014767 -244.998032) (xy 101.973096 -245.031263)
			(xy 101.926938 -245.057912) (xy 101.877324 -245.077384) (xy 101.825362 -245.089244) (xy 101.772212 -245.093228)
			(xy 101.719062 -245.089244) (xy 101.6671 -245.077384) (xy 101.617486 -245.057912) (xy 101.571328 -245.031263)
			(xy 101.529657 -244.998032) (xy 101.493405 -244.958961) (xy 101.463381 -244.914924) (xy 101.440255 -244.866903)
			(xy 101.424545 -244.815973) (xy 101.416602 -244.763269) (xy 101.188022 -244.763269) (xy 101.180079 -244.815973)
			(xy 101.164369 -244.866903) (xy 101.141243 -244.914924) (xy 101.111219 -244.958961) (xy 101.074967 -244.998032)
			(xy 101.033296 -245.031263) (xy 100.987138 -245.057912) (xy 100.937524 -245.077384) (xy 100.885562 -245.089244)
			(xy 100.832412 -245.093228) (xy 100.779262 -245.089244) (xy 100.7273 -245.077384) (xy 100.677686 -245.057912)
			(xy 100.631528 -245.031263) (xy 100.589857 -244.998032) (xy 100.553605 -244.958961) (xy 100.523581 -244.914924)
			(xy 100.500455 -244.866903) (xy 100.484745 -244.815973) (xy 100.476802 -244.763269) (xy 100.248105 -244.763269)
			(xy 100.247071 -244.776898) (xy 100.245164 -244.790214) (xy 100.245164 -245.093236) (xy 100.245603 -245.106858)
			(xy 100.252809 -245.133133) (xy 100.266701 -245.156571) (xy 100.286291 -245.175506) (xy 100.310187 -245.188593)
			(xy 100.336692 -245.194903) (xy 100.35032 -245.194836) (xy 100.362766 -245.194582) (xy 100.38942 -245.195053)
			(xy 100.442132 -245.202993) (xy 100.493072 -245.218702) (xy 100.541101 -245.241828) (xy 100.585147 -245.271854)
			(xy 100.624226 -245.30811) (xy 100.657464 -245.349786) (xy 100.684119 -245.39595) (xy 100.703595 -245.445572)
			(xy 100.715458 -245.497542) (xy 100.719442 -245.5507) (xy 100.717446 -245.577339) (xy 100.946956 -245.577339)
			(xy 100.946956 -245.524041) (xy 100.954899 -245.471337) (xy 100.970609 -245.420407) (xy 100.993735 -245.372386)
			(xy 101.023759 -245.328349) (xy 101.060011 -245.289278) (xy 101.101682 -245.256047) (xy 101.14784 -245.229398)
			(xy 101.197454 -245.209926) (xy 101.249416 -245.198066) (xy 101.302566 -245.194083) (xy 101.355716 -245.198066)
			(xy 101.407678 -245.209926) (xy 101.457292 -245.229398) (xy 101.50345 -245.256047) (xy 101.545121 -245.289278)
			(xy 101.581373 -245.328349) (xy 101.611397 -245.372386) (xy 101.634523 -245.420407) (xy 101.650233 -245.471337)
			(xy 101.658176 -245.524041) (xy 101.658674 -245.55069) (xy 101.658674 -245.5507) (xy 101.885782 -245.5507)
			(xy 101.889765 -245.497552) (xy 101.901624 -245.445591) (xy 101.921095 -245.395978) (xy 101.947741 -245.349821)
			(xy 101.98097 -245.30815) (xy 102.020037 -245.271897) (xy 102.064072 -245.241872) (xy 102.112089 -245.218744)
			(xy 102.163017 -245.20303) (xy 102.215718 -245.195082) (xy 102.242366 -245.194582) (xy 102.266609 -245.195007)
			(xy 102.314645 -245.201592) (xy 102.361341 -245.214645) (xy 102.405829 -245.233923) (xy 102.42677 -245.246144)
			(xy 102.43946 -245.253283) (xy 102.467599 -245.260719) (xy 102.496694 -245.25993) (xy 102.524389 -245.250979)
			(xy 102.548443 -245.23459) (xy 102.566907 -245.212092) (xy 102.573074 -245.1989) (xy 102.583619 -245.17509)
			(xy 102.610648 -245.130583) (xy 102.626922 -245.110254) (xy 102.635565 -245.099135) (xy 102.646911 -245.073371)
			(xy 102.650789 -245.045488) (xy 102.646904 -245.017605) (xy 102.635552 -244.991844) (xy 102.626922 -244.980714)
			(xy 102.611509 -244.96145) (xy 102.585548 -244.919498) (xy 102.565627 -244.874364) (xy 102.552127 -244.826912)
			(xy 102.545305 -244.778051) (xy 102.54488 -244.753384) (xy 102.545378 -244.726735) (xy 102.553321 -244.674031)
			(xy 102.569031 -244.623101) (xy 102.592157 -244.57508) (xy 102.622181 -244.531043) (xy 102.658433 -244.491972)
			(xy 102.700104 -244.458741) (xy 102.746262 -244.432092) (xy 102.795876 -244.41262) (xy 102.847838 -244.40076)
			(xy 102.900988 -244.396777) (xy 102.954138 -244.40076) (xy 103.0061 -244.41262) (xy 103.055714 -244.432092)
			(xy 103.101872 -244.458741) (xy 103.143543 -244.491972) (xy 103.179795 -244.531043) (xy 103.209819 -244.57508)
			(xy 103.232945 -244.623101) (xy 103.248655 -244.674031) (xy 103.256598 -244.726735) (xy 103.257096 -244.753384)
			(xy 103.256673 -244.778053) (xy 103.24987 -244.82692) (xy 103.236379 -244.874377) (xy 103.216457 -244.919515)
			(xy 103.190489 -244.961466) (xy 103.175054 -244.980714) (xy 103.166444 -244.991855) (xy 103.155096 -245.017611)
			(xy 103.151213 -245.045488) (xy 103.155089 -245.073365) (xy 103.166431 -245.099124) (xy 103.175054 -245.110254)
			(xy 103.190495 -245.129497) (xy 103.216452 -245.171454) (xy 103.236368 -245.216594) (xy 103.249862 -245.26405)
			(xy 103.256675 -245.312915) (xy 103.257096 -245.337584) (xy 103.256573 -245.36557) (xy 103.247819 -245.420852)
			(xy 103.230524 -245.474084) (xy 103.205115 -245.523955) (xy 103.172217 -245.569237) (xy 103.13264 -245.608814)
			(xy 103.087358 -245.641713) (xy 103.037487 -245.667123) (xy 102.984256 -245.684418) (xy 102.928973 -245.693172)
			(xy 102.900988 -245.693692) (xy 102.876744 -245.693291) (xy 102.828707 -245.6867) (xy 102.782011 -245.67364)
			(xy 102.737524 -245.654355) (xy 102.716584 -245.64213) (xy 102.703856 -245.635067) (xy 102.675732 -245.627625)
			(xy 102.64665 -245.628403) (xy 102.618964 -245.63734) (xy 102.594916 -245.653711) (xy 102.57645 -245.676191)
			(xy 102.57028 -245.689374) (xy 102.559697 -245.713201) (xy 102.532624 -245.757754) (xy 102.499342 -245.797881)
			(xy 102.460561 -245.832723) (xy 102.417113 -245.861535) (xy 102.369925 -245.8837) (xy 102.320009 -245.898744)
			(xy 102.268433 -245.906345) (xy 102.242366 -245.906798) (xy 102.215718 -245.906318) (xy 102.163017 -245.89837)
			(xy 102.112089 -245.882656) (xy 102.064072 -245.859528) (xy 102.020037 -245.829503) (xy 101.98097 -245.79325)
			(xy 101.947741 -245.751579) (xy 101.921095 -245.705422) (xy 101.901624 -245.655809) (xy 101.889765 -245.603848)
			(xy 101.885782 -245.5507) (xy 101.658674 -245.5507) (xy 101.658176 -245.577339) (xy 101.650233 -245.630043)
			(xy 101.634523 -245.680973) (xy 101.611397 -245.728994) (xy 101.581373 -245.773031) (xy 101.545121 -245.812102)
			(xy 101.50345 -245.845333) (xy 101.457292 -245.871982) (xy 101.407678 -245.891454) (xy 101.355716 -245.903314)
			(xy 101.302566 -245.907298) (xy 101.249416 -245.903314) (xy 101.197454 -245.891454) (xy 101.14784 -245.871982)
			(xy 101.101682 -245.845333) (xy 101.060011 -245.812102) (xy 101.023759 -245.773031) (xy 100.993735 -245.728994)
			(xy 100.970609 -245.680973) (xy 100.954899 -245.630043) (xy 100.946956 -245.577339) (xy 100.717446 -245.577339)
			(xy 100.715458 -245.603858) (xy 100.703595 -245.655828) (xy 100.684119 -245.70545) (xy 100.657464 -245.751614)
			(xy 100.624226 -245.79329) (xy 100.585147 -245.829546) (xy 100.541101 -245.859572) (xy 100.493072 -245.882698)
			(xy 100.442132 -245.898407) (xy 100.38942 -245.906347) (xy 100.362766 -245.906798) (xy 100.35032 -245.906544)
			(xy 100.336687 -245.906495) (xy 100.310168 -245.912769) (xy 100.286256 -245.925841) (xy 100.266659 -245.944778)
			(xy 100.252776 -245.968228) (xy 100.245597 -245.994518) (xy 100.245164 -246.008144) (xy 100.245164 -246.314214)
			(xy 100.245672 -246.317516) (xy 100.247113 -246.32921) (xy 100.248636 -246.352724) (xy 100.24872 -246.364506)
			(xy 100.248641 -246.376288) (xy 100.247676 -246.391155) (xy 100.477056 -246.391155) (xy 100.477056 -246.337857)
			(xy 100.484999 -246.285153) (xy 100.500709 -246.234223) (xy 100.523835 -246.186202) (xy 100.553859 -246.142165)
			(xy 100.590111 -246.103094) (xy 100.631782 -246.069863) (xy 100.67794 -246.043214) (xy 100.727554 -246.023742)
			(xy 100.779516 -246.011882) (xy 100.832666 -246.007899) (xy 100.885816 -246.011882) (xy 100.937778 -246.023742)
			(xy 100.987392 -246.043214) (xy 101.03355 -246.069863) (xy 101.075221 -246.103094) (xy 101.111473 -246.142165)
			(xy 101.141497 -246.186202) (xy 101.164623 -246.234223) (xy 101.180333 -246.285153) (xy 101.188276 -246.337857)
			(xy 101.188774 -246.364506) (xy 101.188276 -246.391155) (xy 101.416602 -246.391155) (xy 101.416602 -246.337857)
			(xy 101.424545 -246.285153) (xy 101.440255 -246.234223) (xy 101.463381 -246.186202) (xy 101.493405 -246.142165)
			(xy 101.529657 -246.103094) (xy 101.571328 -246.069863) (xy 101.617486 -246.043214) (xy 101.6671 -246.023742)
			(xy 101.719062 -246.011882) (xy 101.772212 -246.007899) (xy 101.825362 -246.011882) (xy 101.877324 -246.023742)
			(xy 101.926938 -246.043214) (xy 101.973096 -246.069863) (xy 102.014767 -246.103094) (xy 102.051019 -246.142165)
			(xy 102.081043 -246.186202) (xy 102.104169 -246.234223) (xy 102.119879 -246.285153) (xy 102.127822 -246.337857)
			(xy 102.12832 -246.364506) (xy 102.127822 -246.391155) (xy 102.119879 -246.443859) (xy 102.104169 -246.494789)
			(xy 102.081043 -246.54281) (xy 102.051019 -246.586847) (xy 102.014767 -246.625918) (xy 101.973096 -246.659149)
			(xy 101.926938 -246.685798) (xy 101.877324 -246.70527) (xy 101.825362 -246.71713) (xy 101.772212 -246.721114)
			(xy 101.719062 -246.71713) (xy 101.6671 -246.70527) (xy 101.617486 -246.685798) (xy 101.571328 -246.659149)
			(xy 101.529657 -246.625918) (xy 101.493405 -246.586847) (xy 101.463381 -246.54281) (xy 101.440255 -246.494789)
			(xy 101.424545 -246.443859) (xy 101.416602 -246.391155) (xy 101.188276 -246.391155) (xy 101.180333 -246.443859)
			(xy 101.164623 -246.494789) (xy 101.141497 -246.54281) (xy 101.111473 -246.586847) (xy 101.075221 -246.625918)
			(xy 101.03355 -246.659149) (xy 100.987392 -246.685798) (xy 100.937778 -246.70527) (xy 100.885816 -246.71713)
			(xy 100.832666 -246.721114) (xy 100.779516 -246.71713) (xy 100.727554 -246.70527) (xy 100.67794 -246.685798)
			(xy 100.631782 -246.659149) (xy 100.590111 -246.625918) (xy 100.553859 -246.586847) (xy 100.523835 -246.54281)
			(xy 100.500709 -246.494789) (xy 100.484999 -246.443859) (xy 100.477056 -246.391155) (xy 100.247676 -246.391155)
			(xy 100.247115 -246.399802) (xy 100.245672 -246.411496) (xy 100.245164 -246.414798) (xy 100.245164 -246.720868)
			(xy 100.245607 -246.734488) (xy 100.252819 -246.760755) (xy 100.266713 -246.784185) (xy 100.286301 -246.803114)
			(xy 100.310194 -246.816196) (xy 100.336694 -246.822503) (xy 100.35032 -246.822468) (xy 100.362766 -246.822214)
			(xy 100.389417 -246.822685) (xy 100.442125 -246.830624) (xy 100.49306 -246.846332) (xy 100.541085 -246.869455)
			(xy 100.585127 -246.899479) (xy 100.624203 -246.935732) (xy 100.657438 -246.977404) (xy 100.68409 -247.023564)
			(xy 100.703565 -247.073181) (xy 100.715426 -247.125147) (xy 100.71941 -247.1783) (xy 100.717411 -247.204971)
			(xy 100.946956 -247.204971) (xy 100.946956 -247.151673) (xy 100.954899 -247.098969) (xy 100.970609 -247.048039)
			(xy 100.993735 -247.000018) (xy 101.023759 -246.955981) (xy 101.060011 -246.91691) (xy 101.101682 -246.883679)
			(xy 101.14784 -246.85703) (xy 101.197454 -246.837558) (xy 101.249416 -246.825698) (xy 101.302566 -246.821715)
			(xy 101.355716 -246.825698) (xy 101.407678 -246.837558) (xy 101.457292 -246.85703) (xy 101.50345 -246.883679)
			(xy 101.545121 -246.91691) (xy 101.581373 -246.955981) (xy 101.611397 -247.000018) (xy 101.634523 -247.048039)
			(xy 101.650233 -247.098969) (xy 101.658176 -247.151673) (xy 101.658674 -247.178322) (xy 101.658176 -247.204971)
			(xy 101.886756 -247.204971) (xy 101.886756 -247.151673) (xy 101.894699 -247.098969) (xy 101.910409 -247.048039)
			(xy 101.933535 -247.000018) (xy 101.963559 -246.955981) (xy 101.999811 -246.91691) (xy 102.041482 -246.883679)
			(xy 102.08764 -246.85703) (xy 102.137254 -246.837558) (xy 102.189216 -246.825698) (xy 102.242366 -246.821715)
			(xy 102.295516 -246.825698) (xy 102.347478 -246.837558) (xy 102.397092 -246.85703) (xy 102.44325 -246.883679)
			(xy 102.484921 -246.91691) (xy 102.521173 -246.955981) (xy 102.551197 -247.000018) (xy 102.574323 -247.048039)
			(xy 102.590033 -247.098969) (xy 102.597976 -247.151673) (xy 102.598474 -247.178322) (xy 102.597976 -247.204971)
			(xy 102.590033 -247.257675) (xy 102.574323 -247.308605) (xy 102.551197 -247.356626) (xy 102.521173 -247.400663)
			(xy 102.484921 -247.439734) (xy 102.44325 -247.472965) (xy 102.397092 -247.499614) (xy 102.347478 -247.519086)
			(xy 102.295516 -247.530946) (xy 102.242366 -247.53493) (xy 102.189216 -247.530946) (xy 102.137254 -247.519086)
			(xy 102.08764 -247.499614) (xy 102.041482 -247.472965) (xy 101.999811 -247.439734) (xy 101.963559 -247.400663)
			(xy 101.933535 -247.356626) (xy 101.910409 -247.308605) (xy 101.894699 -247.257675) (xy 101.886756 -247.204971)
			(xy 101.658176 -247.204971) (xy 101.650233 -247.257675) (xy 101.634523 -247.308605) (xy 101.611397 -247.356626)
			(xy 101.581373 -247.400663) (xy 101.545121 -247.439734) (xy 101.50345 -247.472965) (xy 101.457292 -247.499614)
			(xy 101.407678 -247.519086) (xy 101.355716 -247.530946) (xy 101.302566 -247.53493) (xy 101.249416 -247.530946)
			(xy 101.197454 -247.519086) (xy 101.14784 -247.499614) (xy 101.101682 -247.472965) (xy 101.060011 -247.439734)
			(xy 101.023759 -247.400663) (xy 100.993735 -247.356626) (xy 100.970609 -247.308605) (xy 100.954899 -247.257675)
			(xy 100.946956 -247.204971) (xy 100.717411 -247.204971) (xy 100.715426 -247.231453) (xy 100.703565 -247.283419)
			(xy 100.68409 -247.333036) (xy 100.657438 -247.379196) (xy 100.624203 -247.420868) (xy 100.585127 -247.457121)
			(xy 100.541085 -247.487145) (xy 100.49306 -247.510268) (xy 100.442125 -247.525976) (xy 100.389417 -247.533915)
			(xy 100.362766 -247.53443) (xy 100.35032 -247.534176) (xy 100.336684 -247.534127) (xy 100.310158 -247.5404)
			(xy 100.286237 -247.55347) (xy 100.26663 -247.572405) (xy 100.252733 -247.595855) (xy 100.245538 -247.622147)
			(xy 100.245164 -247.635776) (xy 100.245164 -247.941846) (xy 100.245672 -247.945148) (xy 100.247115 -247.956842)
			(xy 100.248643 -247.980356) (xy 100.24872 -247.992138) (xy 100.24864 -248.00392) (xy 100.247674 -248.018787)
			(xy 100.476802 -248.018787) (xy 100.476802 -247.965489) (xy 100.484745 -247.912785) (xy 100.500455 -247.861855)
			(xy 100.523581 -247.813834) (xy 100.553605 -247.769797) (xy 100.589857 -247.730726) (xy 100.631528 -247.697495)
			(xy 100.677686 -247.670846) (xy 100.7273 -247.651374) (xy 100.779262 -247.639514) (xy 100.832412 -247.635531)
			(xy 100.885562 -247.639514) (xy 100.937524 -247.651374) (xy 100.987138 -247.670846) (xy 101.033296 -247.697495)
			(xy 101.074967 -247.730726) (xy 101.111219 -247.769797) (xy 101.141243 -247.813834) (xy 101.164369 -247.861855)
			(xy 101.180079 -247.912785) (xy 101.188022 -247.965489) (xy 101.18852 -247.992138) (xy 101.188022 -248.018787)
			(xy 101.416602 -248.018787) (xy 101.416602 -247.965489) (xy 101.424545 -247.912785) (xy 101.440255 -247.861855)
			(xy 101.463381 -247.813834) (xy 101.493405 -247.769797) (xy 101.529657 -247.730726) (xy 101.571328 -247.697495)
			(xy 101.617486 -247.670846) (xy 101.6671 -247.651374) (xy 101.719062 -247.639514) (xy 101.772212 -247.635531)
			(xy 101.825362 -247.639514) (xy 101.877324 -247.651374) (xy 101.926938 -247.670846) (xy 101.973096 -247.697495)
			(xy 102.014767 -247.730726) (xy 102.051019 -247.769797) (xy 102.081043 -247.813834) (xy 102.104169 -247.861855)
			(xy 102.119879 -247.912785) (xy 102.127822 -247.965489) (xy 102.12832 -247.992138) (xy 102.127822 -248.018787)
			(xy 102.119879 -248.071491) (xy 102.104169 -248.122421) (xy 102.081043 -248.170442) (xy 102.051019 -248.214479)
			(xy 102.014767 -248.25355) (xy 101.973096 -248.286781) (xy 101.926938 -248.31343) (xy 101.877324 -248.332902)
			(xy 101.825362 -248.344762) (xy 101.772212 -248.348746) (xy 101.719062 -248.344762) (xy 101.6671 -248.332902)
			(xy 101.617486 -248.31343) (xy 101.571328 -248.286781) (xy 101.529657 -248.25355) (xy 101.493405 -248.214479)
			(xy 101.463381 -248.170442) (xy 101.440255 -248.122421) (xy 101.424545 -248.071491) (xy 101.416602 -248.018787)
			(xy 101.188022 -248.018787) (xy 101.180079 -248.071491) (xy 101.164369 -248.122421) (xy 101.141243 -248.170442)
			(xy 101.111219 -248.214479) (xy 101.074967 -248.25355) (xy 101.033296 -248.286781) (xy 100.987138 -248.31343)
			(xy 100.937524 -248.332902) (xy 100.885562 -248.344762) (xy 100.832412 -248.348746) (xy 100.779262 -248.344762)
			(xy 100.7273 -248.332902) (xy 100.677686 -248.31343) (xy 100.631528 -248.286781) (xy 100.589857 -248.25355)
			(xy 100.553605 -248.214479) (xy 100.523581 -248.170442) (xy 100.500455 -248.122421) (xy 100.484745 -248.071491)
			(xy 100.476802 -248.018787) (xy 100.247674 -248.018787) (xy 100.247112 -248.027434) (xy 100.245672 -248.039128)
			(xy 100.245164 -248.04243) (xy 100.245164 -248.348754) (xy 100.245605 -248.362375) (xy 100.252815 -248.388646)
			(xy 100.266708 -248.412079) (xy 100.286297 -248.43101) (xy 100.310191 -248.444095) (xy 100.336693 -248.450403)
			(xy 100.35032 -248.450354) (xy 100.362766 -248.4501) (xy 100.389418 -248.450571) (xy 100.442128 -248.458511)
			(xy 100.493065 -248.474219) (xy 100.541092 -248.497343) (xy 100.585136 -248.527368) (xy 100.624213 -248.563622)
			(xy 100.657449 -248.605296) (xy 100.684103 -248.651458) (xy 100.703578 -248.701077) (xy 100.71544 -248.753045)
			(xy 100.719424 -248.8062) (xy 100.717426 -248.832857) (xy 100.946702 -248.832857) (xy 100.946702 -248.779559)
			(xy 100.954645 -248.726855) (xy 100.970355 -248.675925) (xy 100.993481 -248.627904) (xy 101.023505 -248.583867)
			(xy 101.059757 -248.544796) (xy 101.101428 -248.511565) (xy 101.147586 -248.484916) (xy 101.1972 -248.465444)
			(xy 101.249162 -248.453584) (xy 101.302312 -248.449601) (xy 101.355462 -248.453584) (xy 101.407424 -248.465444)
			(xy 101.457038 -248.484916) (xy 101.503196 -248.511565) (xy 101.544867 -248.544796) (xy 101.581119 -248.583867)
			(xy 101.611143 -248.627904) (xy 101.634269 -248.675925) (xy 101.649979 -248.726855) (xy 101.657922 -248.779559)
			(xy 101.65842 -248.8062) (xy 101.8858 -248.8062) (xy 101.889783 -248.753055) (xy 101.901641 -248.701097)
			(xy 101.921111 -248.651486) (xy 101.947756 -248.605331) (xy 101.980983 -248.563663) (xy 102.020049 -248.527411)
			(xy 102.064081 -248.497387) (xy 102.112095 -248.47426) (xy 102.163021 -248.458548) (xy 102.215719 -248.4506)
			(xy 102.242366 -248.4501) (xy 102.271189 -248.450661) (xy 102.328081 -248.459949) (xy 102.382732 -248.478287)
			(xy 102.408482 -248.491248) (xy 102.421896 -248.497633) (xy 102.451043 -248.50328) (xy 102.480584 -248.50031)
			(xy 102.508024 -248.488974) (xy 102.531047 -248.470228) (xy 102.5398 -248.458228) (xy 102.55406 -248.437913)
			(xy 102.58738 -248.401124) (xy 102.625479 -248.369311) (xy 102.667623 -248.34309) (xy 102.712996 -248.322967)
			(xy 102.760721 -248.309331) (xy 102.809876 -248.302447) (xy 102.834694 -248.302018) (xy 102.86268 -248.302518)
			(xy 102.917964 -248.311274) (xy 102.971198 -248.32857) (xy 103.02107 -248.353982) (xy 103.066352 -248.386883)
			(xy 103.10593 -248.426463) (xy 103.138828 -248.471747) (xy 103.164237 -248.521621) (xy 103.181531 -248.574855)
			(xy 103.190283 -248.630139) (xy 103.190802 -248.658126) (xy 103.190402 -248.682796) (xy 103.183593 -248.731664)
			(xy 103.170096 -248.779121) (xy 103.15017 -248.824258) (xy 103.124197 -248.866208) (xy 103.10876 -248.885456)
			(xy 103.100109 -248.896568) (xy 103.088766 -248.922335) (xy 103.08489 -248.95022) (xy 103.088777 -248.978104)
			(xy 103.10013 -249.003866) (xy 103.10876 -249.014996) (xy 103.124175 -249.034259) (xy 103.150136 -249.076211)
			(xy 103.170057 -249.121345) (xy 103.183557 -249.168797) (xy 103.190378 -249.217659) (xy 103.190802 -249.242326)
			(xy 103.190283 -249.27031) (xy 103.181524 -249.325589) (xy 103.164225 -249.378817) (xy 103.138814 -249.428683)
			(xy 103.105914 -249.473961) (xy 103.066337 -249.513535) (xy 103.021056 -249.54643) (xy 102.971187 -249.571838)
			(xy 102.917958 -249.589131) (xy 102.862678 -249.597886) (xy 102.834694 -249.598434) (xy 102.806763 -249.59787)
			(xy 102.751585 -249.589147) (xy 102.698447 -249.571914) (xy 102.648651 -249.546596) (xy 102.603419 -249.513814)
			(xy 102.56386 -249.47437) (xy 102.530946 -249.429234) (xy 102.505483 -249.379512) (xy 102.488097 -249.326423)
			(xy 102.479213 -249.271272) (xy 102.478586 -249.243342) (xy 102.478178 -249.229766) (xy 102.47093 -249.203595)
			(xy 102.457041 -249.18026) (xy 102.437494 -249.16141) (xy 102.413671 -249.148377) (xy 102.387255 -249.142083)
			(xy 102.360114 -249.142972) (xy 102.347014 -249.146568) (xy 102.321475 -249.153908) (xy 102.268933 -249.161822)
			(xy 102.242366 -249.162316) (xy 102.215719 -249.1618) (xy 102.163021 -249.153852) (xy 102.112095 -249.13814)
			(xy 102.064081 -249.115013) (xy 102.020049 -249.084989) (xy 101.980983 -249.048737) (xy 101.947756 -249.007069)
			(xy 101.921111 -248.960914) (xy 101.901641 -248.911303) (xy 101.889783 -248.859345) (xy 101.8858 -248.8062)
			(xy 101.65842 -248.8062) (xy 101.65842 -248.806208) (xy 101.657922 -248.832857) (xy 101.649979 -248.885561)
			(xy 101.634269 -248.936491) (xy 101.611143 -248.984512) (xy 101.581119 -249.028549) (xy 101.544867 -249.06762)
			(xy 101.503196 -249.100851) (xy 101.457038 -249.1275) (xy 101.407424 -249.146972) (xy 101.355462 -249.158832)
			(xy 101.302312 -249.162816) (xy 101.249162 -249.158832) (xy 101.1972 -249.146972) (xy 101.147586 -249.1275)
			(xy 101.101428 -249.100851) (xy 101.059757 -249.06762) (xy 101.023505 -249.028549) (xy 100.993481 -248.984512)
			(xy 100.970355 -248.936491) (xy 100.954645 -248.885561) (xy 100.946702 -248.832857) (xy 100.717426 -248.832857)
			(xy 100.71544 -248.859355) (xy 100.703578 -248.911323) (xy 100.684103 -248.960942) (xy 100.657449 -249.007104)
			(xy 100.624213 -249.048778) (xy 100.585136 -249.085032) (xy 100.541092 -249.115057) (xy 100.493065 -249.138181)
			(xy 100.442128 -249.153889) (xy 100.389418 -249.161829) (xy 100.362766 -249.162316) (xy 100.35032 -249.162062)
			(xy 100.336683 -249.162013) (xy 100.310155 -249.168286) (xy 100.286234 -249.181356) (xy 100.266624 -249.200291)
			(xy 100.252724 -249.22374) (xy 100.245526 -249.250032) (xy 100.245164 -249.263662) (xy 100.245164 -249.569732)
			(xy 100.245672 -249.573034) (xy 100.247112 -249.584728) (xy 100.248634 -249.608242) (xy 100.24872 -249.620024)
			(xy 100.24864 -249.631806) (xy 100.247675 -249.646673) (xy 100.476802 -249.646673) (xy 100.476802 -249.593375)
			(xy 100.484745 -249.540671) (xy 100.500455 -249.489741) (xy 100.523581 -249.44172) (xy 100.553605 -249.397683)
			(xy 100.589857 -249.358612) (xy 100.631528 -249.325381) (xy 100.677686 -249.298732) (xy 100.7273 -249.27926)
			(xy 100.779262 -249.2674) (xy 100.832412 -249.263417) (xy 100.885562 -249.2674) (xy 100.937524 -249.27926)
			(xy 100.987138 -249.298732) (xy 101.033296 -249.325381) (xy 101.074967 -249.358612) (xy 101.111219 -249.397683)
			(xy 101.141243 -249.44172) (xy 101.164369 -249.489741) (xy 101.180079 -249.540671) (xy 101.188022 -249.593375)
			(xy 101.18852 -249.620024) (xy 101.188022 -249.646673) (xy 101.416602 -249.646673) (xy 101.416602 -249.593375)
			(xy 101.424545 -249.540671) (xy 101.440255 -249.489741) (xy 101.463381 -249.44172) (xy 101.493405 -249.397683)
			(xy 101.529657 -249.358612) (xy 101.571328 -249.325381) (xy 101.617486 -249.298732) (xy 101.6671 -249.27926)
			(xy 101.719062 -249.2674) (xy 101.772212 -249.263417) (xy 101.825362 -249.2674) (xy 101.877324 -249.27926)
			(xy 101.926938 -249.298732) (xy 101.973096 -249.325381) (xy 102.014767 -249.358612) (xy 102.051019 -249.397683)
			(xy 102.081043 -249.44172) (xy 102.104169 -249.489741) (xy 102.119879 -249.540671) (xy 102.127822 -249.593375)
			(xy 102.12832 -249.620024) (xy 102.127822 -249.646673) (xy 102.119879 -249.699377) (xy 102.104169 -249.750307)
			(xy 102.081043 -249.798328) (xy 102.051019 -249.842365) (xy 102.014767 -249.881436) (xy 101.973096 -249.914667)
			(xy 101.926938 -249.941316) (xy 101.877324 -249.960788) (xy 101.825362 -249.972648) (xy 101.772212 -249.976632)
			(xy 101.719062 -249.972648) (xy 101.6671 -249.960788) (xy 101.617486 -249.941316) (xy 101.571328 -249.914667)
			(xy 101.529657 -249.881436) (xy 101.493405 -249.842365) (xy 101.463381 -249.798328) (xy 101.440255 -249.750307)
			(xy 101.424545 -249.699377) (xy 101.416602 -249.646673) (xy 101.188022 -249.646673) (xy 101.180079 -249.699377)
			(xy 101.164369 -249.750307) (xy 101.141243 -249.798328) (xy 101.111219 -249.842365) (xy 101.074967 -249.881436)
			(xy 101.033296 -249.914667) (xy 100.987138 -249.941316) (xy 100.937524 -249.960788) (xy 100.885562 -249.972648)
			(xy 100.832412 -249.976632) (xy 100.779262 -249.972648) (xy 100.7273 -249.960788) (xy 100.677686 -249.941316)
			(xy 100.631528 -249.914667) (xy 100.589857 -249.881436) (xy 100.553605 -249.842365) (xy 100.523581 -249.798328)
			(xy 100.500455 -249.750307) (xy 100.484745 -249.699377) (xy 100.476802 -249.646673) (xy 100.247675 -249.646673)
			(xy 100.247113 -249.65532) (xy 100.245672 -249.667014) (xy 100.245164 -249.670316) (xy 100.245164 -251.135134)
			(xy 102.478586 -251.135134) (xy 102.479001 -251.110464) (xy 102.485803 -251.061597) (xy 102.499296 -251.014138)
			(xy 102.519219 -250.969001) (xy 102.545191 -250.927052) (xy 102.560628 -250.907804) (xy 102.569223 -250.896651)
			(xy 102.580575 -250.870899) (xy 102.584462 -250.843026) (xy 102.580589 -250.815151) (xy 102.56925 -250.789393)
			(xy 102.560628 -250.778264) (xy 102.545193 -250.759017) (xy 102.519235 -250.71706) (xy 102.499318 -250.671922)
			(xy 102.485823 -250.624467) (xy 102.479008 -250.575602) (xy 102.478586 -250.550934) (xy 102.479084 -250.524285)
			(xy 102.487027 -250.471581) (xy 102.502737 -250.420651) (xy 102.525863 -250.37263) (xy 102.555887 -250.328593)
			(xy 102.592139 -250.289522) (xy 102.63381 -250.256291) (xy 102.679968 -250.229642) (xy 102.729582 -250.21017)
			(xy 102.781544 -250.19831) (xy 102.834694 -250.194327) (xy 102.887844 -250.19831) (xy 102.939806 -250.21017)
			(xy 102.98942 -250.229642) (xy 103.035578 -250.256291) (xy 103.077249 -250.289522) (xy 103.113501 -250.328593)
			(xy 103.143525 -250.37263) (xy 103.166651 -250.420651) (xy 103.182361 -250.471581) (xy 103.190304 -250.524285)
			(xy 103.190802 -250.550934) (xy 103.190349 -250.575602) (xy 103.183553 -250.624467) (xy 103.170068 -250.671924)
			(xy 103.150154 -250.717062) (xy 103.124191 -250.759014) (xy 103.10876 -250.778264) (xy 103.100101 -250.789371)
			(xy 103.088759 -250.81514) (xy 103.084885 -250.843026) (xy 103.088773 -250.870911) (xy 103.100129 -250.896674)
			(xy 103.10876 -250.907804) (xy 103.124179 -250.927064) (xy 103.150139 -250.969017) (xy 103.170059 -251.014152)
			(xy 103.183559 -251.061605) (xy 103.190378 -251.110466) (xy 103.190802 -251.135134) (xy 103.190304 -251.161783)
			(xy 103.182361 -251.214487) (xy 103.166651 -251.265417) (xy 103.143525 -251.313438) (xy 103.113501 -251.357475)
			(xy 103.077249 -251.396546) (xy 103.035578 -251.429777) (xy 102.98942 -251.456426) (xy 102.939806 -251.475898)
			(xy 102.887844 -251.487758) (xy 102.834694 -251.491742) (xy 102.781544 -251.487758) (xy 102.729582 -251.475898)
			(xy 102.679968 -251.456426) (xy 102.63381 -251.429777) (xy 102.592139 -251.396546) (xy 102.555887 -251.357475)
			(xy 102.525863 -251.313438) (xy 102.502737 -251.265417) (xy 102.487027 -251.214487) (xy 102.479084 -251.161783)
			(xy 102.478586 -251.135134) (xy 100.245164 -251.135134) (xy 100.245164 -253.479808) (xy 100.245566 -253.493254)
			(xy 100.252576 -253.519216) (xy 100.266133 -253.542441) (xy 100.285293 -253.561311) (xy 100.308721 -253.574512)
			(xy 100.334787 -253.581126) (xy 100.361676 -253.580692) (xy 100.374704 -253.577344) (xy 100.398645 -253.570949)
			(xy 100.447718 -253.564061) (xy 100.472494 -253.563628) (xy 100.472748 -253.563628) (xy 100.499392 -253.564129)
			(xy 100.552085 -253.572078) (xy 100.603004 -253.587791) (xy 100.651013 -253.610916) (xy 100.69504 -253.640939)
			(xy 100.734101 -253.677187) (xy 100.767323 -253.718852) (xy 100.793965 -253.765002) (xy 100.813432 -253.814608)
			(xy 100.825289 -253.86656) (xy 100.829271 -253.9197) (xy 100.827271 -253.946385) (xy 101.056938 -253.946385)
			(xy 101.056938 -253.893087) (xy 101.064881 -253.840383) (xy 101.080591 -253.789453) (xy 101.103717 -253.741432)
			(xy 101.133741 -253.697395) (xy 101.169993 -253.658324) (xy 101.211664 -253.625093) (xy 101.257822 -253.598444)
			(xy 101.307436 -253.578972) (xy 101.359398 -253.567112) (xy 101.412548 -253.563129) (xy 101.465698 -253.567112)
			(xy 101.51766 -253.578972) (xy 101.567274 -253.598444) (xy 101.613432 -253.625093) (xy 101.655103 -253.658324)
			(xy 101.691355 -253.697395) (xy 101.721379 -253.741432) (xy 101.744505 -253.789453) (xy 101.760215 -253.840383)
			(xy 101.768158 -253.893087) (xy 101.768656 -253.919736) (xy 101.768158 -253.946385) (xy 101.996738 -253.946385)
			(xy 101.996738 -253.893087) (xy 102.004681 -253.840383) (xy 102.020391 -253.789453) (xy 102.043517 -253.741432)
			(xy 102.073541 -253.697395) (xy 102.109793 -253.658324) (xy 102.151464 -253.625093) (xy 102.197622 -253.598444)
			(xy 102.247236 -253.578972) (xy 102.299198 -253.567112) (xy 102.352348 -253.563129) (xy 102.405498 -253.567112)
			(xy 102.45746 -253.578972) (xy 102.507074 -253.598444) (xy 102.553232 -253.625093) (xy 102.594903 -253.658324)
			(xy 102.631155 -253.697395) (xy 102.661179 -253.741432) (xy 102.684305 -253.789453) (xy 102.700015 -253.840383)
			(xy 102.707958 -253.893087) (xy 102.708456 -253.919736) (xy 102.707958 -253.946385) (xy 102.700015 -253.999089)
			(xy 102.684305 -254.050019) (xy 102.661179 -254.09804) (xy 102.631155 -254.142077) (xy 102.594903 -254.181148)
			(xy 102.553232 -254.214379) (xy 102.507074 -254.241028) (xy 102.45746 -254.2605) (xy 102.405498 -254.27236)
			(xy 102.352348 -254.276344) (xy 102.299198 -254.27236) (xy 102.247236 -254.2605) (xy 102.197622 -254.241028)
			(xy 102.151464 -254.214379) (xy 102.109793 -254.181148) (xy 102.073541 -254.142077) (xy 102.043517 -254.09804)
			(xy 102.020391 -254.050019) (xy 102.004681 -253.999089) (xy 101.996738 -253.946385) (xy 101.768158 -253.946385)
			(xy 101.760215 -253.999089) (xy 101.744505 -254.050019) (xy 101.721379 -254.09804) (xy 101.691355 -254.142077)
			(xy 101.655103 -254.181148) (xy 101.613432 -254.214379) (xy 101.567274 -254.241028) (xy 101.51766 -254.2605)
			(xy 101.465698 -254.27236) (xy 101.412548 -254.276344) (xy 101.359398 -254.27236) (xy 101.307436 -254.2605)
			(xy 101.257822 -254.241028) (xy 101.211664 -254.214379) (xy 101.169993 -254.181148) (xy 101.133741 -254.142077)
			(xy 101.103717 -254.09804) (xy 101.080591 -254.050019) (xy 101.064881 -253.999089) (xy 101.056938 -253.946385)
			(xy 100.827271 -253.946385) (xy 100.825289 -253.97284) (xy 100.813432 -254.024792) (xy 100.793965 -254.074398)
			(xy 100.767323 -254.120548) (xy 100.734101 -254.162213) (xy 100.69504 -254.198461) (xy 100.651013 -254.228484)
			(xy 100.603004 -254.251609) (xy 100.552085 -254.267322) (xy 100.499392 -254.275271) (xy 100.472748 -254.275844)
			(xy 100.472494 -254.275844) (xy 100.447717 -254.275419) (xy 100.398642 -254.268536) (xy 100.374704 -254.262128)
			(xy 100.361673 -254.258835) (xy 100.334808 -254.258452) (xy 100.308771 -254.265088) (xy 100.285366 -254.278283)
			(xy 100.266211 -254.297124) (xy 100.25263 -254.320308) (xy 100.245565 -254.346231) (xy 100.245164 -254.359664)
			(xy 100.245164 -254.472948) (xy 100.264306 -254.491422) (xy 100.297438 -254.533041) (xy 100.324006 -254.579127)
			(xy 100.34342 -254.628655) (xy 100.355245 -254.68052) (xy 100.35922 -254.733567) (xy 100.357229 -254.760201)
			(xy 100.586784 -254.760201) (xy 100.586784 -254.706903) (xy 100.594727 -254.654199) (xy 100.610437 -254.603269)
			(xy 100.633563 -254.555248) (xy 100.663587 -254.511211) (xy 100.699839 -254.47214) (xy 100.74151 -254.438909)
			(xy 100.787668 -254.41226) (xy 100.837282 -254.392788) (xy 100.889244 -254.380928) (xy 100.942394 -254.376945)
			(xy 100.995544 -254.380928) (xy 101.047506 -254.392788) (xy 101.09712 -254.41226) (xy 101.143278 -254.438909)
			(xy 101.184949 -254.47214) (xy 101.221201 -254.511211) (xy 101.251225 -254.555248) (xy 101.274351 -254.603269)
			(xy 101.290061 -254.654199) (xy 101.298004 -254.706903) (xy 101.298502 -254.733552) (xy 101.298004 -254.760201)
			(xy 101.526584 -254.760201) (xy 101.526584 -254.706903) (xy 101.534527 -254.654199) (xy 101.550237 -254.603269)
			(xy 101.573363 -254.555248) (xy 101.603387 -254.511211) (xy 101.639639 -254.47214) (xy 101.68131 -254.438909)
			(xy 101.727468 -254.41226) (xy 101.777082 -254.392788) (xy 101.829044 -254.380928) (xy 101.882194 -254.376945)
			(xy 101.935344 -254.380928) (xy 101.987306 -254.392788) (xy 102.03692 -254.41226) (xy 102.083078 -254.438909)
			(xy 102.124749 -254.47214) (xy 102.161001 -254.511211) (xy 102.191025 -254.555248) (xy 102.214151 -254.603269)
			(xy 102.229861 -254.654199) (xy 102.237804 -254.706903) (xy 102.238302 -254.733552) (xy 102.237804 -254.760201)
			(xy 102.229861 -254.812905) (xy 102.214151 -254.863835) (xy 102.191025 -254.911856) (xy 102.161001 -254.955893)
			(xy 102.124749 -254.994964) (xy 102.083078 -255.028195) (xy 102.03692 -255.054844) (xy 101.987306 -255.074316)
			(xy 101.935344 -255.086176) (xy 101.882194 -255.09016) (xy 101.829044 -255.086176) (xy 101.777082 -255.074316)
			(xy 101.727468 -255.054844) (xy 101.68131 -255.028195) (xy 101.639639 -254.994964) (xy 101.603387 -254.955893)
			(xy 101.573363 -254.911856) (xy 101.550237 -254.863835) (xy 101.534527 -254.812905) (xy 101.526584 -254.760201)
			(xy 101.298004 -254.760201) (xy 101.290061 -254.812905) (xy 101.274351 -254.863835) (xy 101.251225 -254.911856)
			(xy 101.221201 -254.955893) (xy 101.184949 -254.994964) (xy 101.143278 -255.028195) (xy 101.09712 -255.054844)
			(xy 101.047506 -255.074316) (xy 100.995544 -255.086176) (xy 100.942394 -255.09016) (xy 100.889244 -255.086176)
			(xy 100.837282 -255.074316) (xy 100.787668 -255.054844) (xy 100.74151 -255.028195) (xy 100.699839 -254.994964)
			(xy 100.663587 -254.955893) (xy 100.633563 -254.911856) (xy 100.610437 -254.863835) (xy 100.594727 -254.812905)
			(xy 100.586784 -254.760201) (xy 100.357229 -254.760201) (xy 100.355255 -254.786616) (xy 100.343439 -254.838483)
			(xy 100.324035 -254.888014) (xy 100.297474 -254.934105) (xy 100.26435 -254.97573) (xy 100.245164 -254.994156)
			(xy 100.245164 -255.107694) (xy 100.245564 -255.121142) (xy 100.252572 -255.147107) (xy 100.266128 -255.170335)
			(xy 100.285289 -255.189208) (xy 100.308719 -255.202411) (xy 100.334787 -255.209026) (xy 100.361678 -255.208591)
			(xy 100.374704 -255.20523) (xy 100.398645 -255.198836) (xy 100.447718 -255.191948) (xy 100.472494 -255.191514)
			(xy 100.472748 -255.191514) (xy 100.499393 -255.192016) (xy 100.552088 -255.199964) (xy 100.603009 -255.215678)
			(xy 100.65102 -255.238804) (xy 100.695049 -255.268828) (xy 100.734111 -255.305077) (xy 100.767335 -255.346744)
			(xy 100.793978 -255.392896) (xy 100.813446 -255.442503) (xy 100.825303 -255.494458) (xy 100.829285 -255.5476)
			(xy 100.827287 -255.574271) (xy 101.056938 -255.574271) (xy 101.056938 -255.520973) (xy 101.064881 -255.468269)
			(xy 101.080591 -255.417339) (xy 101.103717 -255.369318) (xy 101.133741 -255.325281) (xy 101.169993 -255.28621)
			(xy 101.211664 -255.252979) (xy 101.257822 -255.22633) (xy 101.307436 -255.206858) (xy 101.359398 -255.194998)
			(xy 101.412548 -255.191015) (xy 101.465698 -255.194998) (xy 101.51766 -255.206858) (xy 101.567274 -255.22633)
			(xy 101.613432 -255.252979) (xy 101.655103 -255.28621) (xy 101.691355 -255.325281) (xy 101.721379 -255.369318)
			(xy 101.744505 -255.417339) (xy 101.760215 -255.468269) (xy 101.768158 -255.520973) (xy 101.768656 -255.547622)
			(xy 101.768158 -255.574271) (xy 101.760215 -255.626975) (xy 101.744505 -255.677905) (xy 101.721379 -255.725926)
			(xy 101.691355 -255.769963) (xy 101.655103 -255.809034) (xy 101.613432 -255.842265) (xy 101.567274 -255.868914)
			(xy 101.51766 -255.888386) (xy 101.465698 -255.900246) (xy 101.412548 -255.90423) (xy 101.359398 -255.900246)
			(xy 101.307436 -255.888386) (xy 101.257822 -255.868914) (xy 101.211664 -255.842265) (xy 101.169993 -255.809034)
			(xy 101.133741 -255.769963) (xy 101.103717 -255.725926) (xy 101.080591 -255.677905) (xy 101.064881 -255.626975)
			(xy 101.056938 -255.574271) (xy 100.827287 -255.574271) (xy 100.825303 -255.600742) (xy 100.813446 -255.652697)
			(xy 100.793978 -255.702304) (xy 100.767335 -255.748456) (xy 100.734111 -255.790123) (xy 100.695049 -255.826372)
			(xy 100.65102 -255.856396) (xy 100.603009 -255.879522) (xy 100.552088 -255.895236) (xy 100.499393 -255.903184)
			(xy 100.472748 -255.90373) (xy 100.472494 -255.90373) (xy 100.447717 -255.903304) (xy 100.398642 -255.896422)
			(xy 100.374704 -255.890014) (xy 100.361677 -255.886719) (xy 100.334817 -255.886335) (xy 100.308788 -255.892971)
			(xy 100.285391 -255.906168) (xy 100.266248 -255.925012) (xy 100.252683 -255.948198) (xy 100.245637 -255.97412)
			(xy 100.245164 -255.98755) (xy 100.245164 -256.100834) (xy 100.264299 -256.119308) (xy 100.297419 -256.160925)
			(xy 100.323975 -256.207007) (xy 100.343377 -256.256529) (xy 100.355192 -256.308387) (xy 100.359157 -256.361426)
			(xy 100.35716 -256.388087) (xy 100.587038 -256.388087) (xy 100.587038 -256.334789) (xy 100.594981 -256.282085)
			(xy 100.610691 -256.231155) (xy 100.633817 -256.183134) (xy 100.663841 -256.139097) (xy 100.700093 -256.100026)
			(xy 100.741764 -256.066795) (xy 100.787922 -256.040146) (xy 100.837536 -256.020674) (xy 100.889498 -256.008814)
			(xy 100.942648 -256.004831) (xy 100.995798 -256.008814) (xy 101.04776 -256.020674) (xy 101.097374 -256.040146)
			(xy 101.143532 -256.066795) (xy 101.185203 -256.100026) (xy 101.221455 -256.139097) (xy 101.251479 -256.183134)
			(xy 101.274605 -256.231155) (xy 101.290315 -256.282085) (xy 101.298258 -256.334789) (xy 101.298756 -256.361438)
			(xy 101.298258 -256.388087) (xy 101.526584 -256.388087) (xy 101.526584 -256.334789) (xy 101.534527 -256.282085)
			(xy 101.550237 -256.231155) (xy 101.573363 -256.183134) (xy 101.603387 -256.139097) (xy 101.639639 -256.100026)
			(xy 101.68131 -256.066795) (xy 101.727468 -256.040146) (xy 101.777082 -256.020674) (xy 101.829044 -256.008814)
			(xy 101.882194 -256.004831) (xy 101.935344 -256.008814) (xy 101.987306 -256.020674) (xy 102.03692 -256.040146)
			(xy 102.083078 -256.066795) (xy 102.124749 -256.100026) (xy 102.161001 -256.139097) (xy 102.191025 -256.183134)
			(xy 102.214151 -256.231155) (xy 102.229861 -256.282085) (xy 102.237804 -256.334789) (xy 102.238302 -256.361438)
			(xy 102.237804 -256.388087) (xy 102.229861 -256.440791) (xy 102.214151 -256.491721) (xy 102.191025 -256.539742)
			(xy 102.161001 -256.583779) (xy 102.124749 -256.62285) (xy 102.083078 -256.656081) (xy 102.03692 -256.68273)
			(xy 101.987306 -256.702202) (xy 101.935344 -256.714062) (xy 101.882194 -256.718046) (xy 101.829044 -256.714062)
			(xy 101.777082 -256.702202) (xy 101.727468 -256.68273) (xy 101.68131 -256.656081) (xy 101.639639 -256.62285)
			(xy 101.603387 -256.583779) (xy 101.573363 -256.539742) (xy 101.550237 -256.491721) (xy 101.534527 -256.440791)
			(xy 101.526584 -256.388087) (xy 101.298258 -256.388087) (xy 101.290315 -256.440791) (xy 101.274605 -256.491721)
			(xy 101.251479 -256.539742) (xy 101.221455 -256.583779) (xy 101.185203 -256.62285) (xy 101.143532 -256.656081)
			(xy 101.097374 -256.68273) (xy 101.04776 -256.702202) (xy 100.995798 -256.714062) (xy 100.942648 -256.718046)
			(xy 100.889498 -256.714062) (xy 100.837536 -256.702202) (xy 100.787922 -256.68273) (xy 100.741764 -256.656081)
			(xy 100.700093 -256.62285) (xy 100.663841 -256.583779) (xy 100.633817 -256.539742) (xy 100.610691 -256.491721)
			(xy 100.594981 -256.440791) (xy 100.587038 -256.388087) (xy 100.35716 -256.388087) (xy 100.355184 -256.414464)
			(xy 100.343361 -256.46632) (xy 100.323952 -256.515839) (xy 100.297389 -256.561918) (xy 100.264264 -256.60353)
			(xy 100.245164 -256.622042) (xy 100.245164 -256.735326) (xy 100.245568 -256.748771) (xy 100.252581 -256.774728)
			(xy 100.266139 -256.797949) (xy 100.285298 -256.816815) (xy 100.308724 -256.830013) (xy 100.334787 -256.836626)
			(xy 100.361672 -256.836192) (xy 100.374704 -256.832862) (xy 100.398645 -256.826467) (xy 100.447718 -256.819579)
			(xy 100.472494 -256.819146) (xy 100.472748 -256.819146) (xy 100.499398 -256.819647) (xy 100.552103 -256.827598)
			(xy 100.603034 -256.843314) (xy 100.651055 -256.866445) (xy 100.695091 -256.896474) (xy 100.734161 -256.932731)
			(xy 100.767391 -256.974405) (xy 100.79404 -257.020566) (xy 100.813511 -257.070183) (xy 100.825371 -257.122148)
			(xy 100.829354 -257.1753) (xy 100.82736 -257.201903) (xy 101.056938 -257.201903) (xy 101.056938 -257.148605)
			(xy 101.064881 -257.095901) (xy 101.080591 -257.044971) (xy 101.103717 -256.99695) (xy 101.133741 -256.952913)
			(xy 101.169993 -256.913842) (xy 101.211664 -256.880611) (xy 101.257822 -256.853962) (xy 101.307436 -256.83449)
			(xy 101.359398 -256.82263) (xy 101.412548 -256.818647) (xy 101.465698 -256.82263) (xy 101.51766 -256.83449)
			(xy 101.567274 -256.853962) (xy 101.613432 -256.880611) (xy 101.655103 -256.913842) (xy 101.691355 -256.952913)
			(xy 101.721379 -256.99695) (xy 101.744505 -257.044971) (xy 101.760215 -257.095901) (xy 101.768158 -257.148605)
			(xy 101.768656 -257.175254) (xy 101.768158 -257.201903) (xy 101.996738 -257.201903) (xy 101.996738 -257.148605)
			(xy 102.004681 -257.095901) (xy 102.020391 -257.044971) (xy 102.043517 -256.99695) (xy 102.073541 -256.952913)
			(xy 102.109793 -256.913842) (xy 102.151464 -256.880611) (xy 102.197622 -256.853962) (xy 102.247236 -256.83449)
			(xy 102.299198 -256.82263) (xy 102.352348 -256.818647) (xy 102.405498 -256.82263) (xy 102.45746 -256.83449)
			(xy 102.507074 -256.853962) (xy 102.553232 -256.880611) (xy 102.594903 -256.913842) (xy 102.631155 -256.952913)
			(xy 102.661179 -256.99695) (xy 102.684305 -257.044971) (xy 102.700015 -257.095901) (xy 102.707958 -257.148605)
			(xy 102.708456 -257.175254) (xy 102.707958 -257.201903) (xy 102.700015 -257.254607) (xy 102.684305 -257.305537)
			(xy 102.661179 -257.353558) (xy 102.631155 -257.397595) (xy 102.594903 -257.436666) (xy 102.553232 -257.469897)
			(xy 102.507074 -257.496546) (xy 102.45746 -257.516018) (xy 102.405498 -257.527878) (xy 102.352348 -257.531862)
			(xy 102.299198 -257.527878) (xy 102.247236 -257.516018) (xy 102.197622 -257.496546) (xy 102.151464 -257.469897)
			(xy 102.109793 -257.436666) (xy 102.073541 -257.397595) (xy 102.043517 -257.353558) (xy 102.020391 -257.305537)
			(xy 102.004681 -257.254607) (xy 101.996738 -257.201903) (xy 101.768158 -257.201903) (xy 101.760215 -257.254607)
			(xy 101.744505 -257.305537) (xy 101.721379 -257.353558) (xy 101.691355 -257.397595) (xy 101.655103 -257.436666)
			(xy 101.613432 -257.469897) (xy 101.567274 -257.496546) (xy 101.51766 -257.516018) (xy 101.465698 -257.527878)
			(xy 101.412548 -257.531862) (xy 101.359398 -257.527878) (xy 101.307436 -257.516018) (xy 101.257822 -257.496546)
			(xy 101.211664 -257.469897) (xy 101.169993 -257.436666) (xy 101.133741 -257.397595) (xy 101.103717 -257.353558)
			(xy 101.080591 -257.305537) (xy 101.064881 -257.254607) (xy 101.056938 -257.201903) (xy 100.82736 -257.201903)
			(xy 100.825371 -257.228452) (xy 100.813511 -257.280417) (xy 100.79404 -257.330034) (xy 100.767391 -257.376195)
			(xy 100.734161 -257.417869) (xy 100.695091 -257.454126) (xy 100.651055 -257.484155) (xy 100.603034 -257.507286)
			(xy 100.552103 -257.523002) (xy 100.499398 -257.530953) (xy 100.472748 -257.531362) (xy 100.472494 -257.531362)
			(xy 100.447717 -257.530937) (xy 100.398642 -257.524055) (xy 100.374704 -257.517646) (xy 100.361674 -257.514352)
			(xy 100.33481 -257.51397) (xy 100.308775 -257.520606) (xy 100.285371 -257.533801) (xy 100.266218 -257.552643)
			(xy 100.252641 -257.575827) (xy 100.24558 -257.601749) (xy 100.245164 -257.615182) (xy 100.245164 -257.728466)
			(xy 100.264304 -257.74694) (xy 100.297434 -257.788559) (xy 100.324 -257.834644) (xy 100.343411 -257.88417)
			(xy 100.355234 -257.936034) (xy 100.359207 -257.98908) (xy 100.357215 -258.015719) (xy 100.586784 -258.015719)
			(xy 100.586784 -257.962421) (xy 100.594727 -257.909717) (xy 100.610437 -257.858787) (xy 100.633563 -257.810766)
			(xy 100.663587 -257.766729) (xy 100.699839 -257.727658) (xy 100.74151 -257.694427) (xy 100.787668 -257.667778)
			(xy 100.837282 -257.648306) (xy 100.889244 -257.636446) (xy 100.942394 -257.632463) (xy 100.995544 -257.636446)
			(xy 101.047506 -257.648306) (xy 101.09712 -257.667778) (xy 101.143278 -257.694427) (xy 101.184949 -257.727658)
			(xy 101.221201 -257.766729) (xy 101.251225 -257.810766) (xy 101.274351 -257.858787) (xy 101.290061 -257.909717)
			(xy 101.298004 -257.962421) (xy 101.298502 -257.98907) (xy 101.298004 -258.015719) (xy 101.526584 -258.015719)
			(xy 101.526584 -257.962421) (xy 101.534527 -257.909717) (xy 101.550237 -257.858787) (xy 101.573363 -257.810766)
			(xy 101.603387 -257.766729) (xy 101.639639 -257.727658) (xy 101.68131 -257.694427) (xy 101.727468 -257.667778)
			(xy 101.777082 -257.648306) (xy 101.829044 -257.636446) (xy 101.882194 -257.632463) (xy 101.935344 -257.636446)
			(xy 101.987306 -257.648306) (xy 102.03692 -257.667778) (xy 102.083078 -257.694427) (xy 102.124749 -257.727658)
			(xy 102.161001 -257.766729) (xy 102.191025 -257.810766) (xy 102.214151 -257.858787) (xy 102.229861 -257.909717)
			(xy 102.237804 -257.962421) (xy 102.238302 -257.98907) (xy 102.237804 -258.015719) (xy 102.229861 -258.068423)
			(xy 102.214151 -258.119353) (xy 102.191025 -258.167374) (xy 102.161001 -258.211411) (xy 102.124749 -258.250482)
			(xy 102.083078 -258.283713) (xy 102.03692 -258.310362) (xy 101.987306 -258.329834) (xy 101.935344 -258.341694)
			(xy 101.882194 -258.345678) (xy 101.829044 -258.341694) (xy 101.777082 -258.329834) (xy 101.727468 -258.310362)
			(xy 101.68131 -258.283713) (xy 101.639639 -258.250482) (xy 101.603387 -258.211411) (xy 101.573363 -258.167374)
			(xy 101.550237 -258.119353) (xy 101.534527 -258.068423) (xy 101.526584 -258.015719) (xy 101.298004 -258.015719)
			(xy 101.290061 -258.068423) (xy 101.274351 -258.119353) (xy 101.251225 -258.167374) (xy 101.221201 -258.211411)
			(xy 101.184949 -258.250482) (xy 101.143278 -258.283713) (xy 101.09712 -258.310362) (xy 101.047506 -258.329834)
			(xy 100.995544 -258.341694) (xy 100.942394 -258.345678) (xy 100.889244 -258.341694) (xy 100.837282 -258.329834)
			(xy 100.787668 -258.310362) (xy 100.74151 -258.283713) (xy 100.699839 -258.250482) (xy 100.663587 -258.211411)
			(xy 100.633563 -258.167374) (xy 100.610437 -258.119353) (xy 100.594727 -258.068423) (xy 100.586784 -258.015719)
			(xy 100.357215 -258.015719) (xy 100.35524 -258.042126) (xy 100.343423 -258.093991) (xy 100.324017 -258.143519)
			(xy 100.297457 -258.189608) (xy 100.264332 -258.23123) (xy 100.245164 -258.249674) (xy 100.245164 -258.363212)
			(xy 100.245566 -258.376658) (xy 100.252577 -258.402619) (xy 100.266134 -258.425843) (xy 100.285294 -258.444712)
			(xy 100.308722 -258.457913) (xy 100.334787 -258.464526) (xy 100.361675 -258.464092) (xy 100.374704 -258.460748)
			(xy 100.398645 -258.454353) (xy 100.447718 -258.447465) (xy 100.472494 -258.447032) (xy 100.472748 -258.447032)
			(xy 100.499392 -258.447533) (xy 100.552084 -258.455482) (xy 100.603003 -258.471195) (xy 100.651011 -258.49432)
			(xy 100.695037 -258.524342) (xy 100.734098 -258.56059) (xy 100.76732 -258.602254) (xy 100.793962 -258.648404)
			(xy 100.813428 -258.698009) (xy 100.825285 -258.749961) (xy 100.829267 -258.8031) (xy 100.827267 -258.829789)
			(xy 101.056684 -258.829789) (xy 101.056684 -258.776491) (xy 101.064627 -258.723787) (xy 101.080337 -258.672857)
			(xy 101.103463 -258.624836) (xy 101.133487 -258.580799) (xy 101.169739 -258.541728) (xy 101.21141 -258.508497)
			(xy 101.257568 -258.481848) (xy 101.307182 -258.462376) (xy 101.359144 -258.450516) (xy 101.412294 -258.446533)
			(xy 101.465444 -258.450516) (xy 101.517406 -258.462376) (xy 101.56702 -258.481848) (xy 101.613178 -258.508497)
			(xy 101.654849 -258.541728) (xy 101.691101 -258.580799) (xy 101.721125 -258.624836) (xy 101.744251 -258.672857)
			(xy 101.759961 -258.723787) (xy 101.767904 -258.776491) (xy 101.768402 -258.80314) (xy 101.767904 -258.829789)
			(xy 101.759961 -258.882493) (xy 101.744251 -258.933423) (xy 101.721125 -258.981444) (xy 101.691101 -259.025481)
			(xy 101.654849 -259.064552) (xy 101.613178 -259.097783) (xy 101.56702 -259.124432) (xy 101.517406 -259.143904)
			(xy 101.465444 -259.155764) (xy 101.412294 -259.159748) (xy 101.359144 -259.155764) (xy 101.307182 -259.143904)
			(xy 101.257568 -259.124432) (xy 101.21141 -259.097783) (xy 101.169739 -259.064552) (xy 101.133487 -259.025481)
			(xy 101.103463 -258.981444) (xy 101.080337 -258.933423) (xy 101.064627 -258.882493) (xy 101.056684 -258.829789)
			(xy 100.827267 -258.829789) (xy 100.825285 -258.856239) (xy 100.813428 -258.908191) (xy 100.793962 -258.957796)
			(xy 100.76732 -259.003946) (xy 100.734098 -259.04561) (xy 100.695037 -259.081858) (xy 100.651011 -259.11188)
			(xy 100.603003 -259.135005) (xy 100.552084 -259.150718) (xy 100.499392 -259.158667) (xy 100.472748 -259.159248)
			(xy 100.472494 -259.159248) (xy 100.447717 -259.158823) (xy 100.398642 -259.151941) (xy 100.374704 -259.145532)
			(xy 100.361673 -259.142239) (xy 100.334808 -259.141856) (xy 100.308772 -259.148492) (xy 100.285367 -259.161687)
			(xy 100.266212 -259.180528) (xy 100.252633 -259.203712) (xy 100.245568 -259.229635) (xy 100.245164 -259.243068)
			(xy 100.245164 -259.356352) (xy 100.264305 -259.374826) (xy 100.297437 -259.416445) (xy 100.324005 -259.462531)
			(xy 100.343418 -259.512058) (xy 100.355243 -259.563923) (xy 100.359217 -259.61697) (xy 100.357226 -259.643605)
			(xy 100.586784 -259.643605) (xy 100.586784 -259.590307) (xy 100.594727 -259.537603) (xy 100.610437 -259.486673)
			(xy 100.633563 -259.438652) (xy 100.663587 -259.394615) (xy 100.699839 -259.355544) (xy 100.74151 -259.322313)
			(xy 100.787668 -259.295664) (xy 100.837282 -259.276192) (xy 100.889244 -259.264332) (xy 100.942394 -259.260349)
			(xy 100.995544 -259.264332) (xy 101.047506 -259.276192) (xy 101.09712 -259.295664) (xy 101.143278 -259.322313)
			(xy 101.184949 -259.355544) (xy 101.221201 -259.394615) (xy 101.251225 -259.438652) (xy 101.274351 -259.486673)
			(xy 101.290061 -259.537603) (xy 101.298004 -259.590307) (xy 101.298502 -259.616956) (xy 101.298004 -259.643605)
			(xy 101.290061 -259.696309) (xy 101.281795 -259.723107) (xy 102.510834 -259.723107) (xy 102.510834 -259.669809)
			(xy 102.518777 -259.617105) (xy 102.534487 -259.566175) (xy 102.557613 -259.518154) (xy 102.587637 -259.474117)
			(xy 102.623889 -259.435046) (xy 102.66556 -259.401815) (xy 102.711718 -259.375166) (xy 102.761332 -259.355694)
			(xy 102.813294 -259.343834) (xy 102.866444 -259.339851) (xy 102.919594 -259.343834) (xy 102.971556 -259.355694)
			(xy 103.02117 -259.375166) (xy 103.067328 -259.401815) (xy 103.108999 -259.435046) (xy 103.145251 -259.474117)
			(xy 103.175275 -259.518154) (xy 103.198401 -259.566175) (xy 103.214111 -259.617105) (xy 103.222054 -259.669809)
			(xy 103.222552 -259.696458) (xy 103.222054 -259.723107) (xy 103.214111 -259.775811) (xy 103.198401 -259.826741)
			(xy 103.175275 -259.874762) (xy 103.145251 -259.918799) (xy 103.108999 -259.95787) (xy 103.067328 -259.991101)
			(xy 103.02117 -260.01775) (xy 102.971556 -260.037222) (xy 102.919594 -260.049082) (xy 102.866444 -260.053066)
			(xy 102.813294 -260.049082) (xy 102.761332 -260.037222) (xy 102.711718 -260.01775) (xy 102.66556 -259.991101)
			(xy 102.623889 -259.95787) (xy 102.587637 -259.918799) (xy 102.557613 -259.874762) (xy 102.534487 -259.826741)
			(xy 102.518777 -259.775811) (xy 102.510834 -259.723107) (xy 101.281795 -259.723107) (xy 101.274351 -259.747239)
			(xy 101.251225 -259.79526) (xy 101.221201 -259.839297) (xy 101.184949 -259.878368) (xy 101.143278 -259.911599)
			(xy 101.09712 -259.938248) (xy 101.047506 -259.95772) (xy 100.995544 -259.96958) (xy 100.942394 -259.973564)
			(xy 100.889244 -259.96958) (xy 100.837282 -259.95772) (xy 100.787668 -259.938248) (xy 100.74151 -259.911599)
			(xy 100.699839 -259.878368) (xy 100.663587 -259.839297) (xy 100.633563 -259.79526) (xy 100.610437 -259.747239)
			(xy 100.594727 -259.696309) (xy 100.586784 -259.643605) (xy 100.357226 -259.643605) (xy 100.355252 -259.670018)
			(xy 100.343435 -259.721885) (xy 100.324031 -259.771415) (xy 100.29747 -259.817505) (xy 100.264346 -259.85913)
			(xy 100.245164 -259.87756) (xy 100.245164 -259.990844) (xy 100.24557 -260.004287) (xy 100.252586 -260.030241)
			(xy 100.266145 -260.053456) (xy 100.285303 -260.072319) (xy 100.308727 -260.085515) (xy 100.334787 -260.092126)
			(xy 100.361669 -260.091693) (xy 100.374704 -260.08838) (xy 100.398645 -260.081985) (xy 100.447718 -260.075096)
			(xy 100.472494 -260.074664) (xy 100.472748 -260.074664) (xy 100.500729 -260.075217) (xy 100.556002 -260.083977)
			(xy 100.609225 -260.101276) (xy 100.659086 -260.126686) (xy 100.70436 -260.159582) (xy 100.743931 -260.199155)
			(xy 100.776825 -260.244431) (xy 100.802232 -260.294294) (xy 100.819527 -260.347517) (xy 100.828285 -260.402791)
			(xy 100.828856 -260.430772) (xy 100.828259 -260.459837) (xy 100.81878 -260.517189) (xy 100.800119 -260.572243)
			(xy 100.786946 -260.598158) (xy 100.76942 -260.631432) (xy 101.040184 -260.902196) (xy 101.051868 -260.906006)
			(xy 101.078426 -260.915142) (xy 101.128494 -260.940586) (xy 101.173946 -260.973574) (xy 101.213656 -261.013288)
			(xy 101.246638 -261.058745) (xy 101.272075 -261.108816) (xy 101.28123 -261.135368) (xy 101.28504 -261.147052)
			(xy 101.365558 -261.22757) (xy 101.5238 -261.22757)
		)
		(stroke
			(width 0)
			(type solid)
		)
		(fill yes)
		(layer "In15.Cu")
		(net "PVCCD_HV_CPU1")
	)
	(gr_poly
		(pts
			(xy 356.101904 -58.455814) (xy 356.101904 -54.371494) (xy 355.026976 -53.296566) (xy 351.925382 -53.296566)
			(xy 351.863914 -53.358034) (xy 351.249996 -53.358034) (xy 349.10014 -51.208178) (xy 345.511628 -51.208178)
			(xy 345.497399 -51.208649) (xy 345.470045 -51.216501) (xy 345.445923 -51.231601) (xy 345.426909 -51.252776)
			(xy 345.414482 -51.278378) (xy 345.409609 -51.306416) (xy 345.412668 -51.33471) (xy 345.423422 -51.361058)
			(xy 345.431872 -51.372516) (xy 345.449725 -51.396201) (xy 345.478117 -51.44827) (xy 345.497473 -51.50433)
			(xy 345.507255 -51.562826) (xy 345.507818 -51.59248) (xy 345.507299 -51.620467) (xy 345.498546 -51.675751)
			(xy 345.481252 -51.728986) (xy 345.455843 -51.77886) (xy 345.422945 -51.824145) (xy 345.383368 -51.863725)
			(xy 345.338085 -51.896628) (xy 345.288214 -51.922041) (xy 345.234981 -51.939339) (xy 345.179697 -51.948097)
			(xy 345.15171 -51.948588) (xy 345.125559 -51.948126) (xy 345.073821 -51.940468) (xy 345.023762 -51.925317)
			(xy 344.976462 -51.902997) (xy 344.93294 -51.873992) (xy 344.894135 -51.838926) (xy 344.877136 -51.819048)
			(xy 344.868167 -51.808893) (xy 344.846007 -51.79332) (xy 344.820533 -51.784121) (xy 344.793536 -51.781943)
			(xy 344.766917 -51.786941) (xy 344.742548 -51.798762) (xy 344.722145 -51.816575) (xy 344.707144 -51.839125)
			(xy 344.702384 -51.851814) (xy 344.693079 -51.878059) (xy 344.667487 -51.927509) (xy 344.634516 -51.972379)
			(xy 344.59497 -52.011576) (xy 344.549809 -52.044147) (xy 344.500134 -52.069299) (xy 344.447151 -52.086421)
			(xy 344.39215 -52.095096) (xy 344.36431 -52.095654) (xy 344.337655 -52.095181) (xy 344.28494 -52.087237)
			(xy 344.233998 -52.071525) (xy 344.185967 -52.048396) (xy 344.141919 -52.018366) (xy 344.10284 -51.982106)
			(xy 344.069601 -51.940427) (xy 344.042945 -51.894259) (xy 344.023469 -51.844635) (xy 344.011606 -51.792661)
			(xy 344.007622 -51.7395) (xy 344.011606 -51.686339) (xy 344.023469 -51.634365) (xy 344.042945 -51.584741)
			(xy 344.069601 -51.538573) (xy 344.10284 -51.496894) (xy 344.141919 -51.460634) (xy 344.185967 -51.430604)
			(xy 344.233998 -51.407475) (xy 344.28494 -51.391763) (xy 344.337655 -51.383819) (xy 344.36431 -51.383438)
			(xy 344.39046 -51.383902) (xy 344.442196 -51.391562) (xy 344.492252 -51.406717) (xy 344.539549 -51.429039)
			(xy 344.583068 -51.458047) (xy 344.621868 -51.493115) (xy 344.638884 -51.512978) (xy 344.647856 -51.523143)
			(xy 344.670025 -51.538734) (xy 344.695514 -51.547948) (xy 344.722528 -51.550137) (xy 344.749168 -51.545147)
			(xy 344.773558 -51.533328) (xy 344.793983 -51.515512) (xy 344.809005 -51.492953) (xy 344.813636 -51.480212)
			(xy 344.82394 -51.45124) (xy 344.853067 -51.397092) (xy 344.871548 -51.372516) (xy 344.879956 -51.361046)
			(xy 344.890668 -51.334713) (xy 344.8937 -51.306448) (xy 344.888818 -51.278442) (xy 344.876401 -51.25287)
			(xy 344.857411 -51.231715) (xy 344.833323 -51.216619) (xy 344.806005 -51.208752) (xy 344.791792 -51.208178)
			(xy 344.006424 -51.208178) (xy 343.991323 -51.208711) (xy 343.962436 -51.217519) (xy 343.937394 -51.2344)
			(xy 343.918394 -51.257875) (xy 343.9071 -51.285884) (xy 343.905332 -51.300888) (xy 343.902502 -51.327144)
			(xy 343.890083 -51.37847) (xy 343.870224 -51.4274) (xy 343.84336 -51.472863) (xy 343.810079 -51.513862)
			(xy 343.77111 -51.5495) (xy 343.727308 -51.578995) (xy 343.679632 -51.6017) (xy 343.629126 -51.61712)
			(xy 343.576897 -51.624915) (xy 343.524091 -51.624915) (xy 343.471862 -51.61712) (xy 343.421356 -51.6017)
			(xy 343.37368 -51.578995) (xy 343.329878 -51.5495) (xy 343.290909 -51.513862) (xy 343.257628 -51.472863)
			(xy 343.230764 -51.4274) (xy 343.210905 -51.37847) (xy 343.198486 -51.327144) (xy 343.195656 -51.300888)
			(xy 343.193779 -51.285911) (xy 343.18246 -51.257945) (xy 343.163478 -51.234495) (xy 343.138483 -51.2176)
			(xy 343.109647 -51.208727) (xy 343.094564 -51.208178) (xy 342.377268 -51.208178) (xy 342.362173 -51.208718)
			(xy 342.333299 -51.217537) (xy 342.308272 -51.234421) (xy 342.289284 -51.257892) (xy 342.277998 -51.285894)
			(xy 342.276176 -51.300888) (xy 342.27338 -51.327169) (xy 342.261016 -51.378554) (xy 342.241196 -51.427548)
			(xy 342.214355 -51.473075) (xy 342.181081 -51.514137) (xy 342.142105 -51.549832) (xy 342.098284 -51.579376)
			(xy 342.050577 -51.602121) (xy 342.000034 -51.617567) (xy 341.947763 -51.625376) (xy 341.894913 -51.625376)
			(xy 341.842642 -51.617567) (xy 341.792099 -51.602121) (xy 341.744392 -51.579376) (xy 341.700571 -51.549832)
			(xy 341.661595 -51.514137) (xy 341.628321 -51.473075) (xy 341.60148 -51.427548) (xy 341.58166 -51.378554)
			(xy 341.569296 -51.327169) (xy 341.5665 -51.300888) (xy 341.564622 -51.285914) (xy 341.553301 -51.257956)
			(xy 341.534318 -51.234515) (xy 341.509322 -51.217632) (xy 341.480488 -51.208775) (xy 341.465408 -51.208178)
			(xy 340.746588 -51.208178) (xy 340.731491 -51.208715) (xy 340.702612 -51.21753) (xy 340.67758 -51.234414)
			(xy 340.658587 -51.257886) (xy 340.647299 -51.285891) (xy 340.645496 -51.300888) (xy 340.642702 -51.327168)
			(xy 340.630343 -51.37855) (xy 340.610525 -51.427541) (xy 340.583683 -51.473064) (xy 340.550408 -51.51412)
			(xy 340.51143 -51.549807) (xy 340.467605 -51.579341) (xy 340.419896 -51.602073) (xy 340.369352 -51.617503)
			(xy 340.317082 -51.625294) (xy 340.290658 -51.625754) (xy 340.264651 -51.625286) (xy 340.213188 -51.617732)
			(xy 340.16337 -51.602778) (xy 340.116256 -51.580739) (xy 340.072846 -51.552086) (xy 340.053168 -51.535076)
			(xy 340.04189 -51.525663) (xy 340.015326 -51.513147) (xy 339.9863 -51.508701) (xy 339.957208 -51.512692)
			(xy 339.930451 -51.524791) (xy 339.919056 -51.53406) (xy 339.899519 -51.550399) (xy 339.856684 -51.577948)
			(xy 339.810364 -51.599121) (xy 339.761503 -51.613486) (xy 339.711095 -51.620752) (xy 339.68563 -51.621182)
			(xy 339.657644 -51.620664) (xy 339.60236 -51.611911) (xy 339.549127 -51.594618) (xy 339.499254 -51.569209)
			(xy 339.453971 -51.53631) (xy 339.414392 -51.496732) (xy 339.381493 -51.451449) (xy 339.356084 -51.401577)
			(xy 339.338789 -51.348344) (xy 339.330037 -51.29306) (xy 339.329522 -51.265074) (xy 339.329522 -51.208178)
			(xy 337.656932 -51.208178) (xy 337.655916 -51.257962) (xy 337.6549 -51.284251) (xy 337.646087 -51.336117)
			(xy 337.629741 -51.386123) (xy 337.606217 -51.43318) (xy 337.576027 -51.476265) (xy 337.539828 -51.51444)
			(xy 337.498407 -51.546876) (xy 337.452666 -51.572866) (xy 337.403599 -51.591845) (xy 337.352274 -51.6034)
			(xy 337.299808 -51.60728) (xy 337.247342 -51.6034) (xy 337.196017 -51.591845) (xy 337.14695 -51.572866)
			(xy 337.101209 -51.546876) (xy 337.059788 -51.51444) (xy 337.023589 -51.476265) (xy 336.993399 -51.43318)
			(xy 336.969875 -51.386123) (xy 336.953529 -51.336117) (xy 336.944716 -51.284251) (xy 336.9437 -51.257962)
			(xy 336.942684 -51.208178) (xy 336.056732 -51.208178) (xy 336.055716 -51.257962) (xy 336.0547 -51.284251)
			(xy 336.045887 -51.336117) (xy 336.029541 -51.386123) (xy 336.006017 -51.43318) (xy 335.975827 -51.476265)
			(xy 335.939628 -51.51444) (xy 335.898207 -51.546876) (xy 335.852466 -51.572866) (xy 335.803399 -51.591845)
			(xy 335.752074 -51.6034) (xy 335.699608 -51.60728) (xy 335.647142 -51.6034) (xy 335.595817 -51.591845)
			(xy 335.54675 -51.572866) (xy 335.501009 -51.546876) (xy 335.459588 -51.51444) (xy 335.423389 -51.476265)
			(xy 335.393199 -51.43318) (xy 335.369675 -51.386123) (xy 335.353329 -51.336117) (xy 335.344516 -51.284251)
			(xy 335.3435 -51.257962) (xy 335.342484 -51.208178) (xy 334.451198 -51.208178) (xy 333.860394 -51.798982)
			(xy 333.857092 -51.813714) (xy 333.84948 -51.846017) (xy 333.823906 -51.907251) (xy 333.806292 -51.93538)
			(xy 333.806292 -52.705995) (xy 334.782658 -52.705995) (xy 334.782658 -52.652697) (xy 334.790601 -52.599993)
			(xy 334.806311 -52.549063) (xy 334.829437 -52.501042) (xy 334.859461 -52.457005) (xy 334.895713 -52.417934)
			(xy 334.937384 -52.384703) (xy 334.983542 -52.358054) (xy 335.033156 -52.338582) (xy 335.085118 -52.326722)
			(xy 335.138268 -52.322739) (xy 335.191418 -52.326722) (xy 335.24338 -52.338582) (xy 335.292994 -52.358054)
			(xy 335.339152 -52.384703) (xy 335.380823 -52.417934) (xy 335.417075 -52.457005) (xy 335.447099 -52.501042)
			(xy 335.470225 -52.549063) (xy 335.485935 -52.599993) (xy 335.493878 -52.652697) (xy 335.494376 -52.679346)
			(xy 335.493878 -52.705995) (xy 338.038938 -52.705995) (xy 338.038938 -52.652697) (xy 338.046881 -52.599993)
			(xy 338.062591 -52.549063) (xy 338.085717 -52.501042) (xy 338.115741 -52.457005) (xy 338.151993 -52.417934)
			(xy 338.193664 -52.384703) (xy 338.239822 -52.358054) (xy 338.289436 -52.338582) (xy 338.341398 -52.326722)
			(xy 338.394548 -52.322739) (xy 338.447698 -52.326722) (xy 338.49966 -52.338582) (xy 338.549274 -52.358054)
			(xy 338.595432 -52.384703) (xy 338.637103 -52.417934) (xy 338.673355 -52.457005) (xy 338.699532 -52.4954)
			(xy 339.267318 -52.4954) (xy 339.271301 -52.442253) (xy 339.28316 -52.390294) (xy 339.302632 -52.340683)
			(xy 339.32928 -52.294528) (xy 339.362509 -52.25286) (xy 339.401578 -52.21661) (xy 339.445614 -52.186588)
			(xy 339.493632 -52.163465) (xy 339.54456 -52.147757) (xy 339.59726 -52.139815) (xy 339.623908 -52.139342)
			(xy 339.652254 -52.139895) (xy 339.708228 -52.148895) (xy 339.762064 -52.166665) (xy 339.787484 -52.17922)
			(xy 339.801493 -52.185838) (xy 339.831986 -52.191224) (xy 339.862692 -52.187225) (xy 339.890789 -52.174209)
			(xy 339.913696 -52.153373) (xy 339.929306 -52.12663) (xy 339.93328 -52.111656) (xy 339.939738 -52.08583)
			(xy 339.95923 -52.036294) (xy 339.985883 -51.990215) (xy 340.019102 -51.948619) (xy 340.058147 -51.912435)
			(xy 340.102145 -51.882471) (xy 340.150115 -51.859394) (xy 340.200988 -51.843719) (xy 340.253628 -51.835797)
			(xy 340.280244 -51.835304) (xy 340.306892 -51.835781) (xy 340.359592 -51.84373) (xy 340.410519 -51.859445)
			(xy 340.458535 -51.882573) (xy 340.502568 -51.912599) (xy 340.541635 -51.948853) (xy 340.574862 -51.990523)
			(xy 340.601509 -52.03668) (xy 340.620978 -52.086293) (xy 340.632837 -52.138253) (xy 340.63682 -52.1914)
			(xy 340.63347 -52.236095) (xy 343.19463 -52.236095) (xy 343.19463 -52.182797) (xy 343.202573 -52.130093)
			(xy 343.218283 -52.079163) (xy 343.241409 -52.031142) (xy 343.271433 -51.987105) (xy 343.307685 -51.948034)
			(xy 343.349356 -51.914803) (xy 343.395514 -51.888154) (xy 343.445128 -51.868682) (xy 343.49709 -51.856822)
			(xy 343.55024 -51.852839) (xy 343.60339 -51.856822) (xy 343.655352 -51.868682) (xy 343.704966 -51.888154)
			(xy 343.751124 -51.914803) (xy 343.792795 -51.948034) (xy 343.829047 -51.987105) (xy 343.859071 -52.031142)
			(xy 343.882197 -52.079163) (xy 343.897907 -52.130093) (xy 343.90585 -52.182797) (xy 343.906348 -52.209446)
			(xy 343.90585 -52.236095) (xy 343.897907 -52.288799) (xy 343.882197 -52.339729) (xy 343.859071 -52.38775)
			(xy 343.829047 -52.431787) (xy 343.792795 -52.470858) (xy 343.751124 -52.504089) (xy 343.704966 -52.530738)
			(xy 343.655352 -52.55021) (xy 343.60339 -52.56207) (xy 343.55024 -52.566054) (xy 343.49709 -52.56207)
			(xy 343.445128 -52.55021) (xy 343.395514 -52.530738) (xy 343.349356 -52.504089) (xy 343.307685 -52.470858)
			(xy 343.271433 -52.431787) (xy 343.241409 -52.38775) (xy 343.218283 -52.339729) (xy 343.202573 -52.288799)
			(xy 343.19463 -52.236095) (xy 340.63347 -52.236095) (xy 340.632837 -52.244547) (xy 340.620978 -52.296507)
			(xy 340.601509 -52.34612) (xy 340.574862 -52.392277) (xy 340.541635 -52.433947) (xy 340.502568 -52.470201)
			(xy 340.458535 -52.500227) (xy 340.410519 -52.523355) (xy 340.359592 -52.53907) (xy 340.306892 -52.547019)
			(xy 340.280244 -52.54752) (xy 340.251898 -52.546952) (xy 340.195925 -52.537959) (xy 340.142089 -52.520194)
			(xy 340.116668 -52.507642) (xy 340.102675 -52.500992) (xy 340.072176 -52.49562) (xy 340.041469 -52.499628)
			(xy 340.013372 -52.51265) (xy 339.990464 -52.533489) (xy 339.974849 -52.560232) (xy 339.970872 -52.575206)
			(xy 339.964432 -52.601038) (xy 339.944942 -52.650577) (xy 339.928329 -52.6793) (xy 344.007714 -52.6793)
			(xy 344.011697 -52.626153) (xy 344.023557 -52.574193) (xy 344.043028 -52.524581) (xy 344.069677 -52.478425)
			(xy 344.102907 -52.436756) (xy 344.141977 -52.400506) (xy 344.186013 -52.370484) (xy 344.234032 -52.347361)
			(xy 344.284961 -52.331652) (xy 344.337662 -52.32371) (xy 344.36431 -52.323238) (xy 344.392139 -52.323804)
			(xy 344.447121 -52.332451) (xy 344.500087 -52.349549) (xy 344.549748 -52.374681) (xy 344.594893 -52.407234)
			(xy 344.634422 -52.446416) (xy 344.65133 -52.468526) (xy 344.660779 -52.480458) (xy 344.685232 -52.498554)
			(xy 344.713929 -52.508647) (xy 344.744327 -52.509843) (xy 344.773729 -52.502036) (xy 344.799528 -52.485917)
			(xy 344.819438 -52.462916) (xy 344.826082 -52.449222) (xy 344.836903 -52.425903) (xy 344.864227 -52.38236)
			(xy 344.89753 -52.3432) (xy 344.93612 -52.309238) (xy 344.979194 -52.28118) (xy 345.025856 -52.25961)
			(xy 345.075135 -52.244976) (xy 345.126007 -52.237583) (xy 345.15171 -52.237132) (xy 345.178362 -52.23755)
			(xy 345.23107 -52.245496) (xy 345.282005 -52.261209) (xy 345.33003 -52.284338) (xy 345.374071 -52.314365)
			(xy 345.413144 -52.350622) (xy 345.446378 -52.392296) (xy 345.47303 -52.438459) (xy 345.492503 -52.488078)
			(xy 345.504364 -52.540045) (xy 345.508348 -52.5932) (xy 345.504364 -52.646355) (xy 345.492503 -52.698322)
			(xy 345.47303 -52.747941) (xy 345.446378 -52.794104) (xy 345.413144 -52.835778) (xy 345.374071 -52.872035)
			(xy 345.33003 -52.902062) (xy 345.282005 -52.925191) (xy 345.26792 -52.929536) (xy 347.47455 -52.929536)
			(xy 347.478526 -52.87521) (xy 347.490369 -52.822041) (xy 347.509828 -52.771164) (xy 347.536488 -52.723662)
			(xy 347.569779 -52.680548) (xy 347.608993 -52.642741) (xy 347.653295 -52.611046) (xy 347.701738 -52.58614)
			(xy 347.753292 -52.568552) (xy 347.806858 -52.558658) (xy 347.861293 -52.556668) (xy 347.915438 -52.562626)
			(xy 347.968138 -52.576404) (xy 348.018271 -52.597708) (xy 348.064767 -52.626084) (xy 348.106637 -52.660928)
			(xy 348.142986 -52.701497) (xy 348.173042 -52.746926) (xy 348.196163 -52.796247) (xy 348.211856 -52.848409)
			(xy 348.219787 -52.9023) (xy 348.220284 -52.929536) (xy 348.220108 -52.939188) (xy 348.944182 -52.939188)
			(xy 348.948253 -52.883566) (xy 348.960379 -52.829129) (xy 348.980302 -52.777038) (xy 349.007598 -52.728403)
			(xy 349.041684 -52.68426) (xy 349.081833 -52.645551) (xy 349.127191 -52.6131) (xy 349.176791 -52.587599)
			(xy 349.229575 -52.569592) (xy 349.284418 -52.559462) (xy 349.340152 -52.557425) (xy 349.395589 -52.563525)
			(xy 349.449546 -52.577631) (xy 349.500875 -52.599443) (xy 349.548481 -52.628497) (xy 349.591349 -52.664172)
			(xy 349.628566 -52.705709) (xy 349.659339 -52.752222) (xy 349.683011 -52.802719) (xy 349.699079 -52.856126)
			(xy 349.707199 -52.911302) (xy 349.707708 -52.939188) (xy 349.707199 -52.967074) (xy 349.699079 -53.02225)
			(xy 349.683011 -53.075657) (xy 349.659339 -53.126154) (xy 349.628566 -53.172667) (xy 349.591349 -53.214204)
			(xy 349.548481 -53.249879) (xy 349.500875 -53.278933) (xy 349.449546 -53.300745) (xy 349.395589 -53.314851)
			(xy 349.340152 -53.320951) (xy 349.284418 -53.318914) (xy 349.229575 -53.308784) (xy 349.176791 -53.290777)
			(xy 349.127191 -53.265276) (xy 349.081833 -53.232825) (xy 349.041684 -53.194116) (xy 349.007598 -53.149973)
			(xy 348.980302 -53.101338) (xy 348.960379 -53.049247) (xy 348.948253 -52.99481) (xy 348.944182 -52.939188)
			(xy 348.220108 -52.939188) (xy 348.219787 -52.956772) (xy 348.211856 -53.010663) (xy 348.196163 -53.062825)
			(xy 348.173042 -53.112146) (xy 348.142986 -53.157575) (xy 348.106637 -53.198144) (xy 348.064767 -53.232988)
			(xy 348.018271 -53.261364) (xy 347.968138 -53.282668) (xy 347.915438 -53.296446) (xy 347.861293 -53.302404)
			(xy 347.806858 -53.300414) (xy 347.753292 -53.29052) (xy 347.701738 -53.272932) (xy 347.653295 -53.248026)
			(xy 347.608993 -53.216331) (xy 347.569779 -53.178524) (xy 347.536488 -53.13541) (xy 347.509828 -53.087908)
			(xy 347.490369 -53.037031) (xy 347.478526 -52.983862) (xy 347.47455 -52.929536) (xy 345.26792 -52.929536)
			(xy 345.23107 -52.940904) (xy 345.178362 -52.94885) (xy 345.15171 -52.949348) (xy 345.123879 -52.948846)
			(xy 345.068893 -52.940186) (xy 345.015925 -52.923076) (xy 344.966265 -52.897932) (xy 344.921122 -52.865367)
			(xy 344.881596 -52.826175) (xy 344.86469 -52.80406) (xy 344.855214 -52.792153) (xy 344.830767 -52.77406)
			(xy 344.802076 -52.763967) (xy 344.771685 -52.762768) (xy 344.742289 -52.77057) (xy 344.716493 -52.786682)
			(xy 344.696583 -52.809674) (xy 344.689938 -52.823364) (xy 344.679174 -52.846711) (xy 344.651844 -52.890257)
			(xy 344.618533 -52.929418) (xy 344.579935 -52.963379) (xy 344.536852 -52.991434) (xy 344.490182 -53.012998)
			(xy 344.440895 -53.027625) (xy 344.390016 -53.035008) (xy 344.36431 -53.035454) (xy 344.337662 -53.03489)
			(xy 344.284961 -53.026948) (xy 344.234032 -53.011239) (xy 344.186013 -52.988116) (xy 344.141977 -52.958094)
			(xy 344.102907 -52.921844) (xy 344.069677 -52.880175) (xy 344.043028 -52.834019) (xy 344.023557 -52.784407)
			(xy 344.011697 -52.732447) (xy 344.007714 -52.6793) (xy 339.928329 -52.6793) (xy 339.918289 -52.696659)
			(xy 339.885068 -52.738257) (xy 339.846021 -52.774442) (xy 339.80202 -52.804406) (xy 339.754045 -52.827481)
			(xy 339.703169 -52.843152) (xy 339.650526 -52.851068) (xy 339.623908 -52.851558) (xy 339.59726 -52.850985)
			(xy 339.54456 -52.843043) (xy 339.493632 -52.827335) (xy 339.445614 -52.804212) (xy 339.401578 -52.77419)
			(xy 339.362509 -52.73794) (xy 339.32928 -52.696272) (xy 339.302632 -52.650117) (xy 339.28316 -52.600506)
			(xy 339.271301 -52.548547) (xy 339.267318 -52.4954) (xy 338.699532 -52.4954) (xy 338.703379 -52.501042)
			(xy 338.726505 -52.549063) (xy 338.742215 -52.599993) (xy 338.750158 -52.652697) (xy 338.750656 -52.679346)
			(xy 338.750158 -52.705995) (xy 338.742215 -52.758699) (xy 338.726505 -52.809629) (xy 338.703379 -52.85765)
			(xy 338.673355 -52.901687) (xy 338.637103 -52.940758) (xy 338.595432 -52.973989) (xy 338.549274 -53.000638)
			(xy 338.49966 -53.02011) (xy 338.447698 -53.03197) (xy 338.394548 -53.035954) (xy 338.341398 -53.03197)
			(xy 338.289436 -53.02011) (xy 338.239822 -53.000638) (xy 338.193664 -52.973989) (xy 338.151993 -52.940758)
			(xy 338.115741 -52.901687) (xy 338.085717 -52.85765) (xy 338.062591 -52.809629) (xy 338.046881 -52.758699)
			(xy 338.038938 -52.705995) (xy 335.493878 -52.705995) (xy 335.485935 -52.758699) (xy 335.470225 -52.809629)
			(xy 335.447099 -52.85765) (xy 335.417075 -52.901687) (xy 335.380823 -52.940758) (xy 335.339152 -52.973989)
			(xy 335.292994 -53.000638) (xy 335.24338 -53.02011) (xy 335.191418 -53.03197) (xy 335.138268 -53.035954)
			(xy 335.085118 -53.03197) (xy 335.033156 -53.02011) (xy 334.983542 -53.000638) (xy 334.937384 -52.973989)
			(xy 334.895713 -52.940758) (xy 334.859461 -52.901687) (xy 334.829437 -52.85765) (xy 334.806311 -52.809629)
			(xy 334.790601 -52.758699) (xy 334.782658 -52.705995) (xy 333.806292 -52.705995) (xy 333.806292 -52.712874)
			(xy 333.96174 -52.868322) (xy 333.972743 -52.878585) (xy 333.999263 -52.892769) (xy 334.028762 -52.898624)
			(xy 334.058688 -52.895643) (xy 334.086453 -52.884083) (xy 334.098392 -52.874926) (xy 334.117632 -52.859536)
			(xy 334.159551 -52.833645) (xy 334.204639 -52.81378) (xy 334.252034 -52.80032) (xy 334.300833 -52.793523)
			(xy 334.325468 -52.793138) (xy 334.353454 -52.793656) (xy 334.408736 -52.802408) (xy 334.461969 -52.819702)
			(xy 334.51184 -52.845111) (xy 334.557122 -52.87801) (xy 334.596699 -52.917588) (xy 334.629596 -52.962872)
			(xy 334.655003 -53.012744) (xy 334.672295 -53.065977) (xy 334.681045 -53.12126) (xy 334.681576 -53.149246)
			(xy 334.681156 -53.173879) (xy 334.680875 -53.175895) (xy 335.597998 -53.175895) (xy 335.597998 -53.122597)
			(xy 335.605941 -53.069893) (xy 335.621651 -53.018963) (xy 335.644777 -52.970942) (xy 335.674801 -52.926905)
			(xy 335.711053 -52.887834) (xy 335.752724 -52.854603) (xy 335.798882 -52.827954) (xy 335.848496 -52.808482)
			(xy 335.900458 -52.796622) (xy 335.953608 -52.792639) (xy 336.006758 -52.796622) (xy 336.05872 -52.808482)
			(xy 336.108334 -52.827954) (xy 336.154492 -52.854603) (xy 336.196163 -52.887834) (xy 336.232415 -52.926905)
			(xy 336.262439 -52.970942) (xy 336.285565 -53.018963) (xy 336.301275 -53.069893) (xy 336.309218 -53.122597)
			(xy 336.309716 -53.149246) (xy 336.309218 -53.175895) (xy 337.226138 -53.175895) (xy 337.226138 -53.122597)
			(xy 337.234081 -53.069893) (xy 337.249791 -53.018963) (xy 337.272917 -52.970942) (xy 337.302941 -52.926905)
			(xy 337.339193 -52.887834) (xy 337.380864 -52.854603) (xy 337.427022 -52.827954) (xy 337.476636 -52.808482)
			(xy 337.528598 -52.796622) (xy 337.581748 -52.792639) (xy 337.634898 -52.796622) (xy 337.68686 -52.808482)
			(xy 337.736474 -52.827954) (xy 337.782632 -52.854603) (xy 337.824303 -52.887834) (xy 337.860555 -52.926905)
			(xy 337.890579 -52.970942) (xy 337.913705 -53.018963) (xy 337.929415 -53.069893) (xy 337.937358 -53.122597)
			(xy 337.937856 -53.149246) (xy 337.937358 -53.175895) (xy 339.935048 -53.175895) (xy 339.935048 -53.122597)
			(xy 339.942991 -53.069893) (xy 339.958701 -53.018963) (xy 339.981827 -52.970942) (xy 340.011851 -52.926905)
			(xy 340.048103 -52.887834) (xy 340.089774 -52.854603) (xy 340.135932 -52.827954) (xy 340.185546 -52.808482)
			(xy 340.237508 -52.796622) (xy 340.290658 -52.792639) (xy 340.343808 -52.796622) (xy 340.39577 -52.808482)
			(xy 340.445384 -52.827954) (xy 340.491542 -52.854603) (xy 340.533213 -52.887834) (xy 340.569465 -52.926905)
			(xy 340.599489 -52.970942) (xy 340.622615 -53.018963) (xy 340.638325 -53.069893) (xy 340.646268 -53.122597)
			(xy 340.646766 -53.149246) (xy 340.646273 -53.175641) (xy 341.565728 -53.175641) (xy 341.565728 -53.122343)
			(xy 341.573671 -53.069639) (xy 341.589381 -53.018709) (xy 341.612507 -52.970688) (xy 341.642531 -52.926651)
			(xy 341.678783 -52.88758) (xy 341.720454 -52.854349) (xy 341.766612 -52.8277) (xy 341.816226 -52.808228)
			(xy 341.868188 -52.796368) (xy 341.921338 -52.792385) (xy 341.974488 -52.796368) (xy 342.02645 -52.808228)
			(xy 342.076064 -52.8277) (xy 342.122222 -52.854349) (xy 342.163893 -52.88758) (xy 342.200145 -52.926651)
			(xy 342.230169 -52.970688) (xy 342.253295 -53.018709) (xy 342.269005 -53.069639) (xy 342.276948 -53.122343)
			(xy 342.277446 -53.148992) (xy 342.276948 -53.175641) (xy 342.269005 -53.228345) (xy 342.253295 -53.279275)
			(xy 342.230169 -53.327296) (xy 342.200145 -53.371333) (xy 342.163893 -53.410404) (xy 342.122222 -53.443635)
			(xy 342.076064 -53.470284) (xy 342.02645 -53.489756) (xy 341.974488 -53.501616) (xy 341.921338 -53.5056)
			(xy 341.868188 -53.501616) (xy 341.816226 -53.489756) (xy 341.766612 -53.470284) (xy 341.720454 -53.443635)
			(xy 341.678783 -53.410404) (xy 341.642531 -53.371333) (xy 341.612507 -53.327296) (xy 341.589381 -53.279275)
			(xy 341.573671 -53.228345) (xy 341.565728 -53.175641) (xy 340.646273 -53.175641) (xy 340.646268 -53.175895)
			(xy 340.638325 -53.228599) (xy 340.622615 -53.279529) (xy 340.599489 -53.32755) (xy 340.569465 -53.371587)
			(xy 340.533213 -53.410658) (xy 340.491542 -53.443889) (xy 340.445384 -53.470538) (xy 340.39577 -53.49001)
			(xy 340.343808 -53.50187) (xy 340.290658 -53.505854) (xy 340.237508 -53.50187) (xy 340.185546 -53.49001)
			(xy 340.135932 -53.470538) (xy 340.089774 -53.443889) (xy 340.048103 -53.410658) (xy 340.011851 -53.371587)
			(xy 339.981827 -53.32755) (xy 339.958701 -53.279529) (xy 339.942991 -53.228599) (xy 339.935048 -53.175895)
			(xy 337.937358 -53.175895) (xy 337.929415 -53.228599) (xy 337.913705 -53.279529) (xy 337.890579 -53.32755)
			(xy 337.860555 -53.371587) (xy 337.824303 -53.410658) (xy 337.782632 -53.443889) (xy 337.736474 -53.470538)
			(xy 337.68686 -53.49001) (xy 337.634898 -53.50187) (xy 337.581748 -53.505854) (xy 337.528598 -53.50187)
			(xy 337.476636 -53.49001) (xy 337.427022 -53.470538) (xy 337.380864 -53.443889) (xy 337.339193 -53.410658)
			(xy 337.302941 -53.371587) (xy 337.272917 -53.32755) (xy 337.249791 -53.279529) (xy 337.234081 -53.228599)
			(xy 337.226138 -53.175895) (xy 336.309218 -53.175895) (xy 336.301275 -53.228599) (xy 336.285565 -53.279529)
			(xy 336.262439 -53.32755) (xy 336.232415 -53.371587) (xy 336.196163 -53.410658) (xy 336.154492 -53.443889)
			(xy 336.108334 -53.470538) (xy 336.05872 -53.49001) (xy 336.006758 -53.50187) (xy 335.953608 -53.505854)
			(xy 335.900458 -53.50187) (xy 335.848496 -53.49001) (xy 335.798882 -53.470538) (xy 335.752724 -53.443889)
			(xy 335.711053 -53.410658) (xy 335.674801 -53.371587) (xy 335.644777 -53.32755) (xy 335.621651 -53.279529)
			(xy 335.605941 -53.228599) (xy 335.597998 -53.175895) (xy 334.680875 -53.175895) (xy 334.67436 -53.222674)
			(xy 334.660904 -53.270066) (xy 334.641045 -53.315152) (xy 334.615161 -53.35707) (xy 334.599788 -53.376322)
			(xy 334.590605 -53.38825) (xy 334.579003 -53.416009) (xy 334.576011 -53.445947) (xy 334.581892 -53.475453)
			(xy 334.596132 -53.501957) (xy 334.606392 -53.512974) (xy 334.739213 -53.645795) (xy 336.410798 -53.645795)
			(xy 336.410798 -53.592497) (xy 336.418741 -53.539793) (xy 336.434451 -53.488863) (xy 336.457577 -53.440842)
			(xy 336.487601 -53.396805) (xy 336.523853 -53.357734) (xy 336.565524 -53.324503) (xy 336.611682 -53.297854)
			(xy 336.661296 -53.278382) (xy 336.713258 -53.266522) (xy 336.766408 -53.262539) (xy 336.819558 -53.266522)
			(xy 336.87152 -53.278382) (xy 336.921134 -53.297854) (xy 336.967292 -53.324503) (xy 337.008963 -53.357734)
			(xy 337.045215 -53.396805) (xy 337.075239 -53.440842) (xy 337.098365 -53.488863) (xy 337.114075 -53.539793)
			(xy 337.122018 -53.592497) (xy 337.122516 -53.619146) (xy 337.122018 -53.645795) (xy 338.038938 -53.645795)
			(xy 338.038938 -53.592497) (xy 338.046881 -53.539793) (xy 338.062591 -53.488863) (xy 338.085717 -53.440842)
			(xy 338.115741 -53.396805) (xy 338.151993 -53.357734) (xy 338.193664 -53.324503) (xy 338.239822 -53.297854)
			(xy 338.289436 -53.278382) (xy 338.341398 -53.266522) (xy 338.394548 -53.262539) (xy 338.447698 -53.266522)
			(xy 338.49966 -53.278382) (xy 338.549274 -53.297854) (xy 338.595432 -53.324503) (xy 338.637103 -53.357734)
			(xy 338.673355 -53.396805) (xy 338.703379 -53.440842) (xy 338.726505 -53.488863) (xy 338.742215 -53.539793)
			(xy 338.750158 -53.592497) (xy 338.750656 -53.619146) (xy 338.750163 -53.645541) (xy 342.379544 -53.645541)
			(xy 342.379544 -53.592243) (xy 342.387487 -53.539539) (xy 342.403197 -53.488609) (xy 342.426323 -53.440588)
			(xy 342.456347 -53.396551) (xy 342.492599 -53.35748) (xy 342.53427 -53.324249) (xy 342.580428 -53.2976)
			(xy 342.630042 -53.278128) (xy 342.682004 -53.266268) (xy 342.735154 -53.262285) (xy 342.788304 -53.266268)
			(xy 342.840266 -53.278128) (xy 342.88988 -53.2976) (xy 342.936038 -53.324249) (xy 342.977709 -53.35748)
			(xy 343.013961 -53.396551) (xy 343.043985 -53.440588) (xy 343.067111 -53.488609) (xy 343.082821 -53.539539)
			(xy 343.090764 -53.592243) (xy 343.091262 -53.618892) (xy 343.090764 -53.645541) (xy 343.082821 -53.698245)
			(xy 343.067111 -53.749175) (xy 343.043985 -53.797196) (xy 343.013961 -53.841233) (xy 342.977709 -53.880304)
			(xy 342.936038 -53.913535) (xy 342.88988 -53.940184) (xy 342.840266 -53.959656) (xy 342.788304 -53.971516)
			(xy 342.735154 -53.9755) (xy 342.682004 -53.971516) (xy 342.630042 -53.959656) (xy 342.580428 -53.940184)
			(xy 342.53427 -53.913535) (xy 342.492599 -53.880304) (xy 342.456347 -53.841233) (xy 342.426323 -53.797196)
			(xy 342.403197 -53.749175) (xy 342.387487 -53.698245) (xy 342.379544 -53.645541) (xy 338.750163 -53.645541)
			(xy 338.750158 -53.645795) (xy 338.742215 -53.698499) (xy 338.726505 -53.749429) (xy 338.703379 -53.79745)
			(xy 338.673355 -53.841487) (xy 338.637103 -53.880558) (xy 338.595432 -53.913789) (xy 338.549274 -53.940438)
			(xy 338.49966 -53.95991) (xy 338.447698 -53.97177) (xy 338.394548 -53.975754) (xy 338.341398 -53.97177)
			(xy 338.289436 -53.95991) (xy 338.239822 -53.940438) (xy 338.193664 -53.913789) (xy 338.151993 -53.880558)
			(xy 338.115741 -53.841487) (xy 338.085717 -53.79745) (xy 338.062591 -53.749429) (xy 338.046881 -53.698499)
			(xy 338.038938 -53.645795) (xy 337.122018 -53.645795) (xy 337.114075 -53.698499) (xy 337.098365 -53.749429)
			(xy 337.075239 -53.79745) (xy 337.045215 -53.841487) (xy 337.008963 -53.880558) (xy 336.967292 -53.913789)
			(xy 336.921134 -53.940438) (xy 336.87152 -53.95991) (xy 336.819558 -53.97177) (xy 336.766408 -53.975754)
			(xy 336.713258 -53.97177) (xy 336.661296 -53.95991) (xy 336.611682 -53.940438) (xy 336.565524 -53.913789)
			(xy 336.523853 -53.880558) (xy 336.487601 -53.841487) (xy 336.457577 -53.79745) (xy 336.434451 -53.749429)
			(xy 336.418741 -53.698499) (xy 336.410798 -53.645795) (xy 334.739213 -53.645795) (xy 335.188306 -54.094888)
			(xy 335.188306 -54.115695) (xy 337.226138 -54.115695) (xy 337.226138 -54.062397) (xy 337.234081 -54.009693)
			(xy 337.249791 -53.958763) (xy 337.272917 -53.910742) (xy 337.302941 -53.866705) (xy 337.339193 -53.827634)
			(xy 337.380864 -53.794403) (xy 337.427022 -53.767754) (xy 337.476636 -53.748282) (xy 337.528598 -53.736422)
			(xy 337.581748 -53.732439) (xy 337.634898 -53.736422) (xy 337.68686 -53.748282) (xy 337.736474 -53.767754)
			(xy 337.782632 -53.794403) (xy 337.824303 -53.827634) (xy 337.860555 -53.866705) (xy 337.890579 -53.910742)
			(xy 337.913705 -53.958763) (xy 337.929415 -54.009693) (xy 337.937358 -54.062397) (xy 337.937856 -54.089046)
			(xy 337.937358 -54.115695) (xy 341.565728 -54.115695) (xy 341.565728 -54.062397) (xy 341.573671 -54.009693)
			(xy 341.589381 -53.958763) (xy 341.612507 -53.910742) (xy 341.642531 -53.866705) (xy 341.678783 -53.827634)
			(xy 341.720454 -53.794403) (xy 341.766612 -53.767754) (xy 341.816226 -53.748282) (xy 341.868188 -53.736422)
			(xy 341.921338 -53.732439) (xy 341.974488 -53.736422) (xy 342.02645 -53.748282) (xy 342.076064 -53.767754)
			(xy 342.122222 -53.794403) (xy 342.163893 -53.827634) (xy 342.200145 -53.866705) (xy 342.230169 -53.910742)
			(xy 342.253295 -53.958763) (xy 342.269005 -54.009693) (xy 342.276948 -54.062397) (xy 342.277446 -54.089046)
			(xy 342.276953 -54.115441) (xy 343.194884 -54.115441) (xy 343.194884 -54.062143) (xy 343.202827 -54.009439)
			(xy 343.218537 -53.958509) (xy 343.241663 -53.910488) (xy 343.271687 -53.866451) (xy 343.307939 -53.82738)
			(xy 343.34961 -53.794149) (xy 343.395768 -53.7675) (xy 343.445382 -53.748028) (xy 343.497344 -53.736168)
			(xy 343.550494 -53.732185) (xy 343.603644 -53.736168) (xy 343.655606 -53.748028) (xy 343.70522 -53.7675)
			(xy 343.751378 -53.794149) (xy 343.793049 -53.82738) (xy 343.829301 -53.866451) (xy 343.859325 -53.910488)
			(xy 343.882451 -53.958509) (xy 343.898161 -54.009439) (xy 343.906104 -54.062143) (xy 343.906602 -54.088792)
			(xy 343.906104 -54.115441) (xy 343.898161 -54.168145) (xy 343.882451 -54.219075) (xy 343.859325 -54.267096)
			(xy 343.829301 -54.311133) (xy 343.793049 -54.350204) (xy 343.751378 -54.383435) (xy 343.70522 -54.410084)
			(xy 343.655606 -54.429556) (xy 343.603644 -54.441416) (xy 343.550494 -54.4454) (xy 343.497344 -54.441416)
			(xy 343.445382 -54.429556) (xy 343.395768 -54.410084) (xy 343.34961 -54.383435) (xy 343.307939 -54.350204)
			(xy 343.271687 -54.311133) (xy 343.241663 -54.267096) (xy 343.218537 -54.219075) (xy 343.202827 -54.168145)
			(xy 343.194884 -54.115441) (xy 342.276953 -54.115441) (xy 342.276948 -54.115695) (xy 342.269005 -54.168399)
			(xy 342.253295 -54.219329) (xy 342.230169 -54.26735) (xy 342.200145 -54.311387) (xy 342.163893 -54.350458)
			(xy 342.122222 -54.383689) (xy 342.076064 -54.410338) (xy 342.02645 -54.42981) (xy 341.974488 -54.44167)
			(xy 341.921338 -54.445654) (xy 341.868188 -54.44167) (xy 341.816226 -54.42981) (xy 341.766612 -54.410338)
			(xy 341.720454 -54.383689) (xy 341.678783 -54.350458) (xy 341.642531 -54.311387) (xy 341.612507 -54.26735)
			(xy 341.589381 -54.219329) (xy 341.573671 -54.168399) (xy 341.565728 -54.115695) (xy 337.937358 -54.115695)
			(xy 337.929415 -54.168399) (xy 337.913705 -54.219329) (xy 337.890579 -54.26735) (xy 337.860555 -54.311387)
			(xy 337.824303 -54.350458) (xy 337.782632 -54.383689) (xy 337.736474 -54.410338) (xy 337.68686 -54.42981)
			(xy 337.634898 -54.44167) (xy 337.581748 -54.445654) (xy 337.528598 -54.44167) (xy 337.476636 -54.42981)
			(xy 337.427022 -54.410338) (xy 337.380864 -54.383689) (xy 337.339193 -54.350458) (xy 337.302941 -54.311387)
			(xy 337.272917 -54.26735) (xy 337.249791 -54.219329) (xy 337.234081 -54.168399) (xy 337.226138 -54.115695)
			(xy 335.188306 -54.115695) (xy 335.188306 -54.585595) (xy 336.410798 -54.585595) (xy 336.410798 -54.532297)
			(xy 336.418741 -54.479593) (xy 336.434451 -54.428663) (xy 336.457577 -54.380642) (xy 336.487601 -54.336605)
			(xy 336.523853 -54.297534) (xy 336.565524 -54.264303) (xy 336.611682 -54.237654) (xy 336.661296 -54.218182)
			(xy 336.713258 -54.206322) (xy 336.766408 -54.202339) (xy 336.819558 -54.206322) (xy 336.87152 -54.218182)
			(xy 336.921134 -54.237654) (xy 336.967292 -54.264303) (xy 337.008963 -54.297534) (xy 337.045215 -54.336605)
			(xy 337.075239 -54.380642) (xy 337.098365 -54.428663) (xy 337.114075 -54.479593) (xy 337.122018 -54.532297)
			(xy 337.122516 -54.558946) (xy 337.122018 -54.585595) (xy 338.038938 -54.585595) (xy 338.038938 -54.532297)
			(xy 338.046881 -54.479593) (xy 338.062591 -54.428663) (xy 338.085717 -54.380642) (xy 338.115741 -54.336605)
			(xy 338.151993 -54.297534) (xy 338.193664 -54.264303) (xy 338.239822 -54.237654) (xy 338.289436 -54.218182)
			(xy 338.341398 -54.206322) (xy 338.394548 -54.202339) (xy 338.447698 -54.206322) (xy 338.49966 -54.218182)
			(xy 338.549274 -54.237654) (xy 338.595432 -54.264303) (xy 338.637103 -54.297534) (xy 338.673355 -54.336605)
			(xy 338.703379 -54.380642) (xy 338.726505 -54.428663) (xy 338.742215 -54.479593) (xy 338.750158 -54.532297)
			(xy 338.750656 -54.558946) (xy 338.750158 -54.585595) (xy 339.122248 -54.585595) (xy 339.122248 -54.532297)
			(xy 339.130191 -54.479593) (xy 339.145901 -54.428663) (xy 339.169027 -54.380642) (xy 339.199051 -54.336605)
			(xy 339.235303 -54.297534) (xy 339.276974 -54.264303) (xy 339.323132 -54.237654) (xy 339.372746 -54.218182)
			(xy 339.424708 -54.206322) (xy 339.477858 -54.202339) (xy 339.531008 -54.206322) (xy 339.58297 -54.218182)
			(xy 339.632584 -54.237654) (xy 339.678742 -54.264303) (xy 339.720413 -54.297534) (xy 339.756665 -54.336605)
			(xy 339.786689 -54.380642) (xy 339.809815 -54.428663) (xy 339.825525 -54.479593) (xy 339.833468 -54.532297)
			(xy 339.833966 -54.558946) (xy 339.833468 -54.585595) (xy 340.750388 -54.585595) (xy 340.750388 -54.532297)
			(xy 340.758331 -54.479593) (xy 340.774041 -54.428663) (xy 340.797167 -54.380642) (xy 340.827191 -54.336605)
			(xy 340.863443 -54.297534) (xy 340.905114 -54.264303) (xy 340.951272 -54.237654) (xy 341.000886 -54.218182)
			(xy 341.052848 -54.206322) (xy 341.105998 -54.202339) (xy 341.159148 -54.206322) (xy 341.21111 -54.218182)
			(xy 341.260724 -54.237654) (xy 341.306882 -54.264303) (xy 341.348553 -54.297534) (xy 341.384805 -54.336605)
			(xy 341.414829 -54.380642) (xy 341.437955 -54.428663) (xy 341.453665 -54.479593) (xy 341.461608 -54.532297)
			(xy 341.462106 -54.558946) (xy 341.461613 -54.585341) (xy 342.379544 -54.585341) (xy 342.379544 -54.532043)
			(xy 342.387487 -54.479339) (xy 342.403197 -54.428409) (xy 342.426323 -54.380388) (xy 342.456347 -54.336351)
			(xy 342.492599 -54.29728) (xy 342.53427 -54.264049) (xy 342.580428 -54.2374) (xy 342.630042 -54.217928)
			(xy 342.682004 -54.206068) (xy 342.735154 -54.202085) (xy 342.788304 -54.206068) (xy 342.840266 -54.217928)
			(xy 342.88988 -54.2374) (xy 342.936038 -54.264049) (xy 342.977709 -54.29728) (xy 343.013961 -54.336351)
			(xy 343.043985 -54.380388) (xy 343.067111 -54.428409) (xy 343.082821 -54.479339) (xy 343.090764 -54.532043)
			(xy 343.091262 -54.558692) (xy 343.091262 -54.5587) (xy 344.007984 -54.5587) (xy 344.011967 -54.505553)
			(xy 344.023826 -54.453592) (xy 344.043296 -54.40398) (xy 344.069943 -54.357823) (xy 344.103171 -54.316152)
			(xy 344.142238 -54.2799) (xy 344.186271 -54.249874) (xy 344.234288 -54.226746) (xy 344.285215 -54.211032)
			(xy 344.337916 -54.203084) (xy 344.364564 -54.202584) (xy 344.389502 -54.202992) (xy 344.438893 -54.209937)
			(xy 344.48683 -54.223709) (xy 344.532374 -54.244038) (xy 344.574635 -54.270527) (xy 344.612783 -54.302657)
			(xy 344.62974 -54.320948) (xy 344.639336 -54.331034) (xy 344.662818 -54.34597) (xy 344.68946 -54.354016)
			(xy 344.717285 -54.354573) (xy 344.744228 -54.347601) (xy 344.76829 -54.333617) (xy 344.787685 -54.313658)
			(xy 344.800974 -54.289206) (xy 344.804492 -54.275736) (xy 344.810896 -54.249835) (xy 344.830304 -54.20014)
			(xy 344.856913 -54.153898) (xy 344.890125 -54.112145) (xy 344.929197 -54.075817) (xy 344.973253 -54.045727)
			(xy 345.021306 -54.02255) (xy 345.072281 -54.006805) (xy 345.125034 -53.998843) (xy 345.15171 -53.998368)
			(xy 345.178357 -53.998915) (xy 345.231056 -54.006859) (xy 345.281981 -54.022569) (xy 345.329997 -54.045693)
			(xy 345.37403 -54.075716) (xy 345.413097 -54.111965) (xy 345.446325 -54.153633) (xy 345.472971 -54.199787)
			(xy 345.492442 -54.249397) (xy 345.5043 -54.301355) (xy 345.508283 -54.3545) (xy 345.5043 -54.407645)
			(xy 345.492442 -54.459603) (xy 345.472971 -54.509213) (xy 345.446325 -54.555367) (xy 345.413097 -54.597035)
			(xy 345.37403 -54.633284) (xy 345.329997 -54.663307) (xy 345.281982 -54.686431) (xy 345.231056 -54.702141)
			(xy 345.178357 -54.710085) (xy 345.15171 -54.710584) (xy 345.126771 -54.710204) (xy 345.077379 -54.703255)
			(xy 345.029441 -54.689478) (xy 344.983896 -54.669144) (xy 344.941636 -54.642649) (xy 344.903489 -54.610514)
			(xy 344.886534 -54.59222) (xy 344.876928 -54.582152) (xy 344.853451 -54.567229) (xy 344.826818 -54.559193)
			(xy 344.799004 -54.55864) (xy 344.772073 -54.565611) (xy 344.748021 -54.57959) (xy 344.728633 -54.599538)
			(xy 344.715344 -54.623978) (xy 344.711782 -54.637432) (xy 344.70538 -54.663334) (xy 344.685974 -54.713031)
			(xy 344.659367 -54.759275) (xy 344.626155 -54.801029) (xy 344.587083 -54.837358) (xy 344.543026 -54.867448)
			(xy 344.494971 -54.890624) (xy 344.443995 -54.906368) (xy 344.39124 -54.914327) (xy 344.364564 -54.9148)
			(xy 344.337916 -54.914316) (xy 344.285215 -54.906368) (xy 344.234288 -54.890654) (xy 344.186271 -54.867526)
			(xy 344.142238 -54.8375) (xy 344.103171 -54.801248) (xy 344.069943 -54.759577) (xy 344.043296 -54.71342)
			(xy 344.023826 -54.663808) (xy 344.011967 -54.611847) (xy 344.007984 -54.5587) (xy 343.091262 -54.5587)
			(xy 343.090764 -54.585341) (xy 343.082821 -54.638045) (xy 343.067111 -54.688975) (xy 343.043985 -54.736996)
			(xy 343.013961 -54.781033) (xy 342.977709 -54.820104) (xy 342.936038 -54.853335) (xy 342.88988 -54.879984)
			(xy 342.840266 -54.899456) (xy 342.788304 -54.911316) (xy 342.735154 -54.9153) (xy 342.682004 -54.911316)
			(xy 342.630042 -54.899456) (xy 342.580428 -54.879984) (xy 342.53427 -54.853335) (xy 342.492599 -54.820104)
			(xy 342.456347 -54.781033) (xy 342.426323 -54.736996) (xy 342.403197 -54.688975) (xy 342.387487 -54.638045)
			(xy 342.379544 -54.585341) (xy 341.461613 -54.585341) (xy 341.461608 -54.585595) (xy 341.453665 -54.638299)
			(xy 341.437955 -54.689229) (xy 341.414829 -54.73725) (xy 341.384805 -54.781287) (xy 341.348553 -54.820358)
			(xy 341.306882 -54.853589) (xy 341.260724 -54.880238) (xy 341.21111 -54.89971) (xy 341.159148 -54.91157)
			(xy 341.105998 -54.915554) (xy 341.052848 -54.91157) (xy 341.000886 -54.89971) (xy 340.951272 -54.880238)
			(xy 340.905114 -54.853589) (xy 340.863443 -54.820358) (xy 340.827191 -54.781287) (xy 340.797167 -54.73725)
			(xy 340.774041 -54.689229) (xy 340.758331 -54.638299) (xy 340.750388 -54.585595) (xy 339.833468 -54.585595)
			(xy 339.825525 -54.638299) (xy 339.809815 -54.689229) (xy 339.786689 -54.73725) (xy 339.756665 -54.781287)
			(xy 339.720413 -54.820358) (xy 339.678742 -54.853589) (xy 339.632584 -54.880238) (xy 339.58297 -54.89971)
			(xy 339.531008 -54.91157) (xy 339.477858 -54.915554) (xy 339.424708 -54.91157) (xy 339.372746 -54.89971)
			(xy 339.323132 -54.880238) (xy 339.276974 -54.853589) (xy 339.235303 -54.820358) (xy 339.199051 -54.781287)
			(xy 339.169027 -54.73725) (xy 339.145901 -54.689229) (xy 339.130191 -54.638299) (xy 339.122248 -54.585595)
			(xy 338.750158 -54.585595) (xy 338.742215 -54.638299) (xy 338.726505 -54.689229) (xy 338.703379 -54.73725)
			(xy 338.673355 -54.781287) (xy 338.637103 -54.820358) (xy 338.595432 -54.853589) (xy 338.549274 -54.880238)
			(xy 338.49966 -54.89971) (xy 338.447698 -54.91157) (xy 338.394548 -54.915554) (xy 338.341398 -54.91157)
			(xy 338.289436 -54.89971) (xy 338.239822 -54.880238) (xy 338.193664 -54.853589) (xy 338.151993 -54.820358)
			(xy 338.115741 -54.781287) (xy 338.085717 -54.73725) (xy 338.062591 -54.689229) (xy 338.046881 -54.638299)
			(xy 338.038938 -54.585595) (xy 337.122018 -54.585595) (xy 337.114075 -54.638299) (xy 337.098365 -54.689229)
			(xy 337.075239 -54.73725) (xy 337.045215 -54.781287) (xy 337.008963 -54.820358) (xy 336.967292 -54.853589)
			(xy 336.921134 -54.880238) (xy 336.87152 -54.89971) (xy 336.819558 -54.91157) (xy 336.766408 -54.915554)
			(xy 336.713258 -54.91157) (xy 336.661296 -54.89971) (xy 336.611682 -54.880238) (xy 336.565524 -54.853589)
			(xy 336.523853 -54.820358) (xy 336.487601 -54.781287) (xy 336.457577 -54.73725) (xy 336.434451 -54.689229)
			(xy 336.418741 -54.638299) (xy 336.410798 -54.585595) (xy 335.188306 -54.585595) (xy 335.188306 -55.055495)
			(xy 335.597998 -55.055495) (xy 335.597998 -55.002197) (xy 335.605941 -54.949493) (xy 335.621651 -54.898563)
			(xy 335.644777 -54.850542) (xy 335.674801 -54.806505) (xy 335.711053 -54.767434) (xy 335.752724 -54.734203)
			(xy 335.798882 -54.707554) (xy 335.848496 -54.688082) (xy 335.900458 -54.676222) (xy 335.953608 -54.672239)
			(xy 336.006758 -54.676222) (xy 336.05872 -54.688082) (xy 336.108334 -54.707554) (xy 336.154492 -54.734203)
			(xy 336.196163 -54.767434) (xy 336.232415 -54.806505) (xy 336.262439 -54.850542) (xy 336.285565 -54.898563)
			(xy 336.301275 -54.949493) (xy 336.309218 -55.002197) (xy 336.309716 -55.028846) (xy 336.309218 -55.055495)
			(xy 337.226138 -55.055495) (xy 337.226138 -55.002197) (xy 337.234081 -54.949493) (xy 337.249791 -54.898563)
			(xy 337.272917 -54.850542) (xy 337.302941 -54.806505) (xy 337.339193 -54.767434) (xy 337.380864 -54.734203)
			(xy 337.427022 -54.707554) (xy 337.476636 -54.688082) (xy 337.528598 -54.676222) (xy 337.581748 -54.672239)
			(xy 337.634898 -54.676222) (xy 337.68686 -54.688082) (xy 337.736474 -54.707554) (xy 337.782632 -54.734203)
			(xy 337.824303 -54.767434) (xy 337.860555 -54.806505) (xy 337.890579 -54.850542) (xy 337.913705 -54.898563)
			(xy 337.929415 -54.949493) (xy 337.937358 -55.002197) (xy 337.937856 -55.028846) (xy 337.937358 -55.055495)
			(xy 339.935048 -55.055495) (xy 339.935048 -55.002197) (xy 339.942991 -54.949493) (xy 339.958701 -54.898563)
			(xy 339.981827 -54.850542) (xy 340.011851 -54.806505) (xy 340.048103 -54.767434) (xy 340.089774 -54.734203)
			(xy 340.135932 -54.707554) (xy 340.185546 -54.688082) (xy 340.237508 -54.676222) (xy 340.290658 -54.672239)
			(xy 340.343808 -54.676222) (xy 340.39577 -54.688082) (xy 340.445384 -54.707554) (xy 340.491542 -54.734203)
			(xy 340.533213 -54.767434) (xy 340.569465 -54.806505) (xy 340.599489 -54.850542) (xy 340.622615 -54.898563)
			(xy 340.638325 -54.949493) (xy 340.646268 -55.002197) (xy 340.646766 -55.028846) (xy 340.646268 -55.055495)
			(xy 341.565728 -55.055495) (xy 341.565728 -55.002197) (xy 341.573671 -54.949493) (xy 341.589381 -54.898563)
			(xy 341.612507 -54.850542) (xy 341.642531 -54.806505) (xy 341.678783 -54.767434) (xy 341.720454 -54.734203)
			(xy 341.766612 -54.707554) (xy 341.816226 -54.688082) (xy 341.868188 -54.676222) (xy 341.921338 -54.672239)
			(xy 341.974488 -54.676222) (xy 342.02645 -54.688082) (xy 342.076064 -54.707554) (xy 342.122222 -54.734203)
			(xy 342.163893 -54.767434) (xy 342.200145 -54.806505) (xy 342.230169 -54.850542) (xy 342.253295 -54.898563)
			(xy 342.269005 -54.949493) (xy 342.276948 -55.002197) (xy 342.277446 -55.028846) (xy 342.276953 -55.055241)
			(xy 343.194884 -55.055241) (xy 343.194884 -55.001943) (xy 343.202827 -54.949239) (xy 343.218537 -54.898309)
			(xy 343.241663 -54.850288) (xy 343.271687 -54.806251) (xy 343.307939 -54.76718) (xy 343.34961 -54.733949)
			(xy 343.395768 -54.7073) (xy 343.445382 -54.687828) (xy 343.497344 -54.675968) (xy 343.550494 -54.671985)
			(xy 343.603644 -54.675968) (xy 343.655606 -54.687828) (xy 343.70522 -54.7073) (xy 343.751378 -54.733949)
			(xy 343.793049 -54.76718) (xy 343.829301 -54.806251) (xy 343.859325 -54.850288) (xy 343.882451 -54.898309)
			(xy 343.898161 -54.949239) (xy 343.906104 -55.001943) (xy 343.906602 -55.028592) (xy 343.906104 -55.055241)
			(xy 343.898161 -55.107945) (xy 343.882451 -55.158875) (xy 343.859325 -55.206896) (xy 343.829301 -55.250933)
			(xy 343.793049 -55.290004) (xy 343.751378 -55.323235) (xy 343.70522 -55.349884) (xy 343.655606 -55.369356)
			(xy 343.603644 -55.381216) (xy 343.550494 -55.3852) (xy 343.497344 -55.381216) (xy 343.445382 -55.369356)
			(xy 343.395768 -55.349884) (xy 343.34961 -55.323235) (xy 343.307939 -55.290004) (xy 343.271687 -55.250933)
			(xy 343.241663 -55.206896) (xy 343.218537 -55.158875) (xy 343.202827 -55.107945) (xy 343.194884 -55.055241)
			(xy 342.276953 -55.055241) (xy 342.276948 -55.055495) (xy 342.269005 -55.108199) (xy 342.253295 -55.159129)
			(xy 342.230169 -55.20715) (xy 342.200145 -55.251187) (xy 342.163893 -55.290258) (xy 342.122222 -55.323489)
			(xy 342.076064 -55.350138) (xy 342.02645 -55.36961) (xy 341.974488 -55.38147) (xy 341.921338 -55.385454)
			(xy 341.868188 -55.38147) (xy 341.816226 -55.36961) (xy 341.766612 -55.350138) (xy 341.720454 -55.323489)
			(xy 341.678783 -55.290258) (xy 341.642531 -55.251187) (xy 341.612507 -55.20715) (xy 341.589381 -55.159129)
			(xy 341.573671 -55.108199) (xy 341.565728 -55.055495) (xy 340.646268 -55.055495) (xy 340.638325 -55.108199)
			(xy 340.622615 -55.159129) (xy 340.599489 -55.20715) (xy 340.569465 -55.251187) (xy 340.533213 -55.290258)
			(xy 340.491542 -55.323489) (xy 340.445384 -55.350138) (xy 340.39577 -55.36961) (xy 340.343808 -55.38147)
			(xy 340.290658 -55.385454) (xy 340.237508 -55.38147) (xy 340.185546 -55.36961) (xy 340.135932 -55.350138)
			(xy 340.089774 -55.323489) (xy 340.048103 -55.290258) (xy 340.011851 -55.251187) (xy 339.981827 -55.20715)
			(xy 339.958701 -55.159129) (xy 339.942991 -55.108199) (xy 339.935048 -55.055495) (xy 337.937358 -55.055495)
			(xy 337.929415 -55.108199) (xy 337.913705 -55.159129) (xy 337.890579 -55.20715) (xy 337.860555 -55.251187)
			(xy 337.824303 -55.290258) (xy 337.782632 -55.323489) (xy 337.736474 -55.350138) (xy 337.68686 -55.36961)
			(xy 337.634898 -55.38147) (xy 337.581748 -55.385454) (xy 337.528598 -55.38147) (xy 337.476636 -55.36961)
			(xy 337.427022 -55.350138) (xy 337.380864 -55.323489) (xy 337.339193 -55.290258) (xy 337.302941 -55.251187)
			(xy 337.272917 -55.20715) (xy 337.249791 -55.159129) (xy 337.234081 -55.108199) (xy 337.226138 -55.055495)
			(xy 336.309218 -55.055495) (xy 336.301275 -55.108199) (xy 336.285565 -55.159129) (xy 336.262439 -55.20715)
			(xy 336.232415 -55.251187) (xy 336.196163 -55.290258) (xy 336.154492 -55.323489) (xy 336.108334 -55.350138)
			(xy 336.05872 -55.36961) (xy 336.006758 -55.38147) (xy 335.953608 -55.385454) (xy 335.900458 -55.38147)
			(xy 335.848496 -55.36961) (xy 335.798882 -55.350138) (xy 335.752724 -55.323489) (xy 335.711053 -55.290258)
			(xy 335.674801 -55.251187) (xy 335.644777 -55.20715) (xy 335.621651 -55.159129) (xy 335.605941 -55.108199)
			(xy 335.597998 -55.055495) (xy 335.188306 -55.055495) (xy 335.188306 -55.143908) (xy 335.226406 -55.153814)
			(xy 335.25161 -55.160728) (xy 335.299811 -55.180928) (xy 335.344539 -55.20796) (xy 335.384835 -55.241241)
			(xy 335.41983 -55.280056) (xy 335.448775 -55.323572) (xy 335.471045 -55.370851) (xy 335.486163 -55.420879)
			(xy 335.493803 -55.47258) (xy 335.493801 -55.524843) (xy 335.493719 -55.525395) (xy 336.412068 -55.525395)
			(xy 336.412068 -55.472097) (xy 336.420011 -55.419393) (xy 336.435721 -55.368463) (xy 336.458847 -55.320442)
			(xy 336.488871 -55.276405) (xy 336.525123 -55.237334) (xy 336.566794 -55.204103) (xy 336.612952 -55.177454)
			(xy 336.662566 -55.157982) (xy 336.714528 -55.146122) (xy 336.767678 -55.142139) (xy 336.820828 -55.146122)
			(xy 336.87279 -55.157982) (xy 336.922404 -55.177454) (xy 336.968562 -55.204103) (xy 337.010233 -55.237334)
			(xy 337.046485 -55.276405) (xy 337.076509 -55.320442) (xy 337.099635 -55.368463) (xy 337.115345 -55.419393)
			(xy 337.123288 -55.472097) (xy 337.123786 -55.498746) (xy 337.123288 -55.525395) (xy 338.038938 -55.525395)
			(xy 338.038938 -55.472097) (xy 338.046881 -55.419393) (xy 338.062591 -55.368463) (xy 338.085717 -55.320442)
			(xy 338.115741 -55.276405) (xy 338.151993 -55.237334) (xy 338.193664 -55.204103) (xy 338.239822 -55.177454)
			(xy 338.289436 -55.157982) (xy 338.341398 -55.146122) (xy 338.394548 -55.142139) (xy 338.447698 -55.146122)
			(xy 338.49966 -55.157982) (xy 338.549274 -55.177454) (xy 338.595432 -55.204103) (xy 338.637103 -55.237334)
			(xy 338.673355 -55.276405) (xy 338.703379 -55.320442) (xy 338.726505 -55.368463) (xy 338.742215 -55.419393)
			(xy 338.750158 -55.472097) (xy 338.750656 -55.498746) (xy 338.750158 -55.525395) (xy 339.122248 -55.525395)
			(xy 339.122248 -55.472097) (xy 339.130191 -55.419393) (xy 339.145901 -55.368463) (xy 339.169027 -55.320442)
			(xy 339.199051 -55.276405) (xy 339.235303 -55.237334) (xy 339.276974 -55.204103) (xy 339.323132 -55.177454)
			(xy 339.372746 -55.157982) (xy 339.424708 -55.146122) (xy 339.477858 -55.142139) (xy 339.531008 -55.146122)
			(xy 339.58297 -55.157982) (xy 339.632584 -55.177454) (xy 339.678742 -55.204103) (xy 339.720413 -55.237334)
			(xy 339.756665 -55.276405) (xy 339.786689 -55.320442) (xy 339.809815 -55.368463) (xy 339.825525 -55.419393)
			(xy 339.833468 -55.472097) (xy 339.833966 -55.498746) (xy 339.833468 -55.525395) (xy 340.750388 -55.525395)
			(xy 340.750388 -55.472097) (xy 340.758331 -55.419393) (xy 340.774041 -55.368463) (xy 340.797167 -55.320442)
			(xy 340.827191 -55.276405) (xy 340.863443 -55.237334) (xy 340.905114 -55.204103) (xy 340.951272 -55.177454)
			(xy 341.000886 -55.157982) (xy 341.052848 -55.146122) (xy 341.105998 -55.142139) (xy 341.159148 -55.146122)
			(xy 341.21111 -55.157982) (xy 341.260724 -55.177454) (xy 341.306882 -55.204103) (xy 341.348553 -55.237334)
			(xy 341.384805 -55.276405) (xy 341.414829 -55.320442) (xy 341.437955 -55.368463) (xy 341.453665 -55.419393)
			(xy 341.461608 -55.472097) (xy 341.462106 -55.498746) (xy 341.461613 -55.525141) (xy 342.379544 -55.525141)
			(xy 342.379544 -55.471843) (xy 342.387487 -55.419139) (xy 342.403197 -55.368209) (xy 342.426323 -55.320188)
			(xy 342.456347 -55.276151) (xy 342.492599 -55.23708) (xy 342.53427 -55.203849) (xy 342.580428 -55.1772)
			(xy 342.630042 -55.157728) (xy 342.682004 -55.145868) (xy 342.735154 -55.141885) (xy 342.788304 -55.145868)
			(xy 342.840266 -55.157728) (xy 342.88988 -55.1772) (xy 342.936038 -55.203849) (xy 342.977709 -55.23708)
			(xy 343.013961 -55.276151) (xy 343.043985 -55.320188) (xy 343.067111 -55.368209) (xy 343.082821 -55.419139)
			(xy 343.090764 -55.471843) (xy 343.091262 -55.498492) (xy 343.091262 -55.4985) (xy 344.007984 -55.4985)
			(xy 344.011967 -55.445353) (xy 344.023826 -55.393392) (xy 344.043296 -55.34378) (xy 344.069943 -55.297623)
			(xy 344.103171 -55.255952) (xy 344.142238 -55.2197) (xy 344.186271 -55.189674) (xy 344.234288 -55.166546)
			(xy 344.285215 -55.150832) (xy 344.337916 -55.142884) (xy 344.364564 -55.142384) (xy 344.390797 -55.142811)
			(xy 344.442697 -55.150498) (xy 344.492909 -55.165713) (xy 344.540347 -55.188126) (xy 344.583986 -55.217252)
			(xy 344.622883 -55.252462) (xy 344.6399 -55.272432) (xy 344.648839 -55.282555) (xy 344.67087 -55.298153)
			(xy 344.696221 -55.307428) (xy 344.723117 -55.309732) (xy 344.749676 -55.304902) (xy 344.774039 -55.293278)
			(xy 344.794502 -55.275672) (xy 344.809632 -55.253317) (xy 344.814398 -55.240682) (xy 344.823816 -55.214635)
			(xy 344.849549 -55.165591) (xy 344.882562 -55.121119) (xy 344.922059 -55.082293) (xy 344.967089 -55.050046)
			(xy 345.016566 -55.025155) (xy 345.069299 -55.008222) (xy 345.124017 -54.999652) (xy 345.15171 -54.999128)
			(xy 345.178362 -54.999554) (xy 345.231069 -55.0075) (xy 345.282004 -55.023213) (xy 345.330028 -55.046341)
			(xy 345.374068 -55.076368) (xy 345.413141 -55.112624) (xy 345.446375 -55.154299) (xy 345.473026 -55.200461)
			(xy 345.492499 -55.250079) (xy 345.50436 -55.302046) (xy 345.508344 -55.3552) (xy 345.50436 -55.408354)
			(xy 345.492499 -55.460321) (xy 345.473026 -55.509939) (xy 345.446375 -55.556101) (xy 345.413141 -55.597776)
			(xy 345.374068 -55.634032) (xy 345.330028 -55.664059) (xy 345.282004 -55.687187) (xy 345.231069 -55.7029)
			(xy 345.178362 -55.710846) (xy 345.15171 -55.711344) (xy 345.125479 -55.710856) (xy 345.073582 -55.703179)
			(xy 345.023372 -55.687976) (xy 344.975934 -55.665575) (xy 344.932293 -55.63646) (xy 344.893393 -55.601261)
			(xy 344.876374 -55.581296) (xy 344.867474 -55.571135) (xy 344.845435 -55.555532) (xy 344.820075 -55.546255)
			(xy 344.79317 -55.543953) (xy 344.766603 -55.548788) (xy 344.742234 -55.560421) (xy 344.721769 -55.578038)
			(xy 344.70664 -55.600406) (xy 344.701876 -55.613046) (xy 344.692439 -55.639087) (xy 344.666713 -55.688134)
			(xy 344.633705 -55.732608) (xy 344.594211 -55.771438) (xy 344.549184 -55.803686) (xy 344.499707 -55.828577)
			(xy 344.446975 -55.84551) (xy 344.392256 -55.854077) (xy 344.364564 -55.8546) (xy 344.337916 -55.854116)
			(xy 344.285215 -55.846168) (xy 344.234288 -55.830454) (xy 344.186271 -55.807326) (xy 344.142238 -55.7773)
			(xy 344.103171 -55.741048) (xy 344.069943 -55.699377) (xy 344.043296 -55.65322) (xy 344.023826 -55.603608)
			(xy 344.011967 -55.551647) (xy 344.007984 -55.4985) (xy 343.091262 -55.4985) (xy 343.090764 -55.525141)
			(xy 343.082821 -55.577845) (xy 343.067111 -55.628775) (xy 343.043985 -55.676796) (xy 343.013961 -55.720833)
			(xy 342.977709 -55.759904) (xy 342.936038 -55.793135) (xy 342.88988 -55.819784) (xy 342.840266 -55.839256)
			(xy 342.788304 -55.851116) (xy 342.735154 -55.8551) (xy 342.682004 -55.851116) (xy 342.630042 -55.839256)
			(xy 342.580428 -55.819784) (xy 342.53427 -55.793135) (xy 342.492599 -55.759904) (xy 342.456347 -55.720833)
			(xy 342.426323 -55.676796) (xy 342.403197 -55.628775) (xy 342.387487 -55.577845) (xy 342.379544 -55.525141)
			(xy 341.461613 -55.525141) (xy 341.461608 -55.525395) (xy 341.453665 -55.578099) (xy 341.437955 -55.629029)
			(xy 341.414829 -55.67705) (xy 341.384805 -55.721087) (xy 341.348553 -55.760158) (xy 341.306882 -55.793389)
			(xy 341.260724 -55.820038) (xy 341.21111 -55.83951) (xy 341.159148 -55.85137) (xy 341.105998 -55.855354)
			(xy 341.052848 -55.85137) (xy 341.000886 -55.83951) (xy 340.951272 -55.820038) (xy 340.905114 -55.793389)
			(xy 340.863443 -55.760158) (xy 340.827191 -55.721087) (xy 340.797167 -55.67705) (xy 340.774041 -55.629029)
			(xy 340.758331 -55.578099) (xy 340.750388 -55.525395) (xy 339.833468 -55.525395) (xy 339.825525 -55.578099)
			(xy 339.809815 -55.629029) (xy 339.786689 -55.67705) (xy 339.756665 -55.721087) (xy 339.720413 -55.760158)
			(xy 339.678742 -55.793389) (xy 339.632584 -55.820038) (xy 339.58297 -55.83951) (xy 339.531008 -55.85137)
			(xy 339.477858 -55.855354) (xy 339.424708 -55.85137) (xy 339.372746 -55.83951) (xy 339.323132 -55.820038)
			(xy 339.276974 -55.793389) (xy 339.235303 -55.760158) (xy 339.199051 -55.721087) (xy 339.169027 -55.67705)
			(xy 339.145901 -55.629029) (xy 339.130191 -55.578099) (xy 339.122248 -55.525395) (xy 338.750158 -55.525395)
			(xy 338.742215 -55.578099) (xy 338.726505 -55.629029) (xy 338.703379 -55.67705) (xy 338.673355 -55.721087)
			(xy 338.637103 -55.760158) (xy 338.595432 -55.793389) (xy 338.549274 -55.820038) (xy 338.49966 -55.83951)
			(xy 338.447698 -55.85137) (xy 338.394548 -55.855354) (xy 338.341398 -55.85137) (xy 338.289436 -55.83951)
			(xy 338.239822 -55.820038) (xy 338.193664 -55.793389) (xy 338.151993 -55.760158) (xy 338.115741 -55.721087)
			(xy 338.085717 -55.67705) (xy 338.062591 -55.629029) (xy 338.046881 -55.578099) (xy 338.038938 -55.525395)
			(xy 337.123288 -55.525395) (xy 337.115345 -55.578099) (xy 337.099635 -55.629029) (xy 337.076509 -55.67705)
			(xy 337.046485 -55.721087) (xy 337.010233 -55.760158) (xy 336.968562 -55.793389) (xy 336.922404 -55.820038)
			(xy 336.87279 -55.83951) (xy 336.820828 -55.85137) (xy 336.767678 -55.855354) (xy 336.714528 -55.85137)
			(xy 336.662566 -55.83951) (xy 336.612952 -55.820038) (xy 336.566794 -55.793389) (xy 336.525123 -55.760158)
			(xy 336.488871 -55.721087) (xy 336.458847 -55.67705) (xy 336.435721 -55.629029) (xy 336.420011 -55.578099)
			(xy 336.412068 -55.525395) (xy 335.493719 -55.525395) (xy 335.486158 -55.576543) (xy 335.471037 -55.62657)
			(xy 335.448763 -55.673848) (xy 335.419817 -55.717362) (xy 335.384818 -55.756175) (xy 335.344521 -55.789453)
			(xy 335.29979 -55.816482) (xy 335.251589 -55.83668) (xy 335.226406 -55.843678) (xy 335.188306 -55.853584)
			(xy 335.188306 -55.995295) (xy 335.597998 -55.995295) (xy 335.597998 -55.941997) (xy 335.605941 -55.889293)
			(xy 335.621651 -55.838363) (xy 335.644777 -55.790342) (xy 335.674801 -55.746305) (xy 335.711053 -55.707234)
			(xy 335.752724 -55.674003) (xy 335.798882 -55.647354) (xy 335.848496 -55.627882) (xy 335.900458 -55.616022)
			(xy 335.953608 -55.612039) (xy 336.006758 -55.616022) (xy 336.05872 -55.627882) (xy 336.108334 -55.647354)
			(xy 336.154492 -55.674003) (xy 336.196163 -55.707234) (xy 336.232415 -55.746305) (xy 336.262439 -55.790342)
			(xy 336.285565 -55.838363) (xy 336.301275 -55.889293) (xy 336.309218 -55.941997) (xy 336.309716 -55.968646)
			(xy 336.309218 -55.995295) (xy 337.226138 -55.995295) (xy 337.226138 -55.941997) (xy 337.234081 -55.889293)
			(xy 337.249791 -55.838363) (xy 337.272917 -55.790342) (xy 337.302941 -55.746305) (xy 337.339193 -55.707234)
			(xy 337.380864 -55.674003) (xy 337.427022 -55.647354) (xy 337.476636 -55.627882) (xy 337.528598 -55.616022)
			(xy 337.581748 -55.612039) (xy 337.634898 -55.616022) (xy 337.68686 -55.627882) (xy 337.736474 -55.647354)
			(xy 337.782632 -55.674003) (xy 337.824303 -55.707234) (xy 337.860555 -55.746305) (xy 337.890579 -55.790342)
			(xy 337.913705 -55.838363) (xy 337.929415 -55.889293) (xy 337.937358 -55.941997) (xy 337.937856 -55.968646)
			(xy 337.937358 -55.995295) (xy 339.935048 -55.995295) (xy 339.935048 -55.941997) (xy 339.942991 -55.889293)
			(xy 339.958701 -55.838363) (xy 339.981827 -55.790342) (xy 340.011851 -55.746305) (xy 340.048103 -55.707234)
			(xy 340.089774 -55.674003) (xy 340.135932 -55.647354) (xy 340.185546 -55.627882) (xy 340.237508 -55.616022)
			(xy 340.290658 -55.612039) (xy 340.343808 -55.616022) (xy 340.39577 -55.627882) (xy 340.445384 -55.647354)
			(xy 340.491542 -55.674003) (xy 340.533213 -55.707234) (xy 340.569465 -55.746305) (xy 340.599489 -55.790342)
			(xy 340.622615 -55.838363) (xy 340.638325 -55.889293) (xy 340.646268 -55.941997) (xy 340.646766 -55.968646)
			(xy 340.646268 -55.995295) (xy 341.565728 -55.995295) (xy 341.565728 -55.941997) (xy 341.573671 -55.889293)
			(xy 341.589381 -55.838363) (xy 341.612507 -55.790342) (xy 341.642531 -55.746305) (xy 341.678783 -55.707234)
			(xy 341.720454 -55.674003) (xy 341.766612 -55.647354) (xy 341.816226 -55.627882) (xy 341.868188 -55.616022)
			(xy 341.921338 -55.612039) (xy 341.974488 -55.616022) (xy 342.02645 -55.627882) (xy 342.076064 -55.647354)
			(xy 342.122222 -55.674003) (xy 342.163893 -55.707234) (xy 342.200145 -55.746305) (xy 342.230169 -55.790342)
			(xy 342.253295 -55.838363) (xy 342.269005 -55.889293) (xy 342.276948 -55.941997) (xy 342.277446 -55.968646)
			(xy 342.276953 -55.995041) (xy 343.194884 -55.995041) (xy 343.194884 -55.941743) (xy 343.202827 -55.889039)
			(xy 343.218537 -55.838109) (xy 343.241663 -55.790088) (xy 343.271687 -55.746051) (xy 343.307939 -55.70698)
			(xy 343.34961 -55.673749) (xy 343.395768 -55.6471) (xy 343.445382 -55.627628) (xy 343.497344 -55.615768)
			(xy 343.550494 -55.611785) (xy 343.603644 -55.615768) (xy 343.655606 -55.627628) (xy 343.70522 -55.6471)
			(xy 343.751378 -55.673749) (xy 343.793049 -55.70698) (xy 343.829301 -55.746051) (xy 343.859325 -55.790088)
			(xy 343.882451 -55.838109) (xy 343.898161 -55.889039) (xy 343.906104 -55.941743) (xy 343.906602 -55.968392)
			(xy 343.906104 -55.995041) (xy 343.898161 -56.047745) (xy 343.882451 -56.098675) (xy 343.859325 -56.146696)
			(xy 343.829301 -56.190733) (xy 343.793049 -56.229804) (xy 343.751378 -56.263035) (xy 343.70522 -56.289684)
			(xy 343.655606 -56.309156) (xy 343.603644 -56.321016) (xy 343.550494 -56.325) (xy 343.497344 -56.321016)
			(xy 343.445382 -56.309156) (xy 343.395768 -56.289684) (xy 343.34961 -56.263035) (xy 343.307939 -56.229804)
			(xy 343.271687 -56.190733) (xy 343.241663 -56.146696) (xy 343.218537 -56.098675) (xy 343.202827 -56.047745)
			(xy 343.194884 -55.995041) (xy 342.276953 -55.995041) (xy 342.276948 -55.995295) (xy 342.269005 -56.047999)
			(xy 342.253295 -56.098929) (xy 342.230169 -56.14695) (xy 342.200145 -56.190987) (xy 342.163893 -56.230058)
			(xy 342.122222 -56.263289) (xy 342.076064 -56.289938) (xy 342.02645 -56.30941) (xy 341.974488 -56.32127)
			(xy 341.921338 -56.325254) (xy 341.868188 -56.32127) (xy 341.816226 -56.30941) (xy 341.766612 -56.289938)
			(xy 341.720454 -56.263289) (xy 341.678783 -56.230058) (xy 341.642531 -56.190987) (xy 341.612507 -56.14695)
			(xy 341.589381 -56.098929) (xy 341.573671 -56.047999) (xy 341.565728 -55.995295) (xy 340.646268 -55.995295)
			(xy 340.638325 -56.047999) (xy 340.622615 -56.098929) (xy 340.599489 -56.14695) (xy 340.569465 -56.190987)
			(xy 340.533213 -56.230058) (xy 340.491542 -56.263289) (xy 340.445384 -56.289938) (xy 340.39577 -56.30941)
			(xy 340.343808 -56.32127) (xy 340.290658 -56.325254) (xy 340.237508 -56.32127) (xy 340.185546 -56.30941)
			(xy 340.135932 -56.289938) (xy 340.089774 -56.263289) (xy 340.048103 -56.230058) (xy 340.011851 -56.190987)
			(xy 339.981827 -56.14695) (xy 339.958701 -56.098929) (xy 339.942991 -56.047999) (xy 339.935048 -55.995295)
			(xy 337.937358 -55.995295) (xy 337.929415 -56.047999) (xy 337.913705 -56.098929) (xy 337.890579 -56.14695)
			(xy 337.860555 -56.190987) (xy 337.824303 -56.230058) (xy 337.782632 -56.263289) (xy 337.736474 -56.289938)
			(xy 337.68686 -56.30941) (xy 337.634898 -56.32127) (xy 337.581748 -56.325254) (xy 337.528598 -56.32127)
			(xy 337.476636 -56.30941) (xy 337.427022 -56.289938) (xy 337.380864 -56.263289) (xy 337.339193 -56.230058)
			(xy 337.302941 -56.190987) (xy 337.272917 -56.14695) (xy 337.249791 -56.098929) (xy 337.234081 -56.047999)
			(xy 337.226138 -55.995295) (xy 336.309218 -55.995295) (xy 336.301275 -56.047999) (xy 336.285565 -56.098929)
			(xy 336.262439 -56.14695) (xy 336.232415 -56.190987) (xy 336.196163 -56.230058) (xy 336.154492 -56.263289)
			(xy 336.108334 -56.289938) (xy 336.05872 -56.30941) (xy 336.006758 -56.32127) (xy 335.953608 -56.325254)
			(xy 335.900458 -56.32127) (xy 335.848496 -56.30941) (xy 335.798882 -56.289938) (xy 335.752724 -56.263289)
			(xy 335.711053 -56.230058) (xy 335.674801 -56.190987) (xy 335.644777 -56.14695) (xy 335.621651 -56.098929)
			(xy 335.605941 -56.047999) (xy 335.597998 -55.995295) (xy 335.188306 -55.995295) (xy 335.188306 -56.083708)
			(xy 335.226406 -56.093614) (xy 335.251608 -56.100537) (xy 335.299804 -56.120753) (xy 335.344528 -56.147795)
			(xy 335.38482 -56.181081) (xy 335.419817 -56.219898) (xy 335.448765 -56.263413) (xy 335.471044 -56.31069)
			(xy 335.486176 -56.360715) (xy 335.493835 -56.412414) (xy 335.494376 -56.438546) (xy 335.493935 -56.463861)
			(xy 335.493744 -56.465195) (xy 336.411814 -56.465195) (xy 336.411814 -56.411897) (xy 336.419757 -56.359193)
			(xy 336.435467 -56.308263) (xy 336.458593 -56.260242) (xy 336.488617 -56.216205) (xy 336.524869 -56.177134)
			(xy 336.56654 -56.143903) (xy 336.612698 -56.117254) (xy 336.662312 -56.097782) (xy 336.714274 -56.085922)
			(xy 336.767424 -56.081939) (xy 336.820574 -56.085922) (xy 336.872536 -56.097782) (xy 336.92215 -56.117254)
			(xy 336.968308 -56.143903) (xy 337.009979 -56.177134) (xy 337.046231 -56.216205) (xy 337.076255 -56.260242)
			(xy 337.099381 -56.308263) (xy 337.115091 -56.359193) (xy 337.123034 -56.411897) (xy 337.123532 -56.438546)
			(xy 337.123034 -56.465195) (xy 338.040208 -56.465195) (xy 338.040208 -56.411897) (xy 338.048151 -56.359193)
			(xy 338.063861 -56.308263) (xy 338.086987 -56.260242) (xy 338.117011 -56.216205) (xy 338.153263 -56.177134)
			(xy 338.194934 -56.143903) (xy 338.241092 -56.117254) (xy 338.290706 -56.097782) (xy 338.342668 -56.085922)
			(xy 338.395818 -56.081939) (xy 338.448968 -56.085922) (xy 338.50093 -56.097782) (xy 338.550544 -56.117254)
			(xy 338.596702 -56.143903) (xy 338.638373 -56.177134) (xy 338.674625 -56.216205) (xy 338.704649 -56.260242)
			(xy 338.727775 -56.308263) (xy 338.743485 -56.359193) (xy 338.751428 -56.411897) (xy 338.751926 -56.438546)
			(xy 338.751428 -56.465195) (xy 339.122248 -56.465195) (xy 339.122248 -56.411897) (xy 339.130191 -56.359193)
			(xy 339.145901 -56.308263) (xy 339.169027 -56.260242) (xy 339.199051 -56.216205) (xy 339.235303 -56.177134)
			(xy 339.276974 -56.143903) (xy 339.323132 -56.117254) (xy 339.372746 -56.097782) (xy 339.424708 -56.085922)
			(xy 339.477858 -56.081939) (xy 339.531008 -56.085922) (xy 339.58297 -56.097782) (xy 339.632584 -56.117254)
			(xy 339.678742 -56.143903) (xy 339.720413 -56.177134) (xy 339.756665 -56.216205) (xy 339.786689 -56.260242)
			(xy 339.809815 -56.308263) (xy 339.825525 -56.359193) (xy 339.833468 -56.411897) (xy 339.833966 -56.438546)
			(xy 339.833468 -56.465195) (xy 340.750388 -56.465195) (xy 340.750388 -56.411897) (xy 340.758331 -56.359193)
			(xy 340.774041 -56.308263) (xy 340.797167 -56.260242) (xy 340.827191 -56.216205) (xy 340.863443 -56.177134)
			(xy 340.905114 -56.143903) (xy 340.951272 -56.117254) (xy 341.000886 -56.097782) (xy 341.052848 -56.085922)
			(xy 341.105998 -56.081939) (xy 341.159148 -56.085922) (xy 341.21111 -56.097782) (xy 341.260724 -56.117254)
			(xy 341.306882 -56.143903) (xy 341.348553 -56.177134) (xy 341.384805 -56.216205) (xy 341.414829 -56.260242)
			(xy 341.437955 -56.308263) (xy 341.453665 -56.359193) (xy 341.461608 -56.411897) (xy 341.462106 -56.438546)
			(xy 341.461613 -56.464941) (xy 342.379544 -56.464941) (xy 342.379544 -56.411643) (xy 342.387487 -56.358939)
			(xy 342.403197 -56.308009) (xy 342.426323 -56.259988) (xy 342.456347 -56.215951) (xy 342.492599 -56.17688)
			(xy 342.53427 -56.143649) (xy 342.580428 -56.117) (xy 342.630042 -56.097528) (xy 342.682004 -56.085668)
			(xy 342.735154 -56.081685) (xy 342.788304 -56.085668) (xy 342.840266 -56.097528) (xy 342.88988 -56.117)
			(xy 342.936038 -56.143649) (xy 342.977709 -56.17688) (xy 343.013961 -56.215951) (xy 343.043985 -56.259988)
			(xy 343.067111 -56.308009) (xy 343.082821 -56.358939) (xy 343.090764 -56.411643) (xy 343.091262 -56.438292)
			(xy 343.090764 -56.464941) (xy 343.082821 -56.517645) (xy 343.067111 -56.568575) (xy 343.043985 -56.616596)
			(xy 343.013961 -56.660633) (xy 342.977709 -56.699704) (xy 342.936038 -56.732935) (xy 342.88988 -56.759584)
			(xy 342.840266 -56.779056) (xy 342.788304 -56.790916) (xy 342.735154 -56.7949) (xy 342.682004 -56.790916)
			(xy 342.630042 -56.779056) (xy 342.580428 -56.759584) (xy 342.53427 -56.732935) (xy 342.492599 -56.699704)
			(xy 342.456347 -56.660633) (xy 342.426323 -56.616596) (xy 342.403197 -56.568575) (xy 342.387487 -56.517645)
			(xy 342.379544 -56.464941) (xy 341.461613 -56.464941) (xy 341.461608 -56.465195) (xy 341.453665 -56.517899)
			(xy 341.437955 -56.568829) (xy 341.414829 -56.61685) (xy 341.384805 -56.660887) (xy 341.348553 -56.699958)
			(xy 341.306882 -56.733189) (xy 341.260724 -56.759838) (xy 341.21111 -56.77931) (xy 341.159148 -56.79117)
			(xy 341.105998 -56.795154) (xy 341.052848 -56.79117) (xy 341.000886 -56.77931) (xy 340.951272 -56.759838)
			(xy 340.905114 -56.733189) (xy 340.863443 -56.699958) (xy 340.827191 -56.660887) (xy 340.797167 -56.61685)
			(xy 340.774041 -56.568829) (xy 340.758331 -56.517899) (xy 340.750388 -56.465195) (xy 339.833468 -56.465195)
			(xy 339.825525 -56.517899) (xy 339.809815 -56.568829) (xy 339.786689 -56.61685) (xy 339.756665 -56.660887)
			(xy 339.720413 -56.699958) (xy 339.678742 -56.733189) (xy 339.632584 -56.759838) (xy 339.58297 -56.77931)
			(xy 339.531008 -56.79117) (xy 339.477858 -56.795154) (xy 339.424708 -56.79117) (xy 339.372746 -56.77931)
			(xy 339.323132 -56.759838) (xy 339.276974 -56.733189) (xy 339.235303 -56.699958) (xy 339.199051 -56.660887)
			(xy 339.169027 -56.61685) (xy 339.145901 -56.568829) (xy 339.130191 -56.517899) (xy 339.122248 -56.465195)
			(xy 338.751428 -56.465195) (xy 338.743485 -56.517899) (xy 338.727775 -56.568829) (xy 338.704649 -56.61685)
			(xy 338.674625 -56.660887) (xy 338.638373 -56.699958) (xy 338.596702 -56.733189) (xy 338.550544 -56.759838)
			(xy 338.50093 -56.77931) (xy 338.448968 -56.79117) (xy 338.395818 -56.795154) (xy 338.342668 -56.79117)
			(xy 338.290706 -56.77931) (xy 338.241092 -56.759838) (xy 338.194934 -56.733189) (xy 338.153263 -56.699958)
			(xy 338.117011 -56.660887) (xy 338.086987 -56.61685) (xy 338.063861 -56.568829) (xy 338.048151 -56.517899)
			(xy 338.040208 -56.465195) (xy 337.123034 -56.465195) (xy 337.115091 -56.517899) (xy 337.099381 -56.568829)
			(xy 337.076255 -56.61685) (xy 337.046231 -56.660887) (xy 337.009979 -56.699958) (xy 336.968308 -56.733189)
			(xy 336.92215 -56.759838) (xy 336.872536 -56.77931) (xy 336.820574 -56.79117) (xy 336.767424 -56.795154)
			(xy 336.714274 -56.79117) (xy 336.662312 -56.77931) (xy 336.612698 -56.759838) (xy 336.56654 -56.733189)
			(xy 336.524869 -56.699958) (xy 336.488617 -56.660887) (xy 336.458593 -56.61685) (xy 336.435467 -56.568829)
			(xy 336.419757 -56.517899) (xy 336.411814 -56.465195) (xy 335.493744 -56.465195) (xy 335.486775 -56.513983)
			(xy 335.472592 -56.562585) (xy 335.45167 -56.608691) (xy 335.424432 -56.65137) (xy 335.391426 -56.689763)
			(xy 335.353317 -56.723097) (xy 335.332324 -56.73725) (xy 335.319993 -56.745947) (xy 335.300644 -56.769082)
			(xy 335.288886 -56.796854) (xy 335.28574 -56.826849) (xy 335.291482 -56.856457) (xy 335.30561 -56.883102)
			(xy 335.315814 -56.894222) (xy 335.495392 -57.0738) (xy 335.61401 -57.0738) (xy 335.61401 -57.015634)
			(xy 335.611978 -57.008776) (xy 335.605205 -56.984249) (xy 335.597936 -56.933887) (xy 335.5975 -56.908446)
			(xy 335.597998 -56.881797) (xy 335.605941 -56.829093) (xy 335.621651 -56.778163) (xy 335.644777 -56.730142)
			(xy 335.674801 -56.686105) (xy 335.711053 -56.647034) (xy 335.752724 -56.613803) (xy 335.798882 -56.587154)
			(xy 335.848496 -56.567682) (xy 335.900458 -56.555822) (xy 335.953608 -56.551839) (xy 336.006758 -56.555822)
			(xy 336.05872 -56.567682) (xy 336.108334 -56.587154) (xy 336.154492 -56.613803) (xy 336.196163 -56.647034)
			(xy 336.232415 -56.686105) (xy 336.262439 -56.730142) (xy 336.285565 -56.778163) (xy 336.301275 -56.829093)
			(xy 336.309218 -56.881797) (xy 336.309716 -56.908446) (xy 336.309581 -56.920871) (xy 336.307803 -56.945659)
			(xy 336.30616 -56.957976) (xy 336.304638 -56.97242) (xy 336.308823 -57.001145) (xy 336.32092 -57.027534)
			(xy 336.33995 -57.049455) (xy 336.364377 -57.065138) (xy 336.39223 -57.073318) (xy 336.406744 -57.0738)
			(xy 337.128358 -57.0738) (xy 337.142876 -57.073291) (xy 337.170742 -57.065131) (xy 337.195185 -57.049458)
			(xy 337.214229 -57.02754) (xy 337.226334 -57.001147) (xy 337.230522 -56.972415) (xy 337.228942 -56.957976)
			(xy 337.22729 -56.94566) (xy 337.225508 -56.920872) (xy 337.225386 -56.908446) (xy 337.225884 -56.881797)
			(xy 337.233827 -56.829093) (xy 337.249537 -56.778163) (xy 337.272663 -56.730142) (xy 337.302687 -56.686105)
			(xy 337.338939 -56.647034) (xy 337.38061 -56.613803) (xy 337.426768 -56.587154) (xy 337.476382 -56.567682)
			(xy 337.528344 -56.555822) (xy 337.581494 -56.551839) (xy 337.634644 -56.555822) (xy 337.686606 -56.567682)
			(xy 337.73622 -56.587154) (xy 337.782378 -56.613803) (xy 337.824049 -56.647034) (xy 337.860301 -56.686105)
			(xy 337.890325 -56.730142) (xy 337.913451 -56.778163) (xy 337.929161 -56.829093) (xy 337.937104 -56.881797)
			(xy 337.937602 -56.908446) (xy 337.937467 -56.920871) (xy 337.935689 -56.945659) (xy 337.934046 -56.957976)
			(xy 337.932524 -56.97242) (xy 337.93671 -57.001147) (xy 337.948806 -57.027537) (xy 337.967835 -57.04946)
			(xy 337.992262 -57.065147) (xy 338.020115 -57.07333) (xy 338.03463 -57.0738) (xy 343.633552 -57.0738)
			(xy 344.068146 -56.639206) (xy 344.050366 -56.605932) (xy 344.037182 -56.579975) (xy 344.018505 -56.524838)
			(xy 344.009034 -56.467399) (xy 344.008456 -56.438292) (xy 344.009006 -56.410308) (xy 344.017761 -56.35503)
			(xy 344.035056 -56.301802) (xy 344.060464 -56.251934) (xy 344.09336 -56.206654) (xy 344.132933 -56.167078)
			(xy 344.17821 -56.134179) (xy 344.228076 -56.108767) (xy 344.281303 -56.091468) (xy 344.33658 -56.082708)
			(xy 344.364564 -56.082184) (xy 344.39367 -56.082767) (xy 344.451107 -56.09224) (xy 344.506241 -56.110924)
			(xy 344.532204 -56.124094) (xy 344.565478 -56.141874) (xy 344.70848 -55.998872) (xy 349.28429 -55.998872)
			(xy 349.553369 -56.267951) (xy 350.634558 -56.267951) (xy 350.634558 -56.213449) (xy 350.642313 -56.159503)
			(xy 350.657667 -56.107209) (xy 350.680306 -56.057632) (xy 350.70977 -56.011782) (xy 350.745458 -55.970591)
			(xy 350.786645 -55.934897) (xy 350.832492 -55.905428) (xy 350.882066 -55.882783) (xy 350.934358 -55.867423)
			(xy 350.988303 -55.859661) (xy 351.015554 -55.859172) (xy 351.042924 -55.859605) (xy 351.097102 -55.867417)
			(xy 351.14961 -55.882887) (xy 351.19937 -55.905697) (xy 351.245361 -55.935381) (xy 351.286642 -55.971329)
			(xy 351.30486 -55.99176) (xy 351.315028 -56.002834) (xy 351.340383 -56.018963) (xy 351.369337 -56.02701)
			(xy 351.399379 -56.026279) (xy 351.427906 -56.016832) (xy 351.452447 -55.999489) (xy 351.462086 -55.98795)
			(xy 351.480252 -55.96539) (xy 351.522267 -55.925521) (xy 351.569829 -55.892467) (xy 351.621844 -55.866987)
			(xy 351.677115 -55.84967) (xy 351.73437 -55.840913) (xy 351.76333 -55.840376) (xy 351.790192 -55.840832)
			(xy 351.843385 -55.848373) (xy 351.894994 -55.863302) (xy 351.943998 -55.885323) (xy 351.989429 -55.914001)
			(xy 352.030387 -55.948769) (xy 352.066062 -55.988939) (xy 352.095749 -56.033716) (xy 352.118862 -56.082215)
			(xy 352.134941 -56.133477) (xy 352.139758 -56.159908) (xy 352.142669 -56.174482) (xy 352.155724 -56.201166)
			(xy 352.17589 -56.22298) (xy 352.201469 -56.238087) (xy 352.230308 -56.245215) (xy 352.245168 -56.244998)
			(xy 352.264472 -56.24449) (xy 352.291724 -56.244981) (xy 352.345674 -56.252734) (xy 352.397971 -56.268087)
			(xy 352.447551 -56.290726) (xy 352.493404 -56.320191) (xy 352.534597 -56.355882) (xy 352.570291 -56.397072)
			(xy 352.59976 -56.442923) (xy 352.622403 -56.492501) (xy 352.637759 -56.544797) (xy 352.645517 -56.598746)
			(xy 352.64598 -56.625998) (xy 352.645486 -56.654128) (xy 352.637224 -56.709778) (xy 352.620878 -56.763611)
			(xy 352.596802 -56.814459) (xy 352.56552 -56.86122) (xy 352.527709 -56.90288) (xy 352.48419 -56.938535)
			(xy 352.460306 -56.953404) (xy 352.447564 -56.961695) (xy 352.427203 -56.984243) (xy 352.414358 -57.011776)
			(xy 352.410161 -57.041866) (xy 352.414984 -57.071862) (xy 352.42119 -57.085738) (xy 352.433586 -57.11211)
			(xy 352.451138 -57.167671) (xy 352.460011 -57.22526) (xy 352.46056 -57.254394) (xy 352.460139 -57.281649)
			(xy 352.452382 -57.335604) (xy 352.437024 -57.387905) (xy 352.414379 -57.437489) (xy 352.384907 -57.483344)
			(xy 352.349208 -57.524538) (xy 352.30801 -57.560232) (xy 352.262152 -57.589699) (xy 352.212566 -57.612339)
			(xy 352.160263 -57.62769) (xy 352.106307 -57.635442) (xy 352.079052 -57.635902) (xy 352.050822 -57.635438)
			(xy 351.994976 -57.627138) (xy 351.940964 -57.610696) (xy 351.889966 -57.586473) (xy 351.843095 -57.554996)
			(xy 351.801376 -57.516955) (xy 351.76572 -57.473179) (xy 351.736907 -57.424625) (xy 351.715565 -57.372355)
			(xy 351.702162 -57.31751) (xy 351.699068 -57.289446) (xy 351.697441 -57.275965) (xy 351.687971 -57.250525)
			(xy 351.672124 -57.228486) (xy 351.651024 -57.211408) (xy 351.626165 -57.200504) (xy 351.59931 -57.196546)
			(xy 351.585784 -57.197752) (xy 351.574462 -57.199048) (xy 351.551714 -57.200448) (xy 351.540318 -57.200546)
			(xy 351.513069 -57.200005) (xy 351.459125 -57.192252) (xy 351.406834 -57.176901) (xy 351.357259 -57.154265)
			(xy 351.311411 -57.124804) (xy 351.270221 -57.089118) (xy 351.23453 -57.047934) (xy 351.205062 -57.00209)
			(xy 351.182418 -56.952519) (xy 351.16706 -56.90023) (xy 351.159299 -56.846287) (xy 351.15881 -56.819038)
			(xy 351.159028 -56.799532) (xy 351.162975 -56.76072) (xy 351.166684 -56.741568) (xy 351.16899 -56.728085)
			(xy 351.167219 -56.700803) (xy 351.158274 -56.674967) (xy 351.142795 -56.65243) (xy 351.121893 -56.634806)
			(xy 351.097065 -56.623359) (xy 351.070089 -56.618908) (xy 351.056448 -56.619902) (xy 351.046257 -56.620953)
			(xy 351.025799 -56.622099) (xy 351.015554 -56.622188) (xy 350.988303 -56.621739) (xy 350.934358 -56.613977)
			(xy 350.882066 -56.598617) (xy 350.832492 -56.575972) (xy 350.786645 -56.546503) (xy 350.745458 -56.510809)
			(xy 350.70977 -56.469618) (xy 350.680306 -56.423768) (xy 350.657667 -56.374191) (xy 350.642313 -56.321897)
			(xy 350.634558 -56.267951) (xy 349.553369 -56.267951) (xy 351.096326 -57.810908) (xy 353.33813 -57.810908)
			(xy 354.35159 -58.824368) (xy 355.73335 -58.824368)
		)
		(stroke
			(width 0)
			(type solid)
		)
		(fill yes)
		(layer "In15.Cu")
		(net "P1V8_PCH_AUX")
	)
	(gr_poly
		(pts
			(xy 349.51797 -261.05993) (xy 349.531901 -261.037882) (xy 349.565196 -260.997741) (xy 349.603991 -260.962886)
			(xy 349.647455 -260.934063) (xy 349.694658 -260.911888) (xy 349.744591 -260.896835) (xy 349.796186 -260.889228)
			(xy 349.848338 -260.889228) (xy 349.899933 -260.896835) (xy 349.949866 -260.911888) (xy 349.997069 -260.934063)
			(xy 350.040533 -260.962886) (xy 350.079328 -260.997741) (xy 350.112623 -261.037882) (xy 350.126554 -261.05993)
			(xy 350.375728 -261.05993) (xy 350.389499 -261.059484) (xy 350.416041 -261.052135) (xy 350.43965 -261.037953)
			(xy 350.458605 -261.017972) (xy 350.471524 -260.993649) (xy 350.477465 -260.966757) (xy 350.475995 -260.939255)
			(xy 350.471994 -260.926072) (xy 350.46331 -260.898496) (xy 350.453993 -260.84144) (xy 350.453452 -260.812534)
			(xy 350.45395 -260.785885) (xy 350.461893 -260.733181) (xy 350.477603 -260.682251) (xy 350.500729 -260.63423)
			(xy 350.530753 -260.590193) (xy 350.567005 -260.551122) (xy 350.608676 -260.517891) (xy 350.654834 -260.491242)
			(xy 350.704448 -260.47177) (xy 350.75641 -260.45991) (xy 350.80956 -260.455927) (xy 350.86271 -260.45991)
			(xy 350.914672 -260.47177) (xy 350.964286 -260.491242) (xy 351.010444 -260.517891) (xy 351.052115 -260.551122)
			(xy 351.088367 -260.590193) (xy 351.118391 -260.63423) (xy 351.141517 -260.682251) (xy 351.157227 -260.733181)
			(xy 351.16517 -260.785885) (xy 351.165668 -260.812534) (xy 351.165277 -260.837903) (xy 351.158135 -260.888136)
			(xy 351.151444 -260.91261) (xy 351.148066 -260.925656) (xy 351.14754 -260.952591) (xy 351.154076 -260.978725)
			(xy 351.16722 -261.002241) (xy 351.186057 -261.021501) (xy 351.209274 -261.035164) (xy 351.235257 -261.042279)
			(xy 351.248726 -261.042658) (xy 351.28581 -261.042658) (xy 351.489518 -260.83895) (xy 351.489518 -258.148074)
			(xy 351.489044 -258.133854) (xy 351.481202 -258.106515) (xy 351.466132 -258.082394) (xy 351.445001 -258.063358)
			(xy 351.419444 -258.050879) (xy 351.391437 -258.045924) (xy 351.37725 -258.046982) (xy 351.367818 -258.047936)
			(xy 351.348884 -258.048953) (xy 351.339404 -258.049014) (xy 351.312752 -258.048541) (xy 351.260044 -258.040597)
			(xy 351.209108 -258.024886) (xy 351.161083 -258.001759) (xy 351.117042 -257.971732) (xy 351.077967 -257.935477)
			(xy 351.044733 -257.893803) (xy 351.018081 -257.84764) (xy 350.998607 -257.798022) (xy 350.986745 -257.746055)
			(xy 350.982762 -257.6929) (xy 350.986745 -257.639745) (xy 350.998607 -257.587778) (xy 351.018081 -257.53816)
			(xy 351.044733 -257.491997) (xy 351.077967 -257.450323) (xy 351.117042 -257.414068) (xy 351.161083 -257.384041)
			(xy 351.209108 -257.360914) (xy 351.260044 -257.345203) (xy 351.312752 -257.337259) (xy 351.339404 -257.336798)
			(xy 351.37725 -257.33883) (xy 351.39144 -257.339851) (xy 351.419447 -257.334917) (xy 351.445007 -257.322451)
			(xy 351.466138 -257.303419) (xy 351.4812 -257.279297) (xy 351.489026 -257.251957) (xy 351.489518 -257.237738)
			(xy 351.489518 -249.79249) (xy 352.795078 -248.48693) (xy 352.795078 -245.06555) (xy 351.225358 -243.49583)
			(xy 351.225358 -241.293396) (xy 351.224886 -241.279279) (xy 351.217131 -241.25213) (xy 351.202242 -241.228139)
			(xy 351.181356 -241.20914) (xy 351.156067 -241.196581) (xy 351.128307 -241.191423) (xy 351.100196 -241.194059)
			(xy 351.073879 -241.204288) (xy 351.06229 -241.21237) (xy 351.038919 -241.229446) (xy 350.987795 -241.256581)
			(xy 350.932952 -241.275079) (xy 350.875837 -241.284451) (xy 350.846898 -241.285014) (xy 350.818915 -241.284465)
			(xy 350.763638 -241.27571) (xy 350.71041 -241.258415) (xy 350.660544 -241.233007) (xy 350.615266 -241.200111)
			(xy 350.575692 -241.160537) (xy 350.542795 -241.115259) (xy 350.517387 -241.065393) (xy 350.500091 -241.012166)
			(xy 350.491335 -240.956889) (xy 350.49079 -240.928906) (xy 350.491209 -240.904237) (xy 350.498019 -240.85537)
			(xy 350.51151 -240.807911) (xy 350.531424 -240.76277) (xy 350.557379 -240.720809) (xy 350.572832 -240.701576)
			(xy 350.58146 -240.690446) (xy 350.592808 -240.664685) (xy 350.596691 -240.636805) (xy 350.592811 -240.608923)
			(xy 350.581464 -240.583162) (xy 350.572832 -240.572036) (xy 350.557393 -240.552789) (xy 350.531416 -240.510841)
			(xy 350.511487 -240.465704) (xy 350.497989 -240.418245) (xy 350.491181 -240.369376) (xy 350.49079 -240.344706)
			(xy 350.491244 -240.31896) (xy 350.498662 -240.268005) (xy 350.513343 -240.21865) (xy 350.534981 -240.171925)
			(xy 350.563125 -240.128805) (xy 350.597187 -240.090189) (xy 350.61652 -240.07318) (xy 350.626738 -240.063912)
			(xy 350.642226 -240.041096) (xy 350.651041 -240.014968) (xy 350.652541 -239.987433) (xy 350.646615 -239.960501)
			(xy 350.633697 -239.936139) (xy 350.61473 -239.916123) (xy 350.591096 -239.901914) (xy 350.564522 -239.89455)
			(xy 350.550734 -239.89411) (xy 349.128588 -239.89411) (xy 349.119444 -239.93348) (xy 349.112969 -239.959276)
			(xy 349.093407 -240.008731) (xy 349.066708 -240.054726) (xy 349.033465 -240.09624) (xy 348.994418 -240.132348)
			(xy 348.950435 -240.162247) (xy 348.902495 -240.185273) (xy 348.851664 -240.200913) (xy 348.799072 -240.208819)
			(xy 348.77248 -240.209324) (xy 348.745955 -240.208833) (xy 348.693493 -240.200959) (xy 348.64278 -240.185386)
			(xy 348.594939 -240.162462) (xy 348.55103 -240.132692) (xy 348.53118 -240.11509) (xy 348.519342 -240.10495)
			(xy 348.491134 -240.091722) (xy 348.460254 -240.087596) (xy 348.429563 -240.092953) (xy 348.401907 -240.107298)
			(xy 348.390464 -240.117884) (xy 348.353888 -240.15446) (xy 348.343568 -240.165562) (xy 348.329366 -240.192322)
			(xy 348.323637 -240.22207) (xy 348.326885 -240.25219) (xy 348.338823 -240.280033) (xy 348.358403 -240.30315)
			(xy 348.383903 -240.319508) (xy 348.398338 -240.324132) (xy 348.423002 -240.331459) (xy 348.470071 -240.352231)
			(xy 348.513661 -240.379563) (xy 348.552861 -240.412885) (xy 348.586856 -240.451504) (xy 348.614936 -240.494615)
			(xy 348.636519 -240.541319) (xy 348.651152 -240.590644) (xy 348.658532 -240.641561) (xy 348.658942 -240.667286)
			(xy 348.65842 -240.693935) (xy 348.887024 -240.693935) (xy 348.887024 -240.640637) (xy 348.894967 -240.587933)
			(xy 348.910677 -240.537003) (xy 348.933803 -240.488982) (xy 348.963827 -240.444945) (xy 349.000079 -240.405874)
			(xy 349.04175 -240.372643) (xy 349.087908 -240.345994) (xy 349.137522 -240.326522) (xy 349.189484 -240.314662)
			(xy 349.242634 -240.310679) (xy 349.295784 -240.314662) (xy 349.347746 -240.326522) (xy 349.39736 -240.345994)
			(xy 349.443518 -240.372643) (xy 349.485189 -240.405874) (xy 349.521441 -240.444945) (xy 349.551465 -240.488982)
			(xy 349.574591 -240.537003) (xy 349.590301 -240.587933) (xy 349.598244 -240.640637) (xy 349.598742 -240.667286)
			(xy 349.598244 -240.693935) (xy 349.590301 -240.746639) (xy 349.574591 -240.797569) (xy 349.551465 -240.84559)
			(xy 349.521441 -240.889627) (xy 349.485189 -240.928698) (xy 349.443518 -240.961929) (xy 349.39736 -240.988578)
			(xy 349.347746 -241.00805) (xy 349.295784 -241.01991) (xy 349.242634 -241.023894) (xy 349.189484 -241.01991)
			(xy 349.137522 -241.00805) (xy 349.087908 -240.988578) (xy 349.04175 -240.961929) (xy 349.000079 -240.928698)
			(xy 348.963827 -240.889627) (xy 348.933803 -240.84559) (xy 348.910677 -240.797569) (xy 348.894967 -240.746639)
			(xy 348.887024 -240.693935) (xy 348.65842 -240.693935) (xy 348.658394 -240.695271) (xy 348.649641 -240.750552)
			(xy 348.632348 -240.803783) (xy 348.606941 -240.853653) (xy 348.574046 -240.898936) (xy 348.534472 -240.938515)
			(xy 348.489194 -240.971416) (xy 348.439327 -240.99683) (xy 348.386098 -241.01413) (xy 348.330819 -241.02289)
			(xy 348.302834 -241.023394) (xy 348.274595 -241.022857) (xy 348.218829 -241.013926) (xy 348.191836 -241.005614)
			(xy 348.178673 -241.001799) (xy 348.151306 -241.000555) (xy 348.124595 -241.006637) (xy 348.100464 -241.019605)
			(xy 348.080652 -241.038525) (xy 348.066586 -241.062034) (xy 348.059282 -241.088437) (xy 348.05874 -241.102134)
			(xy 348.05874 -241.20602) (xy 348.078704 -241.223014) (xy 348.113906 -241.261866) (xy 348.143028 -241.305461)
			(xy 348.165439 -241.352857) (xy 348.180654 -241.403028) (xy 348.188345 -241.454888) (xy 348.188345 -241.507315)
			(xy 348.18828 -241.507751) (xy 348.417124 -241.507751) (xy 348.417124 -241.454453) (xy 348.425067 -241.401749)
			(xy 348.440777 -241.350819) (xy 348.463903 -241.302798) (xy 348.493927 -241.258761) (xy 348.530179 -241.21969)
			(xy 348.57185 -241.186459) (xy 348.618008 -241.15981) (xy 348.667622 -241.140338) (xy 348.719584 -241.128478)
			(xy 348.772734 -241.124495) (xy 348.825884 -241.128478) (xy 348.877846 -241.140338) (xy 348.92746 -241.15981)
			(xy 348.973618 -241.186459) (xy 349.015289 -241.21969) (xy 349.051541 -241.258761) (xy 349.081565 -241.302798)
			(xy 349.104691 -241.350819) (xy 349.120401 -241.401749) (xy 349.128344 -241.454453) (xy 349.128842 -241.481102)
			(xy 349.128344 -241.507751) (xy 349.120401 -241.560455) (xy 349.104691 -241.611385) (xy 349.081565 -241.659406)
			(xy 349.051541 -241.703443) (xy 349.015289 -241.742514) (xy 348.973618 -241.775745) (xy 348.92746 -241.802394)
			(xy 348.877846 -241.821866) (xy 348.825884 -241.833726) (xy 348.772734 -241.83771) (xy 348.719584 -241.833726)
			(xy 348.667622 -241.821866) (xy 348.618008 -241.802394) (xy 348.57185 -241.775745) (xy 348.530179 -241.742514)
			(xy 348.493927 -241.703443) (xy 348.463903 -241.659406) (xy 348.440777 -241.611385) (xy 348.425067 -241.560455)
			(xy 348.417124 -241.507751) (xy 348.18828 -241.507751) (xy 348.180653 -241.559175) (xy 348.165438 -241.609346)
			(xy 348.143026 -241.656741) (xy 348.113905 -241.700336) (xy 348.078703 -241.739188) (xy 348.05874 -241.756184)
			(xy 348.05874 -241.86007) (xy 348.059184 -241.873782) (xy 348.066479 -241.900216) (xy 348.080551 -241.923753)
			(xy 348.100383 -241.942693) (xy 348.124543 -241.955667) (xy 348.151285 -241.961738) (xy 348.178679 -241.960469)
			(xy 348.191836 -241.95659) (xy 348.218835 -241.948303) (xy 348.274598 -241.939369) (xy 348.302834 -241.93881)
			(xy 348.32948 -241.939311) (xy 348.382177 -241.947258) (xy 348.433101 -241.96297) (xy 348.481114 -241.986096)
			(xy 348.525145 -242.01612) (xy 348.564209 -242.05237) (xy 348.597435 -242.094037) (xy 348.62408 -242.140191)
			(xy 348.643549 -242.1898) (xy 348.655407 -242.241756) (xy 348.659389 -242.2949) (xy 348.655407 -242.348044)
			(xy 348.643549 -242.4) (xy 348.62408 -242.449609) (xy 348.597435 -242.495763) (xy 348.564209 -242.53743)
			(xy 348.525145 -242.57368) (xy 348.481114 -242.603704) (xy 348.433101 -242.62683) (xy 348.382177 -242.642542)
			(xy 348.32948 -242.650489) (xy 348.302834 -242.651026) (xy 348.274595 -242.650489) (xy 348.218829 -242.641559)
			(xy 348.191836 -242.633246) (xy 348.17867 -242.629432) (xy 348.151298 -242.628191) (xy 348.124582 -242.634272)
			(xy 348.100444 -242.647238) (xy 348.080623 -242.666156) (xy 348.066546 -242.689663) (xy 348.059226 -242.716067)
			(xy 348.05874 -242.729766) (xy 348.05874 -242.833906) (xy 348.078705 -242.8509) (xy 348.113909 -242.889752)
			(xy 348.143033 -242.933348) (xy 348.165445 -242.980745) (xy 348.180663 -243.030917) (xy 348.188355 -243.082778)
			(xy 348.188356 -243.135207) (xy 348.188292 -243.135637) (xy 348.41687 -243.135637) (xy 348.41687 -243.082339)
			(xy 348.424813 -243.029635) (xy 348.440523 -242.978705) (xy 348.463649 -242.930684) (xy 348.493673 -242.886647)
			(xy 348.529925 -242.847576) (xy 348.571596 -242.814345) (xy 348.617754 -242.787696) (xy 348.667368 -242.768224)
			(xy 348.71933 -242.756364) (xy 348.77248 -242.752381) (xy 348.82563 -242.756364) (xy 348.877592 -242.768224)
			(xy 348.927206 -242.787696) (xy 348.973364 -242.814345) (xy 349.015035 -242.847576) (xy 349.051287 -242.886647)
			(xy 349.081311 -242.930684) (xy 349.104437 -242.978705) (xy 349.120147 -243.029635) (xy 349.12809 -243.082339)
			(xy 349.128588 -243.108988) (xy 349.12809 -243.135637) (xy 349.35667 -243.135637) (xy 349.35667 -243.082339)
			(xy 349.364613 -243.029635) (xy 349.380323 -242.978705) (xy 349.403449 -242.930684) (xy 349.433473 -242.886647)
			(xy 349.469725 -242.847576) (xy 349.511396 -242.814345) (xy 349.557554 -242.787696) (xy 349.607168 -242.768224)
			(xy 349.65913 -242.756364) (xy 349.71228 -242.752381) (xy 349.76543 -242.756364) (xy 349.817392 -242.768224)
			(xy 349.867006 -242.787696) (xy 349.913164 -242.814345) (xy 349.954835 -242.847576) (xy 349.991087 -242.886647)
			(xy 350.021111 -242.930684) (xy 350.044237 -242.978705) (xy 350.059947 -243.029635) (xy 350.06789 -243.082339)
			(xy 350.068388 -243.108988) (xy 350.06789 -243.135637) (xy 350.059947 -243.188341) (xy 350.044237 -243.239271)
			(xy 350.021111 -243.287292) (xy 349.991087 -243.331329) (xy 349.954835 -243.3704) (xy 349.913164 -243.403631)
			(xy 349.867006 -243.43028) (xy 349.817392 -243.449752) (xy 349.76543 -243.461612) (xy 349.71228 -243.465596)
			(xy 349.65913 -243.461612) (xy 349.607168 -243.449752) (xy 349.557554 -243.43028) (xy 349.511396 -243.403631)
			(xy 349.469725 -243.3704) (xy 349.433473 -243.331329) (xy 349.403449 -243.287292) (xy 349.380323 -243.239271)
			(xy 349.364613 -243.188341) (xy 349.35667 -243.135637) (xy 349.12809 -243.135637) (xy 349.120147 -243.188341)
			(xy 349.104437 -243.239271) (xy 349.081311 -243.287292) (xy 349.051287 -243.331329) (xy 349.015035 -243.3704)
			(xy 348.973364 -243.403631) (xy 348.927206 -243.43028) (xy 348.877592 -243.449752) (xy 348.82563 -243.461612)
			(xy 348.77248 -243.465596) (xy 348.71933 -243.461612) (xy 348.667368 -243.449752) (xy 348.617754 -243.43028)
			(xy 348.571596 -243.403631) (xy 348.529925 -243.3704) (xy 348.493673 -243.331329) (xy 348.463649 -243.287292)
			(xy 348.440523 -243.239271) (xy 348.424813 -243.188341) (xy 348.41687 -243.135637) (xy 348.188292 -243.135637)
			(xy 348.180666 -243.187069) (xy 348.165451 -243.237241) (xy 348.14304 -243.284639) (xy 348.113919 -243.328236)
			(xy 348.078716 -243.367089) (xy 348.05874 -243.38407) (xy 348.05874 -243.487956) (xy 348.059182 -243.501669)
			(xy 348.066475 -243.528107) (xy 348.080546 -243.551648) (xy 348.100379 -243.57059) (xy 348.124541 -243.583566)
			(xy 348.151285 -243.589639) (xy 348.178682 -243.588368) (xy 348.191836 -243.584476) (xy 348.218835 -243.576189)
			(xy 348.274598 -243.567256) (xy 348.302834 -243.566696) (xy 348.329481 -243.567196) (xy 348.38218 -243.575144)
			(xy 348.433106 -243.590857) (xy 348.481121 -243.613984) (xy 348.525154 -243.644008) (xy 348.56422 -243.68026)
			(xy 348.597447 -243.721929) (xy 348.624093 -243.768084) (xy 348.643563 -243.817695) (xy 348.655421 -243.869654)
			(xy 348.659404 -243.9228) (xy 348.657407 -243.949453) (xy 348.88677 -243.949453) (xy 348.88677 -243.896155)
			(xy 348.894713 -243.843451) (xy 348.910423 -243.792521) (xy 348.933549 -243.7445) (xy 348.963573 -243.700463)
			(xy 348.999825 -243.661392) (xy 349.041496 -243.628161) (xy 349.087654 -243.601512) (xy 349.137268 -243.58204)
			(xy 349.18923 -243.57018) (xy 349.24238 -243.566197) (xy 349.29553 -243.57018) (xy 349.347492 -243.58204)
			(xy 349.397106 -243.601512) (xy 349.443264 -243.628161) (xy 349.484935 -243.661392) (xy 349.521187 -243.700463)
			(xy 349.551211 -243.7445) (xy 349.574337 -243.792521) (xy 349.590047 -243.843451) (xy 349.59799 -243.896155)
			(xy 349.598488 -243.922804) (xy 349.59799 -243.949453) (xy 349.826824 -243.949453) (xy 349.826824 -243.896155)
			(xy 349.834767 -243.843451) (xy 349.850477 -243.792521) (xy 349.873603 -243.7445) (xy 349.903627 -243.700463)
			(xy 349.939879 -243.661392) (xy 349.98155 -243.628161) (xy 350.027708 -243.601512) (xy 350.077322 -243.58204)
			(xy 350.129284 -243.57018) (xy 350.182434 -243.566197) (xy 350.235584 -243.57018) (xy 350.287546 -243.58204)
			(xy 350.33716 -243.601512) (xy 350.383318 -243.628161) (xy 350.424989 -243.661392) (xy 350.461241 -243.700463)
			(xy 350.491265 -243.7445) (xy 350.514391 -243.792521) (xy 350.530101 -243.843451) (xy 350.538044 -243.896155)
			(xy 350.538542 -243.922804) (xy 350.538044 -243.949453) (xy 350.530101 -244.002157) (xy 350.514391 -244.053087)
			(xy 350.491265 -244.101108) (xy 350.461241 -244.145145) (xy 350.424989 -244.184216) (xy 350.383318 -244.217447)
			(xy 350.33716 -244.244096) (xy 350.287546 -244.263568) (xy 350.235584 -244.275428) (xy 350.182434 -244.279412)
			(xy 350.129284 -244.275428) (xy 350.077322 -244.263568) (xy 350.027708 -244.244096) (xy 349.98155 -244.217447)
			(xy 349.939879 -244.184216) (xy 349.903627 -244.145145) (xy 349.873603 -244.101108) (xy 349.850477 -244.053087)
			(xy 349.834767 -244.002157) (xy 349.826824 -243.949453) (xy 349.59799 -243.949453) (xy 349.590047 -244.002157)
			(xy 349.574337 -244.053087) (xy 349.551211 -244.101108) (xy 349.521187 -244.145145) (xy 349.484935 -244.184216)
			(xy 349.443264 -244.217447) (xy 349.397106 -244.244096) (xy 349.347492 -244.263568) (xy 349.29553 -244.275428)
			(xy 349.24238 -244.279412) (xy 349.18923 -244.275428) (xy 349.137268 -244.263568) (xy 349.087654 -244.244096)
			(xy 349.041496 -244.217447) (xy 348.999825 -244.184216) (xy 348.963573 -244.145145) (xy 348.933549 -244.101108)
			(xy 348.910423 -244.053087) (xy 348.894713 -244.002157) (xy 348.88677 -243.949453) (xy 348.657407 -243.949453)
			(xy 348.655421 -243.975946) (xy 348.643563 -244.027905) (xy 348.624093 -244.077516) (xy 348.597447 -244.123671)
			(xy 348.56422 -244.16534) (xy 348.525154 -244.201592) (xy 348.481121 -244.231616) (xy 348.433106 -244.254743)
			(xy 348.38218 -244.270456) (xy 348.329481 -244.278404) (xy 348.302834 -244.278912) (xy 348.274595 -244.278375)
			(xy 348.218829 -244.269445) (xy 348.191836 -244.261132) (xy 348.178674 -244.257316) (xy 348.151308 -244.256072)
			(xy 348.124598 -244.262154) (xy 348.100469 -244.275122) (xy 348.080659 -244.294043) (xy 348.066597 -244.317552)
			(xy 348.059297 -244.343955) (xy 348.05874 -244.357652) (xy 348.05874 -244.461538) (xy 348.078703 -244.478532)
			(xy 348.113902 -244.517383) (xy 348.143021 -244.560978) (xy 348.16543 -244.608373) (xy 348.180643 -244.658542)
			(xy 348.188332 -244.7104) (xy 348.18833 -244.762825) (xy 348.188264 -244.763269) (xy 348.41687 -244.763269)
			(xy 348.41687 -244.709971) (xy 348.424813 -244.657267) (xy 348.440523 -244.606337) (xy 348.463649 -244.558316)
			(xy 348.493673 -244.514279) (xy 348.529925 -244.475208) (xy 348.571596 -244.441977) (xy 348.617754 -244.415328)
			(xy 348.667368 -244.395856) (xy 348.71933 -244.383996) (xy 348.77248 -244.380013) (xy 348.82563 -244.383996)
			(xy 348.877592 -244.395856) (xy 348.927206 -244.415328) (xy 348.973364 -244.441977) (xy 349.015035 -244.475208)
			(xy 349.051287 -244.514279) (xy 349.081311 -244.558316) (xy 349.104437 -244.606337) (xy 349.120147 -244.657267)
			(xy 349.12809 -244.709971) (xy 349.128588 -244.73662) (xy 349.12809 -244.763269) (xy 349.35667 -244.763269)
			(xy 349.35667 -244.709971) (xy 349.364613 -244.657267) (xy 349.380323 -244.606337) (xy 349.403449 -244.558316)
			(xy 349.433473 -244.514279) (xy 349.469725 -244.475208) (xy 349.511396 -244.441977) (xy 349.557554 -244.415328)
			(xy 349.607168 -244.395856) (xy 349.65913 -244.383996) (xy 349.71228 -244.380013) (xy 349.76543 -244.383996)
			(xy 349.817392 -244.395856) (xy 349.867006 -244.415328) (xy 349.913164 -244.441977) (xy 349.954835 -244.475208)
			(xy 349.991087 -244.514279) (xy 350.021111 -244.558316) (xy 350.044237 -244.606337) (xy 350.059947 -244.657267)
			(xy 350.06789 -244.709971) (xy 350.068388 -244.73662) (xy 350.06789 -244.763269) (xy 350.059947 -244.815973)
			(xy 350.044237 -244.866903) (xy 350.021111 -244.914924) (xy 349.991087 -244.958961) (xy 349.954835 -244.998032)
			(xy 349.913164 -245.031263) (xy 349.867006 -245.057912) (xy 349.817392 -245.077384) (xy 349.76543 -245.089244)
			(xy 349.71228 -245.093228) (xy 349.65913 -245.089244) (xy 349.607168 -245.077384) (xy 349.557554 -245.057912)
			(xy 349.511396 -245.031263) (xy 349.469725 -244.998032) (xy 349.433473 -244.958961) (xy 349.403449 -244.914924)
			(xy 349.380323 -244.866903) (xy 349.364613 -244.815973) (xy 349.35667 -244.763269) (xy 349.12809 -244.763269)
			(xy 349.120147 -244.815973) (xy 349.104437 -244.866903) (xy 349.081311 -244.914924) (xy 349.051287 -244.958961)
			(xy 349.015035 -244.998032) (xy 348.973364 -245.031263) (xy 348.927206 -245.057912) (xy 348.877592 -245.077384)
			(xy 348.82563 -245.089244) (xy 348.77248 -245.093228) (xy 348.71933 -245.089244) (xy 348.667368 -245.077384)
			(xy 348.617754 -245.057912) (xy 348.571596 -245.031263) (xy 348.529925 -244.998032) (xy 348.493673 -244.958961)
			(xy 348.463649 -244.914924) (xy 348.440523 -244.866903) (xy 348.424813 -244.815973) (xy 348.41687 -244.763269)
			(xy 348.188264 -244.763269) (xy 348.180637 -244.814683) (xy 348.16542 -244.864851) (xy 348.143009 -244.912244)
			(xy 348.113887 -244.955837) (xy 348.078685 -244.994686) (xy 348.05874 -245.011702) (xy 348.05874 -245.115842)
			(xy 348.05918 -245.129556) (xy 348.066471 -245.155998) (xy 348.080542 -245.179542) (xy 348.100375 -245.198487)
			(xy 348.124539 -245.211466) (xy 348.151286 -245.217539) (xy 348.178685 -245.216268) (xy 348.191836 -245.212362)
			(xy 348.218835 -245.204073) (xy 348.274597 -245.195138) (xy 348.302834 -245.194582) (xy 348.329482 -245.195082)
			(xy 348.382183 -245.20303) (xy 348.433111 -245.218744) (xy 348.481128 -245.241872) (xy 348.525163 -245.271897)
			(xy 348.56423 -245.30815) (xy 348.597459 -245.349821) (xy 348.624105 -245.395978) (xy 348.643576 -245.445591)
			(xy 348.655435 -245.497552) (xy 348.659418 -245.5507) (xy 348.657422 -245.577339) (xy 348.887024 -245.577339)
			(xy 348.887024 -245.524041) (xy 348.894967 -245.471337) (xy 348.910677 -245.420407) (xy 348.933803 -245.372386)
			(xy 348.963827 -245.328349) (xy 349.000079 -245.289278) (xy 349.04175 -245.256047) (xy 349.087908 -245.229398)
			(xy 349.137522 -245.209926) (xy 349.189484 -245.198066) (xy 349.242634 -245.194083) (xy 349.295784 -245.198066)
			(xy 349.347746 -245.209926) (xy 349.39736 -245.229398) (xy 349.443518 -245.256047) (xy 349.485189 -245.289278)
			(xy 349.521441 -245.328349) (xy 349.551465 -245.372386) (xy 349.574591 -245.420407) (xy 349.590301 -245.471337)
			(xy 349.598244 -245.524041) (xy 349.598742 -245.55069) (xy 349.598742 -245.5507) (xy 349.825758 -245.5507)
			(xy 349.829742 -245.497542) (xy 349.841605 -245.445572) (xy 349.861081 -245.39595) (xy 349.887736 -245.349786)
			(xy 349.920974 -245.30811) (xy 349.960053 -245.271854) (xy 350.004099 -245.241828) (xy 350.052128 -245.218702)
			(xy 350.103068 -245.202993) (xy 350.15578 -245.195053) (xy 350.182434 -245.194582) (xy 350.206678 -245.194976)
			(xy 350.254715 -245.201571) (xy 350.301411 -245.214632) (xy 350.345898 -245.233919) (xy 350.366838 -245.246144)
			(xy 350.379547 -245.253245) (xy 350.407679 -245.260687) (xy 350.436768 -245.259904) (xy 350.464459 -245.25096)
			(xy 350.48851 -245.234579) (xy 350.506975 -245.212088) (xy 350.513142 -245.1989) (xy 350.52368 -245.175087)
			(xy 350.550714 -245.130581) (xy 350.56699 -245.110254) (xy 350.575635 -245.099136) (xy 350.586985 -245.073372)
			(xy 350.590865 -245.045488) (xy 350.586978 -245.017604) (xy 350.575622 -244.991843) (xy 350.56699 -244.980714)
			(xy 350.551587 -244.961442) (xy 350.525623 -244.919493) (xy 350.505699 -244.874361) (xy 350.492196 -244.826911)
			(xy 350.485374 -244.778051) (xy 350.484948 -244.753384) (xy 350.485446 -244.726735) (xy 350.493389 -244.674031)
			(xy 350.509099 -244.623101) (xy 350.532225 -244.57508) (xy 350.562249 -244.531043) (xy 350.598501 -244.491972)
			(xy 350.640172 -244.458741) (xy 350.68633 -244.432092) (xy 350.735944 -244.41262) (xy 350.787906 -244.40076)
			(xy 350.841056 -244.396777) (xy 350.894206 -244.40076) (xy 350.946168 -244.41262) (xy 350.995782 -244.432092)
			(xy 351.04194 -244.458741) (xy 351.083611 -244.491972) (xy 351.119863 -244.531043) (xy 351.149887 -244.57508)
			(xy 351.173013 -244.623101) (xy 351.188723 -244.674031) (xy 351.196666 -244.726735) (xy 351.197164 -244.753384)
			(xy 351.196748 -244.778053) (xy 351.189944 -244.826921) (xy 351.176452 -244.874378) (xy 351.156528 -244.919516)
			(xy 351.130558 -244.961466) (xy 351.115122 -244.980714) (xy 351.106514 -244.991856) (xy 351.095169 -245.017612)
			(xy 351.091288 -245.045488) (xy 351.095163 -245.073364) (xy 351.1065 -245.099123) (xy 351.115122 -245.110254)
			(xy 351.130558 -245.129501) (xy 351.156517 -245.171457) (xy 351.176434 -245.216595) (xy 351.189929 -245.264051)
			(xy 351.196743 -245.312915) (xy 351.197164 -245.337584) (xy 351.196673 -245.365571) (xy 351.187918 -245.420856)
			(xy 351.170621 -245.474091) (xy 351.145209 -245.523964) (xy 351.112308 -245.569248) (xy 351.072726 -245.608826)
			(xy 351.02744 -245.641724) (xy 350.977565 -245.667132) (xy 350.924329 -245.684424) (xy 350.869043 -245.693175)
			(xy 350.841056 -245.693692) (xy 350.816812 -245.693306) (xy 350.768774 -245.68671) (xy 350.722078 -245.673646)
			(xy 350.677591 -245.654357) (xy 350.656652 -245.64213) (xy 350.643944 -245.635029) (xy 350.615812 -245.627592)
			(xy 350.586724 -245.628378) (xy 350.559034 -245.637321) (xy 350.534983 -245.6537) (xy 350.516517 -245.676187)
			(xy 350.510348 -245.689374) (xy 350.499791 -245.713213) (xy 350.472715 -245.757767) (xy 350.439429 -245.797895)
			(xy 350.400645 -245.832736) (xy 350.357192 -245.861547) (xy 350.310001 -245.88371) (xy 350.260082 -245.89875)
			(xy 350.208502 -245.906347) (xy 350.182434 -245.906798) (xy 350.15578 -245.906347) (xy 350.103068 -245.898407)
			(xy 350.052128 -245.882698) (xy 350.004099 -245.859572) (xy 349.960053 -245.829546) (xy 349.920974 -245.79329)
			(xy 349.887736 -245.751614) (xy 349.861081 -245.70545) (xy 349.841605 -245.655828) (xy 349.829742 -245.603858)
			(xy 349.825758 -245.5507) (xy 349.598742 -245.5507) (xy 349.598244 -245.577339) (xy 349.590301 -245.630043)
			(xy 349.574591 -245.680973) (xy 349.551465 -245.728994) (xy 349.521441 -245.773031) (xy 349.485189 -245.812102)
			(xy 349.443518 -245.845333) (xy 349.39736 -245.871982) (xy 349.347746 -245.891454) (xy 349.295784 -245.903314)
			(xy 349.242634 -245.907298) (xy 349.189484 -245.903314) (xy 349.137522 -245.891454) (xy 349.087908 -245.871982)
			(xy 349.04175 -245.845333) (xy 349.000079 -245.812102) (xy 348.963827 -245.773031) (xy 348.933803 -245.728994)
			(xy 348.910677 -245.680973) (xy 348.894967 -245.630043) (xy 348.887024 -245.577339) (xy 348.657422 -245.577339)
			(xy 348.655435 -245.603848) (xy 348.643576 -245.655809) (xy 348.624105 -245.705422) (xy 348.597459 -245.751579)
			(xy 348.56423 -245.79325) (xy 348.525163 -245.829503) (xy 348.481128 -245.859528) (xy 348.433111 -245.882656)
			(xy 348.382183 -245.89837) (xy 348.329482 -245.906318) (xy 348.302834 -245.906798) (xy 348.274595 -245.906261)
			(xy 348.218829 -245.89733) (xy 348.191836 -245.889018) (xy 348.178673 -245.885203) (xy 348.151307 -245.883959)
			(xy 348.124596 -245.890041) (xy 348.100465 -245.903009) (xy 348.080653 -245.921929) (xy 348.066589 -245.945438)
			(xy 348.059285 -245.971841) (xy 348.05874 -245.985538) (xy 348.05874 -246.089424) (xy 348.078704 -246.106418)
			(xy 348.113905 -246.14527) (xy 348.143026 -246.188865) (xy 348.165437 -246.23626) (xy 348.180652 -246.286431)
			(xy 348.188342 -246.33829) (xy 348.188341 -246.390717) (xy 348.188276 -246.391155) (xy 348.417124 -246.391155)
			(xy 348.417124 -246.337857) (xy 348.425067 -246.285153) (xy 348.440777 -246.234223) (xy 348.463903 -246.186202)
			(xy 348.493927 -246.142165) (xy 348.530179 -246.103094) (xy 348.57185 -246.069863) (xy 348.618008 -246.043214)
			(xy 348.667622 -246.023742) (xy 348.719584 -246.011882) (xy 348.772734 -246.007899) (xy 348.825884 -246.011882)
			(xy 348.877846 -246.023742) (xy 348.92746 -246.043214) (xy 348.973618 -246.069863) (xy 349.015289 -246.103094)
			(xy 349.051541 -246.142165) (xy 349.081565 -246.186202) (xy 349.104691 -246.234223) (xy 349.120401 -246.285153)
			(xy 349.128344 -246.337857) (xy 349.128842 -246.364506) (xy 349.128344 -246.391155) (xy 349.35667 -246.391155)
			(xy 349.35667 -246.337857) (xy 349.364613 -246.285153) (xy 349.380323 -246.234223) (xy 349.403449 -246.186202)
			(xy 349.433473 -246.142165) (xy 349.469725 -246.103094) (xy 349.511396 -246.069863) (xy 349.557554 -246.043214)
			(xy 349.607168 -246.023742) (xy 349.65913 -246.011882) (xy 349.71228 -246.007899) (xy 349.76543 -246.011882)
			(xy 349.817392 -246.023742) (xy 349.867006 -246.043214) (xy 349.913164 -246.069863) (xy 349.954835 -246.103094)
			(xy 349.991087 -246.142165) (xy 350.021111 -246.186202) (xy 350.044237 -246.234223) (xy 350.059947 -246.285153)
			(xy 350.06789 -246.337857) (xy 350.068388 -246.364506) (xy 350.06789 -246.391155) (xy 350.059947 -246.443859)
			(xy 350.044237 -246.494789) (xy 350.021111 -246.54281) (xy 349.991087 -246.586847) (xy 349.954835 -246.625918)
			(xy 349.913164 -246.659149) (xy 349.867006 -246.685798) (xy 349.817392 -246.70527) (xy 349.76543 -246.71713)
			(xy 349.71228 -246.721114) (xy 349.65913 -246.71713) (xy 349.607168 -246.70527) (xy 349.557554 -246.685798)
			(xy 349.511396 -246.659149) (xy 349.469725 -246.625918) (xy 349.433473 -246.586847) (xy 349.403449 -246.54281)
			(xy 349.380323 -246.494789) (xy 349.364613 -246.443859) (xy 349.35667 -246.391155) (xy 349.128344 -246.391155)
			(xy 349.120401 -246.443859) (xy 349.104691 -246.494789) (xy 349.081565 -246.54281) (xy 349.051541 -246.586847)
			(xy 349.015289 -246.625918) (xy 348.973618 -246.659149) (xy 348.92746 -246.685798) (xy 348.877846 -246.70527)
			(xy 348.825884 -246.71713) (xy 348.772734 -246.721114) (xy 348.719584 -246.71713) (xy 348.667622 -246.70527)
			(xy 348.618008 -246.685798) (xy 348.57185 -246.659149) (xy 348.530179 -246.625918) (xy 348.493927 -246.586847)
			(xy 348.463903 -246.54281) (xy 348.440777 -246.494789) (xy 348.425067 -246.443859) (xy 348.417124 -246.391155)
			(xy 348.188276 -246.391155) (xy 348.18065 -246.442577) (xy 348.165434 -246.492747) (xy 348.143022 -246.540142)
			(xy 348.113901 -246.583736) (xy 348.078699 -246.622587) (xy 348.05874 -246.639588) (xy 348.05874 -246.743474)
			(xy 348.059184 -246.757185) (xy 348.06648 -246.783619) (xy 348.080552 -246.807155) (xy 348.100384 -246.826094)
			(xy 348.124543 -246.839067) (xy 348.151285 -246.845138) (xy 348.178678 -246.843869) (xy 348.191836 -246.839994)
			(xy 348.218835 -246.831707) (xy 348.274598 -246.822773) (xy 348.302834 -246.822214) (xy 348.32948 -246.822715)
			(xy 348.382176 -246.830662) (xy 348.433099 -246.846374) (xy 348.481112 -246.8695) (xy 348.525142 -246.899523)
			(xy 348.564206 -246.935772) (xy 348.597432 -246.977439) (xy 348.624076 -247.023592) (xy 348.643545 -247.073201)
			(xy 348.655403 -247.125157) (xy 348.659385 -247.1783) (xy 348.657387 -247.204971) (xy 348.887024 -247.204971)
			(xy 348.887024 -247.151673) (xy 348.894967 -247.098969) (xy 348.910677 -247.048039) (xy 348.933803 -247.000018)
			(xy 348.963827 -246.955981) (xy 349.000079 -246.91691) (xy 349.04175 -246.883679) (xy 349.087908 -246.85703)
			(xy 349.137522 -246.837558) (xy 349.189484 -246.825698) (xy 349.242634 -246.821715) (xy 349.295784 -246.825698)
			(xy 349.347746 -246.837558) (xy 349.39736 -246.85703) (xy 349.443518 -246.883679) (xy 349.485189 -246.91691)
			(xy 349.521441 -246.955981) (xy 349.551465 -247.000018) (xy 349.574591 -247.048039) (xy 349.590301 -247.098969)
			(xy 349.598244 -247.151673) (xy 349.598742 -247.178322) (xy 349.598244 -247.204971) (xy 349.826824 -247.204971)
			(xy 349.826824 -247.151673) (xy 349.834767 -247.098969) (xy 349.850477 -247.048039) (xy 349.873603 -247.000018)
			(xy 349.903627 -246.955981) (xy 349.939879 -246.91691) (xy 349.98155 -246.883679) (xy 350.027708 -246.85703)
			(xy 350.077322 -246.837558) (xy 350.129284 -246.825698) (xy 350.182434 -246.821715) (xy 350.235584 -246.825698)
			(xy 350.287546 -246.837558) (xy 350.33716 -246.85703) (xy 350.383318 -246.883679) (xy 350.424989 -246.91691)
			(xy 350.461241 -246.955981) (xy 350.491265 -247.000018) (xy 350.514391 -247.048039) (xy 350.530101 -247.098969)
			(xy 350.538044 -247.151673) (xy 350.538542 -247.178322) (xy 350.538044 -247.204971) (xy 350.530101 -247.257675)
			(xy 350.514391 -247.308605) (xy 350.491265 -247.356626) (xy 350.461241 -247.400663) (xy 350.424989 -247.439734)
			(xy 350.383318 -247.472965) (xy 350.33716 -247.499614) (xy 350.287546 -247.519086) (xy 350.235584 -247.530946)
			(xy 350.182434 -247.53493) (xy 350.129284 -247.530946) (xy 350.077322 -247.519086) (xy 350.027708 -247.499614)
			(xy 349.98155 -247.472965) (xy 349.939879 -247.439734) (xy 349.903627 -247.400663) (xy 349.873603 -247.356626)
			(xy 349.850477 -247.308605) (xy 349.834767 -247.257675) (xy 349.826824 -247.204971) (xy 349.598244 -247.204971)
			(xy 349.590301 -247.257675) (xy 349.574591 -247.308605) (xy 349.551465 -247.356626) (xy 349.521441 -247.400663)
			(xy 349.485189 -247.439734) (xy 349.443518 -247.472965) (xy 349.39736 -247.499614) (xy 349.347746 -247.519086)
			(xy 349.295784 -247.530946) (xy 349.242634 -247.53493) (xy 349.189484 -247.530946) (xy 349.137522 -247.519086)
			(xy 349.087908 -247.499614) (xy 349.04175 -247.472965) (xy 349.000079 -247.439734) (xy 348.963827 -247.400663)
			(xy 348.933803 -247.356626) (xy 348.910677 -247.308605) (xy 348.894967 -247.257675) (xy 348.887024 -247.204971)
			(xy 348.657387 -247.204971) (xy 348.655403 -247.231443) (xy 348.643545 -247.283399) (xy 348.624076 -247.333008)
			(xy 348.597432 -247.379161) (xy 348.564206 -247.420828) (xy 348.525142 -247.457077) (xy 348.481112 -247.4871)
			(xy 348.433099 -247.510226) (xy 348.382176 -247.525938) (xy 348.32948 -247.533885) (xy 348.302834 -247.53443)
			(xy 348.274595 -247.533893) (xy 348.218829 -247.524963) (xy 348.191836 -247.51665) (xy 348.17867 -247.512836)
			(xy 348.151299 -247.511595) (xy 348.124583 -247.517676) (xy 348.100446 -247.530642) (xy 348.080625 -247.54956)
			(xy 348.066548 -247.573067) (xy 348.059229 -247.599471) (xy 348.05874 -247.61317) (xy 348.05874 -247.717056)
			(xy 348.078702 -247.73405) (xy 348.113898 -247.772901) (xy 348.143015 -247.816495) (xy 348.165421 -247.863888)
			(xy 348.180632 -247.914056) (xy 348.188319 -247.965913) (xy 348.188315 -248.018336) (xy 348.188248 -248.018787)
			(xy 348.41687 -248.018787) (xy 348.41687 -247.965489) (xy 348.424813 -247.912785) (xy 348.440523 -247.861855)
			(xy 348.463649 -247.813834) (xy 348.493673 -247.769797) (xy 348.529925 -247.730726) (xy 348.571596 -247.697495)
			(xy 348.617754 -247.670846) (xy 348.667368 -247.651374) (xy 348.71933 -247.639514) (xy 348.77248 -247.635531)
			(xy 348.82563 -247.639514) (xy 348.877592 -247.651374) (xy 348.927206 -247.670846) (xy 348.973364 -247.697495)
			(xy 349.015035 -247.730726) (xy 349.051287 -247.769797) (xy 349.081311 -247.813834) (xy 349.104437 -247.861855)
			(xy 349.120147 -247.912785) (xy 349.12809 -247.965489) (xy 349.128588 -247.992138) (xy 349.12809 -248.018787)
			(xy 349.35667 -248.018787) (xy 349.35667 -247.965489) (xy 349.364613 -247.912785) (xy 349.380323 -247.861855)
			(xy 349.403449 -247.813834) (xy 349.433473 -247.769797) (xy 349.469725 -247.730726) (xy 349.511396 -247.697495)
			(xy 349.557554 -247.670846) (xy 349.607168 -247.651374) (xy 349.65913 -247.639514) (xy 349.71228 -247.635531)
			(xy 349.76543 -247.639514) (xy 349.817392 -247.651374) (xy 349.867006 -247.670846) (xy 349.913164 -247.697495)
			(xy 349.954835 -247.730726) (xy 349.991087 -247.769797) (xy 350.021111 -247.813834) (xy 350.044237 -247.861855)
			(xy 350.059947 -247.912785) (xy 350.06789 -247.965489) (xy 350.068388 -247.992138) (xy 350.06789 -248.018787)
			(xy 350.059947 -248.071491) (xy 350.044237 -248.122421) (xy 350.021111 -248.170442) (xy 349.991087 -248.214479)
			(xy 349.954835 -248.25355) (xy 349.913164 -248.286781) (xy 349.867006 -248.31343) (xy 349.817392 -248.332902)
			(xy 349.76543 -248.344762) (xy 349.71228 -248.348746) (xy 349.65913 -248.344762) (xy 349.607168 -248.332902)
			(xy 349.557554 -248.31343) (xy 349.511396 -248.286781) (xy 349.469725 -248.25355) (xy 349.433473 -248.214479)
			(xy 349.403449 -248.170442) (xy 349.380323 -248.122421) (xy 349.364613 -248.071491) (xy 349.35667 -248.018787)
			(xy 349.12809 -248.018787) (xy 349.120147 -248.071491) (xy 349.104437 -248.122421) (xy 349.081311 -248.170442)
			(xy 349.051287 -248.214479) (xy 349.015035 -248.25355) (xy 348.973364 -248.286781) (xy 348.927206 -248.31343)
			(xy 348.877592 -248.332902) (xy 348.82563 -248.344762) (xy 348.77248 -248.348746) (xy 348.71933 -248.344762)
			(xy 348.667368 -248.332902) (xy 348.617754 -248.31343) (xy 348.571596 -248.286781) (xy 348.529925 -248.25355)
			(xy 348.493673 -248.214479) (xy 348.463649 -248.170442) (xy 348.440523 -248.122421) (xy 348.424813 -248.071491)
			(xy 348.41687 -248.018787) (xy 348.188248 -248.018787) (xy 348.180621 -248.070191) (xy 348.165403 -248.120357)
			(xy 348.142991 -248.167747) (xy 348.113869 -248.211337) (xy 348.078667 -248.250183) (xy 348.05874 -248.26722)
			(xy 348.05874 -248.37136) (xy 348.059183 -248.385073) (xy 348.066476 -248.41151) (xy 348.080548 -248.435049)
			(xy 348.10038 -248.453991) (xy 348.124541 -248.466967) (xy 348.151285 -248.473039) (xy 348.178681 -248.471768)
			(xy 348.191836 -248.46788) (xy 348.218835 -248.459593) (xy 348.274598 -248.45066) (xy 348.302834 -248.4501)
			(xy 348.329481 -248.4506) (xy 348.382179 -248.458548) (xy 348.433105 -248.47426) (xy 348.481119 -248.497387)
			(xy 348.525151 -248.527411) (xy 348.564217 -248.563663) (xy 348.597444 -248.605331) (xy 348.624089 -248.651486)
			(xy 348.643559 -248.701097) (xy 348.655417 -248.753055) (xy 348.6594 -248.8062) (xy 348.657402 -248.832857)
			(xy 348.88677 -248.832857) (xy 348.88677 -248.779559) (xy 348.894713 -248.726855) (xy 348.910423 -248.675925)
			(xy 348.933549 -248.627904) (xy 348.963573 -248.583867) (xy 348.999825 -248.544796) (xy 349.041496 -248.511565)
			(xy 349.087654 -248.484916) (xy 349.137268 -248.465444) (xy 349.18923 -248.453584) (xy 349.24238 -248.449601)
			(xy 349.29553 -248.453584) (xy 349.347492 -248.465444) (xy 349.397106 -248.484916) (xy 349.443264 -248.511565)
			(xy 349.484935 -248.544796) (xy 349.521187 -248.583867) (xy 349.551211 -248.627904) (xy 349.574337 -248.675925)
			(xy 349.590047 -248.726855) (xy 349.59799 -248.779559) (xy 349.598488 -248.8062) (xy 349.825776 -248.8062)
			(xy 349.82976 -248.753045) (xy 349.841622 -248.701077) (xy 349.861097 -248.651458) (xy 349.887751 -248.605296)
			(xy 349.920987 -248.563622) (xy 349.960064 -248.527368) (xy 350.004108 -248.497343) (xy 350.052135 -248.474219)
			(xy 350.103072 -248.458511) (xy 350.155782 -248.450571) (xy 350.182434 -248.4501) (xy 350.211256 -248.450674)
			(xy 350.268148 -248.459956) (xy 350.322799 -248.478289) (xy 350.34855 -248.491248) (xy 350.361932 -248.497705)
			(xy 350.391094 -248.503339) (xy 350.420645 -248.500353) (xy 350.448091 -248.488999) (xy 350.471115 -248.470236)
			(xy 350.479868 -248.458228) (xy 350.494148 -248.437928) (xy 350.527464 -248.401138) (xy 350.565561 -248.369324)
			(xy 350.607701 -248.343101) (xy 350.65307 -248.322976) (xy 350.700793 -248.309337) (xy 350.749946 -248.302449)
			(xy 350.774762 -248.302018) (xy 350.802748 -248.302548) (xy 350.85803 -248.311299) (xy 350.911263 -248.328591)
			(xy 350.961135 -248.353999) (xy 351.006418 -248.386896) (xy 351.045996 -248.426473) (xy 351.078895 -248.471754)
			(xy 351.104305 -248.521626) (xy 351.121599 -248.574858) (xy 351.130351 -248.63014) (xy 351.13087 -248.658126)
			(xy 351.130477 -248.682796) (xy 351.123668 -248.731664) (xy 351.11017 -248.779122) (xy 351.090241 -248.824259)
			(xy 351.064266 -248.866209) (xy 351.048828 -248.885456) (xy 351.040179 -248.896569) (xy 351.02884 -248.922336)
			(xy 351.024965 -248.95022) (xy 351.028851 -248.978103) (xy 351.0402 -249.003865) (xy 351.048828 -249.014996)
			(xy 351.064238 -249.034263) (xy 351.0902 -249.076213) (xy 351.110123 -249.121347) (xy 351.123624 -249.168798)
			(xy 351.130445 -249.217659) (xy 351.13087 -249.242326) (xy 351.130412 -249.270314) (xy 351.121651 -249.3256)
			(xy 351.104349 -249.378835) (xy 351.078932 -249.428708) (xy 351.046027 -249.473991) (xy 351.006442 -249.513568)
			(xy 350.961153 -249.546466) (xy 350.911276 -249.571874) (xy 350.858038 -249.589166) (xy 350.80275 -249.597917)
			(xy 350.774762 -249.598434) (xy 350.74683 -249.5979) (xy 350.691651 -249.589171) (xy 350.638512 -249.571935)
			(xy 350.588716 -249.546613) (xy 350.543485 -249.513826) (xy 350.503927 -249.47438) (xy 350.471013 -249.429241)
			(xy 350.445551 -249.379516) (xy 350.428164 -249.326426) (xy 350.419281 -249.271273) (xy 350.418654 -249.243342)
			(xy 350.418159 -249.229773) (xy 350.410917 -249.203616) (xy 350.39704 -249.180291) (xy 350.377509 -249.161446)
			(xy 350.353703 -249.148411) (xy 350.327304 -249.142108) (xy 350.300177 -249.142982) (xy 350.287082 -249.146568)
			(xy 350.261551 -249.153939) (xy 350.209004 -249.161849) (xy 350.182434 -249.162316) (xy 350.155782 -249.161829)
			(xy 350.103072 -249.153889) (xy 350.052135 -249.138181) (xy 350.004108 -249.115057) (xy 349.960064 -249.085032)
			(xy 349.920987 -249.048778) (xy 349.887751 -249.007104) (xy 349.861097 -248.960942) (xy 349.841622 -248.911323)
			(xy 349.82976 -248.859355) (xy 349.825776 -248.8062) (xy 349.598488 -248.8062) (xy 349.598488 -248.806208)
			(xy 349.59799 -248.832857) (xy 349.590047 -248.885561) (xy 349.574337 -248.936491) (xy 349.551211 -248.984512)
			(xy 349.521187 -249.028549) (xy 349.484935 -249.06762) (xy 349.443264 -249.100851) (xy 349.397106 -249.1275)
			(xy 349.347492 -249.146972) (xy 349.29553 -249.158832) (xy 349.24238 -249.162816) (xy 349.18923 -249.158832)
			(xy 349.137268 -249.146972) (xy 349.087654 -249.1275) (xy 349.041496 -249.100851) (xy 348.999825 -249.06762)
			(xy 348.963573 -249.028549) (xy 348.933549 -248.984512) (xy 348.910423 -248.936491) (xy 348.894713 -248.885561)
			(xy 348.88677 -248.832857) (xy 348.657402 -248.832857) (xy 348.655417 -248.859345) (xy 348.643559 -248.911303)
			(xy 348.624089 -248.960914) (xy 348.597444 -249.007069) (xy 348.564217 -249.048737) (xy 348.525151 -249.084989)
			(xy 348.481119 -249.115013) (xy 348.433105 -249.13814) (xy 348.382179 -249.153852) (xy 348.329481 -249.1618)
			(xy 348.302834 -249.162316) (xy 348.274595 -249.161779) (xy 348.218829 -249.152849) (xy 348.191836 -249.144536)
			(xy 348.17867 -249.140722) (xy 348.151297 -249.139481) (xy 348.12458 -249.145563) (xy 348.100442 -249.158529)
			(xy 348.080619 -249.177446) (xy 348.06654 -249.200952) (xy 348.059217 -249.227356) (xy 348.05874 -249.241056)
			(xy 348.05874 -249.344942) (xy 348.078703 -249.361936) (xy 348.113901 -249.400787) (xy 348.14302 -249.444382)
			(xy 348.165428 -249.491776) (xy 348.18064 -249.541945) (xy 348.188329 -249.593803) (xy 348.188327 -249.646228)
			(xy 348.188261 -249.646673) (xy 348.41687 -249.646673) (xy 348.41687 -249.593375) (xy 348.424813 -249.540671)
			(xy 348.440523 -249.489741) (xy 348.463649 -249.44172) (xy 348.493673 -249.397683) (xy 348.529925 -249.358612)
			(xy 348.571596 -249.325381) (xy 348.617754 -249.298732) (xy 348.667368 -249.27926) (xy 348.71933 -249.2674)
			(xy 348.77248 -249.263417) (xy 348.82563 -249.2674) (xy 348.877592 -249.27926) (xy 348.927206 -249.298732)
			(xy 348.973364 -249.325381) (xy 349.015035 -249.358612) (xy 349.051287 -249.397683) (xy 349.081311 -249.44172)
			(xy 349.104437 -249.489741) (xy 349.120147 -249.540671) (xy 349.12809 -249.593375) (xy 349.128588 -249.620024)
			(xy 349.12809 -249.646673) (xy 349.35667 -249.646673) (xy 349.35667 -249.593375) (xy 349.364613 -249.540671)
			(xy 349.380323 -249.489741) (xy 349.403449 -249.44172) (xy 349.433473 -249.397683) (xy 349.469725 -249.358612)
			(xy 349.511396 -249.325381) (xy 349.557554 -249.298732) (xy 349.607168 -249.27926) (xy 349.65913 -249.2674)
			(xy 349.71228 -249.263417) (xy 349.76543 -249.2674) (xy 349.817392 -249.27926) (xy 349.867006 -249.298732)
			(xy 349.913164 -249.325381) (xy 349.954835 -249.358612) (xy 349.991087 -249.397683) (xy 350.021111 -249.44172)
			(xy 350.044237 -249.489741) (xy 350.059947 -249.540671) (xy 350.06789 -249.593375) (xy 350.068388 -249.620024)
			(xy 350.06789 -249.646673) (xy 350.059947 -249.699377) (xy 350.044237 -249.750307) (xy 350.021111 -249.798328)
			(xy 349.991087 -249.842365) (xy 349.954835 -249.881436) (xy 349.913164 -249.914667) (xy 349.867006 -249.941316)
			(xy 349.817392 -249.960788) (xy 349.76543 -249.972648) (xy 349.71228 -249.976632) (xy 349.65913 -249.972648)
			(xy 349.607168 -249.960788) (xy 349.557554 -249.941316) (xy 349.511396 -249.914667) (xy 349.469725 -249.881436)
			(xy 349.433473 -249.842365) (xy 349.403449 -249.798328) (xy 349.380323 -249.750307) (xy 349.364613 -249.699377)
			(xy 349.35667 -249.646673) (xy 349.12809 -249.646673) (xy 349.120147 -249.699377) (xy 349.104437 -249.750307)
			(xy 349.081311 -249.798328) (xy 349.051287 -249.842365) (xy 349.015035 -249.881436) (xy 348.973364 -249.914667)
			(xy 348.927206 -249.941316) (xy 348.877592 -249.960788) (xy 348.82563 -249.972648) (xy 348.77248 -249.976632)
			(xy 348.71933 -249.972648) (xy 348.667368 -249.960788) (xy 348.617754 -249.941316) (xy 348.571596 -249.914667)
			(xy 348.529925 -249.881436) (xy 348.493673 -249.842365) (xy 348.463649 -249.798328) (xy 348.440523 -249.750307)
			(xy 348.424813 -249.699377) (xy 348.41687 -249.646673) (xy 348.188261 -249.646673) (xy 348.180634 -249.698085)
			(xy 348.165417 -249.748252) (xy 348.143005 -249.795645) (xy 348.113883 -249.839237) (xy 348.078681 -249.878085)
			(xy 348.05874 -249.895106) (xy 348.05874 -251.135134) (xy 350.418654 -251.135134) (xy 350.419076 -251.110465)
			(xy 350.425878 -251.061598) (xy 350.439369 -251.01414) (xy 350.459291 -250.969002) (xy 350.485261 -250.927052)
			(xy 350.500696 -250.907804) (xy 350.509293 -250.896652) (xy 350.520649 -250.870901) (xy 350.524537 -250.843026)
			(xy 350.520663 -250.81515) (xy 350.509321 -250.789392) (xy 350.500696 -250.778264) (xy 350.485271 -250.759009)
			(xy 350.45931 -250.717055) (xy 350.43939 -250.671919) (xy 350.425893 -250.624465) (xy 350.419076 -250.575602)
			(xy 350.418654 -250.550934) (xy 350.419152 -250.524285) (xy 350.427095 -250.471581) (xy 350.442805 -250.420651)
			(xy 350.465931 -250.37263) (xy 350.495955 -250.328593) (xy 350.532207 -250.289522) (xy 350.573878 -250.256291)
			(xy 350.620036 -250.229642) (xy 350.66965 -250.21017) (xy 350.721612 -250.19831) (xy 350.774762 -250.194327)
			(xy 350.827912 -250.19831) (xy 350.879874 -250.21017) (xy 350.929488 -250.229642) (xy 350.975646 -250.256291)
			(xy 351.017317 -250.289522) (xy 351.053569 -250.328593) (xy 351.083593 -250.37263) (xy 351.106719 -250.420651)
			(xy 351.122429 -250.471581) (xy 351.130372 -250.524285) (xy 351.13087 -250.550934) (xy 351.130424 -250.575602)
			(xy 351.123628 -250.624468) (xy 351.110141 -250.671926) (xy 351.090225 -250.717063) (xy 351.064261 -250.759015)
			(xy 351.048828 -250.778264) (xy 351.040172 -250.789372) (xy 351.028833 -250.815141) (xy 351.02496 -250.843026)
			(xy 351.028847 -250.87091) (xy 351.040199 -250.896673) (xy 351.048828 -250.907804) (xy 351.064242 -250.927068)
			(xy 351.090204 -250.969019) (xy 351.110125 -251.014153) (xy 351.123626 -251.061605) (xy 351.130445 -251.110467)
			(xy 351.13087 -251.135134) (xy 351.130372 -251.161783) (xy 351.122429 -251.214487) (xy 351.106719 -251.265417)
			(xy 351.083593 -251.313438) (xy 351.053569 -251.357475) (xy 351.017317 -251.396546) (xy 350.975646 -251.429777)
			(xy 350.929488 -251.456426) (xy 350.879874 -251.475898) (xy 350.827912 -251.487758) (xy 350.774762 -251.491742)
			(xy 350.721612 -251.487758) (xy 350.66965 -251.475898) (xy 350.620036 -251.456426) (xy 350.573878 -251.429777)
			(xy 350.532207 -251.396546) (xy 350.495955 -251.357475) (xy 350.465931 -251.313438) (xy 350.442805 -251.265417)
			(xy 350.427095 -251.214487) (xy 350.419152 -251.161783) (xy 350.418654 -251.135134) (xy 348.05874 -251.135134)
			(xy 348.05874 -252.798834) (xy 350.479614 -252.798834) (xy 350.480045 -252.774165) (xy 350.486845 -252.725299)
			(xy 350.500335 -252.677841) (xy 350.520255 -252.632704) (xy 350.546222 -252.590753) (xy 350.561656 -252.571504)
			(xy 350.570249 -252.56035) (xy 350.581597 -252.534598) (xy 350.585484 -252.506726) (xy 350.581612 -252.478852)
			(xy 350.570276 -252.453094) (xy 350.561656 -252.441964) (xy 350.546225 -252.422714) (xy 350.520266 -252.380758)
			(xy 350.500348 -252.335621) (xy 350.486852 -252.288166) (xy 350.480036 -252.239302) (xy 350.479614 -252.214634)
			(xy 350.480112 -252.187985) (xy 350.488055 -252.135281) (xy 350.503765 -252.084351) (xy 350.526891 -252.03633)
			(xy 350.556915 -251.992293) (xy 350.593167 -251.953222) (xy 350.634838 -251.919991) (xy 350.680996 -251.893342)
			(xy 350.73061 -251.87387) (xy 350.782572 -251.86201) (xy 350.835722 -251.858027) (xy 350.888872 -251.86201)
			(xy 350.940834 -251.87387) (xy 350.990448 -251.893342) (xy 351.036606 -251.919991) (xy 351.078277 -251.953222)
			(xy 351.114529 -251.992293) (xy 351.144553 -252.03633) (xy 351.167679 -252.084351) (xy 351.183389 -252.135281)
			(xy 351.191332 -252.187985) (xy 351.19183 -252.214634) (xy 351.191393 -252.239303) (xy 351.184596 -252.288169)
			(xy 351.171108 -252.335627) (xy 351.151189 -252.380765) (xy 351.125222 -252.422716) (xy 351.109788 -252.441964)
			(xy 351.101128 -252.45307) (xy 351.089782 -252.478839) (xy 351.085907 -252.506726) (xy 351.089797 -252.534612)
			(xy 351.101155 -252.560375) (xy 351.109788 -252.571504) (xy 351.125211 -252.590761) (xy 351.15117 -252.632715)
			(xy 351.171089 -252.677851) (xy 351.184587 -252.725304) (xy 351.191406 -252.774166) (xy 351.19183 -252.798834)
			(xy 351.191332 -252.825483) (xy 351.183389 -252.878187) (xy 351.167679 -252.929117) (xy 351.144553 -252.977138)
			(xy 351.114529 -253.021175) (xy 351.078277 -253.060246) (xy 351.036606 -253.093477) (xy 350.990448 -253.120126)
			(xy 350.940834 -253.139598) (xy 350.888872 -253.151458) (xy 350.835722 -253.155442) (xy 350.782572 -253.151458)
			(xy 350.73061 -253.139598) (xy 350.680996 -253.120126) (xy 350.634838 -253.093477) (xy 350.593167 -253.060246)
			(xy 350.556915 -253.021175) (xy 350.526891 -252.977138) (xy 350.503765 -252.929117) (xy 350.488055 -252.878187)
			(xy 350.480112 -252.825483) (xy 350.479614 -252.798834) (xy 348.05874 -252.798834) (xy 348.05874 -253.537974)
			(xy 348.059196 -253.551689) (xy 348.066508 -253.578127) (xy 348.080586 -253.601669) (xy 348.100417 -253.620621)
			(xy 348.124573 -253.633618) (xy 348.151316 -253.639725) (xy 348.178719 -253.638502) (xy 348.204811 -253.630037)
			(xy 348.216474 -253.62281) (xy 348.238424 -253.608841) (xy 348.285521 -253.586731) (xy 348.335334 -253.571709)
			(xy 348.386802 -253.564097) (xy 348.412816 -253.563628) (xy 348.439462 -253.564127) (xy 348.492158 -253.572072)
			(xy 348.543081 -253.587782) (xy 348.591095 -253.610906) (xy 348.635126 -253.640927) (xy 348.67419 -253.677176)
			(xy 348.707416 -253.718841) (xy 348.734061 -253.764994) (xy 348.75353 -253.814602) (xy 348.765389 -253.866557)
			(xy 348.769371 -253.9197) (xy 348.767371 -253.946385) (xy 348.997006 -253.946385) (xy 348.997006 -253.893087)
			(xy 349.004949 -253.840383) (xy 349.020659 -253.789453) (xy 349.043785 -253.741432) (xy 349.073809 -253.697395)
			(xy 349.110061 -253.658324) (xy 349.151732 -253.625093) (xy 349.19789 -253.598444) (xy 349.247504 -253.578972)
			(xy 349.299466 -253.567112) (xy 349.352616 -253.563129) (xy 349.405766 -253.567112) (xy 349.457728 -253.578972)
			(xy 349.507342 -253.598444) (xy 349.5535 -253.625093) (xy 349.595171 -253.658324) (xy 349.631423 -253.697395)
			(xy 349.661447 -253.741432) (xy 349.684573 -253.789453) (xy 349.700283 -253.840383) (xy 349.708226 -253.893087)
			(xy 349.708724 -253.919736) (xy 349.708226 -253.946385) (xy 349.936806 -253.946385) (xy 349.936806 -253.893087)
			(xy 349.944749 -253.840383) (xy 349.960459 -253.789453) (xy 349.983585 -253.741432) (xy 350.013609 -253.697395)
			(xy 350.049861 -253.658324) (xy 350.091532 -253.625093) (xy 350.13769 -253.598444) (xy 350.187304 -253.578972)
			(xy 350.239266 -253.567112) (xy 350.292416 -253.563129) (xy 350.345566 -253.567112) (xy 350.397528 -253.578972)
			(xy 350.447142 -253.598444) (xy 350.4933 -253.625093) (xy 350.534971 -253.658324) (xy 350.571223 -253.697395)
			(xy 350.601247 -253.741432) (xy 350.624373 -253.789453) (xy 350.640083 -253.840383) (xy 350.648026 -253.893087)
			(xy 350.648524 -253.919736) (xy 350.648026 -253.946385) (xy 350.640083 -253.999089) (xy 350.624373 -254.050019)
			(xy 350.601247 -254.09804) (xy 350.571223 -254.142077) (xy 350.534971 -254.181148) (xy 350.4933 -254.214379)
			(xy 350.447142 -254.241028) (xy 350.397528 -254.2605) (xy 350.345566 -254.27236) (xy 350.292416 -254.276344)
			(xy 350.239266 -254.27236) (xy 350.187304 -254.2605) (xy 350.13769 -254.241028) (xy 350.091532 -254.214379)
			(xy 350.049861 -254.181148) (xy 350.013609 -254.142077) (xy 349.983585 -254.09804) (xy 349.960459 -254.050019)
			(xy 349.944749 -253.999089) (xy 349.936806 -253.946385) (xy 349.708226 -253.946385) (xy 349.700283 -253.999089)
			(xy 349.684573 -254.050019) (xy 349.661447 -254.09804) (xy 349.631423 -254.142077) (xy 349.595171 -254.181148)
			(xy 349.5535 -254.214379) (xy 349.507342 -254.241028) (xy 349.457728 -254.2605) (xy 349.405766 -254.27236)
			(xy 349.352616 -254.276344) (xy 349.299466 -254.27236) (xy 349.247504 -254.2605) (xy 349.19789 -254.241028)
			(xy 349.151732 -254.214379) (xy 349.110061 -254.181148) (xy 349.073809 -254.142077) (xy 349.043785 -254.09804)
			(xy 349.020659 -254.050019) (xy 349.004949 -253.999089) (xy 348.997006 -253.946385) (xy 348.767371 -253.946385)
			(xy 348.765389 -253.972843) (xy 348.75353 -254.024798) (xy 348.734061 -254.074406) (xy 348.707416 -254.120559)
			(xy 348.67419 -254.162224) (xy 348.635126 -254.198473) (xy 348.591095 -254.228494) (xy 348.543081 -254.251618)
			(xy 348.492158 -254.267328) (xy 348.439462 -254.275273) (xy 348.412816 -254.275844) (xy 348.386804 -254.27535)
			(xy 348.335338 -254.267739) (xy 348.285528 -254.252722) (xy 348.238432 -254.230617) (xy 348.216474 -254.216662)
			(xy 348.204782 -254.20945) (xy 348.178681 -254.200923) (xy 348.15125 -254.199657) (xy 348.124474 -254.205744)
			(xy 348.100287 -254.218745) (xy 348.080437 -254.237718) (xy 348.066359 -254.261294) (xy 348.059069 -254.287768)
			(xy 348.05874 -254.301498) (xy 348.05874 -254.395224) (xy 348.088712 -254.408686) (xy 348.11337 -254.420359)
			(xy 348.159116 -254.450079) (xy 348.199799 -254.486424) (xy 348.234466 -254.528545) (xy 348.262308 -254.575457)
			(xy 348.282675 -254.626066) (xy 348.295089 -254.679187) (xy 348.299262 -254.73358) (xy 348.297223 -254.760201)
			(xy 348.526852 -254.760201) (xy 348.526852 -254.706903) (xy 348.534795 -254.654199) (xy 348.550505 -254.603269)
			(xy 348.573631 -254.555248) (xy 348.603655 -254.511211) (xy 348.639907 -254.47214) (xy 348.681578 -254.438909)
			(xy 348.727736 -254.41226) (xy 348.77735 -254.392788) (xy 348.829312 -254.380928) (xy 348.882462 -254.376945)
			(xy 348.935612 -254.380928) (xy 348.987574 -254.392788) (xy 349.037188 -254.41226) (xy 349.083346 -254.438909)
			(xy 349.125017 -254.47214) (xy 349.161269 -254.511211) (xy 349.191293 -254.555248) (xy 349.214419 -254.603269)
			(xy 349.230129 -254.654199) (xy 349.238072 -254.706903) (xy 349.23857 -254.733552) (xy 349.238072 -254.760201)
			(xy 349.466652 -254.760201) (xy 349.466652 -254.706903) (xy 349.474595 -254.654199) (xy 349.490305 -254.603269)
			(xy 349.513431 -254.555248) (xy 349.543455 -254.511211) (xy 349.579707 -254.47214) (xy 349.621378 -254.438909)
			(xy 349.667536 -254.41226) (xy 349.71715 -254.392788) (xy 349.769112 -254.380928) (xy 349.822262 -254.376945)
			(xy 349.875412 -254.380928) (xy 349.927374 -254.392788) (xy 349.976988 -254.41226) (xy 350.023146 -254.438909)
			(xy 350.064817 -254.47214) (xy 350.101069 -254.511211) (xy 350.131093 -254.555248) (xy 350.154219 -254.603269)
			(xy 350.169929 -254.654199) (xy 350.177872 -254.706903) (xy 350.17837 -254.733552) (xy 350.177872 -254.760201)
			(xy 350.169929 -254.812905) (xy 350.154219 -254.863835) (xy 350.131093 -254.911856) (xy 350.101069 -254.955893)
			(xy 350.064817 -254.994964) (xy 350.023146 -255.028195) (xy 349.976988 -255.054844) (xy 349.927374 -255.074316)
			(xy 349.875412 -255.086176) (xy 349.822262 -255.09016) (xy 349.769112 -255.086176) (xy 349.71715 -255.074316)
			(xy 349.667536 -255.054844) (xy 349.621378 -255.028195) (xy 349.579707 -254.994964) (xy 349.543455 -254.955893)
			(xy 349.513431 -254.911856) (xy 349.490305 -254.863835) (xy 349.474595 -254.812905) (xy 349.466652 -254.760201)
			(xy 349.238072 -254.760201) (xy 349.230129 -254.812905) (xy 349.214419 -254.863835) (xy 349.191293 -254.911856)
			(xy 349.161269 -254.955893) (xy 349.125017 -254.994964) (xy 349.083346 -255.028195) (xy 349.037188 -255.054844)
			(xy 348.987574 -255.074316) (xy 348.935612 -255.086176) (xy 348.882462 -255.09016) (xy 348.829312 -255.086176)
			(xy 348.77735 -255.074316) (xy 348.727736 -255.054844) (xy 348.681578 -255.028195) (xy 348.639907 -254.994964)
			(xy 348.603655 -254.955893) (xy 348.573631 -254.911856) (xy 348.550505 -254.863835) (xy 348.534795 -254.812905)
			(xy 348.526852 -254.760201) (xy 348.297223 -254.760201) (xy 348.295095 -254.787974) (xy 348.282686 -254.841096)
			(xy 348.262326 -254.891707) (xy 348.234489 -254.938623) (xy 348.199826 -254.980748) (xy 348.159148 -255.017097)
			(xy 348.113404 -255.046822) (xy 348.088712 -255.058418) (xy 348.05874 -255.07188) (xy 348.05874 -255.16586)
			(xy 348.059194 -255.179576) (xy 348.066504 -255.206018) (xy 348.080582 -255.229564) (xy 348.100414 -255.248519)
			(xy 348.124572 -255.261518) (xy 348.151317 -255.267625) (xy 348.178723 -255.266401) (xy 348.204817 -255.257934)
			(xy 348.216474 -255.250696) (xy 348.238425 -255.236727) (xy 348.285521 -255.214618) (xy 348.335334 -255.199597)
			(xy 348.386802 -255.191985) (xy 348.412816 -255.191514) (xy 348.439463 -255.192013) (xy 348.492161 -255.199958)
			(xy 348.543086 -255.215669) (xy 348.591102 -255.238794) (xy 348.635134 -255.268816) (xy 348.6742 -255.305066)
			(xy 348.707428 -255.346734) (xy 348.734074 -255.392888) (xy 348.753544 -255.442498) (xy 348.765402 -255.494455)
			(xy 348.769385 -255.5476) (xy 348.767386 -255.574271) (xy 348.997006 -255.574271) (xy 348.997006 -255.520973)
			(xy 349.004949 -255.468269) (xy 349.020659 -255.417339) (xy 349.043785 -255.369318) (xy 349.073809 -255.325281)
			(xy 349.110061 -255.28621) (xy 349.151732 -255.252979) (xy 349.19789 -255.22633) (xy 349.247504 -255.206858)
			(xy 349.299466 -255.194998) (xy 349.352616 -255.191015) (xy 349.405766 -255.194998) (xy 349.457728 -255.206858)
			(xy 349.507342 -255.22633) (xy 349.5535 -255.252979) (xy 349.595171 -255.28621) (xy 349.631423 -255.325281)
			(xy 349.661447 -255.369318) (xy 349.684573 -255.417339) (xy 349.700283 -255.468269) (xy 349.708226 -255.520973)
			(xy 349.708724 -255.5476) (xy 349.93579 -255.5476) (xy 349.939773 -255.494449) (xy 349.951634 -255.442484)
			(xy 349.971107 -255.392869) (xy 349.997758 -255.346709) (xy 350.030992 -255.305038) (xy 350.070064 -255.268785)
			(xy 350.114104 -255.238761) (xy 350.162127 -255.215637) (xy 350.21306 -255.199928) (xy 350.265766 -255.191986)
			(xy 350.292416 -255.191514) (xy 350.319047 -255.191999) (xy 350.371718 -255.19991) (xy 350.397318 -255.207262)
			(xy 350.410436 -255.210865) (xy 350.437613 -255.211801) (xy 350.46407 -255.205516) (xy 350.487923 -255.192458)
			(xy 350.507473 -255.173557) (xy 350.521328 -255.150158) (xy 350.525334 -255.137158) (xy 350.532552 -255.112393)
			(xy 350.553239 -255.06514) (xy 350.580527 -255.021366) (xy 350.613845 -254.981986) (xy 350.652497 -254.947826)
			(xy 350.695672 -254.9196) (xy 350.742468 -254.897898) (xy 350.791906 -254.883175) (xy 350.84295 -254.875738)
			(xy 350.868742 -254.875284) (xy 350.896726 -254.875802) (xy 350.952004 -254.884563) (xy 351.005231 -254.901863)
			(xy 351.055096 -254.927276) (xy 351.100373 -254.960175) (xy 351.139947 -254.999753) (xy 351.172842 -255.045033)
			(xy 351.19825 -255.094901) (xy 351.215545 -255.148129) (xy 351.2243 -255.203408) (xy 351.22485 -255.231392)
			(xy 351.224429 -255.256224) (xy 351.217528 -255.305407) (xy 351.203859 -255.353153) (xy 351.183687 -255.398537)
			(xy 351.157404 -255.440676) (xy 351.141792 -255.459992) (xy 351.133132 -255.471166) (xy 351.121674 -255.496997)
			(xy 351.117713 -255.524976) (xy 351.121551 -255.552972) (xy 351.132896 -255.578853) (xy 351.141538 -255.59004)
			(xy 351.157024 -255.609292) (xy 351.183064 -255.651281) (xy 351.203044 -255.696469) (xy 351.21658 -255.743987)
			(xy 351.223413 -255.79292) (xy 351.223834 -255.817624) (xy 351.223281 -255.845606) (xy 351.214523 -255.900882)
			(xy 351.197227 -255.954107) (xy 351.171818 -256.003972) (xy 351.138923 -256.049248) (xy 351.099349 -256.088821)
			(xy 351.054073 -256.121717) (xy 351.004209 -256.147126) (xy 350.950984 -256.164423) (xy 350.895708 -256.173181)
			(xy 350.867726 -256.173732) (xy 350.840864 -256.173228) (xy 350.787748 -256.165175) (xy 350.736444 -256.149232)
			(xy 350.688119 -256.125761) (xy 350.643869 -256.095296) (xy 350.604699 -256.058528) (xy 350.571498 -256.016292)
			(xy 350.54502 -255.969546) (xy 350.534986 -255.944624) (xy 350.528894 -255.930216) (xy 350.50942 -255.905754)
			(xy 350.483471 -255.88831) (xy 350.453467 -255.879512) (xy 350.422207 -255.88018) (xy 350.407224 -255.88468)
			(xy 350.379356 -255.893562) (xy 350.321659 -255.90314) (xy 350.292416 -255.90373) (xy 350.265766 -255.903214)
			(xy 350.21306 -255.895272) (xy 350.162127 -255.879563) (xy 350.114104 -255.856439) (xy 350.070064 -255.826415)
			(xy 350.030992 -255.790162) (xy 349.997758 -255.748491) (xy 349.971107 -255.702331) (xy 349.951634 -255.652716)
			(xy 349.939773 -255.600751) (xy 349.93579 -255.5476) (xy 349.708724 -255.5476) (xy 349.708724 -255.547622)
			(xy 349.708226 -255.574271) (xy 349.700283 -255.626975) (xy 349.684573 -255.677905) (xy 349.661447 -255.725926)
			(xy 349.631423 -255.769963) (xy 349.595171 -255.809034) (xy 349.5535 -255.842265) (xy 349.507342 -255.868914)
			(xy 349.457728 -255.888386) (xy 349.405766 -255.900246) (xy 349.352616 -255.90423) (xy 349.299466 -255.900246)
			(xy 349.247504 -255.888386) (xy 349.19789 -255.868914) (xy 349.151732 -255.842265) (xy 349.110061 -255.809034)
			(xy 349.073809 -255.769963) (xy 349.043785 -255.725926) (xy 349.020659 -255.677905) (xy 349.004949 -255.626975)
			(xy 348.997006 -255.574271) (xy 348.767386 -255.574271) (xy 348.765402 -255.600745) (xy 348.753544 -255.652702)
			(xy 348.734074 -255.702312) (xy 348.707428 -255.748466) (xy 348.6742 -255.790134) (xy 348.635134 -255.826384)
			(xy 348.591102 -255.856406) (xy 348.543086 -255.879531) (xy 348.492161 -255.895242) (xy 348.439463 -255.903187)
			(xy 348.412816 -255.90373) (xy 348.386804 -255.903236) (xy 348.335338 -255.895625) (xy 348.285528 -255.880607)
			(xy 348.238433 -255.858501) (xy 348.216474 -255.844548) (xy 348.204786 -255.837332) (xy 348.17869 -255.828798)
			(xy 348.151263 -255.827529) (xy 348.124489 -255.833616) (xy 348.100307 -255.846619) (xy 348.080466 -255.865598)
			(xy 348.066401 -255.889179) (xy 348.059131 -255.915655) (xy 348.05874 -255.929384) (xy 348.05874 -256.02311)
			(xy 348.088712 -256.036572) (xy 348.113363 -256.048246) (xy 348.159097 -256.077963) (xy 348.199766 -256.114304)
			(xy 348.234422 -256.156419) (xy 348.262253 -256.203324) (xy 348.28261 -256.253923) (xy 348.295017 -256.307034)
			(xy 348.299183 -256.361416) (xy 348.297137 -256.388087) (xy 348.527106 -256.388087) (xy 348.527106 -256.334789)
			(xy 348.535049 -256.282085) (xy 348.550759 -256.231155) (xy 348.573885 -256.183134) (xy 348.603909 -256.139097)
			(xy 348.640161 -256.100026) (xy 348.681832 -256.066795) (xy 348.72799 -256.040146) (xy 348.777604 -256.020674)
			(xy 348.829566 -256.008814) (xy 348.882716 -256.004831) (xy 348.935866 -256.008814) (xy 348.987828 -256.020674)
			(xy 349.037442 -256.040146) (xy 349.0836 -256.066795) (xy 349.125271 -256.100026) (xy 349.161523 -256.139097)
			(xy 349.191547 -256.183134) (xy 349.214673 -256.231155) (xy 349.230383 -256.282085) (xy 349.238326 -256.334789)
			(xy 349.238824 -256.361438) (xy 349.238326 -256.388087) (xy 349.466652 -256.388087) (xy 349.466652 -256.334789)
			(xy 349.474595 -256.282085) (xy 349.490305 -256.231155) (xy 349.513431 -256.183134) (xy 349.543455 -256.139097)
			(xy 349.579707 -256.100026) (xy 349.621378 -256.066795) (xy 349.667536 -256.040146) (xy 349.71715 -256.020674)
			(xy 349.769112 -256.008814) (xy 349.822262 -256.004831) (xy 349.875412 -256.008814) (xy 349.927374 -256.020674)
			(xy 349.976988 -256.040146) (xy 350.023146 -256.066795) (xy 350.064817 -256.100026) (xy 350.101069 -256.139097)
			(xy 350.131093 -256.183134) (xy 350.154219 -256.231155) (xy 350.169929 -256.282085) (xy 350.177872 -256.334789)
			(xy 350.17837 -256.361438) (xy 350.177872 -256.388087) (xy 350.169929 -256.440791) (xy 350.154219 -256.491721)
			(xy 350.131093 -256.539742) (xy 350.101069 -256.583779) (xy 350.064817 -256.62285) (xy 350.023146 -256.656081)
			(xy 349.976988 -256.68273) (xy 349.927374 -256.702202) (xy 349.875412 -256.714062) (xy 349.822262 -256.718046)
			(xy 349.769112 -256.714062) (xy 349.71715 -256.702202) (xy 349.667536 -256.68273) (xy 349.621378 -256.656081)
			(xy 349.579707 -256.62285) (xy 349.543455 -256.583779) (xy 349.513431 -256.539742) (xy 349.490305 -256.491721)
			(xy 349.474595 -256.440791) (xy 349.466652 -256.388087) (xy 349.238326 -256.388087) (xy 349.230383 -256.440791)
			(xy 349.214673 -256.491721) (xy 349.191547 -256.539742) (xy 349.161523 -256.583779) (xy 349.125271 -256.62285)
			(xy 349.0836 -256.656081) (xy 349.037442 -256.68273) (xy 348.987828 -256.702202) (xy 348.935866 -256.714062)
			(xy 348.882716 -256.718046) (xy 348.829566 -256.714062) (xy 348.777604 -256.702202) (xy 348.72799 -256.68273)
			(xy 348.681832 -256.656081) (xy 348.640161 -256.62285) (xy 348.603909 -256.583779) (xy 348.573885 -256.539742)
			(xy 348.550759 -256.491721) (xy 348.535049 -256.440791) (xy 348.527106 -256.388087) (xy 348.297137 -256.388087)
			(xy 348.295012 -256.415797) (xy 348.282601 -256.468906) (xy 348.262239 -256.519504) (xy 348.234404 -256.566407)
			(xy 348.199745 -256.608519) (xy 348.159072 -256.644856) (xy 348.113336 -256.674569) (xy 348.088712 -256.686304)
			(xy 348.05874 -256.699766) (xy 348.05874 -256.793492) (xy 348.059198 -256.807205) (xy 348.066513 -256.833639)
			(xy 348.080592 -256.857177) (xy 348.100422 -256.876125) (xy 348.124576 -256.889119) (xy 348.151315 -256.895225)
			(xy 348.178714 -256.894003) (xy 348.204804 -256.885541) (xy 348.216474 -256.878328) (xy 348.238424 -256.864359)
			(xy 348.285521 -256.842247) (xy 348.335333 -256.827225) (xy 348.386802 -256.819613) (xy 348.412816 -256.819146)
			(xy 348.439468 -256.819645) (xy 348.492176 -256.827592) (xy 348.543112 -256.843305) (xy 348.591136 -256.866434)
			(xy 348.635177 -256.896463) (xy 348.674251 -256.93272) (xy 348.707484 -256.974395) (xy 348.734136 -257.020558)
			(xy 348.753609 -257.070177) (xy 348.76547 -257.122145) (xy 348.769454 -257.1753) (xy 348.76746 -257.201903)
			(xy 348.997006 -257.201903) (xy 348.997006 -257.148605) (xy 349.004949 -257.095901) (xy 349.020659 -257.044971)
			(xy 349.043785 -256.99695) (xy 349.073809 -256.952913) (xy 349.110061 -256.913842) (xy 349.151732 -256.880611)
			(xy 349.19789 -256.853962) (xy 349.247504 -256.83449) (xy 349.299466 -256.82263) (xy 349.352616 -256.818647)
			(xy 349.405766 -256.82263) (xy 349.457728 -256.83449) (xy 349.507342 -256.853962) (xy 349.5535 -256.880611)
			(xy 349.595171 -256.913842) (xy 349.631423 -256.952913) (xy 349.661447 -256.99695) (xy 349.684573 -257.044971)
			(xy 349.700283 -257.095901) (xy 349.708226 -257.148605) (xy 349.708724 -257.175254) (xy 349.708226 -257.201903)
			(xy 349.936806 -257.201903) (xy 349.936806 -257.148605) (xy 349.944749 -257.095901) (xy 349.960459 -257.044971)
			(xy 349.983585 -256.99695) (xy 350.013609 -256.952913) (xy 350.049861 -256.913842) (xy 350.091532 -256.880611)
			(xy 350.13769 -256.853962) (xy 350.187304 -256.83449) (xy 350.239266 -256.82263) (xy 350.292416 -256.818647)
			(xy 350.345566 -256.82263) (xy 350.397528 -256.83449) (xy 350.447142 -256.853962) (xy 350.4933 -256.880611)
			(xy 350.534971 -256.913842) (xy 350.571223 -256.952913) (xy 350.601247 -256.99695) (xy 350.624373 -257.044971)
			(xy 350.640083 -257.095901) (xy 350.648026 -257.148605) (xy 350.648524 -257.175254) (xy 350.648026 -257.201903)
			(xy 350.640083 -257.254607) (xy 350.624373 -257.305537) (xy 350.601247 -257.353558) (xy 350.571223 -257.397595)
			(xy 350.534971 -257.436666) (xy 350.4933 -257.469897) (xy 350.447142 -257.496546) (xy 350.397528 -257.516018)
			(xy 350.345566 -257.527878) (xy 350.292416 -257.531862) (xy 350.239266 -257.527878) (xy 350.187304 -257.516018)
			(xy 350.13769 -257.496546) (xy 350.091532 -257.469897) (xy 350.049861 -257.436666) (xy 350.013609 -257.397595)
			(xy 349.983585 -257.353558) (xy 349.960459 -257.305537) (xy 349.944749 -257.254607) (xy 349.936806 -257.201903)
			(xy 349.708226 -257.201903) (xy 349.700283 -257.254607) (xy 349.684573 -257.305537) (xy 349.661447 -257.353558)
			(xy 349.631423 -257.397595) (xy 349.595171 -257.436666) (xy 349.5535 -257.469897) (xy 349.507342 -257.496546)
			(xy 349.457728 -257.516018) (xy 349.405766 -257.527878) (xy 349.352616 -257.531862) (xy 349.299466 -257.527878)
			(xy 349.247504 -257.516018) (xy 349.19789 -257.496546) (xy 349.151732 -257.469897) (xy 349.110061 -257.436666)
			(xy 349.073809 -257.397595) (xy 349.043785 -257.353558) (xy 349.020659 -257.305537) (xy 349.004949 -257.254607)
			(xy 348.997006 -257.201903) (xy 348.76746 -257.201903) (xy 348.76547 -257.228455) (xy 348.753609 -257.280423)
			(xy 348.734136 -257.330042) (xy 348.707484 -257.376205) (xy 348.674251 -257.41788) (xy 348.635177 -257.454137)
			(xy 348.591136 -257.484166) (xy 348.543112 -257.507295) (xy 348.492176 -257.523008) (xy 348.439468 -257.530955)
			(xy 348.412816 -257.531362) (xy 348.386804 -257.530868) (xy 348.335338 -257.523258) (xy 348.285527 -257.508241)
			(xy 348.238431 -257.486137) (xy 348.216474 -257.47218) (xy 348.204783 -257.464967) (xy 348.178682 -257.456439)
			(xy 348.151253 -257.455172) (xy 348.124477 -257.461259) (xy 348.100291 -257.47426) (xy 348.080443 -257.493235)
			(xy 348.066367 -257.516812) (xy 348.059082 -257.543286) (xy 348.05874 -257.557016) (xy 348.05874 -257.650742)
			(xy 348.088712 -257.664204) (xy 348.113368 -257.675877) (xy 348.159112 -257.705596) (xy 348.199792 -257.74194)
			(xy 348.234457 -257.78406) (xy 348.262297 -257.830971) (xy 348.282661 -257.881578) (xy 348.295074 -257.934697)
			(xy 348.299245 -257.989088) (xy 348.297205 -258.015719) (xy 348.526852 -258.015719) (xy 348.526852 -257.962421)
			(xy 348.534795 -257.909717) (xy 348.550505 -257.858787) (xy 348.573631 -257.810766) (xy 348.603655 -257.766729)
			(xy 348.639907 -257.727658) (xy 348.681578 -257.694427) (xy 348.727736 -257.667778) (xy 348.77735 -257.648306)
			(xy 348.829312 -257.636446) (xy 348.882462 -257.632463) (xy 348.935612 -257.636446) (xy 348.987574 -257.648306)
			(xy 349.037188 -257.667778) (xy 349.083346 -257.694427) (xy 349.125017 -257.727658) (xy 349.161269 -257.766729)
			(xy 349.191293 -257.810766) (xy 349.214419 -257.858787) (xy 349.230129 -257.909717) (xy 349.238072 -257.962421)
			(xy 349.23857 -257.98907) (xy 349.238072 -258.015719) (xy 349.466652 -258.015719) (xy 349.466652 -257.962421)
			(xy 349.474595 -257.909717) (xy 349.490305 -257.858787) (xy 349.513431 -257.810766) (xy 349.543455 -257.766729)
			(xy 349.579707 -257.727658) (xy 349.621378 -257.694427) (xy 349.667536 -257.667778) (xy 349.71715 -257.648306)
			(xy 349.769112 -257.636446) (xy 349.822262 -257.632463) (xy 349.875412 -257.636446) (xy 349.927374 -257.648306)
			(xy 349.976988 -257.667778) (xy 350.023146 -257.694427) (xy 350.064817 -257.727658) (xy 350.101069 -257.766729)
			(xy 350.131093 -257.810766) (xy 350.154219 -257.858787) (xy 350.169929 -257.909717) (xy 350.177872 -257.962421)
			(xy 350.17837 -257.98907) (xy 350.177872 -258.015719) (xy 350.169929 -258.068423) (xy 350.154219 -258.119353)
			(xy 350.131093 -258.167374) (xy 350.101069 -258.211411) (xy 350.064817 -258.250482) (xy 350.023146 -258.283713)
			(xy 349.976988 -258.310362) (xy 349.927374 -258.329834) (xy 349.875412 -258.341694) (xy 349.822262 -258.345678)
			(xy 349.769112 -258.341694) (xy 349.71715 -258.329834) (xy 349.667536 -258.310362) (xy 349.621378 -258.283713)
			(xy 349.579707 -258.250482) (xy 349.543455 -258.211411) (xy 349.513431 -258.167374) (xy 349.490305 -258.119353)
			(xy 349.474595 -258.068423) (xy 349.466652 -258.015719) (xy 349.238072 -258.015719) (xy 349.230129 -258.068423)
			(xy 349.214419 -258.119353) (xy 349.191293 -258.167374) (xy 349.161269 -258.211411) (xy 349.125017 -258.250482)
			(xy 349.083346 -258.283713) (xy 349.037188 -258.310362) (xy 348.987574 -258.329834) (xy 348.935612 -258.341694)
			(xy 348.882462 -258.345678) (xy 348.829312 -258.341694) (xy 348.77735 -258.329834) (xy 348.727736 -258.310362)
			(xy 348.681578 -258.283713) (xy 348.639907 -258.250482) (xy 348.603655 -258.211411) (xy 348.573631 -258.167374)
			(xy 348.550505 -258.119353) (xy 348.534795 -258.068423) (xy 348.526852 -258.015719) (xy 348.297205 -258.015719)
			(xy 348.295078 -258.043478) (xy 348.282669 -258.096599) (xy 348.262308 -258.147207) (xy 348.234471 -258.19412)
			(xy 348.199809 -258.236242) (xy 348.159132 -258.272589) (xy 348.11339 -258.302311) (xy 348.088712 -258.313936)
			(xy 348.05874 -258.327398) (xy 348.05874 -258.421378) (xy 348.059196 -258.435093) (xy 348.066509 -258.46153)
			(xy 348.080588 -258.485071) (xy 348.100418 -258.504022) (xy 348.124574 -258.517019) (xy 348.151315 -258.523125)
			(xy 348.178718 -258.521902) (xy 348.204809 -258.513438) (xy 348.216474 -258.506214) (xy 348.238425 -258.492245)
			(xy 348.285521 -258.470135) (xy 348.335334 -258.455113) (xy 348.386802 -258.447501) (xy 348.412816 -258.447032)
			(xy 348.439462 -258.447531) (xy 348.492157 -258.455476) (xy 348.54308 -258.471186) (xy 348.591093 -258.494309)
			(xy 348.635123 -258.52433) (xy 348.674187 -258.560578) (xy 348.707413 -258.602244) (xy 348.734058 -258.648396)
			(xy 348.753527 -258.698003) (xy 348.765385 -258.749958) (xy 348.769367 -258.8031) (xy 348.767367 -258.829789)
			(xy 348.996752 -258.829789) (xy 348.996752 -258.776491) (xy 349.004695 -258.723787) (xy 349.020405 -258.672857)
			(xy 349.043531 -258.624836) (xy 349.073555 -258.580799) (xy 349.109807 -258.541728) (xy 349.151478 -258.508497)
			(xy 349.197636 -258.481848) (xy 349.24725 -258.462376) (xy 349.299212 -258.450516) (xy 349.352362 -258.446533)
			(xy 349.405512 -258.450516) (xy 349.457474 -258.462376) (xy 349.507088 -258.481848) (xy 349.553246 -258.508497)
			(xy 349.594917 -258.541728) (xy 349.631169 -258.580799) (xy 349.661193 -258.624836) (xy 349.684319 -258.672857)
			(xy 349.700029 -258.723787) (xy 349.707972 -258.776491) (xy 349.70847 -258.80314) (xy 349.707972 -258.829789)
			(xy 349.700029 -258.882493) (xy 349.684319 -258.933423) (xy 349.661193 -258.981444) (xy 349.631169 -259.025481)
			(xy 349.594917 -259.064552) (xy 349.553246 -259.097783) (xy 349.507088 -259.124432) (xy 349.457474 -259.143904)
			(xy 349.405512 -259.155764) (xy 349.352362 -259.159748) (xy 349.299212 -259.155764) (xy 349.24725 -259.143904)
			(xy 349.197636 -259.124432) (xy 349.151478 -259.097783) (xy 349.109807 -259.064552) (xy 349.073555 -259.025481)
			(xy 349.043531 -258.981444) (xy 349.020405 -258.933423) (xy 349.004695 -258.882493) (xy 348.996752 -258.829789)
			(xy 348.767367 -258.829789) (xy 348.765385 -258.856242) (xy 348.753527 -258.908197) (xy 348.734058 -258.957805)
			(xy 348.707413 -259.003956) (xy 348.674187 -259.045622) (xy 348.635123 -259.08187) (xy 348.591093 -259.111891)
			(xy 348.54308 -259.135014) (xy 348.492157 -259.150724) (xy 348.439461 -259.158669) (xy 348.412816 -259.159248)
			(xy 348.386804 -259.158754) (xy 348.335338 -259.151143) (xy 348.285527 -259.136126) (xy 348.238432 -259.114021)
			(xy 348.216474 -259.100066) (xy 348.204783 -259.092854) (xy 348.178681 -259.084326) (xy 348.151251 -259.083061)
			(xy 348.124475 -259.089148) (xy 348.100288 -259.102148) (xy 348.080438 -259.121122) (xy 348.066361 -259.144698)
			(xy 348.059072 -259.171172) (xy 348.05874 -259.184902) (xy 348.05874 -259.278628) (xy 348.088712 -259.29209)
			(xy 348.113369 -259.303763) (xy 348.159116 -259.333483) (xy 348.199797 -259.369827) (xy 348.234464 -259.411948)
			(xy 348.262306 -259.458861) (xy 348.282672 -259.509469) (xy 348.295086 -259.562589) (xy 348.299258 -259.616982)
			(xy 348.297218 -259.643605) (xy 348.526852 -259.643605) (xy 348.526852 -259.590307) (xy 348.534795 -259.537603)
			(xy 348.550505 -259.486673) (xy 348.573631 -259.438652) (xy 348.603655 -259.394615) (xy 348.639907 -259.355544)
			(xy 348.681578 -259.322313) (xy 348.727736 -259.295664) (xy 348.77735 -259.276192) (xy 348.829312 -259.264332)
			(xy 348.882462 -259.260349) (xy 348.935612 -259.264332) (xy 348.987574 -259.276192) (xy 349.037188 -259.295664)
			(xy 349.083346 -259.322313) (xy 349.125017 -259.355544) (xy 349.161269 -259.394615) (xy 349.191293 -259.438652)
			(xy 349.214419 -259.486673) (xy 349.230129 -259.537603) (xy 349.238072 -259.590307) (xy 349.23857 -259.616956)
			(xy 349.238072 -259.643605) (xy 349.230129 -259.696309) (xy 349.221863 -259.723107) (xy 350.450902 -259.723107)
			(xy 350.450902 -259.669809) (xy 350.458845 -259.617105) (xy 350.474555 -259.566175) (xy 350.497681 -259.518154)
			(xy 350.527705 -259.474117) (xy 350.563957 -259.435046) (xy 350.605628 -259.401815) (xy 350.651786 -259.375166)
			(xy 350.7014 -259.355694) (xy 350.753362 -259.343834) (xy 350.806512 -259.339851) (xy 350.859662 -259.343834)
			(xy 350.911624 -259.355694) (xy 350.961238 -259.375166) (xy 351.007396 -259.401815) (xy 351.049067 -259.435046)
			(xy 351.085319 -259.474117) (xy 351.115343 -259.518154) (xy 351.138469 -259.566175) (xy 351.154179 -259.617105)
			(xy 351.162122 -259.669809) (xy 351.16262 -259.696458) (xy 351.162122 -259.723107) (xy 351.154179 -259.775811)
			(xy 351.138469 -259.826741) (xy 351.115343 -259.874762) (xy 351.085319 -259.918799) (xy 351.049067 -259.95787)
			(xy 351.007396 -259.991101) (xy 350.961238 -260.01775) (xy 350.911624 -260.037222) (xy 350.859662 -260.049082)
			(xy 350.806512 -260.053066) (xy 350.753362 -260.049082) (xy 350.7014 -260.037222) (xy 350.651786 -260.01775)
			(xy 350.605628 -259.991101) (xy 350.563957 -259.95787) (xy 350.527705 -259.918799) (xy 350.497681 -259.874762)
			(xy 350.474555 -259.826741) (xy 350.458845 -259.775811) (xy 350.450902 -259.723107) (xy 349.221863 -259.723107)
			(xy 349.214419 -259.747239) (xy 349.191293 -259.79526) (xy 349.161269 -259.839297) (xy 349.125017 -259.878368)
			(xy 349.083346 -259.911599) (xy 349.037188 -259.938248) (xy 348.987574 -259.95772) (xy 348.935612 -259.96958)
			(xy 348.882462 -259.973564) (xy 348.829312 -259.96958) (xy 348.77735 -259.95772) (xy 348.727736 -259.938248)
			(xy 348.681578 -259.911599) (xy 348.639907 -259.878368) (xy 348.603655 -259.839297) (xy 348.573631 -259.79526)
			(xy 348.550505 -259.747239) (xy 348.534795 -259.696309) (xy 348.526852 -259.643605) (xy 348.297218 -259.643605)
			(xy 348.295091 -259.671375) (xy 348.282683 -259.724497) (xy 348.262322 -259.775107) (xy 348.234485 -259.822022)
			(xy 348.199822 -259.864147) (xy 348.159144 -259.900495) (xy 348.113401 -259.930219) (xy 348.088712 -259.941822)
			(xy 348.05874 -259.955284) (xy 348.05874 -260.04901) (xy 348.0592 -260.062721) (xy 348.066518 -260.089151)
			(xy 348.080598 -260.112684) (xy 348.100427 -260.131628) (xy 348.124578 -260.14462) (xy 348.151313 -260.150725)
			(xy 348.17871 -260.149504) (xy 348.204796 -260.141044) (xy 348.216474 -260.133846) (xy 348.238424 -260.119876)
			(xy 348.28552 -260.097764) (xy 348.335333 -260.082741) (xy 348.386802 -260.075128) (xy 348.412816 -260.074664)
			(xy 348.440799 -260.075214) (xy 348.496076 -260.083971) (xy 348.549303 -260.101267) (xy 348.599169 -260.126675)
			(xy 348.644446 -260.159571) (xy 348.684021 -260.199144) (xy 348.716919 -260.244421) (xy 348.742329 -260.294286)
			(xy 348.759626 -260.347512) (xy 348.768385 -260.402789) (xy 348.768924 -260.430772) (xy 348.768418 -260.458227)
			(xy 348.759994 -260.512487) (xy 348.743342 -260.564811) (xy 348.718855 -260.613959) (xy 348.687114 -260.658766)
			(xy 348.648872 -260.69817) (xy 348.605036 -260.731237) (xy 348.556642 -260.757183) (xy 348.530926 -260.766814)
			(xy 348.517256 -260.772156) (xy 348.493506 -260.78938) (xy 348.475623 -260.812638) (xy 348.465079 -260.840016)
			(xy 348.462743 -260.869261) (xy 348.468805 -260.897966) (xy 348.482767 -260.923769) (xy 348.492826 -260.934454)
			(xy 348.591124 -261.032752) (xy 348.627192 -260.99643) (xy 348.627446 -260.996176) (xy 348.647705 -260.976213)
			(xy 348.693388 -260.942336) (xy 348.743872 -260.916145) (xy 348.797875 -260.898304) (xy 348.854025 -260.889265)
			(xy 348.882462 -260.888734) (xy 348.908541 -260.889187) (xy 348.96014 -260.896793) (xy 349.010078 -260.911847)
			(xy 349.057284 -260.934027) (xy 349.100748 -260.962858) (xy 349.13954 -260.997723) (xy 349.172829 -261.037876)
			(xy 349.186754 -261.05993)
		)
		(stroke
			(width 0)
			(type solid)
		)
		(fill yes)
		(layer "In15.Cu")
		(net "PVCCD_HV_CPU0")
	)
	(gr_poly
		(pts
			(xy 462.938622 -58.140092) (xy 462.939797 -58.112262) (xy 462.949211 -58.057362) (xy 462.966496 -58.004411)
			(xy 462.991286 -57.95453) (xy 463.023057 -57.908778) (xy 463.041746 -57.888124) (xy 463.051817 -57.876591)
			(xy 463.065157 -57.849047) (xy 463.069738 -57.818787) (xy 463.065149 -57.788528) (xy 463.051802 -57.760987)
			(xy 463.041746 -57.74944) (xy 463.022476 -57.728114) (xy 462.989911 -57.680752) (xy 462.964821 -57.629041)
			(xy 462.947772 -57.574151) (xy 462.939151 -57.517325) (xy 462.939153 -57.459849) (xy 462.947778 -57.403023)
			(xy 462.96483 -57.348134) (xy 462.989924 -57.296425) (xy 463.022492 -57.249066) (xy 463.041746 -57.227724)
			(xy 463.051817 -57.216191) (xy 463.065157 -57.188647) (xy 463.069738 -57.158387) (xy 463.065149 -57.128128)
			(xy 463.051802 -57.100587) (xy 463.041746 -57.08904) (xy 463.02248 -57.067711) (xy 462.989923 -57.020346)
			(xy 462.964839 -56.968634) (xy 462.947796 -56.913744) (xy 462.939178 -56.856919) (xy 462.938622 -56.828182)
			(xy 462.939087 -56.800931) (xy 462.946846 -56.746983) (xy 462.962204 -56.694689) (xy 462.984848 -56.645113)
			(xy 463.014317 -56.599265) (xy 463.050011 -56.558077) (xy 463.091203 -56.522388) (xy 463.137056 -56.492925)
			(xy 463.186634 -56.470287) (xy 463.23893 -56.454936) (xy 463.292879 -56.447183) (xy 463.32013 -56.446674)
			(xy 463.349045 -56.44721) (xy 463.406212 -56.455943) (xy 463.461406 -56.473202) (xy 463.513363 -56.498594)
			(xy 463.560893 -56.531536) (xy 463.602908 -56.571274) (xy 463.62112 -56.59374) (xy 463.631017 -56.605545)
			(xy 463.656341 -56.623064) (xy 463.685734 -56.63224) (xy 463.716526 -56.63224) (xy 463.745919 -56.623064)
			(xy 463.771243 -56.605545) (xy 463.78114 -56.59374) (xy 463.799329 -56.571253) (xy 463.841344 -56.531508)
			(xy 463.888877 -56.498562) (xy 463.94084 -56.473169) (xy 463.99604 -56.455912) (xy 464.053212 -56.447186)
			(xy 464.08213 -56.446674) (xy 464.110868 -56.447198) (xy 464.167692 -56.455826) (xy 464.222578 -56.472882)
			(xy 464.274284 -56.49798) (xy 464.32164 -56.530552) (xy 464.342988 -56.549798) (xy 464.354522 -56.55987)
			(xy 464.382068 -56.573212) (xy 464.41233 -56.577797) (xy 464.442592 -56.573212) (xy 464.470138 -56.55987)
			(xy 464.481672 -56.549798) (xy 464.502999 -56.530528) (xy 464.550362 -56.497963) (xy 464.602073 -56.472872)
			(xy 464.656964 -56.455822) (xy 464.713791 -56.4472) (xy 464.771269 -56.4472) (xy 464.828096 -56.455822)
			(xy 464.882987 -56.472872) (xy 464.934698 -56.497963) (xy 464.982061 -56.530528) (xy 465.003388 -56.549798)
			(xy 465.014922 -56.55987) (xy 465.042468 -56.573212) (xy 465.07273 -56.577797) (xy 465.102992 -56.573212)
			(xy 465.130538 -56.55987) (xy 465.142072 -56.549798) (xy 465.163399 -56.530528) (xy 465.210762 -56.497963)
			(xy 465.262473 -56.472872) (xy 465.317364 -56.455822) (xy 465.374191 -56.4472) (xy 465.431669 -56.4472)
			(xy 465.488496 -56.455822) (xy 465.543387 -56.472872) (xy 465.595098 -56.497963) (xy 465.642461 -56.530528)
			(xy 465.663788 -56.549798) (xy 465.675322 -56.55987) (xy 465.702868 -56.573212) (xy 465.73313 -56.577797)
			(xy 465.763392 -56.573212) (xy 465.790938 -56.55987) (xy 465.802472 -56.549798) (xy 465.8238 -56.53053)
			(xy 465.871164 -56.497971) (xy 465.922876 -56.472885) (xy 465.977766 -56.45584) (xy 466.034592 -56.447223)
			(xy 466.06333 -56.446674) (xy 466.092245 -56.44721) (xy 466.149412 -56.455943) (xy 466.204606 -56.473202)
			(xy 466.256563 -56.498594) (xy 466.304093 -56.531536) (xy 466.346108 -56.571274) (xy 466.36432 -56.59374)
			(xy 466.374217 -56.605545) (xy 466.399541 -56.623064) (xy 466.428934 -56.63224) (xy 466.459726 -56.63224)
			(xy 466.489119 -56.623064) (xy 466.514443 -56.605545) (xy 466.52434 -56.59374) (xy 466.542529 -56.571253)
			(xy 466.584544 -56.531508) (xy 466.632077 -56.498562) (xy 466.68404 -56.473169) (xy 466.73924 -56.455912)
			(xy 466.796412 -56.447186) (xy 466.82533 -56.446674) (xy 466.85258 -56.447162) (xy 466.906526 -56.454922)
			(xy 466.958818 -56.470279) (xy 467.008393 -56.492922) (xy 467.05424 -56.522389) (xy 467.095429 -56.55808)
			(xy 467.131119 -56.599269) (xy 467.160584 -56.645118) (xy 467.183225 -56.694693) (xy 467.198581 -56.746986)
			(xy 467.206339 -56.800932) (xy 467.206838 -56.828182) (xy 467.206318 -56.856921) (xy 467.197697 -56.913749)
			(xy 467.180647 -56.96864) (xy 467.155553 -57.020352) (xy 467.122985 -57.067713) (xy 467.103714 -57.08904)
			(xy 467.093641 -57.100575) (xy 467.080296 -57.128122) (xy 467.075707 -57.158387) (xy 467.080288 -57.188652)
			(xy 467.093626 -57.216203) (xy 467.103714 -57.227724) (xy 467.122984 -57.249052) (xy 467.155549 -57.296415)
			(xy 467.180641 -57.348128) (xy 467.197691 -57.40302) (xy 467.206315 -57.459848) (xy 467.206317 -57.517326)
			(xy 467.197697 -57.574155) (xy 467.18065 -57.629047) (xy 467.155562 -57.680762) (xy 467.123001 -57.728128)
			(xy 467.103714 -57.74944) (xy 467.093641 -57.760975) (xy 467.080296 -57.788522) (xy 467.075707 -57.818787)
			(xy 467.080288 -57.849052) (xy 467.093626 -57.876603) (xy 467.103714 -57.888124) (xy 467.122403 -57.908782)
			(xy 467.154203 -57.954518) (xy 467.179008 -58.004395) (xy 467.196291 -58.057351) (xy 467.205683 -58.112259)
			(xy 467.206838 -58.140092) (xy 467.208108 -58.189622) (xy 468.411052 -58.189622) (xy 469.782398 -56.818276)
			(xy 469.782398 -45.335698) (xy 469.781928 -45.321508) (xy 469.774109 -45.294226) (xy 469.759078 -45.270154)
			(xy 469.737997 -45.251154) (xy 469.712497 -45.238696) (xy 469.684552 -45.233745) (xy 469.656325 -45.236684)
			(xy 469.642952 -45.241464) (xy 469.620336 -45.250124) (xy 469.573467 -45.262313) (xy 469.525434 -45.268484)
			(xy 469.50122 -45.268896) (xy 469.473967 -45.268434) (xy 469.420016 -45.26068) (xy 469.367717 -45.245326)
			(xy 469.318136 -45.222685) (xy 469.272282 -45.193219) (xy 469.231088 -45.157526) (xy 469.195393 -45.116334)
			(xy 469.165924 -45.070482) (xy 469.143281 -45.020902) (xy 469.127925 -44.968604) (xy 469.120167 -44.914653)
			(xy 469.120167 -44.860147) (xy 469.127925 -44.806196) (xy 469.143281 -44.753898) (xy 469.165924 -44.704318)
			(xy 469.195393 -44.658466) (xy 469.231088 -44.617274) (xy 469.272282 -44.581581) (xy 469.318136 -44.552115)
			(xy 469.367717 -44.529474) (xy 469.420016 -44.51412) (xy 469.473967 -44.506366) (xy 469.50122 -44.50588)
			(xy 469.525435 -44.506272) (xy 469.57347 -44.51244) (xy 469.620337 -44.524648) (xy 469.642952 -44.533312)
			(xy 469.656299 -44.538163) (xy 469.684536 -44.541077) (xy 469.712484 -44.536107) (xy 469.737986 -44.523637)
			(xy 469.75907 -44.504631) (xy 469.77411 -44.480556) (xy 469.781944 -44.453271) (xy 469.782398 -44.439078)
			(xy 469.782398 -37.892736) (xy 469.117934 -37.228272) (xy 463.226404 -37.228272) (xy 458.9907 -32.992568)
			(xy 458.9907 -16.484854) (xy 458.67574 -16.169894) (xy 454.764394 -16.169894) (xy 453.99452 -16.939768)
			(xy 453.99452 -18.558764) (xy 453.995048 -18.574149) (xy 454.004204 -18.603526) (xy 454.021695 -18.628841)
			(xy 454.045934 -18.647796) (xy 454.074719 -18.65867) (xy 454.105436 -18.660476) (xy 454.120504 -18.657316)
			(xy 454.143002 -18.652093) (xy 454.18885 -18.646491) (xy 454.211944 -18.64614) (xy 454.212452 -18.64614)
			(xy 454.239704 -18.6466) (xy 454.293653 -18.65435) (xy 454.34595 -18.6697) (xy 454.39553 -18.692337)
			(xy 454.441383 -18.7218) (xy 454.482577 -18.757489) (xy 454.518271 -18.798678) (xy 454.54774 -18.844528)
			(xy 454.570383 -18.894105) (xy 454.585739 -18.9464) (xy 454.593497 -19.000348) (xy 454.593497 -19.054852)
			(xy 454.585739 -19.1088) (xy 454.570383 -19.161095) (xy 454.54774 -19.210672) (xy 454.518271 -19.256522)
			(xy 454.482577 -19.297711) (xy 454.441383 -19.3334) (xy 454.39553 -19.362863) (xy 454.34595 -19.3855)
			(xy 454.293653 -19.40085) (xy 454.239704 -19.4086) (xy 454.212452 -19.409156) (xy 454.211944 -19.409156)
			(xy 454.18885 -19.408805) (xy 454.143002 -19.403205) (xy 454.120504 -19.39798) (xy 454.105443 -19.3948)
			(xy 454.07473 -19.396631) (xy 454.045953 -19.407517) (xy 454.021718 -19.426473) (xy 454.004221 -19.451781)
			(xy 453.995047 -19.481149) (xy 453.99452 -19.496532) (xy 453.99452 -21.14042) (xy 453.994924 -21.153783)
			(xy 454.001868 -21.179592) (xy 454.015274 -21.202713) (xy 454.034224 -21.221561) (xy 454.057417 -21.234842)
			(xy 454.083263 -21.241647) (xy 454.096628 -21.24202) (xy 454.09866 -21.24202) (xy 454.125913 -21.242481)
			(xy 454.179864 -21.250232) (xy 454.232163 -21.265584) (xy 454.281744 -21.288222) (xy 454.327599 -21.317687)
			(xy 454.368794 -21.353378) (xy 454.404489 -21.394569) (xy 454.433958 -21.44042) (xy 454.456602 -21.49)
			(xy 454.471959 -21.542297) (xy 454.479717 -21.596247) (xy 454.479717 -21.650753) (xy 454.471959 -21.704703)
			(xy 454.456602 -21.757) (xy 454.433958 -21.80658) (xy 454.404489 -21.852431) (xy 454.368794 -21.893622)
			(xy 454.327599 -21.929313) (xy 454.281744 -21.958778) (xy 454.232163 -21.981416) (xy 454.179864 -21.996768)
			(xy 454.125913 -22.004519) (xy 454.09866 -22.005036) (xy 454.096628 -22.005036) (xy 454.08326 -22.005368)
			(xy 454.057409 -22.012177) (xy 454.034214 -22.025465) (xy 454.015266 -22.044322) (xy 454.001865 -22.067452)
			(xy 453.994932 -22.09327) (xy 453.99452 -22.106636) (xy 453.99452 -33.553908) (xy 452.61784 -34.930588)
			(xy 436.018432 -34.930588) (xy 434.64734 -36.30168) (xy 435.098188 -36.30168) (xy 435.102261 -36.246021)
			(xy 435.114396 -36.191548) (xy 435.134332 -36.139422) (xy 435.161646 -36.090754) (xy 435.195754 -36.046582)
			(xy 435.235931 -36.007847) (xy 435.281319 -35.975375) (xy 435.330951 -35.949857) (xy 435.383771 -35.931838)
			(xy 435.43865 -35.921701) (xy 435.494421 -35.919663) (xy 435.549895 -35.925766) (xy 435.603888 -35.939882)
			(xy 435.655251 -35.961709) (xy 435.702889 -35.990782) (xy 435.745785 -36.026481) (xy 435.783027 -36.068045)
			(xy 435.813821 -36.114589) (xy 435.837509 -36.16512) (xy 435.853587 -36.218562) (xy 435.861713 -36.273776)
			(xy 435.862222 -36.30168) (xy 435.861713 -36.329584) (xy 435.853587 -36.384798) (xy 435.837509 -36.43824)
			(xy 435.813821 -36.488771) (xy 435.783027 -36.535315) (xy 435.768876 -36.551108) (xy 459.081122 -36.551108)
			(xy 459.085193 -36.495486) (xy 459.097319 -36.441049) (xy 459.117242 -36.388958) (xy 459.144538 -36.340323)
			(xy 459.178624 -36.29618) (xy 459.218773 -36.257471) (xy 459.264131 -36.22502) (xy 459.313731 -36.199519)
			(xy 459.366515 -36.181512) (xy 459.421358 -36.171382) (xy 459.477092 -36.169345) (xy 459.532529 -36.175445)
			(xy 459.586486 -36.189551) (xy 459.637815 -36.211363) (xy 459.685421 -36.240417) (xy 459.728289 -36.276092)
			(xy 459.765506 -36.317629) (xy 459.796279 -36.364142) (xy 459.819951 -36.414639) (xy 459.836019 -36.468046)
			(xy 459.844139 -36.523222) (xy 459.844648 -36.551108) (xy 459.844139 -36.578994) (xy 459.836019 -36.63417)
			(xy 459.819951 -36.687577) (xy 459.796279 -36.738074) (xy 459.765506 -36.784587) (xy 459.728289 -36.826124)
			(xy 459.685421 -36.861799) (xy 459.637815 -36.890853) (xy 459.586486 -36.912665) (xy 459.532529 -36.926771)
			(xy 459.477092 -36.932871) (xy 459.421358 -36.930834) (xy 459.366515 -36.920704) (xy 459.313731 -36.902697)
			(xy 459.264131 -36.877196) (xy 459.218773 -36.844745) (xy 459.178624 -36.806036) (xy 459.144538 -36.761893)
			(xy 459.117242 -36.713258) (xy 459.097319 -36.661167) (xy 459.085193 -36.60673) (xy 459.081122 -36.551108)
			(xy 435.768876 -36.551108) (xy 435.745785 -36.576879) (xy 435.702889 -36.612578) (xy 435.655251 -36.641651)
			(xy 435.603888 -36.663478) (xy 435.549895 -36.677594) (xy 435.494421 -36.683697) (xy 435.43865 -36.681659)
			(xy 435.383771 -36.671522) (xy 435.330951 -36.653503) (xy 435.281319 -36.627985) (xy 435.235931 -36.595513)
			(xy 435.195754 -36.556778) (xy 435.161646 -36.512606) (xy 435.134332 -36.463938) (xy 435.114396 -36.411812)
			(xy 435.102261 -36.357339) (xy 435.098188 -36.30168) (xy 434.64734 -36.30168) (xy 434.23586 -36.71316)
			(xy 434.23586 -37.82314) (xy 435.771288 -37.82314) (xy 435.775361 -37.767481) (xy 435.787496 -37.713008)
			(xy 435.807432 -37.660882) (xy 435.834746 -37.612214) (xy 435.868854 -37.568042) (xy 435.909031 -37.529307)
			(xy 435.954419 -37.496835) (xy 436.004051 -37.471317) (xy 436.056871 -37.453298) (xy 436.11175 -37.443161)
			(xy 436.167521 -37.441123) (xy 436.222995 -37.447226) (xy 436.276988 -37.461342) (xy 436.328351 -37.483169)
			(xy 436.375989 -37.512242) (xy 436.418885 -37.547941) (xy 436.456127 -37.589505) (xy 436.486921 -37.636049)
			(xy 436.510609 -37.68658) (xy 436.526687 -37.740022) (xy 436.534813 -37.795236) (xy 436.535322 -37.82314)
			(xy 436.534813 -37.851044) (xy 436.531742 -37.871908) (xy 437.429908 -37.871908) (xy 437.433981 -37.816249)
			(xy 437.446116 -37.761776) (xy 437.466052 -37.70965) (xy 437.493366 -37.660982) (xy 437.527474 -37.61681)
			(xy 437.567651 -37.578075) (xy 437.613039 -37.545603) (xy 437.662671 -37.520085) (xy 437.715491 -37.502066)
			(xy 437.77037 -37.491929) (xy 437.826141 -37.489891) (xy 437.881615 -37.495994) (xy 437.927346 -37.50795)
			(xy 443.729103 -37.50795) (xy 443.729103 -37.45345) (xy 443.73686 -37.399505) (xy 443.752214 -37.347213)
			(xy 443.774854 -37.297638) (xy 443.80432 -37.251791) (xy 443.84001 -37.210603) (xy 443.881199 -37.174914)
			(xy 443.927047 -37.14545) (xy 443.976622 -37.122811) (xy 444.028915 -37.107457) (xy 444.08286 -37.099703)
			(xy 444.11011 -37.09924) (xy 444.135871 -37.099647) (xy 444.186925 -37.106578) (xy 444.236583 -37.120311)
			(xy 444.283942 -37.140599) (xy 444.328143 -37.167071) (xy 444.368383 -37.199248) (xy 444.386462 -37.217604)
			(xy 444.39626 -37.227225) (xy 444.419813 -37.241321) (xy 444.446271 -37.248633) (xy 444.473719 -37.248633)
			(xy 444.500177 -37.241321) (xy 444.52373 -37.227225) (xy 444.533528 -37.217604) (xy 444.551605 -37.199246)
			(xy 444.591847 -37.167076) (xy 444.63605 -37.140609) (xy 444.68341 -37.120326) (xy 444.733067 -37.106594)
			(xy 444.78412 -37.099664) (xy 444.80988 -37.09924) (xy 444.837137 -37.099606) (xy 444.891097 -37.107361)
			(xy 444.943404 -37.122717) (xy 444.992993 -37.145362) (xy 445.038854 -37.174833) (xy 445.080055 -37.210531)
			(xy 445.115755 -37.25173) (xy 445.145229 -37.297589) (xy 445.167876 -37.347177) (xy 445.183235 -37.399483)
			(xy 445.190993 -37.453443) (xy 445.190993 -37.507957) (xy 445.183235 -37.561917) (xy 445.167876 -37.614223)
			(xy 445.145229 -37.663811) (xy 445.115755 -37.70967) (xy 445.080055 -37.750869) (xy 445.038854 -37.786567)
			(xy 444.992993 -37.816038) (xy 444.943404 -37.838683) (xy 444.891097 -37.854039) (xy 444.837137 -37.861794)
			(xy 444.80988 -37.862256) (xy 444.784121 -37.861791) (xy 444.73307 -37.854872) (xy 444.683413 -37.84115)
			(xy 444.636053 -37.820873) (xy 444.59185 -37.794411) (xy 444.551609 -37.762244) (xy 444.533528 -37.743892)
			(xy 444.523754 -37.734223) (xy 444.500213 -37.720044) (xy 444.473736 -37.712686) (xy 444.446254 -37.712686)
			(xy 444.419777 -37.720044) (xy 444.396236 -37.734223) (xy 444.386462 -37.743892) (xy 444.368389 -37.762254)
			(xy 444.328146 -37.794424) (xy 444.283942 -37.82089) (xy 444.236582 -37.841173) (xy 444.186924 -37.854904)
			(xy 444.135871 -37.861832) (xy 444.11011 -37.862256) (xy 444.08286 -37.861697) (xy 444.028915 -37.853943)
			(xy 443.976622 -37.838589) (xy 443.927047 -37.81595) (xy 443.881199 -37.786486) (xy 443.84001 -37.750797)
			(xy 443.80432 -37.709609) (xy 443.774854 -37.663762) (xy 443.752214 -37.614187) (xy 443.73686 -37.561895)
			(xy 443.729103 -37.50795) (xy 437.927346 -37.50795) (xy 437.935608 -37.51011) (xy 437.986971 -37.531937)
			(xy 438.034609 -37.56101) (xy 438.077505 -37.596709) (xy 438.114747 -37.638273) (xy 438.145541 -37.684817)
			(xy 438.169229 -37.735348) (xy 438.185307 -37.78879) (xy 438.193433 -37.844004) (xy 438.193942 -37.871908)
			(xy 438.193433 -37.899812) (xy 438.185307 -37.955026) (xy 438.169229 -38.008468) (xy 438.145541 -38.058999)
			(xy 438.114747 -38.105543) (xy 438.077505 -38.147107) (xy 438.034609 -38.182806) (xy 437.986971 -38.211879)
			(xy 437.935608 -38.233706) (xy 437.881615 -38.247822) (xy 437.826141 -38.253925) (xy 437.77037 -38.251887)
			(xy 437.715491 -38.24175) (xy 437.662671 -38.223731) (xy 437.613039 -38.198213) (xy 437.567651 -38.165741)
			(xy 437.527474 -38.127006) (xy 437.493366 -38.082834) (xy 437.466052 -38.034166) (xy 437.446116 -37.98204)
			(xy 437.433981 -37.927567) (xy 437.429908 -37.871908) (xy 436.531742 -37.871908) (xy 436.526687 -37.906258)
			(xy 436.510609 -37.9597) (xy 436.486921 -38.010231) (xy 436.456127 -38.056775) (xy 436.418885 -38.098339)
			(xy 436.375989 -38.134038) (xy 436.328351 -38.163111) (xy 436.276988 -38.184938) (xy 436.222995 -38.199054)
			(xy 436.167521 -38.205157) (xy 436.11175 -38.203119) (xy 436.056871 -38.192982) (xy 436.004051 -38.174963)
			(xy 435.954419 -38.149445) (xy 435.909031 -38.116973) (xy 435.868854 -38.078238) (xy 435.834746 -38.034066)
			(xy 435.807432 -37.985398) (xy 435.787496 -37.933272) (xy 435.775361 -37.878799) (xy 435.771288 -37.82314)
			(xy 434.23586 -37.82314) (xy 434.23586 -38.47315) (xy 439.233303 -38.47315) (xy 439.233303 -38.41865)
			(xy 439.24106 -38.364705) (xy 439.256414 -38.312413) (xy 439.279054 -38.262838) (xy 439.30852 -38.216991)
			(xy 439.34421 -38.175803) (xy 439.385399 -38.140114) (xy 439.431247 -38.11065) (xy 439.480822 -38.088011)
			(xy 439.533115 -38.072657) (xy 439.58706 -38.064903) (xy 439.61431 -38.06444) (xy 439.640981 -38.064852)
			(xy 439.693806 -38.072273) (xy 439.74508 -38.086982) (xy 439.793805 -38.108692) (xy 439.839029 -38.13698)
			(xy 439.87987 -38.171294) (xy 439.915532 -38.210965) (xy 439.930794 -38.232842) (xy 439.93915 -38.244325)
			(xy 439.960933 -38.26253) (xy 439.986881 -38.274046) (xy 440.014995 -38.277985) (xy 440.043109 -38.274046)
			(xy 440.069057 -38.26253) (xy 440.09084 -38.244325) (xy 440.099196 -38.232842) (xy 440.114455 -38.210965)
			(xy 440.150129 -38.171312) (xy 440.190976 -38.137011) (xy 440.236201 -38.108733) (xy 440.284923 -38.087026)
			(xy 440.336192 -38.072315) (xy 440.389011 -38.064886) (xy 440.41568 -38.06444) (xy 440.442937 -38.064806)
			(xy 440.496897 -38.072561) (xy 440.549204 -38.087917) (xy 440.598793 -38.110562) (xy 440.644654 -38.140033)
			(xy 440.685855 -38.175731) (xy 440.721555 -38.21693) (xy 440.751029 -38.262789) (xy 440.773676 -38.312377)
			(xy 440.789035 -38.364683) (xy 440.796793 -38.418643) (xy 440.796793 -38.473147) (xy 441.203126 -38.473147)
			(xy 441.203126 -38.418653) (xy 441.210881 -38.364714) (xy 441.226233 -38.312427) (xy 441.24887 -38.262858)
			(xy 441.278331 -38.217014) (xy 441.314016 -38.17583) (xy 441.355198 -38.140143) (xy 441.40104 -38.11068)
			(xy 441.450609 -38.08804) (xy 441.502894 -38.072685) (xy 441.556833 -38.064928) (xy 441.58408 -38.06444)
			(xy 441.611202 -38.06494) (xy 441.664901 -38.072614) (xy 441.716969 -38.087824) (xy 441.766354 -38.110263)
			(xy 441.812059 -38.139477) (xy 441.85316 -38.174876) (xy 441.871354 -38.194996) (xy 441.880514 -38.204826)
			(xy 441.902822 -38.219777) (xy 441.928263 -38.228381) (xy 441.955068 -38.230039) (xy 441.981375 -38.224636)
			(xy 442.005356 -38.212547) (xy 442.015626 -38.203886) (xy 442.036735 -38.185619) (xy 442.083271 -38.154791)
			(xy 442.133803 -38.131073) (xy 442.187252 -38.114974) (xy 442.242477 -38.106837) (xy 442.270388 -38.10635)
			(xy 442.297638 -38.106896) (xy 442.351585 -38.114651) (xy 442.403878 -38.130004) (xy 442.453454 -38.152644)
			(xy 442.499304 -38.182108) (xy 442.540494 -38.217798) (xy 442.576185 -38.258986) (xy 442.595458 -38.288976)
			(xy 452.814434 -38.288976) (xy 452.818505 -38.233354) (xy 452.830631 -38.178917) (xy 452.850554 -38.126826)
			(xy 452.87785 -38.078191) (xy 452.911936 -38.034048) (xy 452.952085 -37.995339) (xy 452.997443 -37.962888)
			(xy 453.047043 -37.937387) (xy 453.099827 -37.91938) (xy 453.15467 -37.90925) (xy 453.210404 -37.907213)
			(xy 453.265841 -37.913313) (xy 453.319798 -37.927419) (xy 453.371127 -37.949231) (xy 453.418733 -37.978285)
			(xy 453.461601 -38.01396) (xy 453.498818 -38.055497) (xy 453.529591 -38.10201) (xy 453.553263 -38.152507)
			(xy 453.569331 -38.205914) (xy 453.577451 -38.26109) (xy 453.57796 -38.288976) (xy 453.577451 -38.316862)
			(xy 453.569331 -38.372038) (xy 453.553263 -38.425445) (xy 453.529591 -38.475942) (xy 453.498818 -38.522455)
			(xy 453.461601 -38.563992) (xy 453.418733 -38.599667) (xy 453.371127 -38.628721) (xy 453.319798 -38.650533)
			(xy 453.265841 -38.664639) (xy 453.210404 -38.670739) (xy 453.15467 -38.668702) (xy 453.099827 -38.658572)
			(xy 453.047043 -38.640565) (xy 452.997443 -38.615064) (xy 452.952085 -38.582613) (xy 452.911936 -38.543904)
			(xy 452.87785 -38.499761) (xy 452.850554 -38.451126) (xy 452.830631 -38.399035) (xy 452.818505 -38.344598)
			(xy 452.814434 -38.288976) (xy 442.595458 -38.288976) (xy 442.60565 -38.304835) (xy 442.628291 -38.354411)
			(xy 442.643646 -38.406704) (xy 442.651403 -38.46065) (xy 442.651403 -38.51515) (xy 442.643646 -38.569096)
			(xy 442.628291 -38.621389) (xy 442.60565 -38.670965) (xy 442.576185 -38.716814) (xy 442.540494 -38.758002)
			(xy 442.499304 -38.793692) (xy 442.453454 -38.823156) (xy 442.403878 -38.845796) (xy 442.351585 -38.861149)
			(xy 442.297638 -38.868904) (xy 442.270388 -38.869366) (xy 442.243265 -38.868886) (xy 442.189566 -38.861208)
			(xy 442.137498 -38.845994) (xy 442.088112 -38.823551) (xy 442.042408 -38.794334) (xy 442.001307 -38.758932)
			(xy 441.983114 -38.73881) (xy 441.973985 -38.72895) (xy 441.951668 -38.713998) (xy 441.926219 -38.705398)
			(xy 441.899408 -38.703745) (xy 441.873096 -38.709156) (xy 441.849112 -38.721254) (xy 441.838842 -38.72992)
			(xy 441.817746 -38.748203) (xy 441.771207 -38.779029) (xy 441.720671 -38.802743) (xy 441.667219 -38.818838)
			(xy 441.611992 -38.826971) (xy 441.58408 -38.827456) (xy 441.556833 -38.826872) (xy 441.502894 -38.819115)
			(xy 441.450609 -38.80376) (xy 441.40104 -38.78112) (xy 441.355198 -38.751657) (xy 441.314016 -38.71597)
			(xy 441.278331 -38.674786) (xy 441.24887 -38.628942) (xy 441.226233 -38.579373) (xy 441.210881 -38.527086)
			(xy 441.203126 -38.473147) (xy 440.796793 -38.473147) (xy 440.796793 -38.473157) (xy 440.789035 -38.527117)
			(xy 440.773676 -38.579423) (xy 440.751029 -38.629011) (xy 440.721555 -38.67487) (xy 440.685855 -38.716069)
			(xy 440.644654 -38.751767) (xy 440.598793 -38.781238) (xy 440.549204 -38.803883) (xy 440.496897 -38.819239)
			(xy 440.442937 -38.826994) (xy 440.41568 -38.827456) (xy 440.389008 -38.827053) (xy 440.336184 -38.819631)
			(xy 440.284909 -38.804921) (xy 440.236184 -38.783209) (xy 440.19096 -38.754919) (xy 440.150119 -38.720604)
			(xy 440.114458 -38.680932) (xy 440.099196 -38.659054) (xy 440.090869 -38.647526) (xy 440.069108 -38.629236)
			(xy 440.043144 -38.617662) (xy 440.014995 -38.613701) (xy 439.986846 -38.617662) (xy 439.960882 -38.629236)
			(xy 439.939121 -38.647526) (xy 439.930794 -38.659054) (xy 439.91554 -38.680934) (xy 439.879866 -38.720588)
			(xy 439.839018 -38.754888) (xy 439.793792 -38.783167) (xy 439.745069 -38.804873) (xy 439.693799 -38.819583)
			(xy 439.64098 -38.827011) (xy 439.61431 -38.827456) (xy 439.58706 -38.826897) (xy 439.533115 -38.819143)
			(xy 439.480822 -38.803789) (xy 439.431247 -38.78115) (xy 439.385399 -38.751686) (xy 439.34421 -38.715997)
			(xy 439.30852 -38.674809) (xy 439.279054 -38.628962) (xy 439.256414 -38.579387) (xy 439.24106 -38.527095)
			(xy 439.233303 -38.47315) (xy 434.23586 -38.47315) (xy 434.23586 -38.903148) (xy 451.819262 -38.903148)
			(xy 451.823333 -38.847526) (xy 451.835459 -38.793089) (xy 451.855382 -38.740998) (xy 451.882678 -38.692363)
			(xy 451.916764 -38.64822) (xy 451.956913 -38.609511) (xy 452.002271 -38.57706) (xy 452.051871 -38.551559)
			(xy 452.104655 -38.533552) (xy 452.159498 -38.523422) (xy 452.215232 -38.521385) (xy 452.270669 -38.527485)
			(xy 452.324626 -38.541591) (xy 452.375955 -38.563403) (xy 452.423561 -38.592457) (xy 452.466429 -38.628132)
			(xy 452.503646 -38.669669) (xy 452.534419 -38.716182) (xy 452.558091 -38.766679) (xy 452.574159 -38.820086)
			(xy 452.582279 -38.875262) (xy 452.582788 -38.903148) (xy 452.582279 -38.931034) (xy 452.574159 -38.98621)
			(xy 452.558091 -39.039617) (xy 452.534419 -39.090114) (xy 452.511915 -39.124128) (xy 458.435202 -39.124128)
			(xy 458.435718 -39.095939) (xy 458.444032 -39.040178) (xy 458.460453 -38.986245) (xy 458.484625 -38.935312)
			(xy 458.516022 -38.888486) (xy 458.553962 -38.846785) (xy 458.597621 -38.811114) (xy 458.646049 -38.78225)
			(xy 458.67193 -38.771068) (xy 458.685302 -38.765069) (xy 458.708126 -38.746699) (xy 458.724798 -38.722608)
			(xy 458.73395 -38.694776) (xy 458.734829 -38.665491) (xy 458.727362 -38.637161) (xy 458.712164 -38.612113)
			(xy 458.701648 -38.601904) (xy 458.682278 -38.583713) (xy 458.648222 -38.542923) (xy 458.620152 -38.497806)
			(xy 458.598608 -38.449232) (xy 458.584008 -38.39814) (xy 458.576634 -38.345517) (xy 458.576172 -38.318948)
			(xy 458.576658 -38.291697) (xy 458.584414 -38.237749) (xy 458.599769 -38.185454) (xy 458.622411 -38.135877)
			(xy 458.651877 -38.090027) (xy 458.687568 -38.048836) (xy 458.728759 -38.013145) (xy 458.774609 -37.983679)
			(xy 458.824186 -37.961037) (xy 458.876481 -37.945682) (xy 458.930429 -37.937926) (xy 458.984931 -37.937926)
			(xy 459.038879 -37.945682) (xy 459.091174 -37.961037) (xy 459.140751 -37.983679) (xy 459.186601 -38.013145)
			(xy 459.227792 -38.048836) (xy 459.263483 -38.090027) (xy 459.292949 -38.135877) (xy 459.315591 -38.185454)
			(xy 459.330946 -38.237749) (xy 459.338702 -38.291697) (xy 459.339188 -38.318948) (xy 459.338658 -38.347136)
			(xy 459.330347 -38.402897) (xy 459.314149 -38.456108) (xy 467.29726 -38.456108) (xy 467.301331 -38.400486)
			(xy 467.313457 -38.346049) (xy 467.33338 -38.293958) (xy 467.360676 -38.245323) (xy 467.394762 -38.20118)
			(xy 467.434911 -38.162471) (xy 467.480269 -38.13002) (xy 467.529869 -38.104519) (xy 467.582653 -38.086512)
			(xy 467.637496 -38.076382) (xy 467.69323 -38.074345) (xy 467.748667 -38.080445) (xy 467.802624 -38.094551)
			(xy 467.853953 -38.116363) (xy 467.901559 -38.145417) (xy 467.944427 -38.181092) (xy 467.981644 -38.222629)
			(xy 468.012417 -38.269142) (xy 468.036089 -38.319639) (xy 468.052157 -38.373046) (xy 468.060277 -38.428222)
			(xy 468.060786 -38.456108) (xy 468.060277 -38.483994) (xy 468.052157 -38.53917) (xy 468.036089 -38.592577)
			(xy 468.012417 -38.643074) (xy 467.981644 -38.689587) (xy 467.944427 -38.731124) (xy 467.901559 -38.766799)
			(xy 467.853953 -38.795853) (xy 467.802624 -38.817665) (xy 467.748667 -38.831771) (xy 467.69323 -38.837871)
			(xy 467.637496 -38.835834) (xy 467.582653 -38.825704) (xy 467.529869 -38.807697) (xy 467.480269 -38.782196)
			(xy 467.434911 -38.749745) (xy 467.394762 -38.711036) (xy 467.360676 -38.666893) (xy 467.33338 -38.618258)
			(xy 467.313457 -38.566167) (xy 467.301331 -38.51173) (xy 467.29726 -38.456108) (xy 459.314149 -38.456108)
			(xy 459.313929 -38.456831) (xy 459.289759 -38.507764) (xy 459.258364 -38.55459) (xy 459.220426 -38.596291)
			(xy 459.176768 -38.631962) (xy 459.128341 -38.660826) (xy 459.10246 -38.672008) (xy 459.089105 -38.678039)
			(xy 459.066286 -38.696405) (xy 459.049615 -38.72049) (xy 459.040463 -38.748314) (xy 459.03958 -38.777592)
			(xy 459.04704 -38.805918) (xy 459.06223 -38.830963) (xy 459.072742 -38.841172) (xy 459.092147 -38.859327)
			(xy 459.1262 -38.900124) (xy 459.154266 -38.945249) (xy 459.175804 -38.993831) (xy 459.190396 -39.044929)
			(xy 459.197761 -39.097557) (xy 459.198218 -39.124128) (xy 459.197732 -39.151379) (xy 459.189976 -39.205327)
			(xy 459.174621 -39.257622) (xy 459.151979 -39.307199) (xy 459.122513 -39.353049) (xy 459.086822 -39.39424)
			(xy 459.045631 -39.429931) (xy 458.999781 -39.459397) (xy 458.953596 -39.48049) (xy 460.204818 -39.48049)
			(xy 460.208891 -39.424831) (xy 460.221026 -39.370358) (xy 460.240962 -39.318232) (xy 460.268276 -39.269564)
			(xy 460.302384 -39.225392) (xy 460.342561 -39.186657) (xy 460.387949 -39.154185) (xy 460.437581 -39.128667)
			(xy 460.490401 -39.110648) (xy 460.54528 -39.100511) (xy 460.601051 -39.098473) (xy 460.656525 -39.104576)
			(xy 460.710518 -39.118692) (xy 460.761881 -39.140519) (xy 460.809519 -39.169592) (xy 460.852415 -39.205291)
			(xy 460.889657 -39.246855) (xy 460.920451 -39.293399) (xy 460.944139 -39.34393) (xy 460.960217 -39.397372)
			(xy 460.968343 -39.452586) (xy 460.968852 -39.48049) (xy 460.968343 -39.508394) (xy 460.960217 -39.563608)
			(xy 460.944139 -39.61705) (xy 460.920451 -39.667581) (xy 460.889657 -39.714125) (xy 460.852415 -39.755689)
			(xy 460.851945 -39.75608) (xy 464.12734 -39.75608) (xy 464.131411 -39.700458) (xy 464.143537 -39.646021)
			(xy 464.16346 -39.59393) (xy 464.190756 -39.545295) (xy 464.224842 -39.501152) (xy 464.264991 -39.462443)
			(xy 464.310349 -39.429992) (xy 464.359949 -39.404491) (xy 464.412733 -39.386484) (xy 464.467576 -39.376354)
			(xy 464.52331 -39.374317) (xy 464.578747 -39.380417) (xy 464.632704 -39.394523) (xy 464.684033 -39.416335)
			(xy 464.731639 -39.445389) (xy 464.774507 -39.481064) (xy 464.811724 -39.522601) (xy 464.842497 -39.569114)
			(xy 464.866169 -39.619611) (xy 464.882237 -39.673018) (xy 464.890357 -39.728194) (xy 464.890866 -39.75608)
			(xy 464.890357 -39.783966) (xy 464.882237 -39.839142) (xy 464.866169 -39.892549) (xy 464.842497 -39.943046)
			(xy 464.811724 -39.989559) (xy 464.774507 -40.031096) (xy 464.731639 -40.066771) (xy 464.684033 -40.095825)
			(xy 464.632704 -40.117637) (xy 464.578747 -40.131743) (xy 464.52331 -40.137843) (xy 464.467576 -40.135806)
			(xy 464.412733 -40.125676) (xy 464.359949 -40.107669) (xy 464.310349 -40.082168) (xy 464.264991 -40.049717)
			(xy 464.224842 -40.011008) (xy 464.190756 -39.966865) (xy 464.16346 -39.91823) (xy 464.143537 -39.866139)
			(xy 464.131411 -39.811702) (xy 464.12734 -39.75608) (xy 460.851945 -39.75608) (xy 460.809519 -39.791388)
			(xy 460.761881 -39.820461) (xy 460.710518 -39.842288) (xy 460.656525 -39.856404) (xy 460.601051 -39.862507)
			(xy 460.54528 -39.860469) (xy 460.490401 -39.850332) (xy 460.437581 -39.832313) (xy 460.387949 -39.806795)
			(xy 460.342561 -39.774323) (xy 460.302384 -39.735588) (xy 460.268276 -39.691416) (xy 460.240962 -39.642748)
			(xy 460.221026 -39.590622) (xy 460.208891 -39.536149) (xy 460.204818 -39.48049) (xy 458.953596 -39.48049)
			(xy 458.950204 -39.482039) (xy 458.897909 -39.497394) (xy 458.843961 -39.50515) (xy 458.789459 -39.50515)
			(xy 458.735511 -39.497394) (xy 458.683216 -39.482039) (xy 458.633639 -39.459397) (xy 458.587789 -39.429931)
			(xy 458.546598 -39.39424) (xy 458.510907 -39.353049) (xy 458.481441 -39.307199) (xy 458.458799 -39.257622)
			(xy 458.443444 -39.205327) (xy 458.435688 -39.151379) (xy 458.435202 -39.124128) (xy 452.511915 -39.124128)
			(xy 452.503646 -39.136627) (xy 452.466429 -39.178164) (xy 452.423561 -39.213839) (xy 452.375955 -39.242893)
			(xy 452.324626 -39.264705) (xy 452.270669 -39.278811) (xy 452.215232 -39.284911) (xy 452.159498 -39.282874)
			(xy 452.104655 -39.272744) (xy 452.051871 -39.254737) (xy 452.002271 -39.229236) (xy 451.956913 -39.196785)
			(xy 451.916764 -39.158076) (xy 451.882678 -39.113933) (xy 451.855382 -39.065298) (xy 451.835459 -39.013207)
			(xy 451.823333 -38.95877) (xy 451.819262 -38.903148) (xy 434.23586 -38.903148) (xy 434.23586 -39.31666)
			(xy 435.019702 -39.31666) (xy 435.023773 -39.261038) (xy 435.035899 -39.206601) (xy 435.055822 -39.15451)
			(xy 435.083118 -39.105875) (xy 435.117204 -39.061732) (xy 435.157353 -39.023023) (xy 435.202711 -38.990572)
			(xy 435.252311 -38.965071) (xy 435.305095 -38.947064) (xy 435.359938 -38.936934) (xy 435.415672 -38.934897)
			(xy 435.471109 -38.940997) (xy 435.525066 -38.955103) (xy 435.576395 -38.976915) (xy 435.624001 -39.005969)
			(xy 435.666869 -39.041644) (xy 435.704086 -39.083181) (xy 435.734859 -39.129694) (xy 435.758531 -39.180191)
			(xy 435.774599 -39.233598) (xy 435.782719 -39.288774) (xy 435.783228 -39.31666) (xy 435.782719 -39.344546)
			(xy 435.774599 -39.399722) (xy 435.758531 -39.453129) (xy 435.734859 -39.503626) (xy 435.704086 -39.550139)
			(xy 435.666869 -39.591676) (xy 435.624001 -39.627351) (xy 435.576395 -39.656405) (xy 435.525066 -39.678217)
			(xy 435.471109 -39.692323) (xy 435.415672 -39.698423) (xy 435.359938 -39.696386) (xy 435.305095 -39.686256)
			(xy 435.252311 -39.668249) (xy 435.202711 -39.642748) (xy 435.157353 -39.610297) (xy 435.117204 -39.571588)
			(xy 435.083118 -39.527445) (xy 435.055822 -39.47881) (xy 435.035899 -39.426719) (xy 435.023773 -39.372282)
			(xy 435.019702 -39.31666) (xy 434.23586 -39.31666) (xy 434.23586 -40.352472) (xy 462.78876 -40.352472)
			(xy 462.792833 -40.296813) (xy 462.804968 -40.24234) (xy 462.824904 -40.190214) (xy 462.852218 -40.141546)
			(xy 462.886326 -40.097374) (xy 462.926503 -40.058639) (xy 462.971891 -40.026167) (xy 463.021523 -40.000649)
			(xy 463.074343 -39.98263) (xy 463.129222 -39.972493) (xy 463.184993 -39.970455) (xy 463.240467 -39.976558)
			(xy 463.29446 -39.990674) (xy 463.345823 -40.012501) (xy 463.393461 -40.041574) (xy 463.436357 -40.077273)
			(xy 463.473599 -40.118837) (xy 463.504393 -40.165381) (xy 463.528081 -40.215912) (xy 463.544159 -40.269354)
			(xy 463.552285 -40.324568) (xy 463.552794 -40.352472) (xy 463.552285 -40.380376) (xy 463.544159 -40.43559)
			(xy 463.528081 -40.489032) (xy 463.504393 -40.539563) (xy 463.473599 -40.586107) (xy 463.436357 -40.627671)
			(xy 463.393461 -40.66337) (xy 463.345823 -40.692443) (xy 463.29446 -40.71427) (xy 463.240467 -40.728386)
			(xy 463.184993 -40.734489) (xy 463.129222 -40.732451) (xy 463.074343 -40.722314) (xy 463.021523 -40.704295)
			(xy 462.971891 -40.678777) (xy 462.926503 -40.646305) (xy 462.886326 -40.60757) (xy 462.852218 -40.563398)
			(xy 462.824904 -40.51473) (xy 462.804968 -40.462604) (xy 462.792833 -40.408131) (xy 462.78876 -40.352472)
			(xy 434.23586 -40.352472) (xy 434.23586 -41.3893) (xy 436.378602 -41.3893) (xy 436.382673 -41.333678)
			(xy 436.394799 -41.279241) (xy 436.414722 -41.22715) (xy 436.442018 -41.178515) (xy 436.476104 -41.134372)
			(xy 436.516253 -41.095663) (xy 436.561611 -41.063212) (xy 436.611211 -41.037711) (xy 436.663995 -41.019704)
			(xy 436.718838 -41.009574) (xy 436.774572 -41.007537) (xy 436.816132 -41.01211) (xy 456.138278 -41.01211)
			(xy 456.142349 -40.956488) (xy 456.154475 -40.902051) (xy 456.174398 -40.84996) (xy 456.201694 -40.801325)
			(xy 456.23578 -40.757182) (xy 456.275929 -40.718473) (xy 456.321287 -40.686022) (xy 456.370887 -40.660521)
			(xy 456.423671 -40.642514) (xy 456.478514 -40.632384) (xy 456.534248 -40.630347) (xy 456.589685 -40.636447)
			(xy 456.643642 -40.650553) (xy 456.694971 -40.672365) (xy 456.742577 -40.701419) (xy 456.785445 -40.737094)
			(xy 456.822662 -40.778631) (xy 456.853435 -40.825144) (xy 456.877107 -40.875641) (xy 456.893175 -40.929048)
			(xy 456.901295 -40.984224) (xy 456.901804 -41.01211) (xy 456.901295 -41.039996) (xy 456.893175 -41.095172)
			(xy 456.877107 -41.148579) (xy 456.853435 -41.199076) (xy 456.822662 -41.245589) (xy 456.785445 -41.287126)
			(xy 456.742577 -41.322801) (xy 456.694971 -41.351855) (xy 456.643642 -41.373667) (xy 456.589685 -41.387773)
			(xy 456.534248 -41.393873) (xy 456.478514 -41.391836) (xy 456.423671 -41.381706) (xy 456.370887 -41.363699)
			(xy 456.321287 -41.338198) (xy 456.275929 -41.305747) (xy 456.23578 -41.267038) (xy 456.201694 -41.222895)
			(xy 456.174398 -41.17426) (xy 456.154475 -41.122169) (xy 456.142349 -41.067732) (xy 456.138278 -41.01211)
			(xy 436.816132 -41.01211) (xy 436.830009 -41.013637) (xy 436.883966 -41.027743) (xy 436.935295 -41.049555)
			(xy 436.982901 -41.078609) (xy 437.025769 -41.114284) (xy 437.062986 -41.155821) (xy 437.093759 -41.202334)
			(xy 437.117431 -41.252831) (xy 437.133499 -41.306238) (xy 437.141619 -41.361414) (xy 437.142128 -41.3893)
			(xy 437.141619 -41.417186) (xy 437.133499 -41.472362) (xy 437.117431 -41.525769) (xy 437.093759 -41.576266)
			(xy 437.062986 -41.622779) (xy 437.036406 -41.652444) (xy 459.570072 -41.652444) (xy 459.574143 -41.596822)
			(xy 459.586269 -41.542385) (xy 459.606192 -41.490294) (xy 459.633488 -41.441659) (xy 459.667574 -41.397516)
			(xy 459.707723 -41.358807) (xy 459.753081 -41.326356) (xy 459.802681 -41.300855) (xy 459.855465 -41.282848)
			(xy 459.910308 -41.272718) (xy 459.966042 -41.270681) (xy 460.021479 -41.276781) (xy 460.075436 -41.290887)
			(xy 460.126765 -41.312699) (xy 460.174371 -41.341753) (xy 460.217239 -41.377428) (xy 460.254456 -41.418965)
			(xy 460.285229 -41.465478) (xy 460.308901 -41.515975) (xy 460.324969 -41.569382) (xy 460.333089 -41.624558)
			(xy 460.333598 -41.652444) (xy 460.333089 -41.68033) (xy 460.324969 -41.735506) (xy 460.308901 -41.788913)
			(xy 460.285229 -41.83941) (xy 460.254456 -41.885923) (xy 460.217239 -41.92746) (xy 460.174371 -41.963135)
			(xy 460.126765 -41.992189) (xy 460.075436 -42.014001) (xy 460.021479 -42.028107) (xy 459.966042 -42.034207)
			(xy 459.910308 -42.03217) (xy 459.855465 -42.02204) (xy 459.802681 -42.004033) (xy 459.753081 -41.978532)
			(xy 459.707723 -41.946081) (xy 459.667574 -41.907372) (xy 459.633488 -41.863229) (xy 459.606192 -41.814594)
			(xy 459.586269 -41.762503) (xy 459.574143 -41.708066) (xy 459.570072 -41.652444) (xy 437.036406 -41.652444)
			(xy 437.025769 -41.664316) (xy 436.982901 -41.699991) (xy 436.935295 -41.729045) (xy 436.883966 -41.750857)
			(xy 436.830009 -41.764963) (xy 436.774572 -41.771063) (xy 436.718838 -41.769026) (xy 436.663995 -41.758896)
			(xy 436.611211 -41.740889) (xy 436.561611 -41.715388) (xy 436.516253 -41.682937) (xy 436.476104 -41.644228)
			(xy 436.442018 -41.600085) (xy 436.414722 -41.55145) (xy 436.394799 -41.499359) (xy 436.382673 -41.444922)
			(xy 436.378602 -41.3893) (xy 434.23586 -41.3893) (xy 434.23586 -42.202354) (xy 434.360066 -42.32656)
			(xy 435.799484 -42.32656) (xy 435.814281 -42.326058) (xy 435.842635 -42.317578) (xy 435.867367 -42.301324)
			(xy 435.886401 -42.278661) (xy 435.898137 -42.251493) (xy 435.901592 -42.222101) (xy 435.89956 -42.207434)
			(xy 435.896819 -42.190934) (xy 435.893893 -42.157611) (xy 435.893718 -42.140886) (xy 435.894204 -42.113635)
			(xy 435.90196 -42.059687) (xy 435.917315 -42.007392) (xy 435.939957 -41.957815) (xy 435.969423 -41.911965)
			(xy 436.005114 -41.870774) (xy 436.046305 -41.835083) (xy 436.092155 -41.805617) (xy 436.141732 -41.782975)
			(xy 436.194027 -41.76762) (xy 436.247975 -41.759864) (xy 436.302477 -41.759864) (xy 436.356425 -41.76762)
			(xy 436.40872 -41.782975) (xy 436.458297 -41.805617) (xy 436.504147 -41.835083) (xy 436.545338 -41.870774)
			(xy 436.581029 -41.911965) (xy 436.610495 -41.957815) (xy 436.633137 -42.007392) (xy 436.648492 -42.059687)
			(xy 436.656248 -42.113635) (xy 436.656734 -42.140886) (xy 436.656552 -42.157611) (xy 436.653623 -42.190932)
			(xy 436.650892 -42.207434) (xy 436.64883 -42.222102) (xy 436.649763 -42.23004) (xy 448.812664 -42.23004)
			(xy 448.816735 -42.174418) (xy 448.828861 -42.119981) (xy 448.848784 -42.06789) (xy 448.87608 -42.019255)
			(xy 448.910166 -41.975112) (xy 448.950315 -41.936403) (xy 448.995673 -41.903952) (xy 449.045273 -41.878451)
			(xy 449.098057 -41.860444) (xy 449.1529 -41.850314) (xy 449.208634 -41.848277) (xy 449.264071 -41.854377)
			(xy 449.318028 -41.868483) (xy 449.369357 -41.890295) (xy 449.416963 -41.919349) (xy 449.459831 -41.955024)
			(xy 449.497048 -41.996561) (xy 449.527821 -42.043074) (xy 449.551493 -42.093571) (xy 449.567561 -42.146978)
			(xy 449.575681 -42.202154) (xy 449.57619 -42.23004) (xy 449.575681 -42.257926) (xy 449.567561 -42.313102)
			(xy 449.551493 -42.366509) (xy 449.527821 -42.417006) (xy 449.497048 -42.463519) (xy 449.459831 -42.505056)
			(xy 449.444796 -42.517568) (xy 450.455282 -42.517568) (xy 450.459353 -42.461946) (xy 450.471479 -42.407509)
			(xy 450.491402 -42.355418) (xy 450.518698 -42.306783) (xy 450.552784 -42.26264) (xy 450.592933 -42.223931)
			(xy 450.638291 -42.19148) (xy 450.687891 -42.165979) (xy 450.740675 -42.147972) (xy 450.795518 -42.137842)
			(xy 450.851252 -42.135805) (xy 450.906689 -42.141905) (xy 450.960646 -42.156011) (xy 451.011975 -42.177823)
			(xy 451.059581 -42.206877) (xy 451.102449 -42.242552) (xy 451.139666 -42.284089) (xy 451.170439 -42.330602)
			(xy 451.194111 -42.381099) (xy 451.210179 -42.434506) (xy 451.218299 -42.489682) (xy 451.218808 -42.517568)
			(xy 451.218299 -42.545454) (xy 451.21231 -42.586148) (xy 463.36153 -42.586148) (xy 463.365601 -42.530526)
			(xy 463.377727 -42.476089) (xy 463.39765 -42.423998) (xy 463.424946 -42.375363) (xy 463.459032 -42.33122)
			(xy 463.499181 -42.292511) (xy 463.544539 -42.26006) (xy 463.594139 -42.234559) (xy 463.646923 -42.216552)
			(xy 463.701766 -42.206422) (xy 463.7575 -42.204385) (xy 463.812937 -42.210485) (xy 463.866894 -42.224591)
			(xy 463.918223 -42.246403) (xy 463.965829 -42.275457) (xy 463.969245 -42.2783) (xy 468.677496 -42.2783)
			(xy 468.681567 -42.222678) (xy 468.693693 -42.168241) (xy 468.713616 -42.11615) (xy 468.740912 -42.067515)
			(xy 468.774998 -42.023372) (xy 468.815147 -41.984663) (xy 468.860505 -41.952212) (xy 468.910105 -41.926711)
			(xy 468.962889 -41.908704) (xy 469.017732 -41.898574) (xy 469.073466 -41.896537) (xy 469.128903 -41.902637)
			(xy 469.18286 -41.916743) (xy 469.234189 -41.938555) (xy 469.281795 -41.967609) (xy 469.324663 -42.003284)
			(xy 469.36188 -42.044821) (xy 469.392653 -42.091334) (xy 469.416325 -42.141831) (xy 469.432393 -42.195238)
			(xy 469.440513 -42.250414) (xy 469.441022 -42.2783) (xy 469.440513 -42.306186) (xy 469.432393 -42.361362)
			(xy 469.416325 -42.414769) (xy 469.392653 -42.465266) (xy 469.36188 -42.511779) (xy 469.324663 -42.553316)
			(xy 469.281795 -42.588991) (xy 469.234189 -42.618045) (xy 469.18286 -42.639857) (xy 469.128903 -42.653963)
			(xy 469.073466 -42.660063) (xy 469.017732 -42.658026) (xy 468.962889 -42.647896) (xy 468.910105 -42.629889)
			(xy 468.860505 -42.604388) (xy 468.815147 -42.571937) (xy 468.774998 -42.533228) (xy 468.740912 -42.489085)
			(xy 468.713616 -42.44045) (xy 468.693693 -42.388359) (xy 468.681567 -42.333922) (xy 468.677496 -42.2783)
			(xy 463.969245 -42.2783) (xy 464.008697 -42.311132) (xy 464.045914 -42.352669) (xy 464.076687 -42.399182)
			(xy 464.100359 -42.449679) (xy 464.116427 -42.503086) (xy 464.124547 -42.558262) (xy 464.125056 -42.586148)
			(xy 464.124547 -42.614034) (xy 464.116427 -42.66921) (xy 464.100359 -42.722617) (xy 464.076687 -42.773114)
			(xy 464.045914 -42.819627) (xy 464.008697 -42.861164) (xy 463.965829 -42.896839) (xy 463.918223 -42.925893)
			(xy 463.866894 -42.947705) (xy 463.812937 -42.961811) (xy 463.7575 -42.967911) (xy 463.701766 -42.965874)
			(xy 463.646923 -42.955744) (xy 463.594139 -42.937737) (xy 463.544539 -42.912236) (xy 463.499181 -42.879785)
			(xy 463.459032 -42.841076) (xy 463.424946 -42.796933) (xy 463.39765 -42.748298) (xy 463.377727 -42.696207)
			(xy 463.365601 -42.64177) (xy 463.36153 -42.586148) (xy 451.21231 -42.586148) (xy 451.210179 -42.60063)
			(xy 451.194111 -42.654037) (xy 451.170439 -42.704534) (xy 451.139666 -42.751047) (xy 451.102449 -42.792584)
			(xy 451.059581 -42.828259) (xy 451.011975 -42.857313) (xy 450.960646 -42.879125) (xy 450.906689 -42.893231)
			(xy 450.851252 -42.899331) (xy 450.795518 -42.897294) (xy 450.740675 -42.887164) (xy 450.687891 -42.869157)
			(xy 450.638291 -42.843656) (xy 450.592933 -42.811205) (xy 450.552784 -42.772496) (xy 450.518698 -42.728353)
			(xy 450.491402 -42.679718) (xy 450.471479 -42.627627) (xy 450.459353 -42.57319) (xy 450.455282 -42.517568)
			(xy 449.444796 -42.517568) (xy 449.416963 -42.540731) (xy 449.369357 -42.569785) (xy 449.318028 -42.591597)
			(xy 449.264071 -42.605703) (xy 449.208634 -42.611803) (xy 449.1529 -42.609766) (xy 449.098057 -42.599636)
			(xy 449.045273 -42.581629) (xy 448.995673 -42.556128) (xy 448.950315 -42.523677) (xy 448.910166 -42.484968)
			(xy 448.87608 -42.440825) (xy 448.848784 -42.39219) (xy 448.828861 -42.340099) (xy 448.816735 -42.285662)
			(xy 448.812664 -42.23004) (xy 436.649763 -42.23004) (xy 436.652286 -42.251508) (xy 436.664025 -42.278689)
			(xy 436.683063 -42.301366) (xy 436.707801 -42.317634) (xy 436.736164 -42.326129) (xy 436.750968 -42.32656)
			(xy 440.2201 -42.32656) (xy 440.245083 -42.327071) (xy 440.294431 -42.334922) (xy 440.341946 -42.350384)
			(xy 440.386463 -42.373078) (xy 440.426889 -42.402447) (xy 440.44489 -42.419778) (xy 441.02147 -42.996358)
			(xy 441.038824 -43.014343) (xy 441.068225 -43.054755) (xy 441.090933 -43.099274) (xy 441.106387 -43.1468)
			(xy 441.114208 -43.19616) (xy 441.114688 -43.221148) (xy 441.114688 -43.647455) (xy 443.507037 -43.647455)
			(xy 443.507037 -43.592945) (xy 443.514795 -43.53899) (xy 443.530152 -43.486689) (xy 443.552797 -43.437105)
			(xy 443.582267 -43.391249) (xy 443.617964 -43.350054) (xy 443.659161 -43.314359) (xy 443.705018 -43.28489)
			(xy 443.754602 -43.262247) (xy 443.806904 -43.246892) (xy 443.860859 -43.239136) (xy 443.888114 -43.238674)
			(xy 443.9166 -43.239208) (xy 443.972939 -43.247682) (xy 444.027392 -43.26444) (xy 444.078747 -43.289109)
			(xy 444.125863 -43.321141) (xy 444.167691 -43.359823) (xy 444.203302 -43.404295) (xy 444.21806 -43.428666)
			(xy 444.225243 -43.440168) (xy 444.24457 -43.459179) (xy 444.268218 -43.472436) (xy 444.294519 -43.479005)
			(xy 444.321623 -43.478424) (xy 444.347619 -43.470733) (xy 444.370676 -43.456474) (xy 444.38917 -43.436652)
			(xy 444.39586 -43.424856) (xy 444.408301 -43.402089) (xy 444.438418 -43.359843) (xy 444.47398 -43.322067)
			(xy 444.514334 -43.289459) (xy 444.558733 -43.262619) (xy 444.60636 -43.242043) (xy 444.656336 -43.22811)
			(xy 444.707739 -43.221077) (xy 444.73368 -43.22064) (xy 444.760099 -43.221102) (xy 444.812433 -43.228384)
			(xy 444.863259 -43.242826) (xy 444.911604 -43.264149) (xy 444.956539 -43.291946) (xy 444.997204 -43.325683)
			(xy 445.03282 -43.364714) (xy 445.048132 -43.386248) (xy 445.056826 -43.397905) (xy 445.079389 -43.416226)
			(xy 445.106196 -43.427457) (xy 445.13508 -43.430691) (xy 445.163707 -43.425667) (xy 445.189764 -43.412791)
			(xy 445.211144 -43.393103) (xy 445.219074 -43.380914) (xy 445.233972 -43.357049) (xy 445.269622 -43.31353)
			(xy 445.311276 -43.275718) (xy 445.358033 -43.244435) (xy 445.408877 -43.220357) (xy 445.462705 -43.204009)
			(xy 445.518352 -43.195744) (xy 445.54648 -43.19524) (xy 445.573737 -43.195606) (xy 445.627697 -43.203361)
			(xy 445.680004 -43.218717) (xy 445.729593 -43.241362) (xy 445.775454 -43.270833) (xy 445.816655 -43.306531)
			(xy 445.852355 -43.34773) (xy 445.881829 -43.393589) (xy 445.904476 -43.443177) (xy 445.919835 -43.495483)
			(xy 445.927593 -43.549443) (xy 445.927593 -43.603957) (xy 445.919835 -43.657917) (xy 445.904476 -43.710223)
			(xy 445.881829 -43.759811) (xy 445.852355 -43.80567) (xy 445.816655 -43.846869) (xy 445.775454 -43.882567)
			(xy 445.729593 -43.912038) (xy 445.680004 -43.934683) (xy 445.627697 -43.950039) (xy 445.573737 -43.957794)
			(xy 445.54648 -43.958256) (xy 445.52006 -43.957826) (xy 445.467724 -43.950538) (xy 445.416897 -43.936091)
			(xy 445.368553 -43.914763) (xy 445.323618 -43.886961) (xy 445.282953 -43.853219) (xy 445.24734 -43.814184)
			(xy 445.232028 -43.792648) (xy 445.223383 -43.780951) (xy 445.200809 -43.76263) (xy 445.173991 -43.751402)
			(xy 445.145097 -43.748173) (xy 445.116462 -43.753204) (xy 445.0904 -43.76609) (xy 445.069016 -43.785788)
			(xy 445.061086 -43.797982) (xy 445.046214 -43.821864) (xy 445.01056 -43.865384) (xy 444.968901 -43.903194)
			(xy 444.92214 -43.934476) (xy 444.871292 -43.95855) (xy 444.817459 -43.974895) (xy 444.76181 -43.983155)
			(xy 444.73368 -43.983656) (xy 444.705194 -43.983112) (xy 444.648856 -43.974638) (xy 444.594405 -43.95788)
			(xy 444.54305 -43.933213) (xy 444.495935 -43.901183) (xy 444.454106 -43.862503) (xy 444.418493 -43.818034)
			(xy 444.403734 -43.793664) (xy 444.396562 -43.782152) (xy 444.377235 -43.763136) (xy 444.353585 -43.749874)
			(xy 444.32728 -43.743303) (xy 444.300172 -43.743886) (xy 444.274173 -43.75158) (xy 444.251115 -43.765845)
			(xy 444.232622 -43.785674) (xy 444.225934 -43.797474) (xy 444.213467 -43.820227) (xy 444.183358 -43.862476)
			(xy 444.1478 -43.900254) (xy 444.107451 -43.932866) (xy 444.063054 -43.959708) (xy 444.01543 -43.980286)
			(xy 443.965456 -43.99422) (xy 443.914054 -44.001253) (xy 443.888114 -44.00169) (xy 443.860859 -44.001264)
			(xy 443.806904 -43.993508) (xy 443.754602 -43.978153) (xy 443.705018 -43.95551) (xy 443.659161 -43.926041)
			(xy 443.617964 -43.890346) (xy 443.582267 -43.849151) (xy 443.552797 -43.803295) (xy 443.530152 -43.753711)
			(xy 443.514795 -43.70141) (xy 443.507037 -43.647455) (xy 441.114688 -43.647455) (xy 441.114688 -44.343066)
			(xy 441.11672 -44.345098) (xy 448.512182 -44.345098) (xy 448.516253 -44.289476) (xy 448.528379 -44.235039)
			(xy 448.548302 -44.182948) (xy 448.575598 -44.134313) (xy 448.609684 -44.09017) (xy 448.649833 -44.051461)
			(xy 448.695191 -44.01901) (xy 448.744791 -43.993509) (xy 448.797575 -43.975502) (xy 448.852418 -43.965372)
			(xy 448.908152 -43.963335) (xy 448.963589 -43.969435) (xy 449.017546 -43.983541) (xy 449.068875 -44.005353)
			(xy 449.116481 -44.034407) (xy 449.159349 -44.070082) (xy 449.196566 -44.111619) (xy 449.218102 -44.14417)
			(xy 451.109015 -44.14417) (xy 451.116769 -44.090213) (xy 451.132124 -44.037908) (xy 451.154765 -43.988321)
			(xy 451.184234 -43.942461) (xy 451.219929 -43.901262) (xy 451.261124 -43.865561) (xy 451.306981 -43.836088)
			(xy 451.356565 -43.81344) (xy 451.408868 -43.798079) (xy 451.462824 -43.790318) (xy 451.49008 -43.789854)
			(xy 451.510908 -43.790362) (xy 451.526097 -43.790584) (xy 451.555559 -43.783265) (xy 451.581564 -43.767602)
			(xy 451.601809 -43.744981) (xy 451.614503 -43.717405) (xy 451.618523 -43.687315) (xy 451.616572 -43.672252)
			(xy 451.614192 -43.656933) (xy 451.611652 -43.626032) (xy 451.611492 -43.61053) (xy 451.611492 -43.609768)
			(xy 451.612012 -43.58252) (xy 451.619773 -43.528578) (xy 451.63513 -43.47629) (xy 451.657773 -43.426719)
			(xy 451.687239 -43.380876) (xy 451.72293 -43.339692) (xy 451.764119 -43.304007) (xy 451.809966 -43.274547)
			(xy 451.85954 -43.251912) (xy 451.91183 -43.236561) (xy 451.965773 -43.228809) (xy 452.02027 -43.228812)
			(xy 452.074212 -43.23657) (xy 452.1265 -43.251926) (xy 452.176071 -43.274568) (xy 452.221915 -43.304033)
			(xy 452.2631 -43.339723) (xy 452.298786 -43.38091) (xy 452.328248 -43.426757) (xy 452.350885 -43.47633)
			(xy 452.366237 -43.52862) (xy 452.373991 -43.582562) (xy 452.373989 -43.637059) (xy 452.366232 -43.691001)
			(xy 452.350877 -43.74329) (xy 452.328237 -43.792862) (xy 452.298773 -43.838707) (xy 452.263085 -43.879892)
			(xy 452.221898 -43.91558) (xy 452.176052 -43.945043) (xy 452.12648 -43.967681) (xy 452.074191 -43.983034)
			(xy 452.020248 -43.99079) (xy 451.993 -43.991276) (xy 451.972172 -43.990768) (xy 451.956981 -43.990493)
			(xy 451.927512 -43.99782) (xy 451.901504 -44.013493) (xy 451.881258 -44.036125) (xy 451.868566 -44.063711)
			(xy 451.865829 -44.08424) (xy 464.920582 -44.08424) (xy 464.924653 -44.028618) (xy 464.936779 -43.974181)
			(xy 464.956702 -43.92209) (xy 464.983998 -43.873455) (xy 465.018084 -43.829312) (xy 465.058233 -43.790603)
			(xy 465.103591 -43.758152) (xy 465.153191 -43.732651) (xy 465.205975 -43.714644) (xy 465.260818 -43.704514)
			(xy 465.316552 -43.702477) (xy 465.371989 -43.708577) (xy 465.425946 -43.722683) (xy 465.477275 -43.744495)
			(xy 465.524881 -43.773549) (xy 465.567749 -43.809224) (xy 465.604966 -43.850761) (xy 465.635739 -43.897274)
			(xy 465.659411 -43.947771) (xy 465.675479 -44.001178) (xy 465.683599 -44.056354) (xy 465.684108 -44.08424)
			(xy 465.683599 -44.112126) (xy 465.675479 -44.167302) (xy 465.659411 -44.220709) (xy 465.635739 -44.271206)
			(xy 465.604966 -44.317719) (xy 465.567749 -44.359256) (xy 465.524881 -44.394931) (xy 465.477275 -44.423985)
			(xy 465.425946 -44.445797) (xy 465.371989 -44.459903) (xy 465.316552 -44.466003) (xy 465.260818 -44.463966)
			(xy 465.205975 -44.453836) (xy 465.153191 -44.435829) (xy 465.103591 -44.410328) (xy 465.058233 -44.377877)
			(xy 465.018084 -44.339168) (xy 464.983998 -44.295025) (xy 464.956702 -44.24639) (xy 464.936779 -44.194299)
			(xy 464.924653 -44.139862) (xy 464.920582 -44.08424) (xy 451.865829 -44.08424) (xy 451.864553 -44.093811)
			(xy 451.866508 -44.108878) (xy 451.86888 -44.124198) (xy 451.871426 -44.155098) (xy 451.871588 -44.1706)
			(xy 451.871588 -44.171362) (xy 451.871186 -44.198618) (xy 451.863433 -44.252576) (xy 451.848081 -44.304881)
			(xy 451.82544 -44.354468) (xy 451.795973 -44.400329) (xy 451.76028 -44.44153) (xy 451.719086 -44.477231)
			(xy 451.67323 -44.506707) (xy 451.623646 -44.529356) (xy 451.571344 -44.544718) (xy 451.517388 -44.552481)
			(xy 451.462876 -44.552485) (xy 451.408919 -44.544732) (xy 451.356614 -44.529378) (xy 451.307026 -44.506737)
			(xy 451.261166 -44.47727) (xy 451.219966 -44.441575) (xy 451.184265 -44.400381) (xy 451.15479 -44.354525)
			(xy 451.132142 -44.304941) (xy 451.11678 -44.252638) (xy 451.109019 -44.198682) (xy 451.109015 -44.14417)
			(xy 449.218102 -44.14417) (xy 449.227339 -44.158132) (xy 449.251011 -44.208629) (xy 449.267079 -44.262036)
			(xy 449.275199 -44.317212) (xy 449.275708 -44.345098) (xy 449.275199 -44.372984) (xy 449.267079 -44.42816)
			(xy 449.251011 -44.481567) (xy 449.227339 -44.532064) (xy 449.196566 -44.578577) (xy 449.159349 -44.620114)
			(xy 449.116481 -44.655789) (xy 449.068875 -44.684843) (xy 449.017546 -44.706655) (xy 448.963589 -44.720761)
			(xy 448.908152 -44.726861) (xy 448.852418 -44.724824) (xy 448.797575 -44.714694) (xy 448.744791 -44.696687)
			(xy 448.695191 -44.671186) (xy 448.649833 -44.638735) (xy 448.609684 -44.600026) (xy 448.575598 -44.555883)
			(xy 448.548302 -44.507248) (xy 448.528379 -44.455157) (xy 448.516253 -44.40072) (xy 448.512182 -44.345098)
			(xy 441.11672 -44.345098) (xy 441.392564 -44.620942) (xy 441.406534 -44.624498) (xy 441.433942 -44.631592)
			(xy 441.486444 -44.652775) (xy 441.535233 -44.681492) (xy 441.579237 -44.717111) (xy 441.617487 -44.758849)
			(xy 441.649142 -44.805786) (xy 441.673504 -44.85689) (xy 441.690037 -44.911035) (xy 441.698378 -44.967031)
			(xy 441.698888 -44.995338) (xy 441.698399 -45.022587) (xy 441.690638 -45.076529) (xy 441.67528 -45.128818)
			(xy 441.652636 -45.178389) (xy 441.623168 -45.224234) (xy 441.587477 -45.265418) (xy 441.546287 -45.301103)
			(xy 441.500439 -45.330564) (xy 441.450864 -45.3532) (xy 441.398573 -45.36855) (xy 441.344629 -45.376303)
			(xy 441.31738 -45.376846) (xy 441.289085 -45.376338) (xy 441.233116 -45.367989) (xy 441.178994 -45.351463)
			(xy 441.127907 -45.327123) (xy 441.080977 -45.295502) (xy 441.039234 -45.257294) (xy 441.003593 -45.213339)
			(xy 440.974838 -45.164601) (xy 440.953598 -45.11215) (xy 440.94654 -45.084746) (xy 440.94654 -45.084492)
			(xy 440.942984 -45.070522) (xy 440.57189 -44.699428) (xy 440.554539 -44.681442) (xy 440.525143 -44.641028)
			(xy 440.50244 -44.596509) (xy 440.48699 -44.548984) (xy 440.479173 -44.499625) (xy 440.478672 -44.474638)
			(xy 440.478672 -43.35272) (xy 440.088528 -42.962576) (xy 439.46953 -42.962576) (xy 439.454792 -42.963054)
			(xy 439.426537 -42.971447) (xy 439.401861 -42.987568) (xy 439.382825 -43.010072) (xy 439.37102 -43.03708)
			(xy 439.36743 -43.066335) (xy 439.369454 -43.08094) (xy 439.371938 -43.096634) (xy 439.374611 -43.128298)
			(xy 439.374788 -43.144186) (xy 439.374788 -43.144948) (xy 439.37427 -43.173251) (xy 439.365898 -43.229236)
			(xy 439.349345 -43.283369) (xy 439.324975 -43.334461) (xy 439.293322 -43.381392) (xy 439.255082 -43.42313)
			(xy 439.211094 -43.458759) (xy 439.162324 -43.487497) (xy 439.109843 -43.508712) (xy 439.082434 -43.515788)
			(xy 439.068464 -43.519344) (xy 439.01233 -43.575478) (xy 438.994345 -43.592831) (xy 438.953932 -43.622229)
			(xy 438.909413 -43.644935) (xy 438.861887 -43.660388) (xy 438.812528 -43.668206) (xy 438.78754 -43.668696)
			(xy 434.23586 -43.668696) (xy 434.23586 -44.147994) (xy 434.530246 -44.44238) (xy 435.807102 -44.44238)
			(xy 435.811173 -44.386758) (xy 435.823299 -44.332321) (xy 435.843222 -44.28023) (xy 435.870518 -44.231595)
			(xy 435.904604 -44.187452) (xy 435.944753 -44.148743) (xy 435.990111 -44.116292) (xy 436.039711 -44.090791)
			(xy 436.092495 -44.072784) (xy 436.147338 -44.062654) (xy 436.203072 -44.060617) (xy 436.258509 -44.066717)
			(xy 436.312466 -44.080823) (xy 436.363795 -44.102635) (xy 436.411401 -44.131689) (xy 436.454269 -44.167364)
			(xy 436.491486 -44.208901) (xy 436.522259 -44.255414) (xy 436.545931 -44.305911) (xy 436.561999 -44.359318)
			(xy 436.570119 -44.414494) (xy 436.570628 -44.44238) (xy 436.570119 -44.470266) (xy 436.561999 -44.525442)
			(xy 436.545931 -44.578849) (xy 436.522259 -44.629346) (xy 436.491486 -44.675859) (xy 436.454269 -44.717396)
			(xy 436.411401 -44.753071) (xy 436.363795 -44.782125) (xy 436.312466 -44.803937) (xy 436.258509 -44.818043)
			(xy 436.203072 -44.824143) (xy 436.147338 -44.822106) (xy 436.092495 -44.811976) (xy 436.039711 -44.793969)
			(xy 435.990111 -44.768468) (xy 435.944753 -44.736017) (xy 435.904604 -44.697308) (xy 435.870518 -44.653165)
			(xy 435.843222 -44.60453) (xy 435.823299 -44.552439) (xy 435.811173 -44.498002) (xy 435.807102 -44.44238)
			(xy 434.530246 -44.44238) (xy 436.605172 -46.517306) (xy 440.994544 -46.517306) (xy 440.998617 -46.461647)
			(xy 441.010752 -46.407174) (xy 441.030688 -46.355048) (xy 441.058002 -46.30638) (xy 441.09211 -46.262208)
			(xy 441.132287 -46.223473) (xy 441.177675 -46.191001) (xy 441.227307 -46.165483) (xy 441.280127 -46.147464)
			(xy 441.335006 -46.137327) (xy 441.390777 -46.135289) (xy 441.446251 -46.141392) (xy 441.500244 -46.155508)
			(xy 441.551607 -46.177335) (xy 441.599245 -46.206408) (xy 441.642141 -46.242107) (xy 441.679383 -46.283671)
			(xy 441.68994 -46.299628) (xy 448.136772 -46.299628) (xy 448.13726 -46.271631) (xy 448.145449 -46.216238)
			(xy 448.161639 -46.162635) (xy 448.185485 -46.111971) (xy 448.216474 -46.065333) (xy 448.253943 -46.023721)
			(xy 448.275202 -46.005496) (xy 448.286212 -45.995817) (xy 448.302594 -45.971518) (xy 448.311411 -45.94357)
			(xy 448.311938 -45.91427) (xy 448.304132 -45.886023) (xy 448.288634 -45.861151) (xy 448.277996 -45.851064)
			(xy 448.258184 -45.832867) (xy 448.223324 -45.791898) (xy 448.194566 -45.746438) (xy 448.17248 -45.697388)
			(xy 448.157505 -45.645722) (xy 448.149938 -45.592464) (xy 448.149472 -45.565568) (xy 448.149958 -45.538317)
			(xy 448.157714 -45.484369) (xy 448.173069 -45.432074) (xy 448.195711 -45.382497) (xy 448.225177 -45.336647)
			(xy 448.260868 -45.295456) (xy 448.302059 -45.259765) (xy 448.347909 -45.230299) (xy 448.397486 -45.207657)
			(xy 448.449781 -45.192302) (xy 448.503729 -45.184546) (xy 448.558231 -45.184546) (xy 448.612179 -45.192302)
			(xy 448.664474 -45.207657) (xy 448.714051 -45.230299) (xy 448.759901 -45.259765) (xy 448.801092 -45.295456)
			(xy 448.836783 -45.336647) (xy 448.84 -45.341653) (xy 451.10904 -45.341653) (xy 451.10904 -45.287147)
			(xy 451.116797 -45.233196) (xy 451.132152 -45.180897) (xy 451.154794 -45.131316) (xy 451.184262 -45.085462)
			(xy 451.219954 -45.044269) (xy 451.261146 -45.008574) (xy 451.306999 -44.979104) (xy 451.356578 -44.956459)
			(xy 451.408876 -44.941101) (xy 451.462827 -44.933341) (xy 451.49008 -44.932854) (xy 451.518399 -44.933351)
			(xy 451.574414 -44.941729) (xy 451.628573 -44.958304) (xy 451.679683 -44.98271) (xy 451.70344 -44.998132)
			(xy 451.715975 -45.006014) (xy 451.74425 -45.014774) (xy 451.77385 -45.015081) (xy 451.802301 -45.006909)
			(xy 451.827226 -44.990941) (xy 451.846542 -44.968511) (xy 451.853046 -44.955206) (xy 451.864625 -44.930321)
			(xy 451.893972 -44.883939) (xy 451.929664 -44.842242) (xy 451.970964 -44.806092) (xy 452.01702 -44.776236)
			(xy 452.066881 -44.75329) (xy 452.119515 -44.737728) (xy 452.173837 -44.729872) (xy 452.20128 -44.7294)
			(xy 452.220855 -44.729693) (xy 452.259793 -44.733761) (xy 452.279004 -44.737528) (xy 452.293033 -44.739944)
			(xy 452.32141 -44.737831) (xy 452.348106 -44.727979) (xy 452.371054 -44.711154) (xy 452.388477 -44.688656)
			(xy 452.399026 -44.662228) (xy 452.400924 -44.64812) (xy 452.404191 -44.620263) (xy 452.417964 -44.56589)
			(xy 452.439551 -44.514121) (xy 452.468489 -44.466072) (xy 452.504152 -44.42278) (xy 452.545772 -44.385178)
			(xy 452.59245 -44.354078) (xy 452.64318 -44.33015) (xy 452.696868 -44.31391) (xy 452.752355 -44.305709)
			(xy 452.7804 -44.30522) (xy 452.807653 -44.30565) (xy 452.861605 -44.313407) (xy 452.913904 -44.328763)
			(xy 452.963484 -44.351406) (xy 453.009338 -44.380874) (xy 453.050531 -44.416569) (xy 453.086226 -44.457762)
			(xy 453.115694 -44.503616) (xy 453.138337 -44.553196) (xy 453.153693 -44.605495) (xy 453.16145 -44.659447)
			(xy 453.16145 -44.713953) (xy 453.153693 -44.767905) (xy 453.138337 -44.820204) (xy 453.115694 -44.869784)
			(xy 453.086226 -44.915638) (xy 453.050531 -44.956831) (xy 453.009338 -44.992526) (xy 452.963484 -45.021994)
			(xy 452.960673 -45.023278) (xy 460.202532 -45.023278) (xy 460.206603 -44.967656) (xy 460.218729 -44.913219)
			(xy 460.238652 -44.861128) (xy 460.265948 -44.812493) (xy 460.300034 -44.76835) (xy 460.340183 -44.729641)
			(xy 460.385541 -44.69719) (xy 460.435141 -44.671689) (xy 460.487925 -44.653682) (xy 460.542768 -44.643552)
			(xy 460.598502 -44.641515) (xy 460.653939 -44.647615) (xy 460.707896 -44.661721) (xy 460.759225 -44.683533)
			(xy 460.806831 -44.712587) (xy 460.849699 -44.748262) (xy 460.886916 -44.789799) (xy 460.917689 -44.836312)
			(xy 460.941361 -44.886809) (xy 460.957429 -44.940216) (xy 460.965549 -44.995392) (xy 460.965993 -45.019722)
			(xy 461.882488 -45.019722) (xy 461.886559 -44.9641) (xy 461.898685 -44.909663) (xy 461.918608 -44.857572)
			(xy 461.945904 -44.808937) (xy 461.97999 -44.764794) (xy 462.020139 -44.726085) (xy 462.065497 -44.693634)
			(xy 462.115097 -44.668133) (xy 462.167881 -44.650126) (xy 462.222724 -44.639996) (xy 462.278458 -44.637959)
			(xy 462.333895 -44.644059) (xy 462.387852 -44.658165) (xy 462.439181 -44.679977) (xy 462.486787 -44.709031)
			(xy 462.529655 -44.744706) (xy 462.566872 -44.786243) (xy 462.597645 -44.832756) (xy 462.621317 -44.883253)
			(xy 462.637385 -44.93666) (xy 462.645505 -44.991836) (xy 462.646014 -45.019722) (xy 462.645505 -45.047608)
			(xy 462.637385 -45.102784) (xy 462.621317 -45.156191) (xy 462.597645 -45.206688) (xy 462.566872 -45.253201)
			(xy 462.529655 -45.294738) (xy 462.486787 -45.330413) (xy 462.439181 -45.359467) (xy 462.387852 -45.381279)
			(xy 462.333895 -45.395385) (xy 462.278458 -45.401485) (xy 462.222724 -45.399448) (xy 462.167881 -45.389318)
			(xy 462.115097 -45.371311) (xy 462.065497 -45.34581) (xy 462.020139 -45.313359) (xy 461.97999 -45.27465)
			(xy 461.945904 -45.230507) (xy 461.918608 -45.181872) (xy 461.898685 -45.129781) (xy 461.886559 -45.075344)
			(xy 461.882488 -45.019722) (xy 460.965993 -45.019722) (xy 460.966058 -45.023278) (xy 460.965549 -45.051164)
			(xy 460.957429 -45.10634) (xy 460.941361 -45.159747) (xy 460.917689 -45.210244) (xy 460.886916 -45.256757)
			(xy 460.849699 -45.298294) (xy 460.806831 -45.333969) (xy 460.759225 -45.363023) (xy 460.707896 -45.384835)
			(xy 460.653939 -45.398941) (xy 460.598502 -45.405041) (xy 460.542768 -45.403004) (xy 460.487925 -45.392874)
			(xy 460.435141 -45.374867) (xy 460.385541 -45.349366) (xy 460.340183 -45.316915) (xy 460.300034 -45.278206)
			(xy 460.265948 -45.234063) (xy 460.238652 -45.185428) (xy 460.218729 -45.133337) (xy 460.206603 -45.0789)
			(xy 460.202532 -45.023278) (xy 452.960673 -45.023278) (xy 452.913904 -45.044637) (xy 452.861605 -45.059993)
			(xy 452.807653 -45.06775) (xy 452.7804 -45.068236) (xy 452.760825 -45.067948) (xy 452.721887 -45.063877)
			(xy 452.702676 -45.060108) (xy 452.688643 -45.057728) (xy 452.660275 -45.059846) (xy 452.633588 -45.069694)
			(xy 452.610644 -45.086512) (xy 452.59322 -45.108998) (xy 452.582662 -45.135413) (xy 452.580756 -45.149516)
			(xy 452.577441 -45.177366) (xy 452.563667 -45.231733) (xy 452.542081 -45.283497) (xy 452.513146 -45.331541)
			(xy 452.477488 -45.374831) (xy 452.435875 -45.412432) (xy 452.389205 -45.443533) (xy 452.338483 -45.467465)
			(xy 452.284803 -45.483712) (xy 452.229322 -45.491922) (xy 452.20128 -45.492416) (xy 452.172962 -45.491895)
			(xy 452.116947 -45.483525) (xy 452.062789 -45.466957) (xy 452.011678 -45.442557) (xy 451.98792 -45.427138)
			(xy 451.975339 -45.419339) (xy 451.947081 -45.410574) (xy 451.917497 -45.410256) (xy 451.889057 -45.418412)
			(xy 451.864138 -45.43436) (xy 451.844821 -45.456769) (xy 451.838314 -45.470064) (xy 451.826673 -45.494918)
			(xy 451.797336 -45.5413) (xy 451.761653 -45.582998) (xy 451.720362 -45.61915) (xy 451.674315 -45.649011)
			(xy 451.624463 -45.671962) (xy 451.571836 -45.68753) (xy 451.528268 -45.693838) (xy 458.651862 -45.693838)
			(xy 458.655933 -45.638216) (xy 458.668059 -45.583779) (xy 458.687982 -45.531688) (xy 458.715278 -45.483053)
			(xy 458.749364 -45.43891) (xy 458.789513 -45.400201) (xy 458.834871 -45.36775) (xy 458.884471 -45.342249)
			(xy 458.937255 -45.324242) (xy 458.992098 -45.314112) (xy 459.047832 -45.312075) (xy 459.103269 -45.318175)
			(xy 459.157226 -45.332281) (xy 459.208555 -45.354093) (xy 459.256161 -45.383147) (xy 459.299029 -45.418822)
			(xy 459.336246 -45.460359) (xy 459.367019 -45.506872) (xy 459.390691 -45.557369) (xy 459.406759 -45.610776)
			(xy 459.414879 -45.665952) (xy 459.415388 -45.693838) (xy 459.414879 -45.721724) (xy 459.406759 -45.7769)
			(xy 459.390691 -45.830307) (xy 459.367019 -45.880804) (xy 459.336246 -45.927317) (xy 459.299029 -45.968854)
			(xy 459.256161 -46.004529) (xy 459.208555 -46.033583) (xy 459.157226 -46.055395) (xy 459.103269 -46.069501)
			(xy 459.047832 -46.075601) (xy 458.992098 -46.073564) (xy 458.937255 -46.063434) (xy 458.884471 -46.045427)
			(xy 458.834871 -46.019926) (xy 458.789513 -45.987475) (xy 458.749364 -45.948766) (xy 458.715278 -45.904623)
			(xy 458.687982 -45.855988) (xy 458.668059 -45.803897) (xy 458.655933 -45.74946) (xy 458.651862 -45.693838)
			(xy 451.528268 -45.693838) (xy 451.517521 -45.695394) (xy 451.49008 -45.69587) (xy 451.462827 -45.695459)
			(xy 451.408876 -45.687699) (xy 451.356578 -45.672341) (xy 451.306999 -45.649696) (xy 451.261146 -45.620226)
			(xy 451.219954 -45.584531) (xy 451.184262 -45.543338) (xy 451.154794 -45.497484) (xy 451.132152 -45.447903)
			(xy 451.116797 -45.395604) (xy 451.10904 -45.341653) (xy 448.84 -45.341653) (xy 448.866249 -45.382497)
			(xy 448.888891 -45.432074) (xy 448.904246 -45.484369) (xy 448.912002 -45.538317) (xy 448.912488 -45.565568)
			(xy 448.911975 -45.593564) (xy 448.903789 -45.648955) (xy 448.887602 -45.702557) (xy 448.86376 -45.75322)
			(xy 448.832776 -45.799859) (xy 448.795314 -45.841473) (xy 448.774058 -45.8597) (xy 448.763048 -45.869382)
			(xy 448.746656 -45.893677) (xy 448.737833 -45.921626) (xy 448.737305 -45.950929) (xy 448.745115 -45.979177)
			(xy 448.760621 -46.004048) (xy 448.771264 -46.014132) (xy 448.791086 -46.032319) (xy 448.825942 -46.073291)
			(xy 448.854698 -46.118754) (xy 448.876781 -46.167805) (xy 448.891755 -46.219473) (xy 448.899322 -46.272731)
			(xy 448.899471 -46.28134) (xy 468.03386 -46.28134) (xy 468.037931 -46.225718) (xy 468.050057 -46.171281)
			(xy 468.06998 -46.11919) (xy 468.097276 -46.070555) (xy 468.131362 -46.026412) (xy 468.171511 -45.987703)
			(xy 468.216869 -45.955252) (xy 468.266469 -45.929751) (xy 468.319253 -45.911744) (xy 468.374096 -45.901614)
			(xy 468.42983 -45.899577) (xy 468.485267 -45.905677) (xy 468.539224 -45.919783) (xy 468.590553 -45.941595)
			(xy 468.638159 -45.970649) (xy 468.681027 -46.006324) (xy 468.718244 -46.047861) (xy 468.749017 -46.094374)
			(xy 468.772689 -46.144871) (xy 468.788757 -46.198278) (xy 468.796877 -46.253454) (xy 468.797386 -46.28134)
			(xy 468.796877 -46.309226) (xy 468.788757 -46.364402) (xy 468.772689 -46.417809) (xy 468.749017 -46.468306)
			(xy 468.718244 -46.514819) (xy 468.681027 -46.556356) (xy 468.638159 -46.592031) (xy 468.590553 -46.621085)
			(xy 468.539224 -46.642897) (xy 468.485267 -46.657003) (xy 468.42983 -46.663103) (xy 468.374096 -46.661066)
			(xy 468.319253 -46.650936) (xy 468.266469 -46.632929) (xy 468.216869 -46.607428) (xy 468.171511 -46.574977)
			(xy 468.131362 -46.536268) (xy 468.097276 -46.492125) (xy 468.06998 -46.44349) (xy 468.050057 -46.391399)
			(xy 468.037931 -46.336962) (xy 468.03386 -46.28134) (xy 448.899471 -46.28134) (xy 448.899788 -46.299628)
			(xy 448.899302 -46.326879) (xy 448.891546 -46.380827) (xy 448.876191 -46.433122) (xy 448.853549 -46.482699)
			(xy 448.824083 -46.528549) (xy 448.788392 -46.56974) (xy 448.747201 -46.605431) (xy 448.701351 -46.634897)
			(xy 448.651774 -46.657539) (xy 448.599479 -46.672894) (xy 448.545531 -46.68065) (xy 448.491029 -46.68065)
			(xy 448.437081 -46.672894) (xy 448.384786 -46.657539) (xy 448.335209 -46.634897) (xy 448.289359 -46.605431)
			(xy 448.248168 -46.56974) (xy 448.212477 -46.528549) (xy 448.183011 -46.482699) (xy 448.160369 -46.433122)
			(xy 448.145014 -46.380827) (xy 448.137258 -46.326879) (xy 448.136772 -46.299628) (xy 441.68994 -46.299628)
			(xy 441.710177 -46.330215) (xy 441.733865 -46.380746) (xy 441.749943 -46.434188) (xy 441.758069 -46.489402)
			(xy 441.758578 -46.517306) (xy 441.758069 -46.54521) (xy 441.749943 -46.600424) (xy 441.733865 -46.653866)
			(xy 441.710177 -46.704397) (xy 441.679383 -46.750941) (xy 441.642141 -46.792505) (xy 441.599245 -46.828204)
			(xy 441.551607 -46.857277) (xy 441.500244 -46.879104) (xy 441.446251 -46.89322) (xy 441.390777 -46.899323)
			(xy 441.335006 -46.897285) (xy 441.280127 -46.887148) (xy 441.227307 -46.869129) (xy 441.177675 -46.843611)
			(xy 441.132287 -46.811139) (xy 441.09211 -46.772404) (xy 441.058002 -46.728232) (xy 441.030688 -46.679564)
			(xy 441.010752 -46.627438) (xy 440.998617 -46.572965) (xy 440.994544 -46.517306) (xy 436.605172 -46.517306)
			(xy 436.662576 -46.57471) (xy 437.90235 -46.57471) (xy 438.177686 -46.850046) (xy 438.177686 -47.186088)
			(xy 466.701122 -47.186088) (xy 466.705193 -47.130466) (xy 466.717319 -47.076029) (xy 466.737242 -47.023938)
			(xy 466.764538 -46.975303) (xy 466.798624 -46.93116) (xy 466.838773 -46.892451) (xy 466.884131 -46.86)
			(xy 466.933731 -46.834499) (xy 466.986515 -46.816492) (xy 467.041358 -46.806362) (xy 467.097092 -46.804325)
			(xy 467.152529 -46.810425) (xy 467.206486 -46.824531) (xy 467.257815 -46.846343) (xy 467.305421 -46.875397)
			(xy 467.348289 -46.911072) (xy 467.385506 -46.952609) (xy 467.416279 -46.999122) (xy 467.439951 -47.049619)
			(xy 467.456019 -47.103026) (xy 467.464139 -47.158202) (xy 467.464648 -47.186088) (xy 467.464139 -47.213974)
			(xy 467.456019 -47.26915) (xy 467.439951 -47.322557) (xy 467.416279 -47.373054) (xy 467.385506 -47.419567)
			(xy 467.348289 -47.461104) (xy 467.305421 -47.496779) (xy 467.257815 -47.525833) (xy 467.206486 -47.547645)
			(xy 467.152529 -47.561751) (xy 467.097092 -47.567851) (xy 467.041358 -47.565814) (xy 466.986515 -47.555684)
			(xy 466.933731 -47.537677) (xy 466.884131 -47.512176) (xy 466.838773 -47.479725) (xy 466.798624 -47.441016)
			(xy 466.764538 -47.396873) (xy 466.737242 -47.348238) (xy 466.717319 -47.296147) (xy 466.705193 -47.24171)
			(xy 466.701122 -47.186088) (xy 438.177686 -47.186088) (xy 438.177686 -48.522954) (xy 444.394267 -48.522954)
			(xy 444.394267 -48.468446) (xy 444.402025 -48.414494) (xy 444.417382 -48.362195) (xy 444.440027 -48.312614)
			(xy 444.469497 -48.266761) (xy 444.505194 -48.225568) (xy 444.546389 -48.189876) (xy 444.592246 -48.16041)
			(xy 444.641829 -48.13777) (xy 444.694129 -48.122417) (xy 444.748082 -48.114665) (xy 444.775336 -48.114204)
			(xy 444.801156 -48.114628) (xy 444.852323 -48.12159) (xy 444.902082 -48.135397) (xy 444.949522 -48.155794)
			(xy 444.993774 -48.182409) (xy 445.034028 -48.214754) (xy 445.069547 -48.252237) (xy 445.084962 -48.272954)
			(xy 445.093605 -48.284241) (xy 445.115945 -48.301811) (xy 445.142256 -48.312556) (xy 445.170509 -48.315647)
			(xy 445.198521 -48.310845) (xy 445.224131 -48.298521) (xy 445.245362 -48.279627) (xy 445.253364 -48.267874)
			(xy 445.268432 -48.244979) (xy 445.304126 -48.203387) (xy 445.345405 -48.167331) (xy 445.391419 -48.137554)
			(xy 445.441221 -48.114669) (xy 445.493786 -48.099147) (xy 445.548032 -48.091308) (xy 445.575436 -48.090836)
			(xy 445.602689 -48.091236) (xy 445.656639 -48.098998) (xy 445.708935 -48.114358) (xy 445.758514 -48.137004)
			(xy 445.804365 -48.166474) (xy 445.845555 -48.20217) (xy 445.881247 -48.243364) (xy 445.910714 -48.289218)
			(xy 445.933355 -48.338799) (xy 445.94871 -48.391096) (xy 445.956466 -48.445047) (xy 445.956466 -48.499553)
			(xy 445.94871 -48.553504) (xy 445.933355 -48.605801) (xy 445.910714 -48.655382) (xy 445.881247 -48.701236)
			(xy 445.845555 -48.74243) (xy 445.804365 -48.778126) (xy 445.758514 -48.807596) (xy 445.708935 -48.830242)
			(xy 445.656639 -48.845602) (xy 445.602689 -48.853364) (xy 445.575436 -48.853852) (xy 445.549617 -48.853393)
			(xy 445.498451 -48.846439) (xy 445.448692 -48.83264) (xy 445.401251 -48.812249) (xy 445.356999 -48.785639)
			(xy 445.316744 -48.753298) (xy 445.281225 -48.715818) (xy 445.26581 -48.695102) (xy 445.257075 -48.683894)
			(xy 445.234755 -48.666333) (xy 445.208465 -48.655589) (xy 445.180234 -48.65249) (xy 445.152239 -48.657275)
			(xy 445.126641 -48.669576) (xy 445.105413 -48.688444) (xy 445.097408 -48.700182) (xy 445.082278 -48.723034)
			(xy 445.046596 -48.764629) (xy 445.005328 -48.800689) (xy 444.959325 -48.830472) (xy 444.909532 -48.853364)
			(xy 444.856975 -48.868895) (xy 444.802737 -48.876743) (xy 444.775336 -48.87722) (xy 444.748082 -48.876735)
			(xy 444.694129 -48.868983) (xy 444.641829 -48.85363) (xy 444.592246 -48.83099) (xy 444.546389 -48.801524)
			(xy 444.505194 -48.765832) (xy 444.469497 -48.724639) (xy 444.440027 -48.678786) (xy 444.417382 -48.629205)
			(xy 444.402025 -48.576906) (xy 444.394267 -48.522954) (xy 438.177686 -48.522954) (xy 438.177686 -49.268148)
			(xy 441.121826 -49.268148) (xy 441.121826 -49.213652) (xy 441.129582 -49.159711) (xy 441.144935 -49.107423)
			(xy 441.167573 -49.057852) (xy 441.197036 -49.012008) (xy 441.232723 -48.970823) (xy 441.273908 -48.935136)
			(xy 441.319752 -48.905673) (xy 441.369323 -48.883035) (xy 441.421611 -48.867682) (xy 441.475552 -48.859926)
			(xy 441.5028 -48.85944) (xy 441.531718 -48.859943) (xy 441.58889 -48.868673) (xy 441.64409 -48.885933)
			(xy 441.696052 -48.911328) (xy 441.743585 -48.944275) (xy 441.785601 -48.984019) (xy 441.80379 -49.006506)
			(xy 441.813687 -49.018311) (xy 441.839011 -49.03583) (xy 441.868404 -49.045006) (xy 441.899196 -49.045006)
			(xy 441.928589 -49.03583) (xy 441.953913 -49.018311) (xy 441.96381 -49.006506) (xy 441.981997 -48.984019)
			(xy 442.024017 -48.944284) (xy 442.071553 -48.911345) (xy 442.123515 -48.885957) (xy 442.178714 -48.868702)
			(xy 442.235884 -48.859974) (xy 442.2648 -48.85944) (xy 442.292055 -48.85983) (xy 442.346009 -48.867587)
			(xy 442.398311 -48.882944) (xy 442.447894 -48.905588) (xy 442.49375 -48.935058) (xy 442.534946 -48.970754)
			(xy 442.570642 -49.01195) (xy 442.600112 -49.057806) (xy 442.622756 -49.107389) (xy 442.638113 -49.159691)
			(xy 442.64587 -49.213645) (xy 442.64587 -49.268148) (xy 442.976026 -49.268148) (xy 442.976026 -49.213652)
			(xy 442.983782 -49.159711) (xy 442.999135 -49.107423) (xy 443.021773 -49.057852) (xy 443.051236 -49.012008)
			(xy 443.086923 -48.970823) (xy 443.128108 -48.935136) (xy 443.173952 -48.905673) (xy 443.223523 -48.883035)
			(xy 443.275811 -48.867682) (xy 443.329752 -48.859926) (xy 443.357 -48.85944) (xy 443.385918 -48.859943)
			(xy 443.44309 -48.868673) (xy 443.49829 -48.885933) (xy 443.550252 -48.911328) (xy 443.597785 -48.944275)
			(xy 443.639801 -48.984019) (xy 443.65799 -49.006506) (xy 443.667887 -49.018311) (xy 443.693211 -49.03583)
			(xy 443.722604 -49.045006) (xy 443.753396 -49.045006) (xy 443.782789 -49.03583) (xy 443.808113 -49.018311)
			(xy 443.81801 -49.006506) (xy 443.836197 -48.984019) (xy 443.878217 -48.944284) (xy 443.925753 -48.911345)
			(xy 443.977715 -48.885957) (xy 444.032914 -48.868702) (xy 444.090084 -48.859974) (xy 444.119 -48.85944)
			(xy 444.146255 -48.85983) (xy 444.200209 -48.867587) (xy 444.252511 -48.882944) (xy 444.302094 -48.905588)
			(xy 444.34795 -48.935058) (xy 444.389146 -48.970754) (xy 444.424842 -49.01195) (xy 444.454312 -49.057806)
			(xy 444.476956 -49.107389) (xy 444.492313 -49.159691) (xy 444.50007 -49.213645) (xy 444.50007 -49.268155)
			(xy 444.492313 -49.322109) (xy 444.476956 -49.374411) (xy 444.454312 -49.423994) (xy 444.424842 -49.46985)
			(xy 444.389146 -49.511046) (xy 444.38025 -49.518754) (xy 448.637656 -49.518754) (xy 448.637656 -49.434058)
			(xy 448.645707 -49.349744) (xy 448.661736 -49.266578) (xy 448.685597 -49.185311) (xy 448.717076 -49.106681)
			(xy 448.755887 -49.0314) (xy 448.801677 -48.960148) (xy 448.854033 -48.893572) (xy 448.912481 -48.832274)
			(xy 448.976491 -48.776809) (xy 449.045483 -48.72768) (xy 449.118833 -48.685331) (xy 449.195876 -48.650147)
			(xy 449.275915 -48.622445) (xy 449.358224 -48.602477) (xy 449.442059 -48.590424) (xy 449.52666 -48.586394)
			(xy 449.611261 -48.590424) (xy 449.695096 -48.602477) (xy 449.777405 -48.622445) (xy 449.857444 -48.650147)
			(xy 449.934487 -48.685331) (xy 450.007837 -48.72768) (xy 450.076829 -48.776809) (xy 450.140839 -48.832274)
			(xy 450.199287 -48.893572) (xy 450.251643 -48.960148) (xy 450.297433 -49.0314) (xy 450.336244 -49.106681)
			(xy 450.367723 -49.185311) (xy 450.391584 -49.266578) (xy 450.407613 -49.349744) (xy 450.415664 -49.434058)
			(xy 450.416168 -49.476406) (xy 450.415664 -49.518754) (xy 456.145896 -49.518754) (xy 456.145896 -49.434058)
			(xy 456.153947 -49.349744) (xy 456.169976 -49.266578) (xy 456.193837 -49.185311) (xy 456.225316 -49.106681)
			(xy 456.264127 -49.0314) (xy 456.309917 -48.960148) (xy 456.362273 -48.893572) (xy 456.420721 -48.832274)
			(xy 456.484731 -48.776809) (xy 456.553723 -48.72768) (xy 456.627073 -48.685331) (xy 456.704116 -48.650147)
			(xy 456.784155 -48.622445) (xy 456.866464 -48.602477) (xy 456.950299 -48.590424) (xy 457.0349 -48.586394)
			(xy 457.119501 -48.590424) (xy 457.203336 -48.602477) (xy 457.285645 -48.622445) (xy 457.365684 -48.650147)
			(xy 457.442727 -48.685331) (xy 457.516077 -48.72768) (xy 457.585069 -48.776809) (xy 457.649079 -48.832274)
			(xy 457.707527 -48.893572) (xy 457.759883 -48.960148) (xy 457.805673 -49.0314) (xy 457.844484 -49.106681)
			(xy 457.875963 -49.185311) (xy 457.899824 -49.266578) (xy 457.915853 -49.349744) (xy 457.923904 -49.434058)
			(xy 457.924408 -49.476406) (xy 457.923904 -49.518754) (xy 457.918901 -49.571148) (xy 466.693502 -49.571148)
			(xy 466.697573 -49.515526) (xy 466.709699 -49.461089) (xy 466.729622 -49.408998) (xy 466.756918 -49.360363)
			(xy 466.791004 -49.31622) (xy 466.831153 -49.277511) (xy 466.876511 -49.24506) (xy 466.926111 -49.219559)
			(xy 466.978895 -49.201552) (xy 467.033738 -49.191422) (xy 467.089472 -49.189385) (xy 467.144909 -49.195485)
			(xy 467.198866 -49.209591) (xy 467.250195 -49.231403) (xy 467.297801 -49.260457) (xy 467.340669 -49.296132)
			(xy 467.377886 -49.337669) (xy 467.408659 -49.384182) (xy 467.432331 -49.434679) (xy 467.448399 -49.488086)
			(xy 467.456519 -49.543262) (xy 467.457028 -49.571148) (xy 467.456519 -49.599034) (xy 467.448399 -49.65421)
			(xy 467.432331 -49.707617) (xy 467.408659 -49.758114) (xy 467.377886 -49.804627) (xy 467.340669 -49.846164)
			(xy 467.297801 -49.881839) (xy 467.250195 -49.910893) (xy 467.198866 -49.932705) (xy 467.144909 -49.946811)
			(xy 467.089472 -49.952911) (xy 467.033738 -49.950874) (xy 466.978895 -49.940744) (xy 466.926111 -49.922737)
			(xy 466.876511 -49.897236) (xy 466.831153 -49.864785) (xy 466.791004 -49.826076) (xy 466.756918 -49.781933)
			(xy 466.729622 -49.733298) (xy 466.709699 -49.681207) (xy 466.697573 -49.62677) (xy 466.693502 -49.571148)
			(xy 457.918901 -49.571148) (xy 457.915853 -49.603068) (xy 457.899824 -49.686234) (xy 457.875963 -49.767501)
			(xy 457.844484 -49.846131) (xy 457.805673 -49.921412) (xy 457.759883 -49.992664) (xy 457.707527 -50.05924)
			(xy 457.649079 -50.120538) (xy 457.585069 -50.176003) (xy 457.516077 -50.225132) (xy 457.442727 -50.267481)
			(xy 457.365684 -50.302665) (xy 457.285645 -50.330367) (xy 457.203336 -50.350335) (xy 457.119501 -50.362388)
			(xy 457.0349 -50.366419) (xy 456.950299 -50.362388) (xy 456.866464 -50.350335) (xy 456.784155 -50.330367)
			(xy 456.704116 -50.302665) (xy 456.627073 -50.267481) (xy 456.553723 -50.225132) (xy 456.484731 -50.176003)
			(xy 456.420721 -50.120538) (xy 456.362273 -50.05924) (xy 456.309917 -49.992664) (xy 456.264127 -49.921412)
			(xy 456.225316 -49.846131) (xy 456.193837 -49.767501) (xy 456.169976 -49.686234) (xy 456.153947 -49.603068)
			(xy 456.145896 -49.518754) (xy 450.415664 -49.518754) (xy 450.407613 -49.603068) (xy 450.391584 -49.686234)
			(xy 450.367723 -49.767501) (xy 450.336244 -49.846131) (xy 450.297433 -49.921412) (xy 450.251643 -49.992664)
			(xy 450.199287 -50.05924) (xy 450.140839 -50.120538) (xy 450.076829 -50.176003) (xy 450.007837 -50.225132)
			(xy 449.934487 -50.267481) (xy 449.857444 -50.302665) (xy 449.777405 -50.330367) (xy 449.695096 -50.350335)
			(xy 449.611261 -50.362388) (xy 449.52666 -50.366419) (xy 449.442059 -50.362388) (xy 449.358224 -50.350335)
			(xy 449.275915 -50.330367) (xy 449.195876 -50.302665) (xy 449.118833 -50.267481) (xy 449.045483 -50.225132)
			(xy 448.976491 -50.176003) (xy 448.912481 -50.120538) (xy 448.854033 -50.05924) (xy 448.801677 -49.992664)
			(xy 448.755887 -49.921412) (xy 448.717076 -49.846131) (xy 448.685597 -49.767501) (xy 448.661736 -49.686234)
			(xy 448.645707 -49.603068) (xy 448.637656 -49.518754) (xy 444.38025 -49.518754) (xy 444.34795 -49.546742)
			(xy 444.302094 -49.576212) (xy 444.252511 -49.598856) (xy 444.200209 -49.614213) (xy 444.146255 -49.62197)
			(xy 444.119 -49.622456) (xy 444.090082 -49.621954) (xy 444.03291 -49.613224) (xy 443.97771 -49.595964)
			(xy 443.925748 -49.570569) (xy 443.878214 -49.537622) (xy 443.836199 -49.497877) (xy 443.81801 -49.47539)
			(xy 443.808113 -49.463585) (xy 443.782789 -49.446066) (xy 443.753396 -49.43689) (xy 443.722604 -49.43689)
			(xy 443.693211 -49.446066) (xy 443.667887 -49.463585) (xy 443.65799 -49.47539) (xy 443.639802 -49.497876)
			(xy 443.597782 -49.537612) (xy 443.550247 -49.570551) (xy 443.498285 -49.595939) (xy 443.443086 -49.613194)
			(xy 443.385916 -49.621922) (xy 443.357 -49.622456) (xy 443.329752 -49.621874) (xy 443.275811 -49.614118)
			(xy 443.223523 -49.598765) (xy 443.173952 -49.576127) (xy 443.128108 -49.546664) (xy 443.086923 -49.510977)
			(xy 443.051236 -49.469792) (xy 443.021773 -49.423948) (xy 442.999135 -49.374377) (xy 442.983782 -49.322089)
			(xy 442.976026 -49.268148) (xy 442.64587 -49.268148) (xy 442.64587 -49.268155) (xy 442.638113 -49.322109)
			(xy 442.622756 -49.374411) (xy 442.600112 -49.423994) (xy 442.570642 -49.46985) (xy 442.534946 -49.511046)
			(xy 442.49375 -49.546742) (xy 442.447894 -49.576212) (xy 442.398311 -49.598856) (xy 442.346009 -49.614213)
			(xy 442.292055 -49.62197) (xy 442.2648 -49.622456) (xy 442.235882 -49.621954) (xy 442.17871 -49.613224)
			(xy 442.12351 -49.595964) (xy 442.071548 -49.570569) (xy 442.024014 -49.537622) (xy 441.981999 -49.497877)
			(xy 441.96381 -49.47539) (xy 441.953913 -49.463585) (xy 441.928589 -49.446066) (xy 441.899196 -49.43689)
			(xy 441.868404 -49.43689) (xy 441.839011 -49.446066) (xy 441.813687 -49.463585) (xy 441.80379 -49.47539)
			(xy 441.785602 -49.497876) (xy 441.743582 -49.537612) (xy 441.696047 -49.570551) (xy 441.644085 -49.595939)
			(xy 441.588886 -49.613194) (xy 441.531716 -49.621922) (xy 441.5028 -49.622456) (xy 441.475552 -49.621874)
			(xy 441.421611 -49.614118) (xy 441.369323 -49.598765) (xy 441.319752 -49.576127) (xy 441.273908 -49.546664)
			(xy 441.232723 -49.510977) (xy 441.197036 -49.469792) (xy 441.167573 -49.423948) (xy 441.144935 -49.374377)
			(xy 441.129582 -49.322089) (xy 441.121826 -49.268148) (xy 438.177686 -49.268148) (xy 438.177686 -50.231548)
			(xy 444.676782 -50.231548) (xy 444.680853 -50.175926) (xy 444.692979 -50.121489) (xy 444.712902 -50.069398)
			(xy 444.740198 -50.020763) (xy 444.774284 -49.97662) (xy 444.814433 -49.937911) (xy 444.859791 -49.90546)
			(xy 444.909391 -49.879959) (xy 444.962175 -49.861952) (xy 445.017018 -49.851822) (xy 445.072752 -49.849785)
			(xy 445.128189 -49.855885) (xy 445.182146 -49.869991) (xy 445.233475 -49.891803) (xy 445.281081 -49.920857)
			(xy 445.323949 -49.956532) (xy 445.361166 -49.998069) (xy 445.391939 -50.044582) (xy 445.415611 -50.095079)
			(xy 445.431679 -50.148486) (xy 445.439799 -50.203662) (xy 445.440308 -50.231548) (xy 445.439799 -50.259434)
			(xy 445.431679 -50.31461) (xy 445.415611 -50.368017) (xy 445.391939 -50.418514) (xy 445.361166 -50.465027)
			(xy 445.323949 -50.506564) (xy 445.281081 -50.542239) (xy 445.233475 -50.571293) (xy 445.182146 -50.593105)
			(xy 445.128189 -50.607211) (xy 445.072752 -50.613311) (xy 445.017018 -50.611274) (xy 444.962175 -50.601144)
			(xy 444.909391 -50.583137) (xy 444.859791 -50.557636) (xy 444.814433 -50.525185) (xy 444.774284 -50.486476)
			(xy 444.740198 -50.442333) (xy 444.712902 -50.393698) (xy 444.692979 -50.341607) (xy 444.680853 -50.28717)
			(xy 444.676782 -50.231548) (xy 438.177686 -50.231548) (xy 438.177686 -50.995834) (xy 439.15838 -51.976528)
			(xy 448.662047 -51.976528) (xy 448.666083 -51.893081) (xy 448.678155 -51.810413) (xy 448.698148 -51.729296)
			(xy 448.725877 -51.650487) (xy 448.761083 -51.574722) (xy 448.803437 -51.502709) (xy 448.852543 -51.43512)
			(xy 448.907944 -51.372586) (xy 448.969121 -51.315691) (xy 449.035504 -51.264965) (xy 449.106472 -51.220884)
			(xy 449.181364 -51.183858) (xy 449.25948 -51.154232) (xy 449.34009 -51.132284) (xy 449.422442 -51.118219)
			(xy 449.505768 -51.112167) (xy 449.589288 -51.114186) (xy 449.672224 -51.124256) (xy 449.7538 -51.142284)
			(xy 449.833256 -51.168101) (xy 449.909849 -51.201466) (xy 449.982865 -51.242067) (xy 450.051621 -51.289526)
			(xy 450.115475 -51.343399) (xy 450.173832 -51.403184) (xy 450.226147 -51.468321) (xy 450.27193 -51.538204)
			(xy 450.310755 -51.612179) (xy 450.34226 -51.689556) (xy 450.366149 -51.769613) (xy 450.3822 -51.851601)
			(xy 450.390263 -51.934756) (xy 450.390768 -51.976528) (xy 456.170287 -51.976528) (xy 456.174323 -51.893081)
			(xy 456.186395 -51.810413) (xy 456.206388 -51.729296) (xy 456.234117 -51.650487) (xy 456.269323 -51.574722)
			(xy 456.311677 -51.502709) (xy 456.360783 -51.43512) (xy 456.416184 -51.372586) (xy 456.477361 -51.315691)
			(xy 456.543744 -51.264965) (xy 456.614712 -51.220884) (xy 456.689604 -51.183858) (xy 456.76772 -51.154232)
			(xy 456.84833 -51.132284) (xy 456.930682 -51.118219) (xy 457.014008 -51.112167) (xy 457.097528 -51.114186)
			(xy 457.180464 -51.124256) (xy 457.26204 -51.142284) (xy 457.341496 -51.168101) (xy 457.418089 -51.201466)
			(xy 457.491105 -51.242067) (xy 457.559861 -51.289526) (xy 457.623715 -51.343399) (xy 457.682072 -51.403184)
			(xy 457.734387 -51.468321) (xy 457.78017 -51.538204) (xy 457.818995 -51.612179) (xy 457.8505 -51.689556)
			(xy 457.874389 -51.769613) (xy 457.89044 -51.851601) (xy 457.898503 -51.934756) (xy 457.899008 -51.976528)
			(xy 457.898503 -52.0183) (xy 457.89044 -52.101455) (xy 457.874389 -52.183443) (xy 457.8505 -52.2635)
			(xy 457.818995 -52.340877) (xy 457.78017 -52.414852) (xy 457.734387 -52.484735) (xy 457.682072 -52.549872)
			(xy 457.623715 -52.609657) (xy 457.559861 -52.66353) (xy 457.491105 -52.710989) (xy 457.418089 -52.75159)
			(xy 457.341496 -52.784955) (xy 457.26204 -52.810772) (xy 457.180464 -52.8288) (xy 457.097528 -52.83887)
			(xy 457.014008 -52.840889) (xy 456.930682 -52.834837) (xy 456.84833 -52.820772) (xy 456.76772 -52.798824)
			(xy 456.689604 -52.769198) (xy 456.614712 -52.732172) (xy 456.543744 -52.688091) (xy 456.477361 -52.637365)
			(xy 456.416184 -52.58047) (xy 456.360783 -52.517936) (xy 456.311677 -52.450347) (xy 456.269323 -52.378334)
			(xy 456.234117 -52.302569) (xy 456.206388 -52.22376) (xy 456.186395 -52.142643) (xy 456.174323 -52.059975)
			(xy 456.170287 -51.976528) (xy 450.390768 -51.976528) (xy 450.390263 -52.0183) (xy 450.3822 -52.101455)
			(xy 450.366149 -52.183443) (xy 450.34226 -52.2635) (xy 450.310755 -52.340877) (xy 450.27193 -52.414852)
			(xy 450.226147 -52.484735) (xy 450.173832 -52.549872) (xy 450.115475 -52.609657) (xy 450.051621 -52.66353)
			(xy 449.982865 -52.710989) (xy 449.909849 -52.75159) (xy 449.833256 -52.784955) (xy 449.7538 -52.810772)
			(xy 449.672224 -52.8288) (xy 449.589288 -52.83887) (xy 449.505768 -52.840889) (xy 449.422442 -52.834837)
			(xy 449.34009 -52.820772) (xy 449.25948 -52.798824) (xy 449.181364 -52.769198) (xy 449.106472 -52.732172)
			(xy 449.035504 -52.688091) (xy 448.969121 -52.637365) (xy 448.907944 -52.58047) (xy 448.852543 -52.517936)
			(xy 448.803437 -52.450347) (xy 448.761083 -52.378334) (xy 448.725877 -52.302569) (xy 448.698148 -52.22376)
			(xy 448.678155 -52.142643) (xy 448.666083 -52.059975) (xy 448.662047 -51.976528) (xy 439.15838 -51.976528)
			(xy 440.309 -53.127148) (xy 440.309 -57.318148) (xy 441.180474 -58.189622) (xy 462.937352 -58.189622)
		)
		(stroke
			(width 0)
			(type solid)
		)
		(fill yes)
		(layer "In15.Cu")
		(net "P3V3_AUX")
	)
	(gr_poly
		(pts
			(xy 310.4388 -432.2064) (xy 310.4388 -418.0078) (xy 301.244 -408.813) (xy 301.244 -408.450542) (xy 301.243575 -408.436629)
			(xy 301.236068 -408.409836) (xy 301.221601 -408.386067) (xy 301.20125 -408.367091) (xy 301.176528 -408.35432)
			(xy 301.149276 -408.348703) (xy 301.121519 -408.350659) (xy 301.095324 -408.360041) (xy 301.083726 -408.367738)
			(xy 301.059414 -408.384274) (xy 301.006778 -408.41047) (xy 300.950749 -408.428289) (xy 300.892651 -408.437309)
			(xy 300.863254 -408.437842) (xy 300.836002 -408.437353) (xy 300.782055 -408.42959) (xy 300.729761 -408.41423)
			(xy 300.680185 -408.391584) (xy 300.634336 -408.362114) (xy 300.593148 -408.326419) (xy 300.557458 -408.285227)
			(xy 300.527994 -408.239374) (xy 300.505354 -408.189796) (xy 300.49 -408.1375) (xy 300.482244 -408.083552)
			(xy 300.482244 -408.029048) (xy 300.49 -407.9751) (xy 300.505354 -407.922804) (xy 300.527994 -407.873226)
			(xy 300.557458 -407.827373) (xy 300.593148 -407.786181) (xy 300.634336 -407.750486) (xy 300.680185 -407.721016)
			(xy 300.729761 -407.69837) (xy 300.782055 -407.68301) (xy 300.836002 -407.675247) (xy 300.863254 -407.674826)
			(xy 300.892652 -407.675365) (xy 300.950753 -407.684374) (xy 301.006785 -407.702187) (xy 301.059423 -407.728382)
			(xy 301.083726 -407.74493) (xy 301.095344 -407.75257) (xy 301.121522 -407.761907) (xy 301.149249 -407.763835)
			(xy 301.176468 -407.758211) (xy 301.201161 -407.745453) (xy 301.221496 -407.726506) (xy 301.235966 -407.702776)
			(xy 301.243497 -407.676022) (xy 301.244 -407.662126) (xy 301.244 -407.412698) (xy 301.243548 -407.399155)
			(xy 301.236372 -407.373036) (xy 301.222579 -407.349724) (xy 301.20314 -407.330861) (xy 301.179425 -407.317774)
			(xy 301.153102 -407.311385) (xy 301.126026 -407.312144) (xy 301.100102 -407.319998) (xy 301.077157 -407.334394)
			(xy 301.067724 -407.344118) (xy 301.049575 -407.363181) (xy 301.008945 -407.396642) (xy 300.964104 -407.424205)
			(xy 300.915902 -407.445348) (xy 300.865253 -407.459669) (xy 300.813117 -407.466899) (xy 300.7868 -407.467308)
			(xy 300.759549 -407.466822) (xy 300.705601 -407.459066) (xy 300.653306 -407.443711) (xy 300.603729 -407.421069)
			(xy 300.557879 -407.391603) (xy 300.516688 -407.355912) (xy 300.480997 -407.314721) (xy 300.451531 -407.268871)
			(xy 300.428889 -407.219294) (xy 300.413534 -407.166999) (xy 300.405778 -407.113051) (xy 300.405292 -407.0858)
			(xy 300.405714 -407.059482) (xy 300.412917 -407.007341) (xy 300.427226 -406.956688) (xy 300.44837 -406.908485)
			(xy 300.475946 -406.863651) (xy 300.50943 -406.823039) (xy 300.528482 -406.804876) (xy 300.538504 -406.795065)
			(xy 300.553204 -406.771192) (xy 300.560843 -406.744218) (xy 300.560843 -406.716182) (xy 300.553204 -406.689208)
			(xy 300.538504 -406.665335) (xy 300.528482 -406.655524) (xy 300.509419 -406.637375) (xy 300.475958 -406.596745)
			(xy 300.448395 -406.551904) (xy 300.427252 -406.503702) (xy 300.412931 -406.453053) (xy 300.405701 -406.400917)
			(xy 300.405292 -406.3746) (xy 300.405764 -406.346593) (xy 300.41392 -406.291176) (xy 300.430099 -406.23755)
			(xy 300.453953 -406.186869) (xy 300.469046 -406.163272) (xy 300.476916 -406.150402) (xy 300.485511 -406.121501)
			(xy 300.48531 -406.091349) (xy 300.476331 -406.062566) (xy 300.459352 -406.037648) (xy 300.435849 -406.018761)
			(xy 300.422056 -406.01265) (xy 300.395852 -406.001637) (xy 300.346763 -405.972986) (xy 300.302468 -405.93737)
			(xy 300.263945 -405.895577) (xy 300.232047 -405.848533) (xy 300.20748 -405.797278) (xy 300.190788 -405.742946)
			(xy 300.18234 -405.686739) (xy 300.181772 -405.65832) (xy 300.182189 -405.632921) (xy 300.188927 -405.582572)
			(xy 300.202287 -405.533562) (xy 300.222033 -405.486759) (xy 300.247815 -405.442989) (xy 300.279177 -405.403029)
			(xy 300.297088 -405.385016) (xy 300.307818 -405.373751) (xy 300.322498 -405.346339) (xy 300.328266 -405.315784)
			(xy 300.324591 -405.284907) (xy 300.311811 -405.25656) (xy 300.301914 -405.244554) (xy 300.284358 -405.224232)
			(xy 300.25453 -405.179574) (xy 300.231257 -405.131176) (xy 300.215 -405.079992) (xy 300.206079 -405.027035)
			(xy 300.204886 -405.000206) (xy 300.203871 -404.984513) (xy 300.193496 -404.954846) (xy 300.174594 -404.929737)
			(xy 300.148954 -404.911561) (xy 300.119001 -404.902041) (xy 300.103286 -404.9014) (xy 284.2006 -404.9014)
			(xy 282.9814 -406.1206) (xy 282.9814 -407.05786) (xy 291.814502 -407.05786) (xy 291.818573 -407.002238)
			(xy 291.830699 -406.947801) (xy 291.850622 -406.89571) (xy 291.877918 -406.847075) (xy 291.912004 -406.802932)
			(xy 291.952153 -406.764223) (xy 291.997511 -406.731772) (xy 292.047111 -406.706271) (xy 292.099895 -406.688264)
			(xy 292.154738 -406.678134) (xy 292.210472 -406.676097) (xy 292.265909 -406.682197) (xy 292.319866 -406.696303)
			(xy 292.371195 -406.718115) (xy 292.418801 -406.747169) (xy 292.453044 -406.775666) (xy 295.040048 -406.775666)
			(xy 295.044119 -406.720044) (xy 295.056245 -406.665607) (xy 295.076168 -406.613516) (xy 295.103464 -406.564881)
			(xy 295.13755 -406.520738) (xy 295.177699 -406.482029) (xy 295.223057 -406.449578) (xy 295.272657 -406.424077)
			(xy 295.325441 -406.40607) (xy 295.380284 -406.39594) (xy 295.436018 -406.393903) (xy 295.491455 -406.400003)
			(xy 295.545412 -406.414109) (xy 295.596741 -406.435921) (xy 295.644347 -406.464975) (xy 295.687215 -406.50065)
			(xy 295.724432 -406.542187) (xy 295.755205 -406.5887) (xy 295.778877 -406.639197) (xy 295.790972 -406.6794)
			(xy 298.865542 -406.6794) (xy 298.869613 -406.623778) (xy 298.881739 -406.569341) (xy 298.901662 -406.51725)
			(xy 298.928958 -406.468615) (xy 298.963044 -406.424472) (xy 299.003193 -406.385763) (xy 299.048551 -406.353312)
			(xy 299.098151 -406.327811) (xy 299.150935 -406.309804) (xy 299.205778 -406.299674) (xy 299.261512 -406.297637)
			(xy 299.316949 -406.303737) (xy 299.370906 -406.317843) (xy 299.422235 -406.339655) (xy 299.469841 -406.368709)
			(xy 299.512709 -406.404384) (xy 299.549926 -406.445921) (xy 299.580699 -406.492434) (xy 299.604371 -406.542931)
			(xy 299.620439 -406.596338) (xy 299.628559 -406.651514) (xy 299.629068 -406.6794) (xy 299.628559 -406.707286)
			(xy 299.620439 -406.762462) (xy 299.604371 -406.815869) (xy 299.580699 -406.866366) (xy 299.549926 -406.912879)
			(xy 299.512709 -406.954416) (xy 299.469841 -406.990091) (xy 299.422235 -407.019145) (xy 299.370906 -407.040957)
			(xy 299.316949 -407.055063) (xy 299.261512 -407.061163) (xy 299.205778 -407.059126) (xy 299.150935 -407.048996)
			(xy 299.098151 -407.030989) (xy 299.048551 -407.005488) (xy 299.003193 -406.973037) (xy 298.963044 -406.934328)
			(xy 298.928958 -406.890185) (xy 298.901662 -406.84155) (xy 298.881739 -406.789459) (xy 298.869613 -406.735022)
			(xy 298.865542 -406.6794) (xy 295.790972 -406.6794) (xy 295.794945 -406.692604) (xy 295.803065 -406.74778)
			(xy 295.803574 -406.775666) (xy 295.803065 -406.803552) (xy 295.794945 -406.858728) (xy 295.778877 -406.912135)
			(xy 295.755205 -406.962632) (xy 295.724432 -407.009145) (xy 295.687215 -407.050682) (xy 295.644347 -407.086357)
			(xy 295.596741 -407.115411) (xy 295.545412 -407.137223) (xy 295.491455 -407.151329) (xy 295.436018 -407.157429)
			(xy 295.380284 -407.155392) (xy 295.325441 -407.145262) (xy 295.272657 -407.127255) (xy 295.223057 -407.101754)
			(xy 295.177699 -407.069303) (xy 295.13755 -407.030594) (xy 295.103464 -406.986451) (xy 295.076168 -406.937816)
			(xy 295.056245 -406.885725) (xy 295.044119 -406.831288) (xy 295.040048 -406.775666) (xy 292.453044 -406.775666)
			(xy 292.461669 -406.782844) (xy 292.498886 -406.824381) (xy 292.529659 -406.870894) (xy 292.553331 -406.921391)
			(xy 292.569399 -406.974798) (xy 292.577519 -407.029974) (xy 292.578028 -407.05786) (xy 292.577519 -407.085746)
			(xy 292.569399 -407.140922) (xy 292.553331 -407.194329) (xy 292.529659 -407.244826) (xy 292.498886 -407.291339)
			(xy 292.461669 -407.332876) (xy 292.418801 -407.368551) (xy 292.371195 -407.397605) (xy 292.319866 -407.419417)
			(xy 292.265909 -407.433523) (xy 292.210472 -407.439623) (xy 292.154738 -407.437586) (xy 292.099895 -407.427456)
			(xy 292.047111 -407.409449) (xy 291.997511 -407.383948) (xy 291.952153 -407.351497) (xy 291.912004 -407.312788)
			(xy 291.877918 -407.268645) (xy 291.850622 -407.22001) (xy 291.830699 -407.167919) (xy 291.818573 -407.113482)
			(xy 291.814502 -407.05786) (xy 282.9814 -407.05786) (xy 282.9814 -407.49982) (xy 289.368482 -407.49982)
			(xy 289.372553 -407.444198) (xy 289.384679 -407.389761) (xy 289.404602 -407.33767) (xy 289.431898 -407.289035)
			(xy 289.465984 -407.244892) (xy 289.506133 -407.206183) (xy 289.551491 -407.173732) (xy 289.601091 -407.148231)
			(xy 289.653875 -407.130224) (xy 289.708718 -407.120094) (xy 289.764452 -407.118057) (xy 289.819889 -407.124157)
			(xy 289.873846 -407.138263) (xy 289.925175 -407.160075) (xy 289.972781 -407.189129) (xy 290.015649 -407.224804)
			(xy 290.052866 -407.266341) (xy 290.083639 -407.312854) (xy 290.107311 -407.363351) (xy 290.123379 -407.416758)
			(xy 290.128127 -407.44902) (xy 296.33926 -407.44902) (xy 296.339746 -407.421769) (xy 296.347502 -407.367821)
			(xy 296.362857 -407.315526) (xy 296.385499 -407.265949) (xy 296.414965 -407.220099) (xy 296.450656 -407.178908)
			(xy 296.491847 -407.143217) (xy 296.537697 -407.113751) (xy 296.587274 -407.091109) (xy 296.639569 -407.075754)
			(xy 296.693517 -407.067998) (xy 296.748019 -407.067998) (xy 296.801967 -407.075754) (xy 296.854262 -407.091109)
			(xy 296.903839 -407.113751) (xy 296.949689 -407.143217) (xy 296.99088 -407.178908) (xy 297.026571 -407.220099)
			(xy 297.056037 -407.265949) (xy 297.078679 -407.315526) (xy 297.094034 -407.367821) (xy 297.10179 -407.421769)
			(xy 297.102276 -407.44902) (xy 297.101502 -407.483304) (xy 297.089227 -407.550766) (xy 297.077892 -407.583132)
			(xy 297.073446 -407.596471) (xy 297.071168 -407.624483) (xy 297.076591 -407.652059) (xy 297.089307 -407.677122)
			(xy 297.108357 -407.697784) (xy 297.132308 -407.712488) (xy 297.14571 -407.716736) (xy 297.172086 -407.724593)
			(xy 297.22241 -407.746873) (xy 297.269008 -407.776158) (xy 297.31091 -407.811839) (xy 297.347246 -407.853174)
			(xy 297.377261 -407.899304) (xy 297.400331 -407.949271) (xy 297.415977 -408.002036) (xy 297.423874 -408.056502)
			(xy 297.424348 -408.08402) (xy 297.423862 -408.111271) (xy 297.416106 -408.165219) (xy 297.400751 -408.217514)
			(xy 297.378109 -408.267091) (xy 297.348643 -408.312941) (xy 297.312952 -408.354132) (xy 297.271761 -408.389823)
			(xy 297.225911 -408.419289) (xy 297.176334 -408.441931) (xy 297.124039 -408.457286) (xy 297.070091 -408.465042)
			(xy 297.015589 -408.465042) (xy 296.961641 -408.457286) (xy 296.909346 -408.441931) (xy 296.859769 -408.419289)
			(xy 296.813919 -408.389823) (xy 296.772728 -408.354132) (xy 296.737037 -408.312941) (xy 296.707571 -408.267091)
			(xy 296.684929 -408.217514) (xy 296.669574 -408.165219) (xy 296.661818 -408.111271) (xy 296.661332 -408.08402)
			(xy 296.662116 -408.049736) (xy 296.674384 -407.982274) (xy 296.685716 -407.949908) (xy 296.690179 -407.936571)
			(xy 296.69247 -407.908553) (xy 296.687051 -407.88097) (xy 296.674331 -407.855901) (xy 296.65527 -407.835239)
			(xy 296.631306 -407.820544) (xy 296.617898 -407.816304) (xy 296.591535 -407.808406) (xy 296.541213 -407.78613)
			(xy 296.494617 -407.75685) (xy 296.452715 -407.721174) (xy 296.416378 -407.679844) (xy 296.386361 -407.633719)
			(xy 296.363288 -407.583758) (xy 296.347638 -407.530998) (xy 296.339737 -407.476536) (xy 296.33926 -407.44902)
			(xy 290.128127 -407.44902) (xy 290.131499 -407.471934) (xy 290.132008 -407.49982) (xy 290.131499 -407.527706)
			(xy 290.123379 -407.582882) (xy 290.107311 -407.636289) (xy 290.083639 -407.686786) (xy 290.052866 -407.733299)
			(xy 290.015649 -407.774836) (xy 289.972781 -407.810511) (xy 289.925175 -407.839565) (xy 289.873846 -407.861377)
			(xy 289.819889 -407.875483) (xy 289.764452 -407.881583) (xy 289.708718 -407.879546) (xy 289.653875 -407.869416)
			(xy 289.601091 -407.851409) (xy 289.551491 -407.825908) (xy 289.506133 -407.793457) (xy 289.465984 -407.754748)
			(xy 289.431898 -407.710605) (xy 289.404602 -407.66197) (xy 289.384679 -407.609879) (xy 289.372553 -407.555442)
			(xy 289.368482 -407.49982) (xy 282.9814 -407.49982) (xy 282.9814 -408.7114) (xy 298.893482 -408.7114)
			(xy 298.897553 -408.655778) (xy 298.909679 -408.601341) (xy 298.929602 -408.54925) (xy 298.956898 -408.500615)
			(xy 298.990984 -408.456472) (xy 299.031133 -408.417763) (xy 299.076491 -408.385312) (xy 299.126091 -408.359811)
			(xy 299.178875 -408.341804) (xy 299.233718 -408.331674) (xy 299.289452 -408.329637) (xy 299.344889 -408.335737)
			(xy 299.398846 -408.349843) (xy 299.450175 -408.371655) (xy 299.497781 -408.400709) (xy 299.540649 -408.436384)
			(xy 299.577866 -408.477921) (xy 299.608639 -408.524434) (xy 299.632311 -408.574931) (xy 299.648379 -408.628338)
			(xy 299.656499 -408.683514) (xy 299.657008 -408.7114) (xy 299.656499 -408.739286) (xy 299.648379 -408.794462)
			(xy 299.632311 -408.847869) (xy 299.608639 -408.898366) (xy 299.577866 -408.944879) (xy 299.540649 -408.986416)
			(xy 299.497781 -409.022091) (xy 299.450175 -409.051145) (xy 299.398846 -409.072957) (xy 299.344889 -409.087063)
			(xy 299.289452 -409.093163) (xy 299.233718 -409.091126) (xy 299.178875 -409.080996) (xy 299.126091 -409.062989)
			(xy 299.076491 -409.037488) (xy 299.031133 -409.005037) (xy 298.990984 -408.966328) (xy 298.956898 -408.922185)
			(xy 298.929602 -408.87355) (xy 298.909679 -408.821459) (xy 298.897553 -408.767022) (xy 298.893482 -408.7114)
			(xy 282.9814 -408.7114) (xy 282.9814 -409.35402) (xy 296.660822 -409.35402) (xy 296.664893 -409.298398)
			(xy 296.677019 -409.243961) (xy 296.696942 -409.19187) (xy 296.724238 -409.143235) (xy 296.758324 -409.099092)
			(xy 296.798473 -409.060383) (xy 296.843831 -409.027932) (xy 296.893431 -409.002431) (xy 296.946215 -408.984424)
			(xy 297.001058 -408.974294) (xy 297.056792 -408.972257) (xy 297.112229 -408.978357) (xy 297.166186 -408.992463)
			(xy 297.217515 -409.014275) (xy 297.265121 -409.043329) (xy 297.307989 -409.079004) (xy 297.345206 -409.120541)
			(xy 297.375979 -409.167054) (xy 297.399651 -409.217551) (xy 297.415719 -409.270958) (xy 297.423839 -409.326134)
			(xy 297.424348 -409.35402) (xy 297.423839 -409.381906) (xy 297.415719 -409.437082) (xy 297.399651 -409.490489)
			(xy 297.375979 -409.540986) (xy 297.345206 -409.587499) (xy 297.307989 -409.629036) (xy 297.265121 -409.664711)
			(xy 297.217515 -409.693765) (xy 297.166186 -409.715577) (xy 297.112229 -409.729683) (xy 297.056792 -409.735783)
			(xy 297.001058 -409.733746) (xy 296.946215 -409.723616) (xy 296.893431 -409.705609) (xy 296.843831 -409.680108)
			(xy 296.798473 -409.647657) (xy 296.758324 -409.608948) (xy 296.724238 -409.564805) (xy 296.696942 -409.51617)
			(xy 296.677019 -409.464079) (xy 296.664893 -409.409642) (xy 296.660822 -409.35402) (xy 282.9814 -409.35402)
			(xy 282.9814 -409.860496) (xy 282.981904 -409.875288) (xy 282.990387 -409.903631) (xy 283.006642 -409.92835)
			(xy 283.029303 -409.947369) (xy 283.056466 -409.959091) (xy 283.08585 -409.96253) (xy 283.114986 -409.957399)
			(xy 283.141427 -409.944127) (xy 283.152596 -409.93441) (xy 283.173932 -409.915095) (xy 283.221327 -409.882448)
			(xy 283.273086 -409.857289) (xy 283.328037 -409.840188) (xy 283.384933 -409.831532) (xy 283.413708 -409.831032)
			(xy 283.440956 -409.831519) (xy 283.494897 -409.839275) (xy 283.547185 -409.85463) (xy 283.596756 -409.877269)
			(xy 283.642601 -409.906732) (xy 283.683786 -409.94242) (xy 283.719473 -409.983606) (xy 283.748935 -410.029451)
			(xy 283.771573 -410.079022) (xy 283.786926 -410.131311) (xy 283.794682 -410.185252) (xy 283.794682 -410.21254)
			(xy 284.21787 -410.21254) (xy 284.221941 -410.156918) (xy 284.234067 -410.102481) (xy 284.25399 -410.05039)
			(xy 284.281286 -410.001755) (xy 284.315372 -409.957612) (xy 284.355521 -409.918903) (xy 284.400879 -409.886452)
			(xy 284.450479 -409.860951) (xy 284.503263 -409.842944) (xy 284.558106 -409.832814) (xy 284.61384 -409.830777)
			(xy 284.669277 -409.836877) (xy 284.723234 -409.850983) (xy 284.774563 -409.872795) (xy 284.822169 -409.901849)
			(xy 284.865037 -409.937524) (xy 284.902254 -409.979061) (xy 284.933027 -410.025574) (xy 284.956699 -410.076071)
			(xy 284.972767 -410.129478) (xy 284.980887 -410.184654) (xy 284.981396 -410.21254) (xy 284.980887 -410.240426)
			(xy 284.972767 -410.295602) (xy 284.956699 -410.349009) (xy 284.933027 -410.399506) (xy 284.902254 -410.446019)
			(xy 284.865037 -410.487556) (xy 284.822169 -410.523231) (xy 284.774563 -410.552285) (xy 284.723234 -410.574097)
			(xy 284.687726 -410.58338) (xy 292.467282 -410.58338) (xy 292.471353 -410.527758) (xy 292.483479 -410.473321)
			(xy 292.503402 -410.42123) (xy 292.530698 -410.372595) (xy 292.564784 -410.328452) (xy 292.604933 -410.289743)
			(xy 292.650291 -410.257292) (xy 292.699891 -410.231791) (xy 292.752675 -410.213784) (xy 292.807518 -410.203654)
			(xy 292.863252 -410.201617) (xy 292.918689 -410.207717) (xy 292.972646 -410.221823) (xy 293.023975 -410.243635)
			(xy 293.071581 -410.272689) (xy 293.114449 -410.308364) (xy 293.151666 -410.349901) (xy 293.182439 -410.396414)
			(xy 293.206111 -410.446911) (xy 293.222179 -410.500318) (xy 293.230299 -410.555494) (xy 293.230808 -410.58338)
			(xy 293.230299 -410.611266) (xy 293.222179 -410.666442) (xy 293.206111 -410.719849) (xy 293.182439 -410.770346)
			(xy 293.151666 -410.816859) (xy 293.114449 -410.858396) (xy 293.071581 -410.894071) (xy 293.056679 -410.903166)
			(xy 295.769282 -410.903166) (xy 295.773353 -410.847544) (xy 295.785479 -410.793107) (xy 295.805402 -410.741016)
			(xy 295.832698 -410.692381) (xy 295.866784 -410.648238) (xy 295.906933 -410.609529) (xy 295.952291 -410.577078)
			(xy 296.001891 -410.551577) (xy 296.054675 -410.53357) (xy 296.109518 -410.52344) (xy 296.165252 -410.521403)
			(xy 296.220689 -410.527503) (xy 296.274646 -410.541609) (xy 296.325975 -410.563421) (xy 296.373581 -410.592475)
			(xy 296.411486 -410.62402) (xy 296.660822 -410.62402) (xy 296.664893 -410.568398) (xy 296.677019 -410.513961)
			(xy 296.696942 -410.46187) (xy 296.724238 -410.413235) (xy 296.758324 -410.369092) (xy 296.798473 -410.330383)
			(xy 296.843831 -410.297932) (xy 296.893431 -410.272431) (xy 296.946215 -410.254424) (xy 297.001058 -410.244294)
			(xy 297.056792 -410.242257) (xy 297.112229 -410.248357) (xy 297.166186 -410.262463) (xy 297.217515 -410.284275)
			(xy 297.265121 -410.313329) (xy 297.307989 -410.349004) (xy 297.326819 -410.37002) (xy 297.953682 -410.37002)
			(xy 297.957753 -410.314398) (xy 297.969879 -410.259961) (xy 297.989802 -410.20787) (xy 298.017098 -410.159235)
			(xy 298.051184 -410.115092) (xy 298.091333 -410.076383) (xy 298.136691 -410.043932) (xy 298.186291 -410.018431)
			(xy 298.239075 -410.000424) (xy 298.293918 -409.990294) (xy 298.349652 -409.988257) (xy 298.405089 -409.994357)
			(xy 298.459046 -410.008463) (xy 298.510375 -410.030275) (xy 298.557981 -410.059329) (xy 298.600849 -410.095004)
			(xy 298.638066 -410.136541) (xy 298.668839 -410.183054) (xy 298.692511 -410.233551) (xy 298.708579 -410.286958)
			(xy 298.716699 -410.342134) (xy 298.717208 -410.37002) (xy 298.716699 -410.397906) (xy 298.708579 -410.453082)
			(xy 298.692511 -410.506489) (xy 298.668839 -410.556986) (xy 298.638066 -410.603499) (xy 298.600849 -410.645036)
			(xy 298.557981 -410.680711) (xy 298.510375 -410.709765) (xy 298.459046 -410.731577) (xy 298.405089 -410.745683)
			(xy 298.349652 -410.751783) (xy 298.293918 -410.749746) (xy 298.239075 -410.739616) (xy 298.186291 -410.721609)
			(xy 298.136691 -410.696108) (xy 298.091333 -410.663657) (xy 298.051184 -410.624948) (xy 298.017098 -410.580805)
			(xy 297.989802 -410.53217) (xy 297.969879 -410.480079) (xy 297.957753 -410.425642) (xy 297.953682 -410.37002)
			(xy 297.326819 -410.37002) (xy 297.345206 -410.390541) (xy 297.375979 -410.437054) (xy 297.399651 -410.487551)
			(xy 297.415719 -410.540958) (xy 297.423839 -410.596134) (xy 297.424348 -410.62402) (xy 297.423839 -410.651906)
			(xy 297.415719 -410.707082) (xy 297.399651 -410.760489) (xy 297.375979 -410.810986) (xy 297.345206 -410.857499)
			(xy 297.307989 -410.899036) (xy 297.265121 -410.934711) (xy 297.217515 -410.963765) (xy 297.166186 -410.985577)
			(xy 297.112229 -410.999683) (xy 297.056792 -411.005783) (xy 297.001058 -411.003746) (xy 296.946215 -410.993616)
			(xy 296.893431 -410.975609) (xy 296.843831 -410.950108) (xy 296.798473 -410.917657) (xy 296.758324 -410.878948)
			(xy 296.724238 -410.834805) (xy 296.696942 -410.78617) (xy 296.677019 -410.734079) (xy 296.664893 -410.679642)
			(xy 296.660822 -410.62402) (xy 296.411486 -410.62402) (xy 296.416449 -410.62815) (xy 296.453666 -410.669687)
			(xy 296.484439 -410.7162) (xy 296.508111 -410.766697) (xy 296.524179 -410.820104) (xy 296.532299 -410.87528)
			(xy 296.532808 -410.903166) (xy 296.532299 -410.931052) (xy 296.524179 -410.986228) (xy 296.508111 -411.039635)
			(xy 296.484439 -411.090132) (xy 296.453666 -411.136645) (xy 296.416449 -411.178182) (xy 296.385238 -411.204156)
			(xy 299.965362 -411.204156) (xy 299.969433 -411.148534) (xy 299.981559 -411.094097) (xy 300.001482 -411.042006)
			(xy 300.028778 -410.993371) (xy 300.062864 -410.949228) (xy 300.103013 -410.910519) (xy 300.148371 -410.878068)
			(xy 300.197971 -410.852567) (xy 300.250755 -410.83456) (xy 300.305598 -410.82443) (xy 300.361332 -410.822393)
			(xy 300.416769 -410.828493) (xy 300.470726 -410.842599) (xy 300.522055 -410.864411) (xy 300.569661 -410.893465)
			(xy 300.612529 -410.92914) (xy 300.649746 -410.970677) (xy 300.680519 -411.01719) (xy 300.704191 -411.067687)
			(xy 300.720259 -411.121094) (xy 300.728379 -411.17627) (xy 300.728888 -411.204156) (xy 300.728379 -411.232042)
			(xy 300.720259 -411.287218) (xy 300.704191 -411.340625) (xy 300.680519 -411.391122) (xy 300.649746 -411.437635)
			(xy 300.612529 -411.479172) (xy 300.569661 -411.514847) (xy 300.522055 -411.543901) (xy 300.470726 -411.565713)
			(xy 300.416769 -411.579819) (xy 300.361332 -411.585919) (xy 300.305598 -411.583882) (xy 300.250755 -411.573752)
			(xy 300.197971 -411.555745) (xy 300.148371 -411.530244) (xy 300.103013 -411.497793) (xy 300.062864 -411.459084)
			(xy 300.028778 -411.414941) (xy 300.001482 -411.366306) (xy 299.981559 -411.314215) (xy 299.969433 -411.259778)
			(xy 299.965362 -411.204156) (xy 296.385238 -411.204156) (xy 296.373581 -411.213857) (xy 296.325975 -411.242911)
			(xy 296.274646 -411.264723) (xy 296.220689 -411.278829) (xy 296.165252 -411.284929) (xy 296.109518 -411.282892)
			(xy 296.054675 -411.272762) (xy 296.001891 -411.254755) (xy 295.952291 -411.229254) (xy 295.906933 -411.196803)
			(xy 295.866784 -411.158094) (xy 295.832698 -411.113951) (xy 295.805402 -411.065316) (xy 295.785479 -411.013225)
			(xy 295.773353 -410.958788) (xy 295.769282 -410.903166) (xy 293.056679 -410.903166) (xy 293.023975 -410.923125)
			(xy 292.972646 -410.944937) (xy 292.918689 -410.959043) (xy 292.863252 -410.965143) (xy 292.807518 -410.963106)
			(xy 292.752675 -410.952976) (xy 292.699891 -410.934969) (xy 292.650291 -410.909468) (xy 292.604933 -410.877017)
			(xy 292.564784 -410.838308) (xy 292.530698 -410.794165) (xy 292.503402 -410.74553) (xy 292.483479 -410.693439)
			(xy 292.471353 -410.639002) (xy 292.467282 -410.58338) (xy 284.687726 -410.58338) (xy 284.669277 -410.588203)
			(xy 284.61384 -410.594303) (xy 284.558106 -410.592266) (xy 284.503263 -410.582136) (xy 284.450479 -410.564129)
			(xy 284.400879 -410.538628) (xy 284.355521 -410.506177) (xy 284.315372 -410.467468) (xy 284.281286 -410.423325)
			(xy 284.25399 -410.37469) (xy 284.234067 -410.322599) (xy 284.221941 -410.268162) (xy 284.21787 -410.21254)
			(xy 283.794682 -410.21254) (xy 283.794682 -410.239748) (xy 283.786926 -410.293689) (xy 283.771573 -410.345978)
			(xy 283.748935 -410.395549) (xy 283.719473 -410.441394) (xy 283.683786 -410.48258) (xy 283.642601 -410.518268)
			(xy 283.596756 -410.547731) (xy 283.547185 -410.57037) (xy 283.494897 -410.585725) (xy 283.440956 -410.593481)
			(xy 283.413708 -410.594048) (xy 283.384934 -410.593524) (xy 283.328039 -410.584878) (xy 283.273089 -410.567782)
			(xy 283.221332 -410.542623) (xy 283.173942 -410.509972) (xy 283.152596 -410.49067) (xy 283.141476 -410.480905)
			(xy 283.115022 -410.467666) (xy 283.085884 -410.462559) (xy 283.056504 -410.466014) (xy 283.029346 -410.477739)
			(xy 283.006684 -410.496753) (xy 282.990418 -410.521461) (xy 282.981912 -410.549794) (xy 282.9814 -410.564584)
			(xy 282.9814 -411.2895) (xy 293.757602 -411.2895) (xy 293.761673 -411.233878) (xy 293.773799 -411.179441)
			(xy 293.793722 -411.12735) (xy 293.821018 -411.078715) (xy 293.855104 -411.034572) (xy 293.895253 -410.995863)
			(xy 293.940611 -410.963412) (xy 293.990211 -410.937911) (xy 294.042995 -410.919904) (xy 294.097838 -410.909774)
			(xy 294.153572 -410.907737) (xy 294.209009 -410.913837) (xy 294.262966 -410.927943) (xy 294.314295 -410.949755)
			(xy 294.361901 -410.978809) (xy 294.404769 -411.014484) (xy 294.441986 -411.056021) (xy 294.472759 -411.102534)
			(xy 294.496431 -411.153031) (xy 294.512499 -411.206438) (xy 294.520619 -411.261614) (xy 294.521128 -411.2895)
			(xy 294.520619 -411.317386) (xy 294.512499 -411.372562) (xy 294.496431 -411.425969) (xy 294.472759 -411.476466)
			(xy 294.441986 -411.522979) (xy 294.404769 -411.564516) (xy 294.361901 -411.600191) (xy 294.314295 -411.629245)
			(xy 294.306871 -411.6324) (xy 295.266362 -411.6324) (xy 295.270433 -411.576778) (xy 295.282559 -411.522341)
			(xy 295.302482 -411.47025) (xy 295.329778 -411.421615) (xy 295.363864 -411.377472) (xy 295.404013 -411.338763)
			(xy 295.449371 -411.306312) (xy 295.498971 -411.280811) (xy 295.551755 -411.262804) (xy 295.606598 -411.252674)
			(xy 295.662332 -411.250637) (xy 295.717769 -411.256737) (xy 295.771726 -411.270843) (xy 295.823055 -411.292655)
			(xy 295.870661 -411.321709) (xy 295.913529 -411.357384) (xy 295.950746 -411.398921) (xy 295.981519 -411.445434)
			(xy 296.005191 -411.495931) (xy 296.021259 -411.549338) (xy 296.029379 -411.604514) (xy 296.029888 -411.6324)
			(xy 296.029379 -411.660286) (xy 296.021259 -411.715462) (xy 296.005191 -411.768869) (xy 295.981519 -411.819366)
			(xy 295.950746 -411.865879) (xy 295.913529 -411.907416) (xy 295.870661 -411.943091) (xy 295.823055 -411.972145)
			(xy 295.771726 -411.993957) (xy 295.717769 -412.008063) (xy 295.662332 -412.014163) (xy 295.606598 -412.012126)
			(xy 295.551755 -412.001996) (xy 295.498971 -411.983989) (xy 295.449371 -411.958488) (xy 295.404013 -411.926037)
			(xy 295.363864 -411.887328) (xy 295.329778 -411.843185) (xy 295.302482 -411.79455) (xy 295.282559 -411.742459)
			(xy 295.270433 -411.688022) (xy 295.266362 -411.6324) (xy 294.306871 -411.6324) (xy 294.262966 -411.651057)
			(xy 294.209009 -411.665163) (xy 294.153572 -411.671263) (xy 294.097838 -411.669226) (xy 294.042995 -411.659096)
			(xy 293.990211 -411.641089) (xy 293.940611 -411.615588) (xy 293.895253 -411.583137) (xy 293.855104 -411.544428)
			(xy 293.821018 -411.500285) (xy 293.793722 -411.45165) (xy 293.773799 -411.399559) (xy 293.761673 -411.345122)
			(xy 293.757602 -411.2895) (xy 282.9814 -411.2895) (xy 282.9814 -411.696154) (xy 289.02355 -411.696154)
			(xy 289.027621 -411.640532) (xy 289.039747 -411.586095) (xy 289.05967 -411.534004) (xy 289.086966 -411.485369)
			(xy 289.121052 -411.441226) (xy 289.161201 -411.402517) (xy 289.206559 -411.370066) (xy 289.256159 -411.344565)
			(xy 289.308943 -411.326558) (xy 289.363786 -411.316428) (xy 289.41952 -411.314391) (xy 289.474957 -411.320491)
			(xy 289.528914 -411.334597) (xy 289.580243 -411.356409) (xy 289.627849 -411.385463) (xy 289.670717 -411.421138)
			(xy 289.707934 -411.462675) (xy 289.738707 -411.509188) (xy 289.762379 -411.559685) (xy 289.778447 -411.613092)
			(xy 289.786567 -411.668268) (xy 289.787076 -411.696154) (xy 289.786567 -411.72404) (xy 289.778447 -411.779216)
			(xy 289.762379 -411.832623) (xy 289.738707 -411.88312) (xy 289.707934 -411.929633) (xy 289.670717 -411.97117)
			(xy 289.627849 -412.006845) (xy 289.580243 -412.035899) (xy 289.528914 -412.057711) (xy 289.474957 -412.071817)
			(xy 289.41952 -412.077917) (xy 289.363786 -412.07588) (xy 289.308943 -412.06575) (xy 289.256159 -412.047743)
			(xy 289.206559 -412.022242) (xy 289.161201 -411.989791) (xy 289.121052 -411.951082) (xy 289.086966 -411.906939)
			(xy 289.05967 -411.858304) (xy 289.039747 -411.806213) (xy 289.027621 -411.751776) (xy 289.02355 -411.696154)
			(xy 282.9814 -411.696154) (xy 282.9814 -412.24708) (xy 297.440602 -412.24708) (xy 297.444673 -412.191458)
			(xy 297.456799 -412.137021) (xy 297.476722 -412.08493) (xy 297.504018 -412.036295) (xy 297.538104 -411.992152)
			(xy 297.578253 -411.953443) (xy 297.623611 -411.920992) (xy 297.673211 -411.895491) (xy 297.725995 -411.877484)
			(xy 297.780838 -411.867354) (xy 297.836572 -411.865317) (xy 297.892009 -411.871417) (xy 297.945966 -411.885523)
			(xy 297.997295 -411.907335) (xy 298.044901 -411.936389) (xy 298.087769 -411.972064) (xy 298.124986 -412.013601)
			(xy 298.155759 -412.060114) (xy 298.179431 -412.110611) (xy 298.195499 -412.164018) (xy 298.203619 -412.219194)
			(xy 298.204128 -412.24708) (xy 298.203619 -412.274966) (xy 298.195499 -412.330142) (xy 298.179431 -412.383549)
			(xy 298.155759 -412.434046) (xy 298.124986 -412.480559) (xy 298.087769 -412.522096) (xy 298.044901 -412.557771)
			(xy 297.997295 -412.586825) (xy 297.945966 -412.608637) (xy 297.892009 -412.622743) (xy 297.836572 -412.628843)
			(xy 297.780838 -412.626806) (xy 297.725995 -412.616676) (xy 297.673211 -412.598669) (xy 297.623611 -412.573168)
			(xy 297.578253 -412.540717) (xy 297.538104 -412.502008) (xy 297.504018 -412.457865) (xy 297.476722 -412.40923)
			(xy 297.456799 -412.357139) (xy 297.444673 -412.302702) (xy 297.440602 -412.24708) (xy 282.9814 -412.24708)
			(xy 282.9814 -412.86684) (xy 283.38221 -412.86684) (xy 283.386281 -412.811218) (xy 283.398407 -412.756781)
			(xy 283.41833 -412.70469) (xy 283.445626 -412.656055) (xy 283.479712 -412.611912) (xy 283.519861 -412.573203)
			(xy 283.565219 -412.540752) (xy 283.614819 -412.515251) (xy 283.667603 -412.497244) (xy 283.722446 -412.487114)
			(xy 283.77818 -412.485077) (xy 283.833617 -412.491177) (xy 283.887574 -412.505283) (xy 283.938903 -412.527095)
			(xy 283.986509 -412.556149) (xy 284.029377 -412.591824) (xy 284.066594 -412.633361) (xy 284.097367 -412.679874)
			(xy 284.121039 -412.730371) (xy 284.137107 -412.783778) (xy 284.145227 -412.838954) (xy 284.145736 -412.86684)
			(xy 284.145227 -412.894726) (xy 284.137107 -412.949902) (xy 284.1232 -412.996126) (xy 287.05251 -412.996126)
			(xy 287.056581 -412.940504) (xy 287.068707 -412.886067) (xy 287.08863 -412.833976) (xy 287.115926 -412.785341)
			(xy 287.150012 -412.741198) (xy 287.190161 -412.702489) (xy 287.235519 -412.670038) (xy 287.285119 -412.644537)
			(xy 287.337903 -412.62653) (xy 287.392746 -412.6164) (xy 287.44848 -412.614363) (xy 287.503917 -412.620463)
			(xy 287.557874 -412.634569) (xy 287.609203 -412.656381) (xy 287.621097 -412.66364) (xy 300.615602 -412.66364)
			(xy 300.619673 -412.608018) (xy 300.631799 -412.553581) (xy 300.651722 -412.50149) (xy 300.679018 -412.452855)
			(xy 300.713104 -412.408712) (xy 300.753253 -412.370003) (xy 300.798611 -412.337552) (xy 300.848211 -412.312051)
			(xy 300.900995 -412.294044) (xy 300.955838 -412.283914) (xy 301.011572 -412.281877) (xy 301.067009 -412.287977)
			(xy 301.120966 -412.302083) (xy 301.172295 -412.323895) (xy 301.219901 -412.352949) (xy 301.262769 -412.388624)
			(xy 301.299986 -412.430161) (xy 301.330759 -412.476674) (xy 301.354431 -412.527171) (xy 301.370499 -412.580578)
			(xy 301.378619 -412.635754) (xy 301.379128 -412.66364) (xy 301.378619 -412.691526) (xy 301.370499 -412.746702)
			(xy 301.354431 -412.800109) (xy 301.330759 -412.850606) (xy 301.299986 -412.897119) (xy 301.262769 -412.938656)
			(xy 301.219901 -412.974331) (xy 301.172295 -413.003385) (xy 301.120966 -413.025197) (xy 301.067009 -413.039303)
			(xy 301.011572 -413.045403) (xy 300.955838 -413.043366) (xy 300.900995 -413.033236) (xy 300.848211 -413.015229)
			(xy 300.798611 -412.989728) (xy 300.753253 -412.957277) (xy 300.713104 -412.918568) (xy 300.679018 -412.874425)
			(xy 300.651722 -412.82579) (xy 300.631799 -412.773699) (xy 300.619673 -412.719262) (xy 300.615602 -412.66364)
			(xy 287.621097 -412.66364) (xy 287.656809 -412.685435) (xy 287.699677 -412.72111) (xy 287.736894 -412.762647)
			(xy 287.767667 -412.80916) (xy 287.791339 -412.859657) (xy 287.807407 -412.913064) (xy 287.815527 -412.96824)
			(xy 287.816036 -412.996126) (xy 287.815527 -413.024012) (xy 287.807407 -413.079188) (xy 287.791339 -413.132595)
			(xy 287.767667 -413.183092) (xy 287.736894 -413.229605) (xy 287.699677 -413.271142) (xy 287.656809 -413.306817)
			(xy 287.609203 -413.335871) (xy 287.557874 -413.357683) (xy 287.503917 -413.371789) (xy 287.44848 -413.377889)
			(xy 287.392746 -413.375852) (xy 287.337903 -413.365722) (xy 287.285119 -413.347715) (xy 287.235519 -413.322214)
			(xy 287.190161 -413.289763) (xy 287.150012 -413.251054) (xy 287.115926 -413.206911) (xy 287.08863 -413.158276)
			(xy 287.068707 -413.106185) (xy 287.056581 -413.051748) (xy 287.05251 -412.996126) (xy 284.1232 -412.996126)
			(xy 284.121039 -413.003309) (xy 284.097367 -413.053806) (xy 284.066594 -413.100319) (xy 284.029377 -413.141856)
			(xy 283.986509 -413.177531) (xy 283.938903 -413.206585) (xy 283.887574 -413.228397) (xy 283.833617 -413.242503)
			(xy 283.77818 -413.248603) (xy 283.722446 -413.246566) (xy 283.667603 -413.236436) (xy 283.614819 -413.218429)
			(xy 283.565219 -413.192928) (xy 283.519861 -413.160477) (xy 283.479712 -413.121768) (xy 283.445626 -413.077625)
			(xy 283.41833 -413.02899) (xy 283.398407 -412.976899) (xy 283.386281 -412.922462) (xy 283.38221 -412.86684)
			(xy 282.9814 -412.86684) (xy 282.9814 -413.178752) (xy 283.005167 -413.19366) (xy 283.048456 -413.229347)
			(xy 283.086058 -413.270983) (xy 283.117164 -413.317672) (xy 283.141105 -413.368409) (xy 283.157365 -413.422104)
			(xy 283.165595 -413.477599) (xy 283.166058 -413.50565) (xy 283.16549 -413.535414) (xy 283.156248 -413.594221)
			(xy 283.143039 -413.63519) (xy 285.97174 -413.63519) (xy 285.975811 -413.579568) (xy 285.987937 -413.525131)
			(xy 286.00786 -413.47304) (xy 286.035156 -413.424405) (xy 286.069242 -413.380262) (xy 286.109391 -413.341553)
			(xy 286.154749 -413.309102) (xy 286.204349 -413.283601) (xy 286.257133 -413.265594) (xy 286.311976 -413.255464)
			(xy 286.36771 -413.253427) (xy 286.423147 -413.259527) (xy 286.477104 -413.273633) (xy 286.528433 -413.295445)
			(xy 286.576039 -413.324499) (xy 286.618907 -413.360174) (xy 286.656124 -413.401711) (xy 286.686897 -413.448224)
			(xy 286.710569 -413.498721) (xy 286.726637 -413.552128) (xy 286.734757 -413.607304) (xy 286.735266 -413.63519)
			(xy 286.734757 -413.663076) (xy 286.726637 -413.718252) (xy 286.725263 -413.72282) (xy 295.484802 -413.72282)
			(xy 295.488873 -413.667198) (xy 295.500999 -413.612761) (xy 295.520922 -413.56067) (xy 295.548218 -413.512035)
			(xy 295.582304 -413.467892) (xy 295.622453 -413.429183) (xy 295.667811 -413.396732) (xy 295.717411 -413.371231)
			(xy 295.770195 -413.353224) (xy 295.825038 -413.343094) (xy 295.880772 -413.341057) (xy 295.936209 -413.347157)
			(xy 295.990166 -413.361263) (xy 296.041495 -413.383075) (xy 296.048811 -413.38754) (xy 298.550582 -413.38754)
			(xy 298.554653 -413.331918) (xy 298.566779 -413.277481) (xy 298.586702 -413.22539) (xy 298.613998 -413.176755)
			(xy 298.648084 -413.132612) (xy 298.688233 -413.093903) (xy 298.733591 -413.061452) (xy 298.783191 -413.035951)
			(xy 298.835975 -413.017944) (xy 298.890818 -413.007814) (xy 298.946552 -413.005777) (xy 299.001989 -413.011877)
			(xy 299.055946 -413.025983) (xy 299.107275 -413.047795) (xy 299.154881 -413.076849) (xy 299.197749 -413.112524)
			(xy 299.234966 -413.154061) (xy 299.265739 -413.200574) (xy 299.289411 -413.251071) (xy 299.305479 -413.304478)
			(xy 299.313599 -413.359654) (xy 299.314108 -413.38754) (xy 299.313599 -413.415426) (xy 299.306863 -413.4612)
			(xy 304.265582 -413.4612) (xy 304.269653 -413.405578) (xy 304.281779 -413.351141) (xy 304.301702 -413.29905)
			(xy 304.328998 -413.250415) (xy 304.363084 -413.206272) (xy 304.403233 -413.167563) (xy 304.448591 -413.135112)
			(xy 304.498191 -413.109611) (xy 304.550975 -413.091604) (xy 304.605818 -413.081474) (xy 304.661552 -413.079437)
			(xy 304.716989 -413.085537) (xy 304.770946 -413.099643) (xy 304.822275 -413.121455) (xy 304.869881 -413.150509)
			(xy 304.912749 -413.186184) (xy 304.949966 -413.227721) (xy 304.980739 -413.274234) (xy 305.004411 -413.324731)
			(xy 305.020479 -413.378138) (xy 305.028599 -413.433314) (xy 305.029108 -413.4612) (xy 305.028599 -413.489086)
			(xy 305.020479 -413.544262) (xy 305.004411 -413.597669) (xy 304.980739 -413.648166) (xy 304.949966 -413.694679)
			(xy 304.912749 -413.736216) (xy 304.869881 -413.771891) (xy 304.822275 -413.800945) (xy 304.770946 -413.822757)
			(xy 304.716989 -413.836863) (xy 304.661552 -413.842963) (xy 304.605818 -413.840926) (xy 304.550975 -413.830796)
			(xy 304.498191 -413.812789) (xy 304.448591 -413.787288) (xy 304.403233 -413.754837) (xy 304.363084 -413.716128)
			(xy 304.328998 -413.671985) (xy 304.301702 -413.62335) (xy 304.281779 -413.571259) (xy 304.269653 -413.516822)
			(xy 304.265582 -413.4612) (xy 299.306863 -413.4612) (xy 299.305479 -413.470602) (xy 299.289411 -413.524009)
			(xy 299.265739 -413.574506) (xy 299.234966 -413.621019) (xy 299.197749 -413.662556) (xy 299.154881 -413.698231)
			(xy 299.107275 -413.727285) (xy 299.055946 -413.749097) (xy 299.001989 -413.763203) (xy 298.946552 -413.769303)
			(xy 298.890818 -413.767266) (xy 298.835975 -413.757136) (xy 298.783191 -413.739129) (xy 298.733591 -413.713628)
			(xy 298.688233 -413.681177) (xy 298.648084 -413.642468) (xy 298.613998 -413.598325) (xy 298.586702 -413.54969)
			(xy 298.566779 -413.497599) (xy 298.554653 -413.443162) (xy 298.550582 -413.38754) (xy 296.048811 -413.38754)
			(xy 296.089101 -413.412129) (xy 296.131969 -413.447804) (xy 296.169186 -413.489341) (xy 296.199959 -413.535854)
			(xy 296.223631 -413.586351) (xy 296.239699 -413.639758) (xy 296.247819 -413.694934) (xy 296.248328 -413.72282)
			(xy 296.247819 -413.750706) (xy 296.239699 -413.805882) (xy 296.223631 -413.859289) (xy 296.199959 -413.909786)
			(xy 296.169186 -413.956299) (xy 296.131969 -413.997836) (xy 296.089101 -414.033511) (xy 296.041495 -414.062565)
			(xy 295.990166 -414.084377) (xy 295.936209 -414.098483) (xy 295.880772 -414.104583) (xy 295.825038 -414.102546)
			(xy 295.770195 -414.092416) (xy 295.717411 -414.074409) (xy 295.667811 -414.048908) (xy 295.622453 -414.016457)
			(xy 295.582304 -413.977748) (xy 295.548218 -413.933605) (xy 295.520922 -413.88497) (xy 295.500999 -413.832879)
			(xy 295.488873 -413.778442) (xy 295.484802 -413.72282) (xy 286.725263 -413.72282) (xy 286.710569 -413.771659)
			(xy 286.686897 -413.822156) (xy 286.656124 -413.868669) (xy 286.618907 -413.910206) (xy 286.576039 -413.945881)
			(xy 286.528433 -413.974935) (xy 286.477104 -413.996747) (xy 286.423147 -414.010853) (xy 286.36771 -414.016953)
			(xy 286.311976 -414.014916) (xy 286.257133 -414.004786) (xy 286.204349 -413.986779) (xy 286.154749 -413.961278)
			(xy 286.109391 -413.928827) (xy 286.069242 -413.890118) (xy 286.035156 -413.845975) (xy 286.00786 -413.79734)
			(xy 285.987937 -413.745249) (xy 285.975811 -413.690812) (xy 285.97174 -413.63519) (xy 283.143039 -413.63519)
			(xy 283.137981 -413.650877) (xy 283.111133 -413.704007) (xy 283.076355 -413.752319) (xy 283.055822 -413.773874)
			(xy 283.046817 -413.78362) (xy 283.033696 -413.806673) (xy 283.02696 -413.832329) (xy 283.027062 -413.858854)
			(xy 283.033997 -413.884457) (xy 283.047296 -413.907408) (xy 283.05633 -413.91713) (xy 283.718 -414.5788)
			(xy 292.989 -414.5788) (xy 293.19474 -414.78454) (xy 300.615602 -414.78454) (xy 300.619673 -414.728918)
			(xy 300.631799 -414.674481) (xy 300.651722 -414.62239) (xy 300.679018 -414.573755) (xy 300.713104 -414.529612)
			(xy 300.753253 -414.490903) (xy 300.798611 -414.458452) (xy 300.848211 -414.432951) (xy 300.900995 -414.414944)
			(xy 300.955838 -414.404814) (xy 301.011572 -414.402777) (xy 301.067009 -414.408877) (xy 301.120966 -414.422983)
			(xy 301.172295 -414.444795) (xy 301.219901 -414.473849) (xy 301.262769 -414.509524) (xy 301.299986 -414.551061)
			(xy 301.330759 -414.597574) (xy 301.354431 -414.648071) (xy 301.370499 -414.701478) (xy 301.378619 -414.756654)
			(xy 301.379128 -414.78454) (xy 301.378619 -414.812426) (xy 301.370499 -414.867602) (xy 301.354431 -414.921009)
			(xy 301.330759 -414.971506) (xy 301.32338 -414.98266) (xy 304.824382 -414.98266) (xy 304.828453 -414.927038)
			(xy 304.840579 -414.872601) (xy 304.860502 -414.82051) (xy 304.887798 -414.771875) (xy 304.921884 -414.727732)
			(xy 304.962033 -414.689023) (xy 305.007391 -414.656572) (xy 305.056991 -414.631071) (xy 305.109775 -414.613064)
			(xy 305.164618 -414.602934) (xy 305.220352 -414.600897) (xy 305.275789 -414.606997) (xy 305.329746 -414.621103)
			(xy 305.381075 -414.642915) (xy 305.428681 -414.671969) (xy 305.471549 -414.707644) (xy 305.508766 -414.749181)
			(xy 305.539539 -414.795694) (xy 305.563211 -414.846191) (xy 305.579279 -414.899598) (xy 305.587399 -414.954774)
			(xy 305.587908 -414.98266) (xy 305.587399 -415.010546) (xy 305.579279 -415.065722) (xy 305.563211 -415.119129)
			(xy 305.539539 -415.169626) (xy 305.508766 -415.216139) (xy 305.471549 -415.257676) (xy 305.428681 -415.293351)
			(xy 305.381075 -415.322405) (xy 305.329746 -415.344217) (xy 305.275789 -415.358323) (xy 305.220352 -415.364423)
			(xy 305.164618 -415.362386) (xy 305.109775 -415.352256) (xy 305.056991 -415.334249) (xy 305.007391 -415.308748)
			(xy 304.962033 -415.276297) (xy 304.921884 -415.237588) (xy 304.887798 -415.193445) (xy 304.860502 -415.14481)
			(xy 304.840579 -415.092719) (xy 304.828453 -415.038282) (xy 304.824382 -414.98266) (xy 301.32338 -414.98266)
			(xy 301.299986 -415.018019) (xy 301.262769 -415.059556) (xy 301.219901 -415.095231) (xy 301.172295 -415.124285)
			(xy 301.120966 -415.146097) (xy 301.067009 -415.160203) (xy 301.011572 -415.166303) (xy 300.955838 -415.164266)
			(xy 300.900995 -415.154136) (xy 300.848211 -415.136129) (xy 300.798611 -415.110628) (xy 300.753253 -415.078177)
			(xy 300.713104 -415.039468) (xy 300.679018 -414.995325) (xy 300.651722 -414.94669) (xy 300.631799 -414.894599)
			(xy 300.619673 -414.840162) (xy 300.615602 -414.78454) (xy 293.19474 -414.78454) (xy 294.0304 -415.6202)
			(xy 294.0304 -416.56) (xy 300.861982 -416.56) (xy 300.866053 -416.504378) (xy 300.878179 -416.449941)
			(xy 300.898102 -416.39785) (xy 300.925398 -416.349215) (xy 300.959484 -416.305072) (xy 300.999633 -416.266363)
			(xy 301.044991 -416.233912) (xy 301.094591 -416.208411) (xy 301.147375 -416.190404) (xy 301.202218 -416.180274)
			(xy 301.257952 -416.178237) (xy 301.313389 -416.184337) (xy 301.367346 -416.198443) (xy 301.418675 -416.220255)
			(xy 301.466281 -416.249309) (xy 301.509149 -416.284984) (xy 301.546366 -416.326521) (xy 301.577139 -416.373034)
			(xy 301.600811 -416.423531) (xy 301.616879 -416.476938) (xy 301.624999 -416.532114) (xy 301.625508 -416.56)
			(xy 301.624999 -416.587886) (xy 301.616879 -416.643062) (xy 301.600811 -416.696469) (xy 301.577139 -416.746966)
			(xy 301.546366 -416.793479) (xy 301.509149 -416.835016) (xy 301.466281 -416.870691) (xy 301.418675 -416.899745)
			(xy 301.367346 -416.921557) (xy 301.313389 -416.935663) (xy 301.257952 -416.941763) (xy 301.202218 -416.939726)
			(xy 301.147375 -416.929596) (xy 301.094591 -416.911589) (xy 301.044991 -416.886088) (xy 300.999633 -416.853637)
			(xy 300.959484 -416.814928) (xy 300.925398 -416.770785) (xy 300.898102 -416.72215) (xy 300.878179 -416.670059)
			(xy 300.866053 -416.615622) (xy 300.861982 -416.56) (xy 294.0304 -416.56) (xy 294.0304 -416.744404)
			(xy 294.030902 -416.759175) (xy 294.039363 -416.787479) (xy 294.055575 -416.812175) (xy 294.078181 -416.831194)
			(xy 294.105286 -416.842942) (xy 294.13462 -416.846437) (xy 294.149272 -416.84448) (xy 294.165464 -416.841858)
			(xy 294.198148 -416.83906) (xy 294.21455 -416.838892) (xy 294.241805 -416.839352) (xy 294.295762 -416.847103)
			(xy 294.348065 -416.862455) (xy 294.397652 -416.885094) (xy 294.443511 -416.914561) (xy 294.48471 -416.950255)
			(xy 294.520409 -416.991449) (xy 294.549882 -417.037304) (xy 294.572528 -417.086888) (xy 294.587886 -417.13919)
			(xy 294.595645 -417.193145) (xy 294.595645 -417.2204) (xy 296.626532 -417.2204) (xy 296.630603 -417.164778)
			(xy 296.642729 -417.110341) (xy 296.662652 -417.05825) (xy 296.689948 -417.009615) (xy 296.724034 -416.965472)
			(xy 296.764183 -416.926763) (xy 296.809541 -416.894312) (xy 296.859141 -416.868811) (xy 296.911925 -416.850804)
			(xy 296.966768 -416.840674) (xy 297.022502 -416.838637) (xy 297.077939 -416.844737) (xy 297.131896 -416.858843)
			(xy 297.183225 -416.880655) (xy 297.230831 -416.909709) (xy 297.273699 -416.945384) (xy 297.310916 -416.986921)
			(xy 297.341689 -417.033434) (xy 297.365361 -417.083931) (xy 297.381429 -417.137338) (xy 297.389549 -417.192514)
			(xy 297.390058 -417.2204) (xy 299.420532 -417.2204) (xy 299.424603 -417.164778) (xy 299.436729 -417.110341)
			(xy 299.456652 -417.05825) (xy 299.483948 -417.009615) (xy 299.518034 -416.965472) (xy 299.558183 -416.926763)
			(xy 299.603541 -416.894312) (xy 299.653141 -416.868811) (xy 299.705925 -416.850804) (xy 299.760768 -416.840674)
			(xy 299.816502 -416.838637) (xy 299.871939 -416.844737) (xy 299.925896 -416.858843) (xy 299.977225 -416.880655)
			(xy 300.024831 -416.909709) (xy 300.067699 -416.945384) (xy 300.104916 -416.986921) (xy 300.135689 -417.033434)
			(xy 300.159361 -417.083931) (xy 300.175429 -417.137338) (xy 300.183549 -417.192514) (xy 300.184058 -417.2204)
			(xy 300.183549 -417.248286) (xy 300.176065 -417.29914) (xy 302.105312 -417.29914) (xy 302.109383 -417.243518)
			(xy 302.121509 -417.189081) (xy 302.141432 -417.13699) (xy 302.168728 -417.088355) (xy 302.202814 -417.044212)
			(xy 302.242963 -417.005503) (xy 302.288321 -416.973052) (xy 302.337921 -416.947551) (xy 302.390705 -416.929544)
			(xy 302.445548 -416.919414) (xy 302.501282 -416.917377) (xy 302.556719 -416.923477) (xy 302.610676 -416.937583)
			(xy 302.662005 -416.959395) (xy 302.709611 -416.988449) (xy 302.752479 -417.024124) (xy 302.789696 -417.065661)
			(xy 302.820469 -417.112174) (xy 302.844141 -417.162671) (xy 302.860209 -417.216078) (xy 302.868329 -417.271254)
			(xy 302.868838 -417.29914) (xy 302.868329 -417.327026) (xy 302.860209 -417.382202) (xy 302.844141 -417.435609)
			(xy 302.820469 -417.486106) (xy 302.789696 -417.532619) (xy 302.752479 -417.574156) (xy 302.709611 -417.609831)
			(xy 302.662005 -417.638885) (xy 302.610676 -417.660697) (xy 302.556719 -417.674803) (xy 302.501282 -417.680903)
			(xy 302.445548 -417.678866) (xy 302.390705 -417.668736) (xy 302.337921 -417.650729) (xy 302.288321 -417.625228)
			(xy 302.242963 -417.592777) (xy 302.202814 -417.554068) (xy 302.168728 -417.509925) (xy 302.141432 -417.46129)
			(xy 302.121509 -417.409199) (xy 302.109383 -417.354762) (xy 302.105312 -417.29914) (xy 300.176065 -417.29914)
			(xy 300.175429 -417.303462) (xy 300.159361 -417.356869) (xy 300.135689 -417.407366) (xy 300.104916 -417.453879)
			(xy 300.067699 -417.495416) (xy 300.024831 -417.531091) (xy 299.977225 -417.560145) (xy 299.925896 -417.581957)
			(xy 299.871939 -417.596063) (xy 299.816502 -417.602163) (xy 299.760768 -417.600126) (xy 299.705925 -417.589996)
			(xy 299.653141 -417.571989) (xy 299.603541 -417.546488) (xy 299.558183 -417.514037) (xy 299.518034 -417.475328)
			(xy 299.483948 -417.431185) (xy 299.456652 -417.38255) (xy 299.436729 -417.330459) (xy 299.424603 -417.276022)
			(xy 299.420532 -417.2204) (xy 297.390058 -417.2204) (xy 297.389549 -417.248286) (xy 297.381429 -417.303462)
			(xy 297.365361 -417.356869) (xy 297.341689 -417.407366) (xy 297.310916 -417.453879) (xy 297.273699 -417.495416)
			(xy 297.230831 -417.531091) (xy 297.183225 -417.560145) (xy 297.131896 -417.581957) (xy 297.077939 -417.596063)
			(xy 297.022502 -417.602163) (xy 296.966768 -417.600126) (xy 296.911925 -417.589996) (xy 296.859141 -417.571989)
			(xy 296.809541 -417.546488) (xy 296.764183 -417.514037) (xy 296.724034 -417.475328) (xy 296.689948 -417.431185)
			(xy 296.662652 -417.38255) (xy 296.642729 -417.330459) (xy 296.630603 -417.276022) (xy 296.626532 -417.2204)
			(xy 294.595645 -417.2204) (xy 294.595645 -417.247655) (xy 294.587886 -417.30161) (xy 294.572528 -417.353912)
			(xy 294.549882 -417.403496) (xy 294.520409 -417.449351) (xy 294.48471 -417.490545) (xy 294.443511 -417.526239)
			(xy 294.397652 -417.555706) (xy 294.348065 -417.578345) (xy 294.295762 -417.593697) (xy 294.241805 -417.601448)
			(xy 294.21455 -417.601908) (xy 294.198148 -417.601747) (xy 294.165464 -417.598945) (xy 294.149272 -417.59632)
			(xy 294.134626 -417.594302) (xy 294.105284 -417.59782) (xy 294.078175 -417.609585) (xy 294.055563 -417.628612)
			(xy 294.039338 -417.653312) (xy 294.030857 -417.68162) (xy 294.0304 -417.696396) (xy 294.0304 -417.990528)
			(xy 294.240202 -417.990528) (xy 294.244273 -417.934906) (xy 294.256399 -417.880469) (xy 294.276322 -417.828378)
			(xy 294.303618 -417.779743) (xy 294.337704 -417.7356) (xy 294.377853 -417.696891) (xy 294.423211 -417.66444)
			(xy 294.472811 -417.638939) (xy 294.525595 -417.620932) (xy 294.580438 -417.610802) (xy 294.636172 -417.608765)
			(xy 294.691609 -417.614865) (xy 294.745566 -417.628971) (xy 294.796895 -417.650783) (xy 294.844501 -417.679837)
			(xy 294.887369 -417.715512) (xy 294.924586 -417.757049) (xy 294.955359 -417.803562) (xy 294.979031 -417.854059)
			(xy 294.995099 -417.907466) (xy 295.003219 -417.962642) (xy 295.003728 -417.990528) (xy 295.484802 -417.990528)
			(xy 295.488873 -417.934906) (xy 295.500999 -417.880469) (xy 295.520922 -417.828378) (xy 295.548218 -417.779743)
			(xy 295.582304 -417.7356) (xy 295.622453 -417.696891) (xy 295.667811 -417.66444) (xy 295.717411 -417.638939)
			(xy 295.770195 -417.620932) (xy 295.825038 -417.610802) (xy 295.880772 -417.608765) (xy 295.936209 -417.614865)
			(xy 295.990166 -417.628971) (xy 296.041495 -417.650783) (xy 296.089101 -417.679837) (xy 296.131969 -417.715512)
			(xy 296.169186 -417.757049) (xy 296.199959 -417.803562) (xy 296.223631 -417.854059) (xy 296.239699 -417.907466)
			(xy 296.247819 -417.962642) (xy 296.248328 -417.990528) (xy 297.034202 -417.990528) (xy 297.038273 -417.934906)
			(xy 297.050399 -417.880469) (xy 297.070322 -417.828378) (xy 297.097618 -417.779743) (xy 297.131704 -417.7356)
			(xy 297.171853 -417.696891) (xy 297.217211 -417.66444) (xy 297.266811 -417.638939) (xy 297.319595 -417.620932)
			(xy 297.374438 -417.610802) (xy 297.430172 -417.608765) (xy 297.485609 -417.614865) (xy 297.539566 -417.628971)
			(xy 297.590895 -417.650783) (xy 297.638501 -417.679837) (xy 297.681369 -417.715512) (xy 297.718586 -417.757049)
			(xy 297.749359 -417.803562) (xy 297.773031 -417.854059) (xy 297.789099 -417.907466) (xy 297.797219 -417.962642)
			(xy 297.797728 -417.990528) (xy 298.278802 -417.990528) (xy 298.282873 -417.934906) (xy 298.294999 -417.880469)
			(xy 298.314922 -417.828378) (xy 298.342218 -417.779743) (xy 298.376304 -417.7356) (xy 298.416453 -417.696891)
			(xy 298.461811 -417.66444) (xy 298.511411 -417.638939) (xy 298.564195 -417.620932) (xy 298.619038 -417.610802)
			(xy 298.674772 -417.608765) (xy 298.730209 -417.614865) (xy 298.784166 -417.628971) (xy 298.835495 -417.650783)
			(xy 298.883101 -417.679837) (xy 298.925969 -417.715512) (xy 298.963186 -417.757049) (xy 298.993959 -417.803562)
			(xy 299.017631 -417.854059) (xy 299.033699 -417.907466) (xy 299.041819 -417.962642) (xy 299.042328 -417.990528)
			(xy 299.828202 -417.990528) (xy 299.832273 -417.934906) (xy 299.844399 -417.880469) (xy 299.864322 -417.828378)
			(xy 299.891618 -417.779743) (xy 299.925704 -417.7356) (xy 299.965853 -417.696891) (xy 300.011211 -417.66444)
			(xy 300.060811 -417.638939) (xy 300.113595 -417.620932) (xy 300.168438 -417.610802) (xy 300.224172 -417.608765)
			(xy 300.279609 -417.614865) (xy 300.333566 -417.628971) (xy 300.384895 -417.650783) (xy 300.432501 -417.679837)
			(xy 300.475369 -417.715512) (xy 300.512586 -417.757049) (xy 300.543359 -417.803562) (xy 300.567031 -417.854059)
			(xy 300.583099 -417.907466) (xy 300.591219 -417.962642) (xy 300.591728 -417.990528) (xy 301.072802 -417.990528)
			(xy 301.076873 -417.934906) (xy 301.088999 -417.880469) (xy 301.108922 -417.828378) (xy 301.136218 -417.779743)
			(xy 301.170304 -417.7356) (xy 301.210453 -417.696891) (xy 301.255811 -417.66444) (xy 301.305411 -417.638939)
			(xy 301.358195 -417.620932) (xy 301.413038 -417.610802) (xy 301.468772 -417.608765) (xy 301.524209 -417.614865)
			(xy 301.578166 -417.628971) (xy 301.629495 -417.650783) (xy 301.677101 -417.679837) (xy 301.719969 -417.715512)
			(xy 301.757186 -417.757049) (xy 301.787959 -417.803562) (xy 301.811631 -417.854059) (xy 301.827699 -417.907466)
			(xy 301.835819 -417.962642) (xy 301.836328 -417.990528) (xy 301.835819 -418.018414) (xy 301.828335 -418.069268)
			(xy 302.512982 -418.069268) (xy 302.517053 -418.013646) (xy 302.529179 -417.959209) (xy 302.549102 -417.907118)
			(xy 302.576398 -417.858483) (xy 302.610484 -417.81434) (xy 302.650633 -417.775631) (xy 302.695991 -417.74318)
			(xy 302.745591 -417.717679) (xy 302.798375 -417.699672) (xy 302.853218 -417.689542) (xy 302.908952 -417.687505)
			(xy 302.964389 -417.693605) (xy 303.018346 -417.707711) (xy 303.069675 -417.729523) (xy 303.117281 -417.758577)
			(xy 303.160149 -417.794252) (xy 303.197366 -417.835789) (xy 303.228139 -417.882302) (xy 303.251811 -417.932799)
			(xy 303.267879 -417.986206) (xy 303.275999 -418.041382) (xy 303.276508 -418.069268) (xy 303.757582 -418.069268)
			(xy 303.761653 -418.013646) (xy 303.773779 -417.959209) (xy 303.793702 -417.907118) (xy 303.820998 -417.858483)
			(xy 303.855084 -417.81434) (xy 303.895233 -417.775631) (xy 303.940591 -417.74318) (xy 303.990191 -417.717679)
			(xy 304.042975 -417.699672) (xy 304.097818 -417.689542) (xy 304.153552 -417.687505) (xy 304.208989 -417.693605)
			(xy 304.262946 -417.707711) (xy 304.314275 -417.729523) (xy 304.361881 -417.758577) (xy 304.404749 -417.794252)
			(xy 304.441966 -417.835789) (xy 304.472739 -417.882302) (xy 304.496411 -417.932799) (xy 304.512479 -417.986206)
			(xy 304.520599 -418.041382) (xy 304.521108 -418.069268) (xy 304.520599 -418.097154) (xy 304.512479 -418.15233)
			(xy 304.496411 -418.205737) (xy 304.472739 -418.256234) (xy 304.441966 -418.302747) (xy 304.404749 -418.344284)
			(xy 304.361881 -418.379959) (xy 304.314275 -418.409013) (xy 304.262946 -418.430825) (xy 304.208989 -418.444931)
			(xy 304.153552 -418.451031) (xy 304.097818 -418.448994) (xy 304.042975 -418.438864) (xy 303.990191 -418.420857)
			(xy 303.940591 -418.395356) (xy 303.895233 -418.362905) (xy 303.855084 -418.324196) (xy 303.820998 -418.280053)
			(xy 303.793702 -418.231418) (xy 303.773779 -418.179327) (xy 303.761653 -418.12489) (xy 303.757582 -418.069268)
			(xy 303.276508 -418.069268) (xy 303.275999 -418.097154) (xy 303.267879 -418.15233) (xy 303.251811 -418.205737)
			(xy 303.228139 -418.256234) (xy 303.197366 -418.302747) (xy 303.160149 -418.344284) (xy 303.117281 -418.379959)
			(xy 303.069675 -418.409013) (xy 303.018346 -418.430825) (xy 302.964389 -418.444931) (xy 302.908952 -418.451031)
			(xy 302.853218 -418.448994) (xy 302.798375 -418.438864) (xy 302.745591 -418.420857) (xy 302.695991 -418.395356)
			(xy 302.650633 -418.362905) (xy 302.610484 -418.324196) (xy 302.576398 -418.280053) (xy 302.549102 -418.231418)
			(xy 302.529179 -418.179327) (xy 302.517053 -418.12489) (xy 302.512982 -418.069268) (xy 301.828335 -418.069268)
			(xy 301.827699 -418.07359) (xy 301.811631 -418.126997) (xy 301.787959 -418.177494) (xy 301.757186 -418.224007)
			(xy 301.719969 -418.265544) (xy 301.677101 -418.301219) (xy 301.629495 -418.330273) (xy 301.578166 -418.352085)
			(xy 301.524209 -418.366191) (xy 301.468772 -418.372291) (xy 301.413038 -418.370254) (xy 301.358195 -418.360124)
			(xy 301.305411 -418.342117) (xy 301.255811 -418.316616) (xy 301.210453 -418.284165) (xy 301.170304 -418.245456)
			(xy 301.136218 -418.201313) (xy 301.108922 -418.152678) (xy 301.088999 -418.100587) (xy 301.076873 -418.04615)
			(xy 301.072802 -417.990528) (xy 300.591728 -417.990528) (xy 300.591219 -418.018414) (xy 300.583099 -418.07359)
			(xy 300.567031 -418.126997) (xy 300.543359 -418.177494) (xy 300.512586 -418.224007) (xy 300.475369 -418.265544)
			(xy 300.432501 -418.301219) (xy 300.384895 -418.330273) (xy 300.333566 -418.352085) (xy 300.279609 -418.366191)
			(xy 300.224172 -418.372291) (xy 300.168438 -418.370254) (xy 300.113595 -418.360124) (xy 300.060811 -418.342117)
			(xy 300.011211 -418.316616) (xy 299.965853 -418.284165) (xy 299.925704 -418.245456) (xy 299.891618 -418.201313)
			(xy 299.864322 -418.152678) (xy 299.844399 -418.100587) (xy 299.832273 -418.04615) (xy 299.828202 -417.990528)
			(xy 299.042328 -417.990528) (xy 299.041819 -418.018414) (xy 299.033699 -418.07359) (xy 299.017631 -418.126997)
			(xy 298.993959 -418.177494) (xy 298.963186 -418.224007) (xy 298.925969 -418.265544) (xy 298.883101 -418.301219)
			(xy 298.835495 -418.330273) (xy 298.784166 -418.352085) (xy 298.730209 -418.366191) (xy 298.674772 -418.372291)
			(xy 298.619038 -418.370254) (xy 298.564195 -418.360124) (xy 298.511411 -418.342117) (xy 298.461811 -418.316616)
			(xy 298.416453 -418.284165) (xy 298.376304 -418.245456) (xy 298.342218 -418.201313) (xy 298.314922 -418.152678)
			(xy 298.294999 -418.100587) (xy 298.282873 -418.04615) (xy 298.278802 -417.990528) (xy 297.797728 -417.990528)
			(xy 297.797219 -418.018414) (xy 297.789099 -418.07359) (xy 297.773031 -418.126997) (xy 297.749359 -418.177494)
			(xy 297.718586 -418.224007) (xy 297.681369 -418.265544) (xy 297.638501 -418.301219) (xy 297.590895 -418.330273)
			(xy 297.539566 -418.352085) (xy 297.485609 -418.366191) (xy 297.430172 -418.372291) (xy 297.374438 -418.370254)
			(xy 297.319595 -418.360124) (xy 297.266811 -418.342117) (xy 297.217211 -418.316616) (xy 297.171853 -418.284165)
			(xy 297.131704 -418.245456) (xy 297.097618 -418.201313) (xy 297.070322 -418.152678) (xy 297.050399 -418.100587)
			(xy 297.038273 -418.04615) (xy 297.034202 -417.990528) (xy 296.248328 -417.990528) (xy 296.247819 -418.018414)
			(xy 296.239699 -418.07359) (xy 296.223631 -418.126997) (xy 296.199959 -418.177494) (xy 296.169186 -418.224007)
			(xy 296.131969 -418.265544) (xy 296.089101 -418.301219) (xy 296.041495 -418.330273) (xy 295.990166 -418.352085)
			(xy 295.936209 -418.366191) (xy 295.880772 -418.372291) (xy 295.825038 -418.370254) (xy 295.770195 -418.360124)
			(xy 295.717411 -418.342117) (xy 295.667811 -418.316616) (xy 295.622453 -418.284165) (xy 295.582304 -418.245456)
			(xy 295.548218 -418.201313) (xy 295.520922 -418.152678) (xy 295.500999 -418.100587) (xy 295.488873 -418.04615)
			(xy 295.484802 -417.990528) (xy 295.003728 -417.990528) (xy 295.003219 -418.018414) (xy 294.995099 -418.07359)
			(xy 294.979031 -418.126997) (xy 294.955359 -418.177494) (xy 294.924586 -418.224007) (xy 294.887369 -418.265544)
			(xy 294.844501 -418.301219) (xy 294.796895 -418.330273) (xy 294.745566 -418.352085) (xy 294.691609 -418.366191)
			(xy 294.636172 -418.372291) (xy 294.580438 -418.370254) (xy 294.525595 -418.360124) (xy 294.472811 -418.342117)
			(xy 294.423211 -418.316616) (xy 294.377853 -418.284165) (xy 294.337704 -418.245456) (xy 294.303618 -418.201313)
			(xy 294.276322 -418.152678) (xy 294.256399 -418.100587) (xy 294.244273 -418.04615) (xy 294.240202 -417.990528)
			(xy 294.0304 -417.990528) (xy 294.0304 -419.73627) (xy 294.863264 -419.73627) (xy 294.867335 -419.680648)
			(xy 294.879461 -419.626211) (xy 294.899384 -419.57412) (xy 294.92668 -419.525485) (xy 294.960766 -419.481342)
			(xy 295.000915 -419.442633) (xy 295.046273 -419.410182) (xy 295.095873 -419.384681) (xy 295.148657 -419.366674)
			(xy 295.2035 -419.356544) (xy 295.259234 -419.354507) (xy 295.314671 -419.360607) (xy 295.368628 -419.374713)
			(xy 295.419957 -419.396525) (xy 295.467563 -419.425579) (xy 295.510431 -419.461254) (xy 295.547648 -419.502791)
			(xy 295.578421 -419.549304) (xy 295.602093 -419.599801) (xy 295.618161 -419.653208) (xy 295.626281 -419.708384)
			(xy 295.62679 -419.73627) (xy 297.657264 -419.73627) (xy 297.661335 -419.680648) (xy 297.673461 -419.626211)
			(xy 297.693384 -419.57412) (xy 297.72068 -419.525485) (xy 297.754766 -419.481342) (xy 297.794915 -419.442633)
			(xy 297.840273 -419.410182) (xy 297.889873 -419.384681) (xy 297.942657 -419.366674) (xy 297.9975 -419.356544)
			(xy 298.053234 -419.354507) (xy 298.108671 -419.360607) (xy 298.162628 -419.374713) (xy 298.213957 -419.396525)
			(xy 298.261563 -419.425579) (xy 298.304431 -419.461254) (xy 298.341648 -419.502791) (xy 298.372421 -419.549304)
			(xy 298.396093 -419.599801) (xy 298.412161 -419.653208) (xy 298.420281 -419.708384) (xy 298.42079 -419.73627)
			(xy 300.451264 -419.73627) (xy 300.455335 -419.680648) (xy 300.467461 -419.626211) (xy 300.487384 -419.57412)
			(xy 300.51468 -419.525485) (xy 300.548766 -419.481342) (xy 300.588915 -419.442633) (xy 300.634273 -419.410182)
			(xy 300.683873 -419.384681) (xy 300.736657 -419.366674) (xy 300.7915 -419.356544) (xy 300.847234 -419.354507)
			(xy 300.902671 -419.360607) (xy 300.956628 -419.374713) (xy 301.007957 -419.396525) (xy 301.055563 -419.425579)
			(xy 301.098431 -419.461254) (xy 301.135648 -419.502791) (xy 301.166421 -419.549304) (xy 301.190093 -419.599801)
			(xy 301.206161 -419.653208) (xy 301.214281 -419.708384) (xy 301.21479 -419.73627) (xy 301.214281 -419.764156)
			(xy 301.206161 -419.819332) (xy 301.200202 -419.83914) (xy 305.896262 -419.83914) (xy 305.900333 -419.783518)
			(xy 305.912459 -419.729081) (xy 305.932382 -419.67699) (xy 305.959678 -419.628355) (xy 305.993764 -419.584212)
			(xy 306.033913 -419.545503) (xy 306.079271 -419.513052) (xy 306.128871 -419.487551) (xy 306.181655 -419.469544)
			(xy 306.236498 -419.459414) (xy 306.292232 -419.457377) (xy 306.347669 -419.463477) (xy 306.401626 -419.477583)
			(xy 306.452955 -419.499395) (xy 306.500561 -419.528449) (xy 306.543429 -419.564124) (xy 306.580646 -419.605661)
			(xy 306.611419 -419.652174) (xy 306.635091 -419.702671) (xy 306.651159 -419.756078) (xy 306.659279 -419.811254)
			(xy 306.659788 -419.83914) (xy 306.659279 -419.867026) (xy 306.651159 -419.922202) (xy 306.635091 -419.975609)
			(xy 306.611419 -420.026106) (xy 306.580646 -420.072619) (xy 306.543429 -420.114156) (xy 306.500561 -420.149831)
			(xy 306.452955 -420.178885) (xy 306.401626 -420.200697) (xy 306.347669 -420.214803) (xy 306.292232 -420.220903)
			(xy 306.236498 -420.218866) (xy 306.181655 -420.208736) (xy 306.128871 -420.190729) (xy 306.079271 -420.165228)
			(xy 306.033913 -420.132777) (xy 305.993764 -420.094068) (xy 305.959678 -420.049925) (xy 305.932382 -420.00129)
			(xy 305.912459 -419.949199) (xy 305.900333 -419.894762) (xy 305.896262 -419.83914) (xy 301.200202 -419.83914)
			(xy 301.190093 -419.872739) (xy 301.166421 -419.923236) (xy 301.135648 -419.969749) (xy 301.098431 -420.011286)
			(xy 301.055563 -420.046961) (xy 301.007957 -420.076015) (xy 300.956628 -420.097827) (xy 300.902671 -420.111933)
			(xy 300.847234 -420.118033) (xy 300.7915 -420.115996) (xy 300.736657 -420.105866) (xy 300.683873 -420.087859)
			(xy 300.634273 -420.062358) (xy 300.588915 -420.029907) (xy 300.548766 -419.991198) (xy 300.51468 -419.947055)
			(xy 300.487384 -419.89842) (xy 300.467461 -419.846329) (xy 300.455335 -419.791892) (xy 300.451264 -419.73627)
			(xy 298.42079 -419.73627) (xy 298.420281 -419.764156) (xy 298.412161 -419.819332) (xy 298.396093 -419.872739)
			(xy 298.372421 -419.923236) (xy 298.341648 -419.969749) (xy 298.304431 -420.011286) (xy 298.261563 -420.046961)
			(xy 298.213957 -420.076015) (xy 298.162628 -420.097827) (xy 298.108671 -420.111933) (xy 298.053234 -420.118033)
			(xy 297.9975 -420.115996) (xy 297.942657 -420.105866) (xy 297.889873 -420.087859) (xy 297.840273 -420.062358)
			(xy 297.794915 -420.029907) (xy 297.754766 -419.991198) (xy 297.72068 -419.947055) (xy 297.693384 -419.89842)
			(xy 297.673461 -419.846329) (xy 297.661335 -419.791892) (xy 297.657264 -419.73627) (xy 295.62679 -419.73627)
			(xy 295.626281 -419.764156) (xy 295.618161 -419.819332) (xy 295.602093 -419.872739) (xy 295.578421 -419.923236)
			(xy 295.547648 -419.969749) (xy 295.510431 -420.011286) (xy 295.467563 -420.046961) (xy 295.419957 -420.076015)
			(xy 295.368628 -420.097827) (xy 295.314671 -420.111933) (xy 295.259234 -420.118033) (xy 295.2035 -420.115996)
			(xy 295.148657 -420.105866) (xy 295.095873 -420.087859) (xy 295.046273 -420.062358) (xy 295.000915 -420.029907)
			(xy 294.960766 -419.991198) (xy 294.92668 -419.947055) (xy 294.899384 -419.89842) (xy 294.879461 -419.846329)
			(xy 294.867335 -419.791892) (xy 294.863264 -419.73627) (xy 294.0304 -419.73627) (xy 294.0304 -421.23741)
			(xy 307.07406 -421.23741) (xy 307.078131 -421.181788) (xy 307.090257 -421.127351) (xy 307.11018 -421.07526)
			(xy 307.137476 -421.026625) (xy 307.171562 -420.982482) (xy 307.211711 -420.943773) (xy 307.257069 -420.911322)
			(xy 307.306669 -420.885821) (xy 307.359453 -420.867814) (xy 307.414296 -420.857684) (xy 307.47003 -420.855647)
			(xy 307.525467 -420.861747) (xy 307.579424 -420.875853) (xy 307.630753 -420.897665) (xy 307.678359 -420.926719)
			(xy 307.721227 -420.962394) (xy 307.758444 -421.003931) (xy 307.789217 -421.050444) (xy 307.812889 -421.100941)
			(xy 307.828957 -421.154348) (xy 307.837077 -421.209524) (xy 307.837586 -421.23741) (xy 307.837077 -421.265296)
			(xy 307.828957 -421.320472) (xy 307.812889 -421.373879) (xy 307.789217 -421.424376) (xy 307.758444 -421.470889)
			(xy 307.721227 -421.512426) (xy 307.678359 -421.548101) (xy 307.630753 -421.577155) (xy 307.579424 -421.598967)
			(xy 307.525467 -421.613073) (xy 307.47003 -421.619173) (xy 307.414296 -421.617136) (xy 307.359453 -421.607006)
			(xy 307.306669 -421.588999) (xy 307.257069 -421.563498) (xy 307.211711 -421.531047) (xy 307.171562 -421.492338)
			(xy 307.137476 -421.448195) (xy 307.11018 -421.39956) (xy 307.090257 -421.347469) (xy 307.078131 -421.293032)
			(xy 307.07406 -421.23741) (xy 294.0304 -421.23741) (xy 294.0304 -423.954448) (xy 294.667684 -423.954448)
			(xy 294.671755 -423.898826) (xy 294.683881 -423.844389) (xy 294.703804 -423.792298) (xy 294.7311 -423.743663)
			(xy 294.765186 -423.69952) (xy 294.805335 -423.660811) (xy 294.850693 -423.62836) (xy 294.900293 -423.602859)
			(xy 294.953077 -423.584852) (xy 295.00792 -423.574722) (xy 295.063654 -423.572685) (xy 295.119091 -423.578785)
			(xy 295.173048 -423.592891) (xy 295.224377 -423.614703) (xy 295.271983 -423.643757) (xy 295.314851 -423.679432)
			(xy 295.352068 -423.720969) (xy 295.382841 -423.767482) (xy 295.406513 -423.817979) (xy 295.422581 -423.871386)
			(xy 295.430701 -423.926562) (xy 295.43121 -423.954448) (xy 297.461684 -423.954448) (xy 297.465755 -423.898826)
			(xy 297.477881 -423.844389) (xy 297.497804 -423.792298) (xy 297.5251 -423.743663) (xy 297.559186 -423.69952)
			(xy 297.599335 -423.660811) (xy 297.644693 -423.62836) (xy 297.694293 -423.602859) (xy 297.747077 -423.584852)
			(xy 297.80192 -423.574722) (xy 297.857654 -423.572685) (xy 297.913091 -423.578785) (xy 297.967048 -423.592891)
			(xy 298.018377 -423.614703) (xy 298.065983 -423.643757) (xy 298.108851 -423.679432) (xy 298.146068 -423.720969)
			(xy 298.176841 -423.767482) (xy 298.200513 -423.817979) (xy 298.216581 -423.871386) (xy 298.224701 -423.926562)
			(xy 298.22521 -423.954448) (xy 300.255684 -423.954448) (xy 300.259755 -423.898826) (xy 300.271881 -423.844389)
			(xy 300.291804 -423.792298) (xy 300.3191 -423.743663) (xy 300.353186 -423.69952) (xy 300.393335 -423.660811)
			(xy 300.438693 -423.62836) (xy 300.488293 -423.602859) (xy 300.541077 -423.584852) (xy 300.59592 -423.574722)
			(xy 300.651654 -423.572685) (xy 300.707091 -423.578785) (xy 300.761048 -423.592891) (xy 300.812377 -423.614703)
			(xy 300.859983 -423.643757) (xy 300.902851 -423.679432) (xy 300.940068 -423.720969) (xy 300.970841 -423.767482)
			(xy 300.994513 -423.817979) (xy 301.010581 -423.871386) (xy 301.018701 -423.926562) (xy 301.01921 -423.954448)
			(xy 301.018701 -423.982334) (xy 301.011217 -424.033188) (xy 302.940464 -424.033188) (xy 302.944535 -423.977566)
			(xy 302.956661 -423.923129) (xy 302.976584 -423.871038) (xy 303.00388 -423.822403) (xy 303.037966 -423.77826)
			(xy 303.078115 -423.739551) (xy 303.123473 -423.7071) (xy 303.173073 -423.681599) (xy 303.225857 -423.663592)
			(xy 303.2807 -423.653462) (xy 303.336434 -423.651425) (xy 303.391871 -423.657525) (xy 303.445828 -423.671631)
			(xy 303.497157 -423.693443) (xy 303.544763 -423.722497) (xy 303.587631 -423.758172) (xy 303.624848 -423.799709)
			(xy 303.655621 -423.846222) (xy 303.679293 -423.896719) (xy 303.695361 -423.950126) (xy 303.703481 -424.005302)
			(xy 303.70399 -424.033188) (xy 303.703481 -424.061074) (xy 303.695361 -424.11625) (xy 303.679293 -424.169657)
			(xy 303.655621 -424.220154) (xy 303.624848 -424.266667) (xy 303.587631 -424.308204) (xy 303.544763 -424.343879)
			(xy 303.497157 -424.372933) (xy 303.445828 -424.394745) (xy 303.391871 -424.408851) (xy 303.336434 -424.414951)
			(xy 303.2807 -424.412914) (xy 303.225857 -424.402784) (xy 303.173073 -424.384777) (xy 303.123473 -424.359276)
			(xy 303.078115 -424.326825) (xy 303.037966 -424.288116) (xy 303.00388 -424.243973) (xy 302.976584 -424.195338)
			(xy 302.956661 -424.143247) (xy 302.944535 -424.08881) (xy 302.940464 -424.033188) (xy 301.011217 -424.033188)
			(xy 301.010581 -424.03751) (xy 300.994513 -424.090917) (xy 300.970841 -424.141414) (xy 300.940068 -424.187927)
			(xy 300.902851 -424.229464) (xy 300.859983 -424.265139) (xy 300.812377 -424.294193) (xy 300.761048 -424.316005)
			(xy 300.707091 -424.330111) (xy 300.651654 -424.336211) (xy 300.59592 -424.334174) (xy 300.541077 -424.324044)
			(xy 300.488293 -424.306037) (xy 300.438693 -424.280536) (xy 300.393335 -424.248085) (xy 300.353186 -424.209376)
			(xy 300.3191 -424.165233) (xy 300.291804 -424.116598) (xy 300.271881 -424.064507) (xy 300.259755 -424.01007)
			(xy 300.255684 -423.954448) (xy 298.22521 -423.954448) (xy 298.224701 -423.982334) (xy 298.216581 -424.03751)
			(xy 298.200513 -424.090917) (xy 298.176841 -424.141414) (xy 298.146068 -424.187927) (xy 298.108851 -424.229464)
			(xy 298.065983 -424.265139) (xy 298.018377 -424.294193) (xy 297.967048 -424.316005) (xy 297.913091 -424.330111)
			(xy 297.857654 -424.336211) (xy 297.80192 -424.334174) (xy 297.747077 -424.324044) (xy 297.694293 -424.306037)
			(xy 297.644693 -424.280536) (xy 297.599335 -424.248085) (xy 297.559186 -424.209376) (xy 297.5251 -424.165233)
			(xy 297.497804 -424.116598) (xy 297.477881 -424.064507) (xy 297.465755 -424.01007) (xy 297.461684 -423.954448)
			(xy 295.43121 -423.954448) (xy 295.430701 -423.982334) (xy 295.422581 -424.03751) (xy 295.406513 -424.090917)
			(xy 295.382841 -424.141414) (xy 295.352068 -424.187927) (xy 295.314851 -424.229464) (xy 295.271983 -424.265139)
			(xy 295.224377 -424.294193) (xy 295.173048 -424.316005) (xy 295.119091 -424.330111) (xy 295.063654 -424.336211)
			(xy 295.00792 -424.334174) (xy 294.953077 -424.324044) (xy 294.900293 -424.306037) (xy 294.850693 -424.280536)
			(xy 294.805335 -424.248085) (xy 294.765186 -424.209376) (xy 294.7311 -424.165233) (xy 294.703804 -424.116598)
			(xy 294.683881 -424.064507) (xy 294.671755 -424.01007) (xy 294.667684 -423.954448) (xy 294.0304 -423.954448)
			(xy 294.0304 -425.831) (xy 307.968902 -425.831) (xy 307.972973 -425.775378) (xy 307.985099 -425.720941)
			(xy 308.005022 -425.66885) (xy 308.032318 -425.620215) (xy 308.066404 -425.576072) (xy 308.106553 -425.537363)
			(xy 308.151911 -425.504912) (xy 308.201511 -425.479411) (xy 308.254295 -425.461404) (xy 308.309138 -425.451274)
			(xy 308.364872 -425.449237) (xy 308.420309 -425.455337) (xy 308.474266 -425.469443) (xy 308.525595 -425.491255)
			(xy 308.573201 -425.520309) (xy 308.616069 -425.555984) (xy 308.653286 -425.597521) (xy 308.684059 -425.644034)
			(xy 308.707731 -425.694531) (xy 308.723799 -425.747938) (xy 308.731919 -425.803114) (xy 308.732428 -425.831)
			(xy 308.731919 -425.858886) (xy 308.723799 -425.914062) (xy 308.707731 -425.967469) (xy 308.684059 -426.017966)
			(xy 308.653286 -426.064479) (xy 308.616069 -426.106016) (xy 308.573201 -426.141691) (xy 308.525595 -426.170745)
			(xy 308.474266 -426.192557) (xy 308.420309 -426.206663) (xy 308.364872 -426.212763) (xy 308.309138 -426.210726)
			(xy 308.254295 -426.200596) (xy 308.201511 -426.182589) (xy 308.151911 -426.157088) (xy 308.106553 -426.124637)
			(xy 308.066404 -426.085928) (xy 308.032318 -426.041785) (xy 308.005022 -425.99315) (xy 307.985099 -425.941059)
			(xy 307.972973 -425.886622) (xy 307.968902 -425.831) (xy 294.0304 -425.831) (xy 294.0304 -426.567854)
			(xy 294.03082 -426.577491) (xy 294.037926 -426.595408) (xy 294.051121 -426.609458) (xy 294.068558 -426.617673)
			(xy 294.078152 -426.618654) (xy 294.106924 -426.62088) (xy 294.163362 -426.63291) (xy 294.217346 -426.6533)
			(xy 294.267644 -426.681586) (xy 294.313109 -426.717123) (xy 294.352706 -426.7591) (xy 294.385531 -426.806561)
			(xy 294.410836 -426.858423) (xy 294.428044 -426.913504) (xy 294.436763 -426.970547) (xy 294.437308 -426.9994)
			(xy 294.437098 -427.015934) (xy 294.434173 -427.048874) (xy 294.431466 -427.065186) (xy 294.427148 -427.091348)
			(xy 294.504665 -427.168818) (xy 304.699922 -427.168818) (xy 304.703993 -427.113196) (xy 304.716119 -427.058759)
			(xy 304.736042 -427.006668) (xy 304.763338 -426.958033) (xy 304.797424 -426.91389) (xy 304.837573 -426.875181)
			(xy 304.882931 -426.84273) (xy 304.932531 -426.817229) (xy 304.985315 -426.799222) (xy 305.040158 -426.789092)
			(xy 305.095892 -426.787055) (xy 305.151329 -426.793155) (xy 305.205286 -426.807261) (xy 305.256615 -426.829073)
			(xy 305.304221 -426.858127) (xy 305.347089 -426.893802) (xy 305.384306 -426.935339) (xy 305.415079 -426.981852)
			(xy 305.438751 -427.032349) (xy 305.454819 -427.085756) (xy 305.462939 -427.140932) (xy 305.463448 -427.168818)
			(xy 305.462939 -427.196704) (xy 305.454819 -427.25188) (xy 305.438751 -427.305287) (xy 305.415079 -427.355784)
			(xy 305.384306 -427.402297) (xy 305.347089 -427.443834) (xy 305.304221 -427.479509) (xy 305.256615 -427.508563)
			(xy 305.205286 -427.530375) (xy 305.151329 -427.544481) (xy 305.095892 -427.550581) (xy 305.040158 -427.548544)
			(xy 304.985315 -427.538414) (xy 304.932531 -427.520407) (xy 304.882931 -427.494906) (xy 304.837573 -427.462455)
			(xy 304.797424 -427.423746) (xy 304.763338 -427.379603) (xy 304.736042 -427.330968) (xy 304.716119 -427.278877)
			(xy 304.703993 -427.22444) (xy 304.699922 -427.168818) (xy 294.504665 -427.168818) (xy 294.850566 -427.514512)
			(xy 299.01769 -427.514512) (xy 299.315124 -427.8122) (xy 299.974 -427.8122) (xy 300.32452 -428.16272)
			(xy 306.241702 -428.16272) (xy 306.245773 -428.107098) (xy 306.257899 -428.052661) (xy 306.277822 -428.00057)
			(xy 306.305118 -427.951935) (xy 306.339204 -427.907792) (xy 306.379353 -427.869083) (xy 306.424711 -427.836632)
			(xy 306.474311 -427.811131) (xy 306.527095 -427.793124) (xy 306.581938 -427.782994) (xy 306.637672 -427.780957)
			(xy 306.693109 -427.787057) (xy 306.747066 -427.801163) (xy 306.798395 -427.822975) (xy 306.846001 -427.852029)
			(xy 306.865288 -427.86808) (xy 308.789322 -427.86808) (xy 308.793393 -427.812458) (xy 308.805519 -427.758021)
			(xy 308.825442 -427.70593) (xy 308.852738 -427.657295) (xy 308.886824 -427.613152) (xy 308.926973 -427.574443)
			(xy 308.972331 -427.541992) (xy 309.021931 -427.516491) (xy 309.074715 -427.498484) (xy 309.129558 -427.488354)
			(xy 309.185292 -427.486317) (xy 309.240729 -427.492417) (xy 309.294686 -427.506523) (xy 309.346015 -427.528335)
			(xy 309.393621 -427.557389) (xy 309.436489 -427.593064) (xy 309.473706 -427.634601) (xy 309.504479 -427.681114)
			(xy 309.528151 -427.731611) (xy 309.544219 -427.785018) (xy 309.552339 -427.840194) (xy 309.552848 -427.86808)
			(xy 309.552339 -427.895966) (xy 309.544219 -427.951142) (xy 309.528151 -428.004549) (xy 309.504479 -428.055046)
			(xy 309.473706 -428.101559) (xy 309.436489 -428.143096) (xy 309.393621 -428.178771) (xy 309.346015 -428.207825)
			(xy 309.294686 -428.229637) (xy 309.240729 -428.243743) (xy 309.185292 -428.249843) (xy 309.129558 -428.247806)
			(xy 309.074715 -428.237676) (xy 309.021931 -428.219669) (xy 308.972331 -428.194168) (xy 308.926973 -428.161717)
			(xy 308.886824 -428.123008) (xy 308.852738 -428.078865) (xy 308.825442 -428.03023) (xy 308.805519 -427.978139)
			(xy 308.793393 -427.923702) (xy 308.789322 -427.86808) (xy 306.865288 -427.86808) (xy 306.888869 -427.887704)
			(xy 306.926086 -427.929241) (xy 306.956859 -427.975754) (xy 306.980531 -428.026251) (xy 306.996599 -428.079658)
			(xy 307.004719 -428.134834) (xy 307.005228 -428.16272) (xy 307.004719 -428.190606) (xy 306.996599 -428.245782)
			(xy 306.980531 -428.299189) (xy 306.956859 -428.349686) (xy 306.926086 -428.396199) (xy 306.888869 -428.437736)
			(xy 306.846001 -428.473411) (xy 306.798395 -428.502465) (xy 306.747066 -428.524277) (xy 306.693109 -428.538383)
			(xy 306.637672 -428.544483) (xy 306.581938 -428.542446) (xy 306.527095 -428.532316) (xy 306.474311 -428.514309)
			(xy 306.424711 -428.488808) (xy 306.379353 -428.456357) (xy 306.339204 -428.417648) (xy 306.305118 -428.373505)
			(xy 306.277822 -428.32487) (xy 306.257899 -428.272779) (xy 306.245773 -428.218342) (xy 306.241702 -428.16272)
			(xy 300.32452 -428.16272) (xy 301.01286 -428.85106) (xy 302.064672 -428.85106) (xy 302.068743 -428.795438)
			(xy 302.080869 -428.741001) (xy 302.100792 -428.68891) (xy 302.128088 -428.640275) (xy 302.162174 -428.596132)
			(xy 302.202323 -428.557423) (xy 302.247681 -428.524972) (xy 302.297281 -428.499471) (xy 302.350065 -428.481464)
			(xy 302.404908 -428.471334) (xy 302.460642 -428.469297) (xy 302.516079 -428.475397) (xy 302.570036 -428.489503)
			(xy 302.621365 -428.511315) (xy 302.668971 -428.540369) (xy 302.711839 -428.576044) (xy 302.749056 -428.617581)
			(xy 302.779829 -428.664094) (xy 302.803501 -428.714591) (xy 302.819569 -428.767998) (xy 302.827689 -428.823174)
			(xy 302.828198 -428.85106) (xy 302.827989 -428.86249) (xy 304.800252 -428.86249) (xy 304.804323 -428.806868)
			(xy 304.816449 -428.752431) (xy 304.836372 -428.70034) (xy 304.863668 -428.651705) (xy 304.897754 -428.607562)
			(xy 304.937903 -428.568853) (xy 304.983261 -428.536402) (xy 305.032861 -428.510901) (xy 305.085645 -428.492894)
			(xy 305.140488 -428.482764) (xy 305.196222 -428.480727) (xy 305.251659 -428.486827) (xy 305.305616 -428.500933)
			(xy 305.356945 -428.522745) (xy 305.404551 -428.551799) (xy 305.447419 -428.587474) (xy 305.484636 -428.629011)
			(xy 305.515409 -428.675524) (xy 305.539081 -428.726021) (xy 305.555149 -428.779428) (xy 305.563269 -428.834604)
			(xy 305.563778 -428.86249) (xy 305.563269 -428.890376) (xy 305.557467 -428.9298) (xy 307.543452 -428.9298)
			(xy 307.547523 -428.874178) (xy 307.559649 -428.819741) (xy 307.579572 -428.76765) (xy 307.606868 -428.719015)
			(xy 307.640954 -428.674872) (xy 307.681103 -428.636163) (xy 307.726461 -428.603712) (xy 307.776061 -428.578211)
			(xy 307.828845 -428.560204) (xy 307.883688 -428.550074) (xy 307.939422 -428.548037) (xy 307.994859 -428.554137)
			(xy 308.048816 -428.568243) (xy 308.100145 -428.590055) (xy 308.147751 -428.619109) (xy 308.190619 -428.654784)
			(xy 308.227836 -428.696321) (xy 308.258609 -428.742834) (xy 308.282281 -428.793331) (xy 308.298349 -428.846738)
			(xy 308.306469 -428.901914) (xy 308.306978 -428.9298) (xy 308.306469 -428.957686) (xy 308.298349 -429.012862)
			(xy 308.282281 -429.066269) (xy 308.258609 -429.116766) (xy 308.227836 -429.163279) (xy 308.190619 -429.204816)
			(xy 308.147751 -429.240491) (xy 308.100145 -429.269545) (xy 308.048816 -429.291357) (xy 307.994859 -429.305463)
			(xy 307.939422 -429.311563) (xy 307.883688 -429.309526) (xy 307.828845 -429.299396) (xy 307.776061 -429.281389)
			(xy 307.726461 -429.255888) (xy 307.681103 -429.223437) (xy 307.640954 -429.184728) (xy 307.606868 -429.140585)
			(xy 307.579572 -429.09195) (xy 307.559649 -429.039859) (xy 307.547523 -428.985422) (xy 307.543452 -428.9298)
			(xy 305.557467 -428.9298) (xy 305.555149 -428.945552) (xy 305.539081 -428.998959) (xy 305.515409 -429.049456)
			(xy 305.484636 -429.095969) (xy 305.447419 -429.137506) (xy 305.404551 -429.173181) (xy 305.356945 -429.202235)
			(xy 305.305616 -429.224047) (xy 305.251659 -429.238153) (xy 305.196222 -429.244253) (xy 305.140488 -429.242216)
			(xy 305.085645 -429.232086) (xy 305.032861 -429.214079) (xy 304.983261 -429.188578) (xy 304.937903 -429.156127)
			(xy 304.897754 -429.117418) (xy 304.863668 -429.073275) (xy 304.836372 -429.02464) (xy 304.816449 -428.972549)
			(xy 304.804323 -428.918112) (xy 304.800252 -428.86249) (xy 302.827989 -428.86249) (xy 302.827689 -428.878946)
			(xy 302.819569 -428.934122) (xy 302.803501 -428.987529) (xy 302.779829 -429.038026) (xy 302.749056 -429.084539)
			(xy 302.711839 -429.126076) (xy 302.668971 -429.161751) (xy 302.621365 -429.190805) (xy 302.570036 -429.212617)
			(xy 302.516079 -429.226723) (xy 302.460642 -429.232823) (xy 302.404908 -429.230786) (xy 302.350065 -429.220656)
			(xy 302.297281 -429.202649) (xy 302.247681 -429.177148) (xy 302.202323 -429.144697) (xy 302.162174 -429.105988)
			(xy 302.128088 -429.061845) (xy 302.100792 -429.01321) (xy 302.080869 -428.961119) (xy 302.068743 -428.906682)
			(xy 302.064672 -428.85106) (xy 301.01286 -428.85106) (xy 301.782988 -429.621188) (xy 302.472342 -429.621188)
			(xy 302.476413 -429.565566) (xy 302.488539 -429.511129) (xy 302.508462 -429.459038) (xy 302.535758 -429.410403)
			(xy 302.569844 -429.36626) (xy 302.609993 -429.327551) (xy 302.655351 -429.2951) (xy 302.704951 -429.269599)
			(xy 302.757735 -429.251592) (xy 302.812578 -429.241462) (xy 302.868312 -429.239425) (xy 302.923749 -429.245525)
			(xy 302.977706 -429.259631) (xy 303.029035 -429.281443) (xy 303.076641 -429.310497) (xy 303.119509 -429.346172)
			(xy 303.156726 -429.387709) (xy 303.187499 -429.434222) (xy 303.211171 -429.484719) (xy 303.227239 -429.538126)
			(xy 303.235359 -429.593302) (xy 303.235868 -429.621188) (xy 303.716942 -429.621188) (xy 303.721013 -429.565566)
			(xy 303.733139 -429.511129) (xy 303.753062 -429.459038) (xy 303.780358 -429.410403) (xy 303.814444 -429.36626)
			(xy 303.854593 -429.327551) (xy 303.899951 -429.2951) (xy 303.949551 -429.269599) (xy 304.002335 -429.251592)
			(xy 304.057178 -429.241462) (xy 304.112912 -429.239425) (xy 304.168349 -429.245525) (xy 304.222306 -429.259631)
			(xy 304.273635 -429.281443) (xy 304.321241 -429.310497) (xy 304.364109 -429.346172) (xy 304.401326 -429.387709)
			(xy 304.432099 -429.434222) (xy 304.455771 -429.484719) (xy 304.471839 -429.538126) (xy 304.479959 -429.593302)
			(xy 304.480468 -429.621188) (xy 304.480259 -429.632618) (xy 305.207922 -429.632618) (xy 305.211993 -429.576996)
			(xy 305.224119 -429.522559) (xy 305.244042 -429.470468) (xy 305.271338 -429.421833) (xy 305.305424 -429.37769)
			(xy 305.345573 -429.338981) (xy 305.390931 -429.30653) (xy 305.440531 -429.281029) (xy 305.493315 -429.263022)
			(xy 305.548158 -429.252892) (xy 305.603892 -429.250855) (xy 305.659329 -429.256955) (xy 305.713286 -429.271061)
			(xy 305.764615 -429.292873) (xy 305.812221 -429.321927) (xy 305.855089 -429.357602) (xy 305.892306 -429.399139)
			(xy 305.923079 -429.445652) (xy 305.946751 -429.496149) (xy 305.962819 -429.549556) (xy 305.970939 -429.604732)
			(xy 305.971448 -429.632618) (xy 306.452522 -429.632618) (xy 306.456593 -429.576996) (xy 306.468719 -429.522559)
			(xy 306.488642 -429.470468) (xy 306.515938 -429.421833) (xy 306.550024 -429.37769) (xy 306.590173 -429.338981)
			(xy 306.635531 -429.30653) (xy 306.685131 -429.281029) (xy 306.737915 -429.263022) (xy 306.792758 -429.252892)
			(xy 306.848492 -429.250855) (xy 306.903929 -429.256955) (xy 306.957886 -429.271061) (xy 307.009215 -429.292873)
			(xy 307.056821 -429.321927) (xy 307.099689 -429.357602) (xy 307.136906 -429.399139) (xy 307.167679 -429.445652)
			(xy 307.191351 -429.496149) (xy 307.207419 -429.549556) (xy 307.215539 -429.604732) (xy 307.216048 -429.632618)
			(xy 307.215539 -429.660504) (xy 307.209737 -429.699928) (xy 307.951122 -429.699928) (xy 307.955193 -429.644306)
			(xy 307.967319 -429.589869) (xy 307.987242 -429.537778) (xy 308.014538 -429.489143) (xy 308.048624 -429.445)
			(xy 308.088773 -429.406291) (xy 308.134131 -429.37384) (xy 308.183731 -429.348339) (xy 308.236515 -429.330332)
			(xy 308.291358 -429.320202) (xy 308.347092 -429.318165) (xy 308.402529 -429.324265) (xy 308.456486 -429.338371)
			(xy 308.507815 -429.360183) (xy 308.555421 -429.389237) (xy 308.598289 -429.424912) (xy 308.635506 -429.466449)
			(xy 308.666279 -429.512962) (xy 308.689951 -429.563459) (xy 308.706019 -429.616866) (xy 308.714139 -429.672042)
			(xy 308.714648 -429.699928) (xy 309.195722 -429.699928) (xy 309.199793 -429.644306) (xy 309.211919 -429.589869)
			(xy 309.231842 -429.537778) (xy 309.259138 -429.489143) (xy 309.293224 -429.445) (xy 309.333373 -429.406291)
			(xy 309.378731 -429.37384) (xy 309.428331 -429.348339) (xy 309.481115 -429.330332) (xy 309.535958 -429.320202)
			(xy 309.591692 -429.318165) (xy 309.647129 -429.324265) (xy 309.701086 -429.338371) (xy 309.752415 -429.360183)
			(xy 309.800021 -429.389237) (xy 309.842889 -429.424912) (xy 309.880106 -429.466449) (xy 309.910879 -429.512962)
			(xy 309.934551 -429.563459) (xy 309.950619 -429.616866) (xy 309.958739 -429.672042) (xy 309.959248 -429.699928)
			(xy 309.958739 -429.727814) (xy 309.950619 -429.78299) (xy 309.934551 -429.836397) (xy 309.910879 -429.886894)
			(xy 309.880106 -429.933407) (xy 309.842889 -429.974944) (xy 309.800021 -430.010619) (xy 309.752415 -430.039673)
			(xy 309.701086 -430.061485) (xy 309.647129 -430.075591) (xy 309.591692 -430.081691) (xy 309.535958 -430.079654)
			(xy 309.481115 -430.069524) (xy 309.428331 -430.051517) (xy 309.378731 -430.026016) (xy 309.333373 -429.993565)
			(xy 309.293224 -429.954856) (xy 309.259138 -429.910713) (xy 309.231842 -429.862078) (xy 309.211919 -429.809987)
			(xy 309.199793 -429.75555) (xy 309.195722 -429.699928) (xy 308.714648 -429.699928) (xy 308.714139 -429.727814)
			(xy 308.706019 -429.78299) (xy 308.689951 -429.836397) (xy 308.666279 -429.886894) (xy 308.635506 -429.933407)
			(xy 308.598289 -429.974944) (xy 308.555421 -430.010619) (xy 308.507815 -430.039673) (xy 308.456486 -430.061485)
			(xy 308.402529 -430.075591) (xy 308.347092 -430.081691) (xy 308.291358 -430.079654) (xy 308.236515 -430.069524)
			(xy 308.183731 -430.051517) (xy 308.134131 -430.026016) (xy 308.088773 -429.993565) (xy 308.048624 -429.954856)
			(xy 308.014538 -429.910713) (xy 307.987242 -429.862078) (xy 307.967319 -429.809987) (xy 307.955193 -429.75555)
			(xy 307.951122 -429.699928) (xy 307.209737 -429.699928) (xy 307.207419 -429.71568) (xy 307.191351 -429.769087)
			(xy 307.167679 -429.819584) (xy 307.136906 -429.866097) (xy 307.099689 -429.907634) (xy 307.056821 -429.943309)
			(xy 307.009215 -429.972363) (xy 306.957886 -429.994175) (xy 306.903929 -430.008281) (xy 306.848492 -430.014381)
			(xy 306.792758 -430.012344) (xy 306.737915 -430.002214) (xy 306.685131 -429.984207) (xy 306.635531 -429.958706)
			(xy 306.590173 -429.926255) (xy 306.550024 -429.887546) (xy 306.515938 -429.843403) (xy 306.488642 -429.794768)
			(xy 306.468719 -429.742677) (xy 306.456593 -429.68824) (xy 306.452522 -429.632618) (xy 305.971448 -429.632618)
			(xy 305.970939 -429.660504) (xy 305.962819 -429.71568) (xy 305.946751 -429.769087) (xy 305.923079 -429.819584)
			(xy 305.892306 -429.866097) (xy 305.855089 -429.907634) (xy 305.812221 -429.943309) (xy 305.764615 -429.972363)
			(xy 305.713286 -429.994175) (xy 305.659329 -430.008281) (xy 305.603892 -430.014381) (xy 305.548158 -430.012344)
			(xy 305.493315 -430.002214) (xy 305.440531 -429.984207) (xy 305.390931 -429.958706) (xy 305.345573 -429.926255)
			(xy 305.305424 -429.887546) (xy 305.271338 -429.843403) (xy 305.244042 -429.794768) (xy 305.224119 -429.742677)
			(xy 305.211993 -429.68824) (xy 305.207922 -429.632618) (xy 304.480259 -429.632618) (xy 304.479959 -429.649074)
			(xy 304.471839 -429.70425) (xy 304.455771 -429.757657) (xy 304.432099 -429.808154) (xy 304.401326 -429.854667)
			(xy 304.364109 -429.896204) (xy 304.321241 -429.931879) (xy 304.273635 -429.960933) (xy 304.222306 -429.982745)
			(xy 304.168349 -429.996851) (xy 304.112912 -430.002951) (xy 304.057178 -430.000914) (xy 304.002335 -429.990784)
			(xy 303.949551 -429.972777) (xy 303.899951 -429.947276) (xy 303.854593 -429.914825) (xy 303.814444 -429.876116)
			(xy 303.780358 -429.831973) (xy 303.753062 -429.783338) (xy 303.733139 -429.731247) (xy 303.721013 -429.67681)
			(xy 303.716942 -429.621188) (xy 303.235868 -429.621188) (xy 303.235359 -429.649074) (xy 303.227239 -429.70425)
			(xy 303.211171 -429.757657) (xy 303.187499 -429.808154) (xy 303.156726 -429.854667) (xy 303.119509 -429.896204)
			(xy 303.076641 -429.931879) (xy 303.029035 -429.960933) (xy 302.977706 -429.982745) (xy 302.923749 -429.996851)
			(xy 302.868312 -430.002951) (xy 302.812578 -430.000914) (xy 302.757735 -429.990784) (xy 302.704951 -429.972777)
			(xy 302.655351 -429.947276) (xy 302.609993 -429.914825) (xy 302.569844 -429.876116) (xy 302.535758 -429.831973)
			(xy 302.508462 -429.783338) (xy 302.488539 -429.731247) (xy 302.476413 -429.67681) (xy 302.472342 -429.621188)
			(xy 301.782988 -429.621188) (xy 302.5394 -430.3776) (xy 302.5394 -431.36693) (xy 303.095404 -431.36693)
			(xy 303.099475 -431.311308) (xy 303.111601 -431.256871) (xy 303.131524 -431.20478) (xy 303.15882 -431.156145)
			(xy 303.192906 -431.112002) (xy 303.233055 -431.073293) (xy 303.278413 -431.040842) (xy 303.328013 -431.015341)
			(xy 303.380797 -430.997334) (xy 303.43564 -430.987204) (xy 303.491374 -430.985167) (xy 303.546811 -430.991267)
			(xy 303.600768 -431.005373) (xy 303.652097 -431.027185) (xy 303.699703 -431.056239) (xy 303.742571 -431.091914)
			(xy 303.779788 -431.133451) (xy 303.810561 -431.179964) (xy 303.834233 -431.230461) (xy 303.850301 -431.283868)
			(xy 303.858421 -431.339044) (xy 303.85893 -431.36693) (xy 303.858721 -431.37836) (xy 305.830984 -431.37836)
			(xy 305.835055 -431.322738) (xy 305.847181 -431.268301) (xy 305.867104 -431.21621) (xy 305.8944 -431.167575)
			(xy 305.928486 -431.123432) (xy 305.968635 -431.084723) (xy 306.013993 -431.052272) (xy 306.063593 -431.026771)
			(xy 306.116377 -431.008764) (xy 306.17122 -430.998634) (xy 306.226954 -430.996597) (xy 306.282391 -431.002697)
			(xy 306.336348 -431.016803) (xy 306.387677 -431.038615) (xy 306.435283 -431.067669) (xy 306.478151 -431.103344)
			(xy 306.515368 -431.144881) (xy 306.546141 -431.191394) (xy 306.569813 -431.241891) (xy 306.585881 -431.295298)
			(xy 306.594001 -431.350474) (xy 306.59451 -431.37836) (xy 306.594001 -431.406246) (xy 306.588199 -431.44567)
			(xy 308.574184 -431.44567) (xy 308.578255 -431.390048) (xy 308.590381 -431.335611) (xy 308.610304 -431.28352)
			(xy 308.6376 -431.234885) (xy 308.671686 -431.190742) (xy 308.711835 -431.152033) (xy 308.757193 -431.119582)
			(xy 308.806793 -431.094081) (xy 308.859577 -431.076074) (xy 308.91442 -431.065944) (xy 308.970154 -431.063907)
			(xy 309.025591 -431.070007) (xy 309.079548 -431.084113) (xy 309.130877 -431.105925) (xy 309.178483 -431.134979)
			(xy 309.221351 -431.170654) (xy 309.258568 -431.212191) (xy 309.289341 -431.258704) (xy 309.313013 -431.309201)
			(xy 309.329081 -431.362608) (xy 309.337201 -431.417784) (xy 309.33771 -431.44567) (xy 309.337201 -431.473556)
			(xy 309.329081 -431.528732) (xy 309.313013 -431.582139) (xy 309.289341 -431.632636) (xy 309.258568 -431.679149)
			(xy 309.221351 -431.720686) (xy 309.178483 -431.756361) (xy 309.130877 -431.785415) (xy 309.079548 -431.807227)
			(xy 309.025591 -431.821333) (xy 308.970154 -431.827433) (xy 308.91442 -431.825396) (xy 308.859577 -431.815266)
			(xy 308.806793 -431.797259) (xy 308.757193 -431.771758) (xy 308.711835 -431.739307) (xy 308.671686 -431.700598)
			(xy 308.6376 -431.656455) (xy 308.610304 -431.60782) (xy 308.590381 -431.555729) (xy 308.578255 -431.501292)
			(xy 308.574184 -431.44567) (xy 306.588199 -431.44567) (xy 306.585881 -431.461422) (xy 306.569813 -431.514829)
			(xy 306.546141 -431.565326) (xy 306.515368 -431.611839) (xy 306.478151 -431.653376) (xy 306.435283 -431.689051)
			(xy 306.387677 -431.718105) (xy 306.336348 -431.739917) (xy 306.282391 -431.754023) (xy 306.226954 -431.760123)
			(xy 306.17122 -431.758086) (xy 306.116377 -431.747956) (xy 306.063593 -431.729949) (xy 306.013993 -431.704448)
			(xy 305.968635 -431.671997) (xy 305.928486 -431.633288) (xy 305.8944 -431.589145) (xy 305.867104 -431.54051)
			(xy 305.847181 -431.488419) (xy 305.835055 -431.433982) (xy 305.830984 -431.37836) (xy 303.858721 -431.37836)
			(xy 303.858421 -431.394816) (xy 303.850301 -431.449992) (xy 303.834233 -431.503399) (xy 303.810561 -431.553896)
			(xy 303.779788 -431.600409) (xy 303.742571 -431.641946) (xy 303.699703 -431.677621) (xy 303.652097 -431.706675)
			(xy 303.600768 -431.728487) (xy 303.546811 -431.742593) (xy 303.491374 -431.748693) (xy 303.43564 -431.746656)
			(xy 303.380797 -431.736526) (xy 303.328013 -431.718519) (xy 303.278413 -431.693018) (xy 303.233055 -431.660567)
			(xy 303.192906 -431.621858) (xy 303.15882 -431.577715) (xy 303.131524 -431.52908) (xy 303.111601 -431.476989)
			(xy 303.099475 -431.422552) (xy 303.095404 -431.36693) (xy 302.5394 -431.36693) (xy 302.5394 -432.435)
			(xy 310.2102 -432.435)
		)
		(stroke
			(width 0)
			(type solid)
		)
		(fill yes)
		(layer "In15.Cu")
		(net "P3V3_AUX")
	)
	(gr_poly
		(pts
			(xy 59.741816 -182.436008) (xy 59.741816 -181.910228) (xy 57.489852 -181.910228) (xy 57.460887 -181.909693)
			(xy 57.40367 -181.900638) (xy 57.348574 -181.882743) (xy 57.296956 -181.856448) (xy 57.250087 -181.822401)
			(xy 57.229248 -181.802278) (xy 57.071006 -181.64429) (xy 57.01284 -181.586124) (xy 56.933084 -181.506368)
			(xy 56.908711 -181.491611) (xy 56.864237 -181.456001) (xy 56.825552 -181.414173) (xy 56.793518 -181.367058)
			(xy 56.768846 -181.315703) (xy 56.752086 -181.261249) (xy 56.74361 -181.204909) (xy 56.743092 -181.176422)
			(xy 56.743554 -181.149168) (xy 56.751308 -181.095215) (xy 56.766662 -181.042914) (xy 56.789304 -180.993331)
			(xy 56.818771 -180.947476) (xy 56.854465 -180.90628) (xy 56.895658 -180.870584) (xy 56.941512 -180.841114)
			(xy 56.991094 -180.81847) (xy 57.043393 -180.803113) (xy 57.097346 -180.795355) (xy 57.1246 -180.794914)
			(xy 57.153087 -180.795443) (xy 57.209427 -180.803916) (xy 57.26388 -180.820674) (xy 57.315235 -180.845344)
			(xy 57.36235 -180.877377) (xy 57.404177 -180.916061) (xy 57.439786 -180.960535) (xy 57.454546 -180.984906)
			(xy 57.505346 -181.035706) (xy 57.542176 -181.07279) (xy 57.642506 -181.17312) (xy 59.741816 -181.17312)
			(xy 59.741816 -142.167864) (xy 45.844206 -128.270254) (xy 44.927012 -129.187194) (xy 44.455588 -129.658618)
			(xy 44.455588 -133.483858) (xy 44.45512 -133.519512) (xy 44.447163 -133.590373) (xy 44.43132 -133.659897)
			(xy 44.407793 -133.727211) (xy 44.376876 -133.791466) (xy 44.338958 -133.851856) (xy 44.294517 -133.90762)
			(xy 44.26966 -133.933184) (xy 37.27958 -140.92301) (xy 37.27958 -144.48872) (xy 51.012924 -144.48872)
			(xy 51.012928 -144.434227) (xy 51.020687 -144.380288) (xy 51.036042 -144.328003) (xy 51.058683 -144.278435)
			(xy 51.088146 -144.232593) (xy 51.123834 -144.191411) (xy 51.165019 -144.155727) (xy 51.210863 -144.126267)
			(xy 51.260433 -144.103631) (xy 51.312719 -144.08828) (xy 51.366659 -144.080526) (xy 51.421152 -144.080526)
			(xy 51.475091 -144.088282) (xy 51.527377 -144.103635) (xy 51.576946 -144.126272) (xy 51.62279 -144.155734)
			(xy 51.663974 -144.191419) (xy 51.69966 -144.232602) (xy 51.729122 -144.278444) (xy 51.736434 -144.294455)
			(xy 53.058229 -144.294455) (xy 53.058229 -144.239945) (xy 53.065987 -144.185989) (xy 53.081345 -144.133686)
			(xy 53.10399 -144.084102) (xy 53.133461 -144.038245) (xy 53.169159 -143.997049) (xy 53.210356 -143.961353)
			(xy 53.256214 -143.931883) (xy 53.305799 -143.90924) (xy 53.358102 -143.893884) (xy 53.412059 -143.886128)
			(xy 53.439314 -143.885666) (xy 53.472576 -143.886375) (xy 53.5381 -143.897867) (xy 53.569616 -143.908526)
			(xy 53.583198 -143.913028) (xy 53.611739 -143.914958) (xy 53.639697 -143.908906) (xy 53.664884 -143.895343)
			(xy 53.685327 -143.875334) (xy 53.699426 -143.850443) (xy 53.70322 -143.836644) (xy 53.710286 -143.809161)
			(xy 53.73138 -143.756484) (xy 53.760045 -143.707514) (xy 53.795649 -143.663332) (xy 53.837407 -143.624912)
			(xy 53.884396 -143.593104) (xy 53.93558 -143.568608) (xy 53.989828 -143.551967) (xy 54.045943 -143.543547)
			(xy 54.074314 -143.54302) (xy 54.101567 -143.543451) (xy 54.155517 -143.55121) (xy 54.207814 -143.566567)
			(xy 54.257393 -143.589211) (xy 54.303245 -143.618679) (xy 54.344436 -143.654374) (xy 54.380129 -143.695566)
			(xy 54.409596 -143.74142) (xy 54.432238 -143.790999) (xy 54.447593 -143.843297) (xy 54.45535 -143.897247)
			(xy 54.45535 -143.951753) (xy 54.447593 -144.005703) (xy 54.432238 -144.058001) (xy 54.409596 -144.10758)
			(xy 54.380129 -144.153434) (xy 54.344436 -144.194626) (xy 54.303245 -144.230321) (xy 54.257393 -144.259789)
			(xy 54.207814 -144.282433) (xy 54.155517 -144.29779) (xy 54.101567 -144.305549) (xy 54.074314 -144.306036)
			(xy 54.041052 -144.305319) (xy 53.975529 -144.293832) (xy 53.944012 -144.283176) (xy 53.930421 -144.278704)
			(xy 53.901885 -144.276768) (xy 53.873929 -144.282814) (xy 53.848744 -144.296371) (xy 53.828301 -144.316375)
			(xy 53.814203 -144.341261) (xy 53.810408 -144.355058) (xy 53.803409 -144.38256) (xy 53.78231 -144.435241)
			(xy 53.753638 -144.484215) (xy 53.718025 -144.528399) (xy 53.676259 -144.566818) (xy 53.62926 -144.598624)
			(xy 53.578068 -144.623114) (xy 53.523811 -144.639749) (xy 53.467689 -144.64816) (xy 53.439314 -144.648682)
			(xy 53.412059 -144.648272) (xy 53.358102 -144.640516) (xy 53.305799 -144.62516) (xy 53.256214 -144.602517)
			(xy 53.210356 -144.573047) (xy 53.169159 -144.537351) (xy 53.133461 -144.496155) (xy 53.10399 -144.450298)
			(xy 53.081345 -144.400714) (xy 53.065987 -144.348411) (xy 53.058229 -144.294455) (xy 51.736434 -144.294455)
			(xy 51.751761 -144.328013) (xy 51.767116 -144.380299) (xy 51.774873 -144.434237) (xy 51.77536 -144.461484)
			(xy 51.77493 -144.486875) (xy 51.768173 -144.537207) (xy 51.761898 -144.561814) (xy 51.758525 -144.576472)
			(xy 51.759445 -144.606518) (xy 51.769069 -144.634996) (xy 51.786564 -144.65944) (xy 51.810415 -144.677736)
			(xy 51.838559 -144.688299) (xy 51.868558 -144.690215) (xy 51.88331 -144.68729) (xy 51.904903 -144.682524)
			(xy 51.948829 -144.677431) (xy 51.97094 -144.67713) (xy 51.998187 -144.677621) (xy 52.052126 -144.685382)
			(xy 52.104412 -144.700739) (xy 52.153979 -144.723381) (xy 52.199821 -144.752847) (xy 52.241002 -144.788536)
			(xy 52.276686 -144.829723) (xy 52.306145 -144.875568) (xy 52.32878 -144.925139) (xy 52.34413 -144.977427)
			(xy 52.351883 -145.031367) (xy 52.351881 -145.085861) (xy 52.344124 -145.139801) (xy 52.32877 -145.192087)
			(xy 52.306131 -145.241657) (xy 52.276669 -145.2875) (xy 52.240982 -145.328684) (xy 52.199798 -145.36437)
			(xy 52.153955 -145.393832) (xy 52.104385 -145.416471) (xy 52.052099 -145.431824) (xy 51.998159 -145.439581)
			(xy 51.943665 -145.439583) (xy 51.889725 -145.431829) (xy 51.837437 -145.416479) (xy 51.787866 -145.393844)
			(xy 51.742021 -145.364384) (xy 51.700835 -145.328701) (xy 51.665146 -145.287519) (xy 51.63568 -145.241678)
			(xy 51.613039 -145.19211) (xy 51.597681 -145.139824) (xy 51.589921 -145.085885) (xy 51.589432 -145.058638)
			(xy 51.589867 -145.033247) (xy 51.596621 -144.982916) (xy 51.602894 -144.958308) (xy 51.606253 -144.943646)
			(xy 51.605338 -144.913601) (xy 51.595718 -144.885123) (xy 51.578225 -144.860677) (xy 51.554375 -144.842382)
			(xy 51.526232 -144.83182) (xy 51.496234 -144.829906) (xy 51.481482 -144.832832) (xy 51.459889 -144.8376)
			(xy 51.415963 -144.842691) (xy 51.393852 -144.842992) (xy 51.366605 -144.84247) (xy 51.312667 -144.834709)
			(xy 51.260383 -144.81935) (xy 51.210816 -144.796707) (xy 51.164976 -144.767241) (xy 51.123796 -144.731551)
			(xy 51.088114 -144.690364) (xy 51.058657 -144.644518) (xy 51.036024 -144.594947) (xy 51.020675 -144.54266)
			(xy 51.012924 -144.48872) (xy 37.27958 -144.48872) (xy 37.27958 -146.75866) (xy 43.126914 -146.75866)
			(xy 43.127436 -146.729921) (xy 43.136063 -146.673095) (xy 43.153114 -146.618205) (xy 43.178206 -146.566493)
			(xy 43.210769 -146.51913) (xy 43.230038 -146.497802) (xy 43.240134 -146.486238) (xy 43.253567 -146.458655)
			(xy 43.258189 -146.428324) (xy 43.253582 -146.397991) (xy 43.240162 -146.370401) (xy 43.230038 -146.358864)
			(xy 43.21077 -146.337534) (xy 43.178203 -146.290173) (xy 43.15311 -146.238462) (xy 43.136059 -146.183572)
			(xy 43.127435 -146.126745) (xy 43.126914 -146.098006) (xy 43.12738 -146.070636) (xy 43.135197 -146.016457)
			(xy 43.150686 -145.963953) (xy 43.173528 -145.914206) (xy 43.203253 -145.86824) (xy 43.220894 -145.847308)
			(xy 43.230126 -145.835977) (xy 43.242304 -145.80942) (xy 43.246478 -145.780505) (xy 43.242307 -145.751588)
			(xy 43.23013 -145.725031) (xy 43.220894 -145.713704) (xy 43.203242 -145.692782) (xy 43.173533 -145.646806)
			(xy 43.150699 -145.597056) (xy 43.135211 -145.544553) (xy 43.127386 -145.490376) (xy 43.126914 -145.463006)
			(xy 43.127361 -145.435752) (xy 43.135118 -145.3818) (xy 43.150474 -145.3295) (xy 43.173117 -145.279919)
			(xy 43.202587 -145.234064) (xy 43.238282 -145.192871) (xy 43.279477 -145.157177) (xy 43.325333 -145.12771)
			(xy 43.374915 -145.105068) (xy 43.427215 -145.089714) (xy 43.481168 -145.08196) (xy 43.508422 -145.081498)
			(xy 43.535793 -145.081952) (xy 43.589972 -145.089773) (xy 43.642476 -145.105265) (xy 43.692222 -145.128109)
			(xy 43.738189 -145.157836) (xy 43.75912 -145.175478) (xy 43.770448 -145.184714) (xy 43.797005 -145.19689)
			(xy 43.825922 -145.201063) (xy 43.854839 -145.19689) (xy 43.881396 -145.184714) (xy 43.892724 -145.175478)
			(xy 43.913671 -145.157858) (xy 43.95964 -145.128144) (xy 44.009384 -145.105305) (xy 44.061881 -145.089809)
			(xy 44.116054 -145.081975) (xy 44.143422 -145.081498) (xy 44.172161 -145.082009) (xy 44.228989 -145.090635)
			(xy 44.28388 -145.107688) (xy 44.335592 -145.132782) (xy 44.382954 -145.16535) (xy 44.40428 -145.184622)
			(xy 44.415814 -145.194694) (xy 44.44336 -145.208036) (xy 44.473622 -145.212621) (xy 44.503884 -145.208036)
			(xy 44.53143 -145.194694) (xy 44.542964 -145.184622) (xy 44.564291 -145.165352) (xy 44.611654 -145.132787)
			(xy 44.663365 -145.107696) (xy 44.718256 -145.090646) (xy 44.775083 -145.082024) (xy 44.832561 -145.082024)
			(xy 44.889388 -145.090646) (xy 44.944279 -145.107696) (xy 44.99599 -145.132787) (xy 45.043353 -145.165352)
			(xy 45.06468 -145.184622) (xy 45.076214 -145.194694) (xy 45.10376 -145.208036) (xy 45.134022 -145.212621)
			(xy 45.164284 -145.208036) (xy 45.19183 -145.194694) (xy 45.203364 -145.184622) (xy 45.224691 -145.165352)
			(xy 45.272054 -145.132787) (xy 45.323765 -145.107696) (xy 45.378656 -145.090646) (xy 45.435483 -145.082024)
			(xy 45.492961 -145.082024) (xy 45.549788 -145.090646) (xy 45.604679 -145.107696) (xy 45.65639 -145.132787)
			(xy 45.703753 -145.165352) (xy 45.72508 -145.184622) (xy 45.736614 -145.194694) (xy 45.76416 -145.208036)
			(xy 45.794422 -145.212621) (xy 45.824684 -145.208036) (xy 45.85223 -145.194694) (xy 45.863764 -145.184622)
			(xy 45.885091 -145.165352) (xy 45.932454 -145.132787) (xy 45.984165 -145.107696) (xy 46.039056 -145.090646)
			(xy 46.095883 -145.082024) (xy 46.153361 -145.082024) (xy 46.210188 -145.090646) (xy 46.265079 -145.107696)
			(xy 46.31679 -145.132787) (xy 46.364153 -145.165352) (xy 46.38548 -145.184622) (xy 46.397014 -145.194694)
			(xy 46.42456 -145.208036) (xy 46.454822 -145.212621) (xy 46.485084 -145.208036) (xy 46.51263 -145.194694)
			(xy 46.524164 -145.184622) (xy 46.545491 -145.165352) (xy 46.592854 -145.132787) (xy 46.644565 -145.107696)
			(xy 46.699456 -145.090646) (xy 46.756283 -145.082024) (xy 46.813761 -145.082024) (xy 46.870588 -145.090646)
			(xy 46.925479 -145.107696) (xy 46.97719 -145.132787) (xy 47.024553 -145.165352) (xy 47.04588 -145.184622)
			(xy 47.057414 -145.194694) (xy 47.08496 -145.208036) (xy 47.115222 -145.212621) (xy 47.145484 -145.208036)
			(xy 47.17303 -145.194694) (xy 47.184564 -145.184622) (xy 47.20588 -145.165338) (xy 47.253245 -145.132774)
			(xy 47.30496 -145.107685) (xy 47.359853 -145.090637) (xy 47.416682 -145.082017) (xy 47.445422 -145.081498)
			(xy 47.472674 -145.081957) (xy 47.526623 -145.089717) (xy 47.578919 -145.105075) (xy 47.628496 -145.127719)
			(xy 47.674347 -145.157189) (xy 47.715537 -145.192883) (xy 47.751228 -145.234076) (xy 47.780694 -145.279928)
			(xy 47.803335 -145.329508) (xy 47.818689 -145.381804) (xy 47.826445 -145.435754) (xy 47.82693 -145.463006)
			(xy 47.826467 -145.489242) (xy 47.819271 -145.541217) (xy 47.805017 -145.591715) (xy 47.783973 -145.639781)
			(xy 47.756538 -145.684508) (xy 47.723228 -145.725051) (xy 47.704248 -145.743168) (xy 47.696871 -145.750692)
			(xy 47.688442 -145.769979) (xy 47.688444 -145.791029) (xy 47.696876 -145.810315) (xy 47.704248 -145.817844)
			(xy 47.725584 -145.83918) (xy 47.733113 -145.846552) (xy 47.752398 -145.854983) (xy 47.773446 -145.854983)
			(xy 47.792731 -145.846552) (xy 47.80026 -145.83918) (xy 47.818371 -145.820192) (xy 47.858911 -145.786874)
			(xy 47.903638 -145.759432) (xy 47.951706 -145.738384) (xy 48.002206 -145.724128) (xy 48.054185 -145.716934)
			(xy 48.080422 -145.716498) (xy 48.107674 -145.716957) (xy 48.161623 -145.724717) (xy 48.213919 -145.740075)
			(xy 48.263496 -145.762719) (xy 48.309347 -145.792189) (xy 48.350537 -145.827883) (xy 48.386228 -145.869076)
			(xy 48.400993 -145.892052) (xy 49.996289 -145.892052) (xy 49.996289 -145.837548) (xy 50.004047 -145.783598)
			(xy 50.019404 -145.731301) (xy 50.042047 -145.681722) (xy 50.071517 -145.635871) (xy 50.107212 -145.594681)
			(xy 50.148406 -145.55899) (xy 50.194261 -145.529526) (xy 50.243842 -145.506888) (xy 50.296141 -145.491537)
			(xy 50.350092 -145.483786) (xy 50.377344 -145.483326) (xy 50.407031 -145.483911) (xy 50.465689 -145.493102)
			(xy 50.522215 -145.511271) (xy 50.575243 -145.537978) (xy 50.623492 -145.57258) (xy 50.665798 -145.614239)
			(xy 50.683922 -145.637758) (xy 50.692348 -145.648365) (xy 50.713661 -145.665072) (xy 50.738615 -145.675591)
			(xy 50.765456 -145.679181) (xy 50.792297 -145.675591) (xy 50.817251 -145.665072) (xy 50.838564 -145.648365)
			(xy 50.84699 -145.637758) (xy 50.86512 -145.614243) (xy 50.907427 -145.572585) (xy 50.955675 -145.537982)
			(xy 51.008701 -145.511271) (xy 51.065225 -145.493095) (xy 51.123881 -145.483893) (xy 51.153568 -145.483326)
			(xy 51.180825 -145.483719) (xy 51.234784 -145.491473) (xy 51.28709 -145.506827) (xy 51.336679 -145.52947)
			(xy 51.38254 -145.55894) (xy 51.423741 -145.594637) (xy 51.459441 -145.635834) (xy 51.488915 -145.681693)
			(xy 51.511561 -145.73128) (xy 51.52692 -145.783585) (xy 51.534679 -145.837543) (xy 51.534679 -145.892057)
			(xy 51.52692 -145.946015) (xy 51.511561 -145.99832) (xy 51.488915 -146.047907) (xy 51.459441 -146.093766)
			(xy 51.423741 -146.134963) (xy 51.38254 -146.17066) (xy 51.336679 -146.20013) (xy 51.28709 -146.222773)
			(xy 51.234784 -146.238127) (xy 51.180825 -146.245881) (xy 51.153568 -146.246342) (xy 51.123881 -146.24576)
			(xy 51.065222 -146.23657) (xy 51.008695 -146.218402) (xy 50.955667 -146.191694) (xy 50.907418 -146.157091)
			(xy 50.865114 -146.11543) (xy 50.84699 -146.09191) (xy 50.838564 -146.081303) (xy 50.817251 -146.064596)
			(xy 50.792297 -146.054077) (xy 50.765456 -146.050487) (xy 50.738615 -146.054077) (xy 50.713661 -146.064596)
			(xy 50.692348 -146.081303) (xy 50.683922 -146.09191) (xy 50.665776 -146.115412) (xy 50.623474 -146.157073)
			(xy 50.575229 -146.191678) (xy 50.522206 -146.218392) (xy 50.465685 -146.23657) (xy 50.40703 -146.245774)
			(xy 50.377344 -146.246342) (xy 50.350092 -146.245814) (xy 50.296141 -146.238063) (xy 50.243842 -146.222712)
			(xy 50.194261 -146.200074) (xy 50.148406 -146.17061) (xy 50.107212 -146.134919) (xy 50.071517 -146.093729)
			(xy 50.042047 -146.047878) (xy 50.019404 -145.998299) (xy 50.004047 -145.946002) (xy 49.996289 -145.892052)
			(xy 48.400993 -145.892052) (xy 48.415694 -145.914928) (xy 48.438335 -145.964508) (xy 48.453689 -146.016804)
			(xy 48.461445 -146.070754) (xy 48.46193 -146.098006) (xy 48.461402 -146.126745) (xy 48.452779 -146.183571)
			(xy 48.43573 -146.238462) (xy 48.410639 -146.290174) (xy 48.378076 -146.337537) (xy 48.358806 -146.358864)
			(xy 48.348699 -146.3704) (xy 48.335361 -146.398008) (xy 48.330783 -146.428324) (xy 48.335375 -146.458639)
			(xy 48.348727 -146.48624) (xy 48.358806 -146.497802) (xy 48.378048 -146.519154) (xy 48.41062 -146.566508)
			(xy 48.435719 -146.618213) (xy 48.452776 -146.673099) (xy 48.461405 -146.729923) (xy 48.46193 -146.75866)
			(xy 48.461408 -146.785911) (xy 48.453657 -146.839859) (xy 48.438307 -146.892154) (xy 48.415671 -146.941732)
			(xy 48.386209 -146.987585) (xy 48.350521 -147.028777) (xy 48.309334 -147.064472) (xy 48.263487 -147.093941)
			(xy 48.213912 -147.116585) (xy 48.161619 -147.131943) (xy 48.107673 -147.139703) (xy 48.080422 -147.140168)
			(xy 48.053052 -147.139697) (xy 47.998873 -147.131881) (xy 47.946369 -147.116394) (xy 47.896622 -147.093553)
			(xy 47.850656 -147.063829) (xy 47.829724 -147.046188) (xy 47.818396 -147.036952) (xy 47.791839 -147.024776)
			(xy 47.762922 -147.020603) (xy 47.734005 -147.024776) (xy 47.707448 -147.036952) (xy 47.69612 -147.046188)
			(xy 47.67519 -147.063829) (xy 47.629217 -147.093541) (xy 47.579469 -147.116377) (xy 47.526968 -147.131867)
			(xy 47.472791 -147.139695) (xy 47.445422 -147.140168) (xy 47.416685 -147.139613) (xy 47.359859 -147.130995)
			(xy 47.30497 -147.113951) (xy 47.253257 -147.088867) (xy 47.205893 -147.05631) (xy 47.184564 -147.037044)
			(xy 47.17303 -147.026972) (xy 47.145484 -147.01363) (xy 47.115222 -147.009045) (xy 47.08496 -147.01363)
			(xy 47.057414 -147.026972) (xy 47.04588 -147.037044) (xy 47.024553 -147.056314) (xy 46.97719 -147.088879)
			(xy 46.925479 -147.11397) (xy 46.870588 -147.13102) (xy 46.813761 -147.139642) (xy 46.756283 -147.139642)
			(xy 46.699456 -147.13102) (xy 46.644565 -147.11397) (xy 46.592854 -147.088879) (xy 46.545491 -147.056314)
			(xy 46.524164 -147.037044) (xy 46.51263 -147.026972) (xy 46.485084 -147.01363) (xy 46.454822 -147.009045)
			(xy 46.42456 -147.01363) (xy 46.397014 -147.026972) (xy 46.38548 -147.037044) (xy 46.364153 -147.056314)
			(xy 46.31679 -147.088879) (xy 46.265079 -147.11397) (xy 46.210188 -147.13102) (xy 46.153361 -147.139642)
			(xy 46.095883 -147.139642) (xy 46.039056 -147.13102) (xy 45.984165 -147.11397) (xy 45.932454 -147.088879)
			(xy 45.885091 -147.056314) (xy 45.863764 -147.037044) (xy 45.85223 -147.026972) (xy 45.824684 -147.01363)
			(xy 45.794422 -147.009045) (xy 45.76416 -147.01363) (xy 45.736614 -147.026972) (xy 45.72508 -147.037044)
			(xy 45.703753 -147.056314) (xy 45.65639 -147.088879) (xy 45.604679 -147.11397) (xy 45.549788 -147.13102)
			(xy 45.492961 -147.139642) (xy 45.435483 -147.139642) (xy 45.378656 -147.13102) (xy 45.323765 -147.11397)
			(xy 45.272054 -147.088879) (xy 45.224691 -147.056314) (xy 45.203364 -147.037044) (xy 45.19183 -147.026972)
			(xy 45.164284 -147.01363) (xy 45.134022 -147.009045) (xy 45.10376 -147.01363) (xy 45.076214 -147.026972)
			(xy 45.06468 -147.037044) (xy 45.043353 -147.056314) (xy 44.99599 -147.088879) (xy 44.944279 -147.11397)
			(xy 44.889388 -147.13102) (xy 44.832561 -147.139642) (xy 44.775083 -147.139642) (xy 44.718256 -147.13102)
			(xy 44.663365 -147.11397) (xy 44.611654 -147.088879) (xy 44.564291 -147.056314) (xy 44.542964 -147.037044)
			(xy 44.53143 -147.026972) (xy 44.503884 -147.01363) (xy 44.473622 -147.009045) (xy 44.44336 -147.01363)
			(xy 44.415814 -147.026972) (xy 44.40428 -147.037044) (xy 44.382941 -147.056301) (xy 44.335583 -147.08887)
			(xy 44.283874 -147.113965) (xy 44.228986 -147.131019) (xy 44.17216 -147.139645) (xy 44.143422 -147.140168)
			(xy 44.116052 -147.139697) (xy 44.061873 -147.131881) (xy 44.009369 -147.116394) (xy 43.959622 -147.093553)
			(xy 43.913656 -147.063829) (xy 43.892724 -147.046188) (xy 43.881396 -147.036952) (xy 43.854839 -147.024776)
			(xy 43.825922 -147.020603) (xy 43.797005 -147.024776) (xy 43.770448 -147.036952) (xy 43.75912 -147.046188)
			(xy 43.73819 -147.063829) (xy 43.692217 -147.093541) (xy 43.642469 -147.116377) (xy 43.589968 -147.131867)
			(xy 43.535791 -147.139695) (xy 43.508422 -147.140168) (xy 43.481168 -147.139724) (xy 43.427214 -147.131969)
			(xy 43.374914 -147.116614) (xy 43.325331 -147.093971) (xy 43.279476 -147.064502) (xy 43.238282 -147.028806)
			(xy 43.202588 -146.98761) (xy 43.17312 -146.941753) (xy 43.15048 -146.89217) (xy 43.135127 -146.839868)
			(xy 43.127375 -146.785914) (xy 43.126914 -146.75866) (xy 37.27958 -146.75866) (xy 37.27958 -147.977451)
			(xy 50.206652 -147.977451) (xy 50.206652 -147.922949) (xy 50.214408 -147.869001) (xy 50.229762 -147.816707)
			(xy 50.252401 -147.767129) (xy 50.281865 -147.721277) (xy 50.317554 -147.680086) (xy 50.358742 -147.644392)
			(xy 50.40459 -147.614922) (xy 50.454165 -147.592277) (xy 50.506458 -147.576917) (xy 50.560405 -147.569155)
			(xy 50.587656 -147.568666) (xy 50.617561 -147.569202) (xy 50.67664 -147.578514) (xy 50.705258 -147.587208)
			(xy 50.719167 -147.591239) (xy 50.748099 -147.592148) (xy 50.776118 -147.584883) (xy 50.800963 -147.570032)
			(xy 50.820629 -147.548792) (xy 50.833527 -147.522879) (xy 50.836576 -147.508722) (xy 50.843165 -147.475884)
			(xy 50.866284 -147.413031) (xy 50.88255 -147.383754) (xy 50.889618 -147.370804) (xy 50.896647 -147.342161)
			(xy 50.895197 -147.312704) (xy 50.885389 -147.28489) (xy 50.868042 -147.261039) (xy 50.844601 -147.243141)
			(xy 50.830988 -147.23745) (xy 50.80422 -147.226735) (xy 50.753979 -147.19845) (xy 50.70857 -147.162922)
			(xy 50.669027 -147.120963) (xy 50.636253 -147.073528) (xy 50.610993 -147.0217) (xy 50.593825 -146.96666)
			(xy 50.585139 -146.909662) (xy 50.584608 -146.880834) (xy 50.585094 -146.853583) (xy 50.59285 -146.799635)
			(xy 50.608205 -146.74734) (xy 50.630847 -146.697763) (xy 50.660313 -146.651913) (xy 50.696004 -146.610722)
			(xy 50.737195 -146.575031) (xy 50.783045 -146.545565) (xy 50.832622 -146.522923) (xy 50.884917 -146.507568)
			(xy 50.938865 -146.499812) (xy 50.993367 -146.499812) (xy 51.047315 -146.507568) (xy 51.09961 -146.522923)
			(xy 51.149187 -146.545565) (xy 51.195037 -146.575031) (xy 51.236228 -146.610722) (xy 51.271919 -146.651913)
			(xy 51.301385 -146.697763) (xy 51.324027 -146.74734) (xy 51.339382 -146.799635) (xy 51.347138 -146.853583)
			(xy 51.347624 -146.880834) (xy 51.347239 -146.90607) (xy 51.340617 -146.956104) (xy 51.32744 -147.004824)
			(xy 51.30794 -147.051376) (xy 51.295554 -147.073366) (xy 51.28846 -147.086303) (xy 51.281434 -147.114951)
			(xy 51.282888 -147.144412) (xy 51.292701 -147.172229) (xy 51.310054 -147.196081) (xy 51.3335 -147.21398)
			(xy 51.347116 -147.21967) (xy 51.373892 -147.230366) (xy 51.424134 -147.258654) (xy 51.469543 -147.294184)
			(xy 51.509085 -147.336146) (xy 51.541859 -147.383583) (xy 51.567117 -147.435414) (xy 51.584283 -147.490457)
			(xy 51.592966 -147.547457) (xy 51.593496 -147.576286) (xy 51.593032 -147.603539) (xy 51.585276 -147.657491)
			(xy 51.569921 -147.709789) (xy 51.54728 -147.75937) (xy 51.517812 -147.805224) (xy 51.482118 -147.846417)
			(xy 51.440925 -147.882111) (xy 51.395072 -147.911579) (xy 51.345491 -147.934221) (xy 51.293193 -147.949576)
			(xy 51.239241 -147.957331) (xy 51.211988 -147.957794) (xy 51.182083 -147.957273) (xy 51.123003 -147.947951)
			(xy 51.094386 -147.939252) (xy 51.080457 -147.935302) (xy 51.051539 -147.934385) (xy 51.02353 -147.941636)
			(xy 50.998691 -147.956471) (xy 50.979026 -147.977693) (xy 50.966122 -148.003589) (xy 50.963068 -148.017738)
			(xy 50.957919 -148.043816) (xy 50.941346 -148.09432) (xy 50.917921 -148.142034) (xy 50.888096 -148.186032)
			(xy 50.852451 -148.225463) (xy 50.811676 -148.259561) (xy 50.76656 -148.287667) (xy 50.717979 -148.309236)
			(xy 50.666873 -148.323849) (xy 50.614233 -148.331225) (xy 50.587656 -148.331682) (xy 50.560405 -148.331245)
			(xy 50.506458 -148.323483) (xy 50.454165 -148.308123) (xy 50.40459 -148.285478) (xy 50.358742 -148.256008)
			(xy 50.317554 -148.220314) (xy 50.281865 -148.179123) (xy 50.252401 -148.133271) (xy 50.229762 -148.083693)
			(xy 50.214408 -148.031399) (xy 50.206652 -147.977451) (xy 37.27958 -147.977451) (xy 37.27958 -150.44547)
			(xy 50.99304 -150.44547) (xy 50.993427 -150.418214) (xy 51.001189 -150.364258) (xy 51.016552 -150.311956)
			(xy 51.039201 -150.262372) (xy 51.068677 -150.216517) (xy 51.104379 -150.175323) (xy 51.145579 -150.13963)
			(xy 51.191441 -150.110164) (xy 51.241029 -150.087524) (xy 51.293334 -150.072173) (xy 51.347292 -150.064422)
			(xy 51.374548 -150.063962) (xy 51.402122 -150.064442) (xy 51.456695 -150.072388) (xy 51.509556 -150.088109)
			(xy 51.559603 -150.111276) (xy 51.605792 -150.141408) (xy 51.647163 -150.177875) (xy 51.665378 -150.198582)
			(xy 51.675276 -150.20948) (xy 51.699926 -150.225555) (xy 51.728134 -150.233939) (xy 51.757562 -150.233939)
			(xy 51.78577 -150.225555) (xy 51.81042 -150.20948) (xy 51.820318 -150.198582) (xy 51.838512 -150.177855)
			(xy 51.879885 -150.141387) (xy 51.926079 -150.111257) (xy 51.97613 -150.088094) (xy 52.028995 -150.072381)
			(xy 52.083572 -150.064445) (xy 52.111148 -150.063962) (xy 52.137649 -150.064415) (xy 52.19014 -150.071762)
			(xy 52.241107 -150.086307) (xy 52.289569 -150.10777) (xy 52.334592 -150.135737) (xy 52.355242 -150.152354)
			(xy 52.367396 -150.161784) (xy 52.395794 -150.173573) (xy 52.426411 -150.176397) (xy 52.456486 -150.170003)
			(xy 52.483306 -150.154967) (xy 52.504451 -150.132645) (xy 52.511706 -150.11908) (xy 52.523817 -150.095395)
			(xy 52.553737 -150.051413) (xy 52.589605 -150.01213) (xy 52.630693 -149.978345) (xy 52.653184 -149.96414)
			(xy 52.665431 -149.956248) (xy 52.685104 -149.934769) (xy 52.697907 -149.908607) (xy 52.702796 -149.879894)
			(xy 52.699373 -149.850969) (xy 52.694078 -149.837394) (xy 52.684593 -149.814182) (xy 52.671241 -149.76585)
			(xy 52.664511 -149.716161) (xy 52.664106 -149.69109) (xy 52.66454 -149.666021) (xy 52.671286 -149.616338)
			(xy 52.684614 -149.568004) (xy 52.694078 -149.544786) (xy 52.699333 -149.531207) (xy 52.702713 -149.502299)
			(xy 52.697811 -149.47361) (xy 52.685024 -149.447464) (xy 52.665389 -149.42598) (xy 52.653184 -149.41804)
			(xy 52.630024 -149.403514) (xy 52.587899 -149.368668) (xy 52.551317 -149.328041) (xy 52.521063 -149.282506)
			(xy 52.497786 -149.233039) (xy 52.481986 -149.180703) (xy 52.474001 -149.126619) (xy 52.474003 -149.07195)
			(xy 52.481993 -149.017867) (xy 52.497797 -148.965532) (xy 52.521079 -148.916067) (xy 52.551336 -148.870534)
			(xy 52.587922 -148.829911) (xy 52.630049 -148.795068) (xy 52.653184 -148.7805) (xy 52.66539 -148.772551)
			(xy 52.685063 -148.751088) (xy 52.697871 -148.724941) (xy 52.702771 -148.696241) (xy 52.699363 -148.667326)
			(xy 52.694078 -148.653754) (xy 52.684581 -148.630547) (xy 52.671233 -148.582213) (xy 52.664508 -148.532522)
			(xy 52.664106 -148.50745) (xy 52.664627 -148.479565) (xy 52.672939 -148.424418) (xy 52.689377 -148.371126)
			(xy 52.713575 -148.32088) (xy 52.744991 -148.274801) (xy 52.782924 -148.233919) (xy 52.826526 -148.199147)
			(xy 52.874824 -148.171262) (xy 52.926739 -148.150887) (xy 52.98111 -148.138477) (xy 53.036724 -148.13431)
			(xy 53.092338 -148.138477) (xy 53.146709 -148.150887) (xy 53.198624 -148.171262) (xy 53.246922 -148.199147)
			(xy 53.290524 -148.233919) (xy 53.328457 -148.274801) (xy 53.359873 -148.32088) (xy 53.384071 -148.371126)
			(xy 53.400509 -148.424418) (xy 53.408821 -148.479565) (xy 53.409342 -148.50745) (xy 53.408875 -148.534782)
			(xy 53.400906 -148.588863) (xy 53.385118 -148.641198) (xy 53.36185 -148.690662) (xy 53.331601 -148.736195)
			(xy 53.295022 -148.776817) (xy 53.252897 -148.811655) (xy 53.229764 -148.82622) (xy 53.217537 -148.834138)
			(xy 53.19787 -148.855612) (xy 53.185068 -148.881767) (xy 53.180173 -148.910472) (xy 53.183584 -148.939392)
			(xy 53.18887 -148.952966) (xy 53.198345 -148.976181) (xy 53.211701 -149.024512) (xy 53.218435 -149.074199)
			(xy 53.218842 -149.09927) (xy 53.218431 -149.12434) (xy 53.211677 -149.174023) (xy 53.198339 -149.222357)
			(xy 53.18887 -149.245574) (xy 53.183624 -149.259151) (xy 53.180262 -149.288051) (xy 53.185173 -149.316729)
			(xy 53.197961 -149.342863) (xy 53.217591 -149.364338) (xy 53.229764 -149.37232) (xy 53.252885 -149.386903)
			(xy 53.295003 -149.421747) (xy 53.331579 -149.462369) (xy 53.361829 -149.507898) (xy 53.385103 -149.557358)
			(xy 53.400902 -149.609688) (xy 53.408888 -149.663764) (xy 53.408889 -149.718426) (xy 53.400905 -149.772502)
			(xy 53.385107 -149.824832) (xy 53.361834 -149.874292) (xy 53.331585 -149.919823) (xy 53.29501 -149.960446)
			(xy 53.252893 -149.995291) (xy 53.229764 -150.00986) (xy 53.217509 -150.017739) (xy 53.197842 -150.039225)
			(xy 53.185043 -150.06539) (xy 53.180156 -150.094104) (xy 53.183577 -150.12303) (xy 53.18887 -150.136606)
			(xy 53.198357 -150.159817) (xy 53.211708 -150.208149) (xy 53.218438 -150.257838) (xy 53.218842 -150.28291)
			(xy 53.21837 -150.309752) (xy 53.210665 -150.362881) (xy 53.195416 -150.414354) (xy 53.172938 -150.463106)
			(xy 53.143697 -150.508127) (xy 53.108298 -150.548487) (xy 53.067473 -150.583349) (xy 53.022069 -150.611993)
			(xy 52.973024 -150.633824) (xy 52.947316 -150.641558) (xy 52.932841 -150.646276) (xy 52.907286 -150.662788)
			(xy 52.887726 -150.686092) (xy 52.875894 -150.714122) (xy 52.87284 -150.744393) (xy 52.878835 -150.774222)
			(xy 52.885594 -150.787862) (xy 52.900228 -150.816008) (xy 52.920955 -150.875959) (xy 52.931453 -150.938517)
			(xy 52.932076 -150.970234) (xy 52.931855 -150.988253) (xy 52.928421 -151.024128) (xy 52.925218 -151.041862)
			(xy 52.922936 -151.057077) (xy 52.926453 -151.087622) (xy 52.938901 -151.115736) (xy 52.959153 -151.138871)
			(xy 52.985373 -151.154931) (xy 53.000148 -151.15921) (xy 53.027191 -151.166611) (xy 53.078917 -151.188241)
			(xy 53.126922 -151.217205) (xy 53.170174 -151.25288) (xy 53.207741 -151.294499) (xy 53.238815 -151.341165)
			(xy 53.262728 -151.391876) (xy 53.278965 -151.44554) (xy 53.287177 -151.501001) (xy 53.287676 -151.529034)
			(xy 53.287254 -151.556288) (xy 53.279492 -151.610239) (xy 53.264131 -151.662537) (xy 53.241483 -151.712117)
			(xy 53.21201 -151.757968) (xy 53.176312 -151.799159) (xy 53.135115 -151.83485) (xy 53.089259 -151.864315)
			(xy 53.039675 -151.886954) (xy 52.987375 -151.902306) (xy 52.933422 -151.910058) (xy 52.906168 -151.910542)
			(xy 52.878594 -151.91005) (xy 52.824022 -151.902105) (xy 52.771161 -151.886387) (xy 52.721115 -151.863222)
			(xy 52.674925 -151.833093) (xy 52.633554 -151.796628) (xy 52.615338 -151.775922) (xy 52.60544 -151.765024)
			(xy 52.58079 -151.748949) (xy 52.552582 -151.740565) (xy 52.523154 -151.740565) (xy 52.494946 -151.748949)
			(xy 52.470296 -151.765024) (xy 52.460398 -151.775922) (xy 52.442183 -151.796628) (xy 52.400812 -151.833093)
			(xy 52.354622 -151.86322) (xy 52.304575 -151.886383) (xy 52.251714 -151.902099) (xy 52.197142 -151.910039)
			(xy 52.141994 -151.910039) (xy 52.087422 -151.902099) (xy 52.034561 -151.886383) (xy 51.984514 -151.86322)
			(xy 51.938324 -151.833093) (xy 51.896953 -151.796628) (xy 51.878738 -151.775922) (xy 51.86884 -151.765024)
			(xy 51.84419 -151.748949) (xy 51.815982 -151.740565) (xy 51.786554 -151.740565) (xy 51.758346 -151.748949)
			(xy 51.733696 -151.765024) (xy 51.723798 -151.775922) (xy 51.705596 -151.796642) (xy 51.664225 -151.83311)
			(xy 51.618033 -151.863241) (xy 51.567983 -151.886405) (xy 51.515119 -151.90212) (xy 51.460543 -151.910058)
			(xy 51.432968 -151.910542) (xy 51.405718 -151.910052) (xy 51.351772 -151.902292) (xy 51.299479 -151.886935)
			(xy 51.249904 -151.864292) (xy 51.204055 -151.834826) (xy 51.162866 -151.799135) (xy 51.127175 -151.757946)
			(xy 51.097709 -151.712098) (xy 51.075066 -151.662523) (xy 51.059708 -151.61023) (xy 51.051948 -151.556284)
			(xy 51.05146 -151.529034) (xy 51.052043 -151.501181) (xy 51.060161 -151.44607) (xy 51.0762 -151.392722)
			(xy 51.09982 -151.342272) (xy 51.130519 -151.295788) (xy 51.167647 -151.254258) (xy 51.210414 -151.218563)
			(xy 51.257914 -151.189461) (xy 51.309138 -151.167569) (xy 51.33594 -151.159972) (xy 51.350063 -151.155719)
			(xy 51.375204 -151.14032) (xy 51.394916 -151.118396) (xy 51.407566 -151.091764) (xy 51.412104 -151.062632)
			(xy 51.410616 -151.047958) (xy 51.408945 -151.034942) (xy 51.407166 -151.008757) (xy 51.40706 -150.995634)
			(xy 51.407158 -150.981485) (xy 51.409189 -150.953262) (xy 51.411124 -150.939246) (xy 51.412683 -150.925896)
			(xy 51.409585 -150.899209) (xy 51.39962 -150.874259) (xy 51.38348 -150.852781) (xy 51.362288 -150.836267)
			(xy 51.337516 -150.825867) (xy 51.324256 -150.823676) (xy 51.297113 -150.81953) (xy 51.244287 -150.804561)
			(xy 51.194152 -150.782174) (xy 51.147744 -150.752832) (xy 51.106021 -150.717141) (xy 51.069844 -150.675838)
			(xy 51.039961 -150.629777) (xy 51.016989 -150.579907) (xy 51.001402 -150.52726) (xy 50.993522 -150.472923)
			(xy 50.99304 -150.44547) (xy 37.27958 -150.44547) (xy 37.27958 -151.644871) (xy 43.782962 -151.644871)
			(xy 43.786968 -151.589723) (xy 43.798892 -151.535731) (xy 43.818485 -151.484026) (xy 43.845337 -151.435691)
			(xy 43.878885 -151.391738) (xy 43.898312 -151.372062) (xy 43.907656 -151.362295) (xy 43.921334 -151.338994)
			(xy 43.928423 -151.312922) (xy 43.928426 -151.285903) (xy 43.921344 -151.259829) (xy 43.907671 -151.236525)
			(xy 43.898312 -151.226774) (xy 43.880473 -151.208774) (xy 43.849246 -151.16886) (xy 43.823579 -151.125162)
			(xy 43.803922 -151.078452) (xy 43.790624 -151.029549) (xy 43.783917 -150.979317) (xy 43.783504 -150.953978)
			(xy 43.783957 -150.926726) (xy 43.791717 -150.872776) (xy 43.807076 -150.82048) (xy 43.82972 -150.770902)
			(xy 43.85919 -150.725051) (xy 43.894885 -150.683861) (xy 43.936078 -150.64817) (xy 43.981932 -150.618704)
			(xy 44.031512 -150.596064) (xy 44.083809 -150.58071) (xy 44.13776 -150.572955) (xy 44.165012 -150.57247)
			(xy 44.194271 -150.573037) (xy 44.252103 -150.581981) (xy 44.307894 -150.599642) (xy 44.360337 -150.625607)
			(xy 44.408206 -150.659268) (xy 44.42968 -150.67915) (xy 44.439987 -150.688465) (xy 44.464413 -150.701673)
			(xy 44.491499 -150.707794) (xy 44.519231 -150.706373) (xy 44.545549 -150.697515) (xy 44.568497 -150.681879)
			(xy 44.577762 -150.67153) (xy 44.596006 -150.650711) (xy 44.637408 -150.613972) (xy 44.683688 -150.583606)
			(xy 44.733873 -150.560253) (xy 44.786908 -150.544404) (xy 44.841678 -150.536392) (xy 44.869354 -150.535894)
			(xy 44.896723 -150.536388) (xy 44.950901 -150.5442) (xy 45.003404 -150.559682) (xy 45.053151 -150.582518)
			(xy 45.099119 -150.612236) (xy 45.120052 -150.629874) (xy 45.13138 -150.63911) (xy 45.157937 -150.651286)
			(xy 45.186854 -150.655459) (xy 45.215771 -150.651286) (xy 45.242328 -150.63911) (xy 45.253656 -150.629874)
			(xy 45.274589 -150.612233) (xy 45.320557 -150.582509) (xy 45.370303 -150.559663) (xy 45.422805 -150.544167)
			(xy 45.476983 -150.536338) (xy 45.531725 -150.536338) (xy 45.585903 -150.544167) (xy 45.638405 -150.559663)
			(xy 45.688151 -150.582509) (xy 45.734119 -150.612233) (xy 45.755052 -150.629874) (xy 45.76638 -150.63911)
			(xy 45.792937 -150.651286) (xy 45.821854 -150.655459) (xy 45.850771 -150.651286) (xy 45.877328 -150.63911)
			(xy 45.888656 -150.629874) (xy 45.909589 -150.612233) (xy 45.955557 -150.582509) (xy 46.005303 -150.559663)
			(xy 46.057805 -150.544167) (xy 46.111983 -150.536338) (xy 46.166725 -150.536338) (xy 46.220903 -150.544167)
			(xy 46.273405 -150.559663) (xy 46.323151 -150.582509) (xy 46.369119 -150.612233) (xy 46.390052 -150.629874)
			(xy 46.40138 -150.63911) (xy 46.427937 -150.651286) (xy 46.456854 -150.655459) (xy 46.485771 -150.651286)
			(xy 46.512328 -150.63911) (xy 46.523656 -150.629874) (xy 46.54459 -150.612238) (xy 46.590563 -150.582527)
			(xy 46.64031 -150.55969) (xy 46.69281 -150.544199) (xy 46.746985 -150.536369) (xy 46.774354 -150.535894)
			(xy 46.804152 -150.536484) (xy 46.863022 -150.545758) (xy 46.919734 -150.56407) (xy 46.972911 -150.590976)
			(xy 47.021258 -150.625822) (xy 47.042832 -150.646384) (xy 47.054372 -150.657021) (xy 47.082273 -150.671355)
			(xy 47.113206 -150.676557) (xy 47.144261 -150.672139) (xy 47.172516 -150.658516) (xy 47.18431 -150.648162)
			(xy 47.205669 -150.628715) (xy 47.25316 -150.595835) (xy 47.305067 -150.570493) (xy 47.360201 -150.553269)
			(xy 47.417303 -150.544556) (xy 47.446184 -150.544022) (xy 47.473438 -150.54447) (xy 47.527391 -150.552226)
			(xy 47.579691 -150.567581) (xy 47.629273 -150.590224) (xy 47.675128 -150.619693) (xy 47.716321 -150.655389)
			(xy 47.752015 -150.696584) (xy 47.781483 -150.742439) (xy 47.804124 -150.792022) (xy 47.819477 -150.844323)
			(xy 47.827231 -150.898276) (xy 47.827692 -150.92553) (xy 47.827299 -150.950869) (xy 47.820586 -151.001101)
			(xy 47.807281 -151.050002) (xy 47.787619 -151.096711) (xy 47.761946 -151.140406) (xy 47.730715 -151.180317)
			(xy 47.712884 -151.198326) (xy 47.703553 -151.208104) (xy 47.689874 -151.231402) (xy 47.682784 -151.257471)
			(xy 47.682779 -151.284487) (xy 47.689858 -151.310559) (xy 47.703527 -151.333863) (xy 47.712884 -151.343614)
			(xy 47.732318 -151.363281) (xy 47.76586 -151.407234) (xy 47.792706 -151.455569) (xy 47.812293 -151.507273)
			(xy 47.824211 -151.561262) (xy 47.828212 -151.616407) (xy 47.824209 -151.671552) (xy 47.812289 -151.725541)
			(xy 47.7927 -151.777244) (xy 47.765852 -151.825578) (xy 47.732309 -151.86953) (xy 47.712884 -151.889206)
			(xy 47.703473 -151.898913) (xy 47.6898 -151.922231) (xy 47.68272 -151.948319) (xy 47.682729 -151.975351)
			(xy 47.689827 -152.001433) (xy 47.703516 -152.024742) (xy 47.712884 -152.034494) (xy 47.730707 -152.05251)
			(xy 47.761935 -152.09242) (xy 47.787605 -152.136114) (xy 47.807264 -152.182822) (xy 47.820566 -152.231722)
			(xy 47.827277 -152.281952) (xy 47.827692 -152.30729) (xy 47.827235 -152.334543) (xy 47.819479 -152.388495)
			(xy 47.804124 -152.440794) (xy 47.781481 -152.490375) (xy 47.752013 -152.536229) (xy 47.716318 -152.577423)
			(xy 47.675125 -152.613116) (xy 47.62927 -152.642584) (xy 47.579689 -152.665226) (xy 47.527389 -152.680581)
			(xy 47.473437 -152.688336) (xy 47.446184 -152.688798) (xy 47.416385 -152.688249) (xy 47.357513 -152.678966)
			(xy 47.300799 -152.660644) (xy 47.247624 -152.633728) (xy 47.199279 -152.598874) (xy 47.177706 -152.578308)
			(xy 47.166217 -152.567611) (xy 47.138297 -152.553284) (xy 47.107349 -152.548094) (xy 47.076284 -152.552527)
			(xy 47.048023 -152.566167) (xy 47.036228 -152.57653) (xy 47.014852 -152.595958) (xy 46.967366 -152.628841)
			(xy 46.915463 -152.654186) (xy 46.860333 -152.671415) (xy 46.803234 -152.680133) (xy 46.774354 -152.68067)
			(xy 46.746985 -152.68018) (xy 46.692806 -152.672369) (xy 46.640303 -152.656886) (xy 46.590556 -152.634049)
			(xy 46.544588 -152.604329) (xy 46.523656 -152.58669) (xy 46.512328 -152.577454) (xy 46.485771 -152.565278)
			(xy 46.456854 -152.561105) (xy 46.427937 -152.565278) (xy 46.40138 -152.577454) (xy 46.390052 -152.58669)
			(xy 46.369119 -152.604331) (xy 46.323151 -152.634055) (xy 46.273405 -152.656901) (xy 46.220903 -152.672397)
			(xy 46.166725 -152.680226) (xy 46.111983 -152.680226) (xy 46.057805 -152.672397) (xy 46.005303 -152.656901)
			(xy 45.955557 -152.634055) (xy 45.909589 -152.604331) (xy 45.888656 -152.58669) (xy 45.877328 -152.577454)
			(xy 45.850771 -152.565278) (xy 45.821854 -152.561105) (xy 45.792937 -152.565278) (xy 45.76638 -152.577454)
			(xy 45.755052 -152.58669) (xy 45.734119 -152.604331) (xy 45.688151 -152.634055) (xy 45.638405 -152.656901)
			(xy 45.585903 -152.672397) (xy 45.531725 -152.680226) (xy 45.476983 -152.680226) (xy 45.422805 -152.672397)
			(xy 45.370303 -152.656901) (xy 45.320557 -152.634055) (xy 45.274589 -152.604331) (xy 45.253656 -152.58669)
			(xy 45.242328 -152.577454) (xy 45.215771 -152.565278) (xy 45.186854 -152.561105) (xy 45.157937 -152.565278)
			(xy 45.13138 -152.577454) (xy 45.120052 -152.58669) (xy 45.09911 -152.604317) (xy 45.05314 -152.634031)
			(xy 45.003395 -152.656869) (xy 44.950897 -152.672363) (xy 44.896723 -152.680194) (xy 44.869354 -152.68067)
			(xy 44.840094 -152.680113) (xy 44.782263 -152.671165) (xy 44.726473 -152.653501) (xy 44.674029 -152.627534)
			(xy 44.62616 -152.593872) (xy 44.604686 -152.57399) (xy 44.594404 -152.564648) (xy 44.569969 -152.551451)
			(xy 44.542878 -152.545339) (xy 44.515144 -152.546766) (xy 44.488824 -152.555626) (xy 44.465872 -152.571261)
			(xy 44.456604 -152.58161) (xy 44.438387 -152.602453) (xy 44.396978 -152.639189) (xy 44.350692 -152.669551)
			(xy 44.300502 -152.692899) (xy 44.247463 -152.708743) (xy 44.19269 -152.71675) (xy 44.165012 -152.717246)
			(xy 44.137763 -152.716711) (xy 44.083819 -152.708957) (xy 44.031527 -152.693605) (xy 43.981953 -152.670968)
			(xy 43.936104 -152.641507) (xy 43.894915 -152.60582) (xy 43.859223 -152.564636) (xy 43.829756 -152.518791)
			(xy 43.807112 -152.469219) (xy 43.791754 -152.41693) (xy 43.783993 -152.362987) (xy 43.783504 -152.335738)
			(xy 43.783942 -152.3104) (xy 43.790646 -152.26017) (xy 43.803942 -152.21127) (xy 43.823596 -152.164561)
			(xy 43.849261 -152.120865) (xy 43.880485 -152.080952) (xy 43.898312 -152.062942) (xy 43.907675 -152.053192)
			(xy 43.921352 -152.029887) (xy 43.928439 -152.00381) (xy 43.928438 -151.976787) (xy 43.921351 -151.950711)
			(xy 43.907674 -151.927405) (xy 43.898312 -151.917654) (xy 43.878846 -151.898018) (xy 43.845305 -151.85406)
			(xy 43.818461 -151.805721) (xy 43.798875 -151.754012) (xy 43.786959 -151.700019) (xy 43.782962 -151.644871)
			(xy 37.27958 -151.644871) (xy 37.27958 -153.12472) (xy 51.012924 -153.12472) (xy 51.012928 -153.070227)
			(xy 51.020687 -153.016288) (xy 51.036042 -152.964003) (xy 51.058683 -152.914435) (xy 51.088146 -152.868593)
			(xy 51.123834 -152.827411) (xy 51.165019 -152.791727) (xy 51.210863 -152.762267) (xy 51.260433 -152.739631)
			(xy 51.312719 -152.72428) (xy 51.366659 -152.716526) (xy 51.421152 -152.716526) (xy 51.475091 -152.724282)
			(xy 51.527377 -152.739635) (xy 51.576946 -152.762272) (xy 51.62279 -152.791734) (xy 51.663974 -152.827419)
			(xy 51.69966 -152.868602) (xy 51.729122 -152.914444) (xy 51.736434 -152.930455) (xy 53.058229 -152.930455)
			(xy 53.058229 -152.875945) (xy 53.065987 -152.821989) (xy 53.081345 -152.769686) (xy 53.10399 -152.720102)
			(xy 53.133461 -152.674245) (xy 53.169159 -152.633049) (xy 53.210356 -152.597353) (xy 53.256214 -152.567883)
			(xy 53.305799 -152.54524) (xy 53.358102 -152.529884) (xy 53.412059 -152.522128) (xy 53.439314 -152.521666)
			(xy 53.466685 -152.522108) (xy 53.520866 -152.529929) (xy 53.57337 -152.545423) (xy 53.623117 -152.56827)
			(xy 53.669082 -152.598001) (xy 53.690012 -152.615646) (xy 53.70134 -152.624882) (xy 53.727897 -152.637058)
			(xy 53.756814 -152.641231) (xy 53.785731 -152.637058) (xy 53.812288 -152.624882) (xy 53.823616 -152.615646)
			(xy 53.844575 -152.59804) (xy 53.89054 -152.568322) (xy 53.94028 -152.545479) (xy 53.992775 -152.52998)
			(xy 54.046947 -152.522144) (xy 54.074314 -152.521666) (xy 54.101563 -152.522205) (xy 54.155505 -152.529963)
			(xy 54.207795 -152.545318) (xy 54.257367 -152.567958) (xy 54.303212 -152.597423) (xy 54.344398 -152.633112)
			(xy 54.380085 -152.674299) (xy 54.409548 -152.720146) (xy 54.432187 -152.769719) (xy 54.44754 -152.822009)
			(xy 54.455296 -152.875951) (xy 54.455296 -152.930449) (xy 54.44754 -152.984391) (xy 54.432187 -153.036681)
			(xy 54.409548 -153.086254) (xy 54.380085 -153.132101) (xy 54.344398 -153.173288) (xy 54.303212 -153.208977)
			(xy 54.257367 -153.238442) (xy 54.207795 -153.261082) (xy 54.155505 -153.276437) (xy 54.101563 -153.284195)
			(xy 54.074314 -153.284682) (xy 54.046944 -153.284212) (xy 53.992765 -153.276396) (xy 53.940262 -153.260908)
			(xy 53.890515 -153.238067) (xy 53.844548 -153.208343) (xy 53.823616 -153.190702) (xy 53.812288 -153.181466)
			(xy 53.785731 -153.16929) (xy 53.756814 -153.165117) (xy 53.727897 -153.16929) (xy 53.70134 -153.181466)
			(xy 53.690012 -153.190702) (xy 53.669086 -153.208349) (xy 53.623112 -153.23806) (xy 53.573363 -153.260894)
			(xy 53.520861 -153.276383) (xy 53.466684 -153.284209) (xy 53.439314 -153.284682) (xy 53.412059 -153.284272)
			(xy 53.358102 -153.276516) (xy 53.305799 -153.26116) (xy 53.256214 -153.238517) (xy 53.210356 -153.209047)
			(xy 53.169159 -153.173351) (xy 53.133461 -153.132155) (xy 53.10399 -153.086298) (xy 53.081345 -153.036714)
			(xy 53.065987 -152.984411) (xy 53.058229 -152.930455) (xy 51.736434 -152.930455) (xy 51.751761 -152.964013)
			(xy 51.767116 -153.016299) (xy 51.774873 -153.070237) (xy 51.77536 -153.097484) (xy 51.77493 -153.122875)
			(xy 51.768173 -153.173207) (xy 51.761898 -153.197814) (xy 51.758525 -153.212472) (xy 51.759445 -153.242518)
			(xy 51.769069 -153.270996) (xy 51.786564 -153.29544) (xy 51.810415 -153.313736) (xy 51.838559 -153.324299)
			(xy 51.868558 -153.326215) (xy 51.88331 -153.32329) (xy 51.904903 -153.318524) (xy 51.948829 -153.313431)
			(xy 51.97094 -153.31313) (xy 51.998187 -153.313621) (xy 52.052126 -153.321382) (xy 52.104412 -153.336739)
			(xy 52.153979 -153.359381) (xy 52.199821 -153.388847) (xy 52.241002 -153.424536) (xy 52.276686 -153.465723)
			(xy 52.306145 -153.511568) (xy 52.32878 -153.561139) (xy 52.34413 -153.613427) (xy 52.351883 -153.667367)
			(xy 52.351881 -153.721861) (xy 52.344124 -153.775801) (xy 52.32877 -153.828087) (xy 52.306131 -153.877657)
			(xy 52.276669 -153.9235) (xy 52.240982 -153.964684) (xy 52.199798 -154.00037) (xy 52.153955 -154.029832)
			(xy 52.104385 -154.052471) (xy 52.052099 -154.067824) (xy 51.998159 -154.075581) (xy 51.943665 -154.075583)
			(xy 51.889725 -154.067829) (xy 51.837437 -154.052479) (xy 51.787866 -154.029844) (xy 51.742021 -154.000384)
			(xy 51.700835 -153.964701) (xy 51.665146 -153.923519) (xy 51.63568 -153.877678) (xy 51.613039 -153.82811)
			(xy 51.597681 -153.775824) (xy 51.589921 -153.721885) (xy 51.589432 -153.694638) (xy 51.589867 -153.669247)
			(xy 51.596621 -153.618916) (xy 51.602894 -153.594308) (xy 51.606253 -153.579646) (xy 51.605338 -153.549601)
			(xy 51.595718 -153.521123) (xy 51.578225 -153.496677) (xy 51.554375 -153.478382) (xy 51.526232 -153.46782)
			(xy 51.496234 -153.465906) (xy 51.481482 -153.468832) (xy 51.459889 -153.4736) (xy 51.415963 -153.478691)
			(xy 51.393852 -153.478992) (xy 51.366605 -153.47847) (xy 51.312667 -153.470709) (xy 51.260383 -153.45535)
			(xy 51.210816 -153.432707) (xy 51.164976 -153.403241) (xy 51.123796 -153.367551) (xy 51.088114 -153.326364)
			(xy 51.058657 -153.280518) (xy 51.036024 -153.230947) (xy 51.020675 -153.17866) (xy 51.012924 -153.12472)
			(xy 37.27958 -153.12472) (xy 37.27958 -154.528052) (xy 49.996289 -154.528052) (xy 49.996289 -154.473548)
			(xy 50.004047 -154.419598) (xy 50.019404 -154.367301) (xy 50.042047 -154.317722) (xy 50.071517 -154.271871)
			(xy 50.107212 -154.230681) (xy 50.148406 -154.19499) (xy 50.194261 -154.165526) (xy 50.243842 -154.142888)
			(xy 50.296141 -154.127537) (xy 50.350092 -154.119786) (xy 50.377344 -154.119326) (xy 50.407031 -154.119911)
			(xy 50.465689 -154.129102) (xy 50.522215 -154.147271) (xy 50.575243 -154.173978) (xy 50.623492 -154.20858)
			(xy 50.665798 -154.250239) (xy 50.683922 -154.273758) (xy 50.692348 -154.284365) (xy 50.713661 -154.301072)
			(xy 50.738615 -154.311591) (xy 50.765456 -154.315181) (xy 50.792297 -154.311591) (xy 50.817251 -154.301072)
			(xy 50.838564 -154.284365) (xy 50.84699 -154.273758) (xy 50.86512 -154.250243) (xy 50.907427 -154.208585)
			(xy 50.955675 -154.173982) (xy 51.008701 -154.147271) (xy 51.065225 -154.129095) (xy 51.123881 -154.119893)
			(xy 51.153568 -154.119326) (xy 51.180825 -154.119719) (xy 51.234784 -154.127473) (xy 51.28709 -154.142827)
			(xy 51.336679 -154.16547) (xy 51.38254 -154.19494) (xy 51.423741 -154.230637) (xy 51.459441 -154.271834)
			(xy 51.488915 -154.317693) (xy 51.511561 -154.36728) (xy 51.52692 -154.419585) (xy 51.534679 -154.473543)
			(xy 51.534679 -154.528057) (xy 51.52692 -154.582015) (xy 51.511561 -154.63432) (xy 51.488915 -154.683907)
			(xy 51.459441 -154.729766) (xy 51.423741 -154.770963) (xy 51.38254 -154.80666) (xy 51.336679 -154.83613)
			(xy 51.28709 -154.858773) (xy 51.234784 -154.874127) (xy 51.180825 -154.881881) (xy 51.153568 -154.882342)
			(xy 51.123881 -154.88176) (xy 51.065222 -154.87257) (xy 51.008695 -154.854402) (xy 50.955667 -154.827694)
			(xy 50.907418 -154.793091) (xy 50.865114 -154.75143) (xy 50.84699 -154.72791) (xy 50.838564 -154.717303)
			(xy 50.817251 -154.700596) (xy 50.792297 -154.690077) (xy 50.765456 -154.686487) (xy 50.738615 -154.690077)
			(xy 50.713661 -154.700596) (xy 50.692348 -154.717303) (xy 50.683922 -154.72791) (xy 50.665776 -154.751412)
			(xy 50.623474 -154.793073) (xy 50.575229 -154.827678) (xy 50.522206 -154.854392) (xy 50.465685 -154.87257)
			(xy 50.40703 -154.881774) (xy 50.377344 -154.882342) (xy 50.350092 -154.881814) (xy 50.296141 -154.874063)
			(xy 50.243842 -154.858712) (xy 50.194261 -154.836074) (xy 50.148406 -154.80661) (xy 50.107212 -154.770919)
			(xy 50.071517 -154.729729) (xy 50.042047 -154.683878) (xy 50.019404 -154.634299) (xy 50.004047 -154.582002)
			(xy 49.996289 -154.528052) (xy 37.27958 -154.528052) (xy 37.27958 -156.613451) (xy 50.206652 -156.613451)
			(xy 50.206652 -156.558949) (xy 50.214408 -156.505001) (xy 50.229762 -156.452707) (xy 50.252401 -156.403129)
			(xy 50.281865 -156.357277) (xy 50.317554 -156.316086) (xy 50.358742 -156.280392) (xy 50.40459 -156.250922)
			(xy 50.454165 -156.228277) (xy 50.506458 -156.212917) (xy 50.560405 -156.205155) (xy 50.587656 -156.204666)
			(xy 50.617561 -156.205202) (xy 50.67664 -156.214514) (xy 50.705258 -156.223208) (xy 50.719167 -156.227239)
			(xy 50.748099 -156.228148) (xy 50.776118 -156.220883) (xy 50.800963 -156.206032) (xy 50.820629 -156.184792)
			(xy 50.833527 -156.158879) (xy 50.836576 -156.144722) (xy 50.843165 -156.111884) (xy 50.866284 -156.049031)
			(xy 50.88255 -156.019754) (xy 50.889618 -156.006804) (xy 50.896647 -155.978161) (xy 50.895197 -155.948704)
			(xy 50.885389 -155.92089) (xy 50.868042 -155.897039) (xy 50.844601 -155.879141) (xy 50.830988 -155.87345)
			(xy 50.80422 -155.862735) (xy 50.753979 -155.83445) (xy 50.70857 -155.798922) (xy 50.669027 -155.756963)
			(xy 50.636253 -155.709528) (xy 50.610993 -155.6577) (xy 50.593825 -155.60266) (xy 50.585139 -155.545662)
			(xy 50.584608 -155.516834) (xy 50.585094 -155.489583) (xy 50.59285 -155.435635) (xy 50.608205 -155.38334)
			(xy 50.630847 -155.333763) (xy 50.660313 -155.287913) (xy 50.696004 -155.246722) (xy 50.737195 -155.211031)
			(xy 50.783045 -155.181565) (xy 50.832622 -155.158923) (xy 50.884917 -155.143568) (xy 50.938865 -155.135812)
			(xy 50.993367 -155.135812) (xy 51.047315 -155.143568) (xy 51.09961 -155.158923) (xy 51.149187 -155.181565)
			(xy 51.195037 -155.211031) (xy 51.236228 -155.246722) (xy 51.271919 -155.287913) (xy 51.301385 -155.333763)
			(xy 51.324027 -155.38334) (xy 51.339382 -155.435635) (xy 51.347138 -155.489583) (xy 51.347624 -155.516834)
			(xy 51.347239 -155.54207) (xy 51.340617 -155.592104) (xy 51.32744 -155.640824) (xy 51.30794 -155.687376)
			(xy 51.295554 -155.709366) (xy 51.28846 -155.722303) (xy 51.281434 -155.750951) (xy 51.282888 -155.780412)
			(xy 51.292701 -155.808229) (xy 51.310054 -155.832081) (xy 51.3335 -155.84998) (xy 51.347116 -155.85567)
			(xy 51.373892 -155.866366) (xy 51.424134 -155.894654) (xy 51.469543 -155.930184) (xy 51.509085 -155.972146)
			(xy 51.541859 -156.019583) (xy 51.567117 -156.071414) (xy 51.584283 -156.126457) (xy 51.592966 -156.183457)
			(xy 51.593496 -156.212286) (xy 51.593032 -156.239539) (xy 51.585276 -156.293491) (xy 51.569921 -156.345789)
			(xy 51.54728 -156.39537) (xy 51.517812 -156.441224) (xy 51.482118 -156.482417) (xy 51.440925 -156.518111)
			(xy 51.395072 -156.547579) (xy 51.345491 -156.570221) (xy 51.293193 -156.585576) (xy 51.239241 -156.593331)
			(xy 51.211988 -156.593794) (xy 51.182083 -156.593273) (xy 51.123003 -156.583951) (xy 51.094386 -156.575252)
			(xy 51.080457 -156.571302) (xy 51.051539 -156.570385) (xy 51.02353 -156.577636) (xy 50.998691 -156.592471)
			(xy 50.979026 -156.613693) (xy 50.966122 -156.639589) (xy 50.963068 -156.653738) (xy 50.957919 -156.679816)
			(xy 50.941346 -156.73032) (xy 50.917921 -156.778034) (xy 50.888096 -156.822032) (xy 50.852451 -156.861463)
			(xy 50.811676 -156.895561) (xy 50.76656 -156.923667) (xy 50.717979 -156.945236) (xy 50.666873 -156.959849)
			(xy 50.614233 -156.967225) (xy 50.587656 -156.967682) (xy 50.560405 -156.967245) (xy 50.506458 -156.959483)
			(xy 50.454165 -156.944123) (xy 50.40459 -156.921478) (xy 50.358742 -156.892008) (xy 50.317554 -156.856314)
			(xy 50.281865 -156.815123) (xy 50.252401 -156.769271) (xy 50.229762 -156.719693) (xy 50.214408 -156.667399)
			(xy 50.206652 -156.613451) (xy 37.27958 -156.613451) (xy 37.27958 -156.79166) (xy 37.279112 -156.827313)
			(xy 37.271154 -156.898174) (xy 37.255312 -156.967699) (xy 37.231784 -157.035012) (xy 37.200866 -157.099267)
			(xy 37.162948 -157.159656) (xy 37.118506 -157.215419) (xy 37.093652 -157.240986) (xy 36.37534 -157.959044)
			(xy 36.37534 -159.08147) (xy 50.99304 -159.08147) (xy 50.993427 -159.054214) (xy 51.001189 -159.000258)
			(xy 51.016552 -158.947956) (xy 51.039201 -158.898372) (xy 51.068677 -158.852517) (xy 51.104379 -158.811323)
			(xy 51.145579 -158.77563) (xy 51.191441 -158.746164) (xy 51.241029 -158.723524) (xy 51.293334 -158.708173)
			(xy 51.347292 -158.700422) (xy 51.374548 -158.699962) (xy 51.402122 -158.700442) (xy 51.456695 -158.708388)
			(xy 51.509556 -158.724109) (xy 51.559603 -158.747276) (xy 51.605792 -158.777408) (xy 51.647163 -158.813875)
			(xy 51.665378 -158.834582) (xy 51.675276 -158.84548) (xy 51.699926 -158.861555) (xy 51.728134 -158.869939)
			(xy 51.757562 -158.869939) (xy 51.78577 -158.861555) (xy 51.81042 -158.84548) (xy 51.820318 -158.834582)
			(xy 51.838512 -158.813855) (xy 51.879885 -158.777387) (xy 51.926079 -158.747257) (xy 51.97613 -158.724094)
			(xy 52.028995 -158.708381) (xy 52.083572 -158.700445) (xy 52.111148 -158.699962) (xy 52.137649 -158.700415)
			(xy 52.19014 -158.707762) (xy 52.241107 -158.722307) (xy 52.289569 -158.74377) (xy 52.334592 -158.771737)
			(xy 52.355242 -158.788354) (xy 52.367396 -158.797784) (xy 52.395794 -158.809573) (xy 52.426411 -158.812397)
			(xy 52.456486 -158.806003) (xy 52.483306 -158.790967) (xy 52.504451 -158.768645) (xy 52.511706 -158.75508)
			(xy 52.523817 -158.731395) (xy 52.553737 -158.687413) (xy 52.589605 -158.64813) (xy 52.630693 -158.614345)
			(xy 52.653184 -158.60014) (xy 52.665431 -158.592248) (xy 52.685104 -158.570769) (xy 52.697907 -158.544607)
			(xy 52.702796 -158.515894) (xy 52.699373 -158.486969) (xy 52.694078 -158.473394) (xy 52.684593 -158.450182)
			(xy 52.671241 -158.40185) (xy 52.664511 -158.352161) (xy 52.664106 -158.32709) (xy 52.66454 -158.302021)
			(xy 52.671286 -158.252338) (xy 52.684614 -158.204004) (xy 52.694078 -158.180786) (xy 52.699333 -158.167207)
			(xy 52.702713 -158.138299) (xy 52.697811 -158.10961) (xy 52.685024 -158.083464) (xy 52.665389 -158.06198)
			(xy 52.653184 -158.05404) (xy 52.630024 -158.039514) (xy 52.587899 -158.004668) (xy 52.551317 -157.964041)
			(xy 52.521063 -157.918506) (xy 52.497786 -157.869039) (xy 52.481986 -157.816703) (xy 52.474001 -157.762619)
			(xy 52.474003 -157.70795) (xy 52.481993 -157.653867) (xy 52.497797 -157.601532) (xy 52.521079 -157.552067)
			(xy 52.551336 -157.506534) (xy 52.587922 -157.465911) (xy 52.630049 -157.431068) (xy 52.653184 -157.4165)
			(xy 52.66539 -157.408551) (xy 52.685063 -157.387088) (xy 52.697871 -157.360941) (xy 52.702771 -157.332241)
			(xy 52.699363 -157.303326) (xy 52.694078 -157.289754) (xy 52.684581 -157.266547) (xy 52.671233 -157.218213)
			(xy 52.664508 -157.168522) (xy 52.664106 -157.14345) (xy 52.664627 -157.115565) (xy 52.672939 -157.060418)
			(xy 52.689377 -157.007126) (xy 52.713575 -156.95688) (xy 52.744991 -156.910801) (xy 52.782924 -156.869919)
			(xy 52.826526 -156.835147) (xy 52.874824 -156.807262) (xy 52.926739 -156.786887) (xy 52.98111 -156.774477)
			(xy 53.036724 -156.77031) (xy 53.092338 -156.774477) (xy 53.146709 -156.786887) (xy 53.198624 -156.807262)
			(xy 53.246922 -156.835147) (xy 53.290524 -156.869919) (xy 53.328457 -156.910801) (xy 53.359873 -156.95688)
			(xy 53.384071 -157.007126) (xy 53.400509 -157.060418) (xy 53.408821 -157.115565) (xy 53.409342 -157.14345)
			(xy 53.408875 -157.170782) (xy 53.400906 -157.224863) (xy 53.385118 -157.277198) (xy 53.36185 -157.326662)
			(xy 53.331601 -157.372195) (xy 53.295022 -157.412817) (xy 53.252897 -157.447655) (xy 53.229764 -157.46222)
			(xy 53.217537 -157.470138) (xy 53.19787 -157.491612) (xy 53.185068 -157.517767) (xy 53.180173 -157.546472)
			(xy 53.183584 -157.575392) (xy 53.18887 -157.588966) (xy 53.198345 -157.612181) (xy 53.211701 -157.660512)
			(xy 53.218435 -157.710199) (xy 53.218842 -157.73527) (xy 53.218431 -157.76034) (xy 53.211677 -157.810023)
			(xy 53.198339 -157.858357) (xy 53.18887 -157.881574) (xy 53.183624 -157.895151) (xy 53.180262 -157.924051)
			(xy 53.185173 -157.952729) (xy 53.197961 -157.978863) (xy 53.217591 -158.000338) (xy 53.229764 -158.00832)
			(xy 53.252885 -158.022903) (xy 53.295003 -158.057747) (xy 53.331579 -158.098369) (xy 53.361829 -158.143898)
			(xy 53.385103 -158.193358) (xy 53.400902 -158.245688) (xy 53.408888 -158.299764) (xy 53.408889 -158.354426)
			(xy 53.400905 -158.408502) (xy 53.385107 -158.460832) (xy 53.361834 -158.510292) (xy 53.331585 -158.555823)
			(xy 53.29501 -158.596446) (xy 53.252893 -158.631291) (xy 53.229764 -158.64586) (xy 53.217509 -158.653739)
			(xy 53.197842 -158.675225) (xy 53.185043 -158.70139) (xy 53.180156 -158.730104) (xy 53.183577 -158.75903)
			(xy 53.18887 -158.772606) (xy 53.198357 -158.795817) (xy 53.211708 -158.844149) (xy 53.218438 -158.893838)
			(xy 53.218842 -158.91891) (xy 53.21837 -158.945752) (xy 53.210665 -158.998881) (xy 53.195416 -159.050354)
			(xy 53.172938 -159.099106) (xy 53.143697 -159.144127) (xy 53.108298 -159.184487) (xy 53.067473 -159.219349)
			(xy 53.022069 -159.247993) (xy 52.973024 -159.269824) (xy 52.947316 -159.277558) (xy 52.932841 -159.282276)
			(xy 52.907286 -159.298788) (xy 52.887726 -159.322092) (xy 52.875894 -159.350122) (xy 52.87284 -159.380393)
			(xy 52.878835 -159.410222) (xy 52.885594 -159.423862) (xy 52.900228 -159.452008) (xy 52.920955 -159.511959)
			(xy 52.931453 -159.574517) (xy 52.932076 -159.606234) (xy 52.931855 -159.624253) (xy 52.928421 -159.660128)
			(xy 52.925218 -159.677862) (xy 52.922936 -159.693077) (xy 52.926453 -159.723622) (xy 52.938901 -159.751736)
			(xy 52.959153 -159.774871) (xy 52.985373 -159.790931) (xy 53.000148 -159.79521) (xy 53.027191 -159.802611)
			(xy 53.078917 -159.824241) (xy 53.126922 -159.853205) (xy 53.170174 -159.88888) (xy 53.207741 -159.930499)
			(xy 53.238815 -159.977165) (xy 53.262728 -160.027876) (xy 53.278965 -160.08154) (xy 53.287177 -160.137001)
			(xy 53.287676 -160.165034) (xy 53.287254 -160.192288) (xy 53.279492 -160.246239) (xy 53.264131 -160.298537)
			(xy 53.241483 -160.348117) (xy 53.21201 -160.393968) (xy 53.176312 -160.435159) (xy 53.135115 -160.47085)
			(xy 53.089259 -160.500315) (xy 53.039675 -160.522954) (xy 52.987375 -160.538306) (xy 52.933422 -160.546058)
			(xy 52.906168 -160.546542) (xy 52.878594 -160.54605) (xy 52.824022 -160.538105) (xy 52.771161 -160.522387)
			(xy 52.721115 -160.499222) (xy 52.674925 -160.469093) (xy 52.633554 -160.432628) (xy 52.615338 -160.411922)
			(xy 52.60544 -160.401024) (xy 52.58079 -160.384949) (xy 52.552582 -160.376565) (xy 52.523154 -160.376565)
			(xy 52.494946 -160.384949) (xy 52.470296 -160.401024) (xy 52.460398 -160.411922) (xy 52.442183 -160.432628)
			(xy 52.400812 -160.469093) (xy 52.354622 -160.49922) (xy 52.304575 -160.522383) (xy 52.251714 -160.538099)
			(xy 52.197142 -160.546039) (xy 52.141994 -160.546039) (xy 52.087422 -160.538099) (xy 52.034561 -160.522383)
			(xy 51.984514 -160.49922) (xy 51.938324 -160.469093) (xy 51.896953 -160.432628) (xy 51.878738 -160.411922)
			(xy 51.86884 -160.401024) (xy 51.84419 -160.384949) (xy 51.815982 -160.376565) (xy 51.786554 -160.376565)
			(xy 51.758346 -160.384949) (xy 51.733696 -160.401024) (xy 51.723798 -160.411922) (xy 51.705596 -160.432642)
			(xy 51.664225 -160.46911) (xy 51.618033 -160.499241) (xy 51.567983 -160.522405) (xy 51.515119 -160.53812)
			(xy 51.460543 -160.546058) (xy 51.432968 -160.546542) (xy 51.405718 -160.546052) (xy 51.351772 -160.538292)
			(xy 51.299479 -160.522935) (xy 51.249904 -160.500292) (xy 51.204055 -160.470826) (xy 51.162866 -160.435135)
			(xy 51.127175 -160.393946) (xy 51.097709 -160.348098) (xy 51.075066 -160.298523) (xy 51.059708 -160.24623)
			(xy 51.051948 -160.192284) (xy 51.05146 -160.165034) (xy 51.052043 -160.137181) (xy 51.060161 -160.08207)
			(xy 51.0762 -160.028722) (xy 51.09982 -159.978272) (xy 51.130519 -159.931788) (xy 51.167647 -159.890258)
			(xy 51.210414 -159.854563) (xy 51.257914 -159.825461) (xy 51.309138 -159.803569) (xy 51.33594 -159.795972)
			(xy 51.350063 -159.791719) (xy 51.375204 -159.77632) (xy 51.394916 -159.754396) (xy 51.407566 -159.727764)
			(xy 51.412104 -159.698632) (xy 51.410616 -159.683958) (xy 51.408945 -159.670942) (xy 51.407166 -159.644757)
			(xy 51.40706 -159.631634) (xy 51.407158 -159.617485) (xy 51.409189 -159.589262) (xy 51.411124 -159.575246)
			(xy 51.412683 -159.561896) (xy 51.409585 -159.535209) (xy 51.39962 -159.510259) (xy 51.38348 -159.488781)
			(xy 51.362288 -159.472267) (xy 51.337516 -159.461867) (xy 51.324256 -159.459676) (xy 51.297113 -159.45553)
			(xy 51.244287 -159.440561) (xy 51.194152 -159.418174) (xy 51.147744 -159.388832) (xy 51.106021 -159.353141)
			(xy 51.069844 -159.311838) (xy 51.039961 -159.265777) (xy 51.016989 -159.215907) (xy 51.001402 -159.16326)
			(xy 50.993522 -159.108923) (xy 50.99304 -159.08147) (xy 36.37534 -159.08147) (xy 36.37534 -161.891218)
			(xy 43.505377 -161.891218) (xy 43.509413 -161.807771) (xy 43.521485 -161.725103) (xy 43.541478 -161.643986)
			(xy 43.569207 -161.565177) (xy 43.604413 -161.489412) (xy 43.646767 -161.417399) (xy 43.695873 -161.34981)
			(xy 43.751274 -161.287276) (xy 43.812451 -161.230381) (xy 43.878834 -161.179655) (xy 43.949802 -161.135574)
			(xy 44.024694 -161.098548) (xy 44.10281 -161.068922) (xy 44.18342 -161.046974) (xy 44.265772 -161.032909)
			(xy 44.349098 -161.026857) (xy 44.432618 -161.028876) (xy 44.515554 -161.038946) (xy 44.59713 -161.056974)
			(xy 44.676586 -161.082791) (xy 44.753179 -161.116156) (xy 44.826195 -161.156757) (xy 44.894951 -161.204216)
			(xy 44.958805 -161.258089) (xy 45.017162 -161.317874) (xy 45.069477 -161.383011) (xy 45.11526 -161.452894)
			(xy 45.154085 -161.526869) (xy 45.18559 -161.604246) (xy 45.209479 -161.684303) (xy 45.224439 -161.76072)
			(xy 51.012924 -161.76072) (xy 51.012928 -161.706227) (xy 51.020687 -161.652288) (xy 51.036042 -161.600003)
			(xy 51.058683 -161.550435) (xy 51.088146 -161.504593) (xy 51.123834 -161.463411) (xy 51.165019 -161.427727)
			(xy 51.210863 -161.398267) (xy 51.260433 -161.375631) (xy 51.312719 -161.36028) (xy 51.366659 -161.352526)
			(xy 51.421152 -161.352526) (xy 51.475091 -161.360282) (xy 51.527377 -161.375635) (xy 51.576946 -161.398272)
			(xy 51.62279 -161.427734) (xy 51.663974 -161.463419) (xy 51.69966 -161.504602) (xy 51.729122 -161.550444)
			(xy 51.736434 -161.566455) (xy 53.058229 -161.566455) (xy 53.058229 -161.511945) (xy 53.065987 -161.457989)
			(xy 53.081345 -161.405686) (xy 53.10399 -161.356102) (xy 53.133461 -161.310245) (xy 53.169159 -161.269049)
			(xy 53.210356 -161.233353) (xy 53.256214 -161.203883) (xy 53.305799 -161.18124) (xy 53.358102 -161.165884)
			(xy 53.412059 -161.158128) (xy 53.439314 -161.157666) (xy 53.466685 -161.158108) (xy 53.520866 -161.165929)
			(xy 53.57337 -161.181423) (xy 53.623117 -161.20427) (xy 53.669082 -161.234001) (xy 53.690012 -161.251646)
			(xy 53.70134 -161.260882) (xy 53.727897 -161.273058) (xy 53.756814 -161.277231) (xy 53.785731 -161.273058)
			(xy 53.812288 -161.260882) (xy 53.823616 -161.251646) (xy 53.844575 -161.23404) (xy 53.89054 -161.204322)
			(xy 53.94028 -161.181479) (xy 53.992775 -161.16598) (xy 54.046947 -161.158144) (xy 54.074314 -161.157666)
			(xy 54.101563 -161.158205) (xy 54.155505 -161.165963) (xy 54.207795 -161.181318) (xy 54.257367 -161.203958)
			(xy 54.303212 -161.233423) (xy 54.344398 -161.269112) (xy 54.380085 -161.310299) (xy 54.409548 -161.356146)
			(xy 54.432187 -161.405719) (xy 54.44754 -161.458009) (xy 54.455296 -161.511951) (xy 54.455296 -161.566449)
			(xy 54.44754 -161.620391) (xy 54.432187 -161.672681) (xy 54.409548 -161.722254) (xy 54.380085 -161.768101)
			(xy 54.344398 -161.809288) (xy 54.303212 -161.844977) (xy 54.257367 -161.874442) (xy 54.207795 -161.897082)
			(xy 54.155505 -161.912437) (xy 54.101563 -161.920195) (xy 54.074314 -161.920682) (xy 54.046944 -161.920212)
			(xy 53.992765 -161.912396) (xy 53.940262 -161.896908) (xy 53.890515 -161.874067) (xy 53.844548 -161.844343)
			(xy 53.823616 -161.826702) (xy 53.812288 -161.817466) (xy 53.785731 -161.80529) (xy 53.756814 -161.801117)
			(xy 53.727897 -161.80529) (xy 53.70134 -161.817466) (xy 53.690012 -161.826702) (xy 53.669086 -161.844349)
			(xy 53.623112 -161.87406) (xy 53.573363 -161.896894) (xy 53.520861 -161.912383) (xy 53.466684 -161.920209)
			(xy 53.439314 -161.920682) (xy 53.412059 -161.920272) (xy 53.358102 -161.912516) (xy 53.305799 -161.89716)
			(xy 53.256214 -161.874517) (xy 53.210356 -161.845047) (xy 53.169159 -161.809351) (xy 53.133461 -161.768155)
			(xy 53.10399 -161.722298) (xy 53.081345 -161.672714) (xy 53.065987 -161.620411) (xy 53.058229 -161.566455)
			(xy 51.736434 -161.566455) (xy 51.751761 -161.600013) (xy 51.767116 -161.652299) (xy 51.774873 -161.706237)
			(xy 51.77536 -161.733484) (xy 51.77493 -161.758875) (xy 51.768173 -161.809207) (xy 51.761898 -161.833814)
			(xy 51.758525 -161.848472) (xy 51.759445 -161.878518) (xy 51.769069 -161.906996) (xy 51.786564 -161.93144)
			(xy 51.810415 -161.949736) (xy 51.838559 -161.960299) (xy 51.868558 -161.962215) (xy 51.88331 -161.95929)
			(xy 51.904903 -161.954524) (xy 51.948829 -161.949431) (xy 51.97094 -161.94913) (xy 51.998187 -161.949621)
			(xy 52.052126 -161.957382) (xy 52.104412 -161.972739) (xy 52.153979 -161.995381) (xy 52.199821 -162.024847)
			(xy 52.241002 -162.060536) (xy 52.276686 -162.101723) (xy 52.306145 -162.147568) (xy 52.32878 -162.197139)
			(xy 52.34413 -162.249427) (xy 52.351883 -162.303367) (xy 52.351881 -162.357861) (xy 52.344124 -162.411801)
			(xy 52.32877 -162.464087) (xy 52.306131 -162.513657) (xy 52.276669 -162.5595) (xy 52.240982 -162.600684)
			(xy 52.199798 -162.63637) (xy 52.153955 -162.665832) (xy 52.104385 -162.688471) (xy 52.052099 -162.703824)
			(xy 51.998159 -162.711581) (xy 51.943665 -162.711583) (xy 51.889725 -162.703829) (xy 51.837437 -162.688479)
			(xy 51.787866 -162.665844) (xy 51.742021 -162.636384) (xy 51.700835 -162.600701) (xy 51.665146 -162.559519)
			(xy 51.63568 -162.513678) (xy 51.613039 -162.46411) (xy 51.597681 -162.411824) (xy 51.589921 -162.357885)
			(xy 51.589432 -162.330638) (xy 51.589867 -162.305247) (xy 51.596621 -162.254916) (xy 51.602894 -162.230308)
			(xy 51.606253 -162.215646) (xy 51.605338 -162.185601) (xy 51.595718 -162.157123) (xy 51.578225 -162.132677)
			(xy 51.554375 -162.114382) (xy 51.526232 -162.10382) (xy 51.496234 -162.101906) (xy 51.481482 -162.104832)
			(xy 51.459889 -162.1096) (xy 51.415963 -162.114691) (xy 51.393852 -162.114992) (xy 51.366605 -162.11447)
			(xy 51.312667 -162.106709) (xy 51.260383 -162.09135) (xy 51.210816 -162.068707) (xy 51.164976 -162.039241)
			(xy 51.123796 -162.003551) (xy 51.088114 -161.962364) (xy 51.058657 -161.916518) (xy 51.036024 -161.866947)
			(xy 51.020675 -161.81466) (xy 51.012924 -161.76072) (xy 45.224439 -161.76072) (xy 45.22553 -161.766291)
			(xy 45.233593 -161.849446) (xy 45.234098 -161.891218) (xy 45.233593 -161.93299) (xy 45.22553 -162.016145)
			(xy 45.209479 -162.098133) (xy 45.18559 -162.17819) (xy 45.154085 -162.255567) (xy 45.11526 -162.329542)
			(xy 45.069477 -162.399425) (xy 45.017162 -162.464562) (xy 44.958805 -162.524347) (xy 44.894951 -162.57822)
			(xy 44.826195 -162.625679) (xy 44.753179 -162.66628) (xy 44.676586 -162.699645) (xy 44.59713 -162.725462)
			(xy 44.515554 -162.74349) (xy 44.432618 -162.75356) (xy 44.349098 -162.755579) (xy 44.265772 -162.749527)
			(xy 44.18342 -162.735462) (xy 44.10281 -162.713514) (xy 44.024694 -162.683888) (xy 43.949802 -162.646862)
			(xy 43.878834 -162.602781) (xy 43.812451 -162.552055) (xy 43.751274 -162.49516) (xy 43.695873 -162.432626)
			(xy 43.646767 -162.365037) (xy 43.604413 -162.293024) (xy 43.569207 -162.217259) (xy 43.541478 -162.13845)
			(xy 43.521485 -162.057333) (xy 43.509413 -161.974665) (xy 43.505377 -161.891218) (xy 36.37534 -161.891218)
			(xy 36.37534 -163.164052) (xy 49.996289 -163.164052) (xy 49.996289 -163.109548) (xy 50.004047 -163.055598)
			(xy 50.019404 -163.003301) (xy 50.042047 -162.953722) (xy 50.071517 -162.907871) (xy 50.107212 -162.866681)
			(xy 50.148406 -162.83099) (xy 50.194261 -162.801526) (xy 50.243842 -162.778888) (xy 50.296141 -162.763537)
			(xy 50.350092 -162.755786) (xy 50.377344 -162.755326) (xy 50.407031 -162.755911) (xy 50.465689 -162.765102)
			(xy 50.522215 -162.783271) (xy 50.575243 -162.809978) (xy 50.623492 -162.84458) (xy 50.665798 -162.886239)
			(xy 50.683922 -162.909758) (xy 50.692348 -162.920365) (xy 50.713661 -162.937072) (xy 50.738615 -162.947591)
			(xy 50.765456 -162.951181) (xy 50.792297 -162.947591) (xy 50.817251 -162.937072) (xy 50.838564 -162.920365)
			(xy 50.84699 -162.909758) (xy 50.86512 -162.886243) (xy 50.907427 -162.844585) (xy 50.955675 -162.809982)
			(xy 51.008701 -162.783271) (xy 51.065225 -162.765095) (xy 51.123881 -162.755893) (xy 51.153568 -162.755326)
			(xy 51.180825 -162.755719) (xy 51.234784 -162.763473) (xy 51.28709 -162.778827) (xy 51.336679 -162.80147)
			(xy 51.38254 -162.83094) (xy 51.423741 -162.866637) (xy 51.459441 -162.907834) (xy 51.488915 -162.953693)
			(xy 51.511561 -163.00328) (xy 51.52692 -163.055585) (xy 51.534679 -163.109543) (xy 51.534679 -163.164057)
			(xy 51.52692 -163.218015) (xy 51.511561 -163.27032) (xy 51.488915 -163.319907) (xy 51.459441 -163.365766)
			(xy 51.423741 -163.406963) (xy 51.38254 -163.44266) (xy 51.336679 -163.47213) (xy 51.28709 -163.494773)
			(xy 51.234784 -163.510127) (xy 51.180825 -163.517881) (xy 51.153568 -163.518342) (xy 51.123881 -163.51776)
			(xy 51.065222 -163.50857) (xy 51.008695 -163.490402) (xy 50.955667 -163.463694) (xy 50.907418 -163.429091)
			(xy 50.865114 -163.38743) (xy 50.84699 -163.36391) (xy 50.838564 -163.353303) (xy 50.817251 -163.336596)
			(xy 50.792297 -163.326077) (xy 50.765456 -163.322487) (xy 50.738615 -163.326077) (xy 50.713661 -163.336596)
			(xy 50.692348 -163.353303) (xy 50.683922 -163.36391) (xy 50.665776 -163.387412) (xy 50.623474 -163.429073)
			(xy 50.575229 -163.463678) (xy 50.522206 -163.490392) (xy 50.465685 -163.50857) (xy 50.40703 -163.517774)
			(xy 50.377344 -163.518342) (xy 50.350092 -163.517814) (xy 50.296141 -163.510063) (xy 50.243842 -163.494712)
			(xy 50.194261 -163.472074) (xy 50.148406 -163.44261) (xy 50.107212 -163.406919) (xy 50.071517 -163.365729)
			(xy 50.042047 -163.319878) (xy 50.019404 -163.270299) (xy 50.004047 -163.218002) (xy 49.996289 -163.164052)
			(xy 36.37534 -163.164052) (xy 36.37534 -164.433688) (xy 43.480986 -164.433688) (xy 43.480986 -164.348992)
			(xy 43.489037 -164.264678) (xy 43.505066 -164.181512) (xy 43.528927 -164.100245) (xy 43.560406 -164.021615)
			(xy 43.599217 -163.946334) (xy 43.645007 -163.875082) (xy 43.697363 -163.808506) (xy 43.755811 -163.747208)
			(xy 43.819821 -163.691743) (xy 43.888813 -163.642614) (xy 43.962163 -163.600265) (xy 44.039206 -163.565081)
			(xy 44.119245 -163.537379) (xy 44.201554 -163.517411) (xy 44.285389 -163.505358) (xy 44.36999 -163.501328)
			(xy 44.454591 -163.505358) (xy 44.538426 -163.517411) (xy 44.620735 -163.537379) (xy 44.700774 -163.565081)
			(xy 44.777817 -163.600265) (xy 44.851167 -163.642614) (xy 44.920159 -163.691743) (xy 44.984169 -163.747208)
			(xy 45.042617 -163.808506) (xy 45.094973 -163.875082) (xy 45.140763 -163.946334) (xy 45.179574 -164.021615)
			(xy 45.211053 -164.100245) (xy 45.234914 -164.181512) (xy 45.250943 -164.264678) (xy 45.258994 -164.348992)
			(xy 45.259498 -164.39134) (xy 45.258994 -164.433688) (xy 45.250943 -164.518002) (xy 45.234914 -164.601168)
			(xy 45.211053 -164.682435) (xy 45.179574 -164.761065) (xy 45.140763 -164.836346) (xy 45.094973 -164.907598)
			(xy 45.042617 -164.974174) (xy 44.984169 -165.035472) (xy 44.920159 -165.090937) (xy 44.851167 -165.140066)
			(xy 44.777817 -165.182415) (xy 44.700774 -165.217599) (xy 44.620735 -165.245301) (xy 44.603629 -165.249451)
			(xy 50.206652 -165.249451) (xy 50.206652 -165.194949) (xy 50.214408 -165.141001) (xy 50.229762 -165.088707)
			(xy 50.252401 -165.039129) (xy 50.281865 -164.993277) (xy 50.317554 -164.952086) (xy 50.358742 -164.916392)
			(xy 50.40459 -164.886922) (xy 50.454165 -164.864277) (xy 50.506458 -164.848917) (xy 50.560405 -164.841155)
			(xy 50.587656 -164.840666) (xy 50.617561 -164.841202) (xy 50.67664 -164.850514) (xy 50.705258 -164.859208)
			(xy 50.719167 -164.863239) (xy 50.748099 -164.864148) (xy 50.776118 -164.856883) (xy 50.800963 -164.842032)
			(xy 50.820629 -164.820792) (xy 50.833527 -164.794879) (xy 50.836576 -164.780722) (xy 50.843165 -164.747884)
			(xy 50.866284 -164.685031) (xy 50.88255 -164.655754) (xy 50.889618 -164.642804) (xy 50.896647 -164.614161)
			(xy 50.895197 -164.584704) (xy 50.885389 -164.55689) (xy 50.868042 -164.533039) (xy 50.844601 -164.515141)
			(xy 50.830988 -164.50945) (xy 50.80422 -164.498735) (xy 50.753979 -164.47045) (xy 50.70857 -164.434922)
			(xy 50.669027 -164.392963) (xy 50.636253 -164.345528) (xy 50.610993 -164.2937) (xy 50.593825 -164.23866)
			(xy 50.585139 -164.181662) (xy 50.584608 -164.152834) (xy 50.585094 -164.125583) (xy 50.59285 -164.071635)
			(xy 50.608205 -164.01934) (xy 50.630847 -163.969763) (xy 50.660313 -163.923913) (xy 50.696004 -163.882722)
			(xy 50.737195 -163.847031) (xy 50.783045 -163.817565) (xy 50.832622 -163.794923) (xy 50.884917 -163.779568)
			(xy 50.938865 -163.771812) (xy 50.993367 -163.771812) (xy 51.047315 -163.779568) (xy 51.09961 -163.794923)
			(xy 51.149187 -163.817565) (xy 51.195037 -163.847031) (xy 51.236228 -163.882722) (xy 51.271919 -163.923913)
			(xy 51.301385 -163.969763) (xy 51.324027 -164.01934) (xy 51.339382 -164.071635) (xy 51.347138 -164.125583)
			(xy 51.347624 -164.152834) (xy 51.347239 -164.17807) (xy 51.340617 -164.228104) (xy 51.32744 -164.276824)
			(xy 51.30794 -164.323376) (xy 51.295554 -164.345366) (xy 51.28846 -164.358303) (xy 51.281434 -164.386951)
			(xy 51.282888 -164.416412) (xy 51.292701 -164.444229) (xy 51.310054 -164.468081) (xy 51.3335 -164.48598)
			(xy 51.347116 -164.49167) (xy 51.373892 -164.502366) (xy 51.424134 -164.530654) (xy 51.469543 -164.566184)
			(xy 51.509085 -164.608146) (xy 51.541859 -164.655583) (xy 51.567117 -164.707414) (xy 51.584283 -164.762457)
			(xy 51.592966 -164.819457) (xy 51.593496 -164.848286) (xy 51.593032 -164.875539) (xy 51.585276 -164.929491)
			(xy 51.569921 -164.981789) (xy 51.54728 -165.03137) (xy 51.517812 -165.077224) (xy 51.482118 -165.118417)
			(xy 51.440925 -165.154111) (xy 51.395072 -165.183579) (xy 51.345491 -165.206221) (xy 51.293193 -165.221576)
			(xy 51.239241 -165.229331) (xy 51.211988 -165.229794) (xy 51.182083 -165.229273) (xy 51.123003 -165.219951)
			(xy 51.094386 -165.211252) (xy 51.080457 -165.207302) (xy 51.051539 -165.206385) (xy 51.02353 -165.213636)
			(xy 50.998691 -165.228471) (xy 50.979026 -165.249693) (xy 50.966122 -165.275589) (xy 50.963068 -165.289738)
			(xy 50.957919 -165.315816) (xy 50.941346 -165.36632) (xy 50.917921 -165.414034) (xy 50.888096 -165.458032)
			(xy 50.852451 -165.497463) (xy 50.811676 -165.531561) (xy 50.76656 -165.559667) (xy 50.717979 -165.581236)
			(xy 50.666873 -165.595849) (xy 50.614233 -165.603225) (xy 50.587656 -165.603682) (xy 50.560405 -165.603245)
			(xy 50.506458 -165.595483) (xy 50.454165 -165.580123) (xy 50.40459 -165.557478) (xy 50.358742 -165.528008)
			(xy 50.317554 -165.492314) (xy 50.281865 -165.451123) (xy 50.252401 -165.405271) (xy 50.229762 -165.355693)
			(xy 50.214408 -165.303399) (xy 50.206652 -165.249451) (xy 44.603629 -165.249451) (xy 44.538426 -165.265269)
			(xy 44.454591 -165.277322) (xy 44.36999 -165.281353) (xy 44.285389 -165.277322) (xy 44.201554 -165.265269)
			(xy 44.119245 -165.245301) (xy 44.039206 -165.217599) (xy 43.962163 -165.182415) (xy 43.888813 -165.140066)
			(xy 43.819821 -165.090937) (xy 43.755811 -165.035472) (xy 43.697363 -164.974174) (xy 43.645007 -164.907598)
			(xy 43.599217 -164.836346) (xy 43.560406 -164.761065) (xy 43.528927 -164.682435) (xy 43.505066 -164.601168)
			(xy 43.489037 -164.518002) (xy 43.480986 -164.433688) (xy 36.37534 -164.433688) (xy 36.37534 -167.71747)
			(xy 50.99304 -167.71747) (xy 50.993427 -167.690214) (xy 51.001189 -167.636258) (xy 51.016552 -167.583956)
			(xy 51.039201 -167.534372) (xy 51.068677 -167.488517) (xy 51.104379 -167.447323) (xy 51.145579 -167.41163)
			(xy 51.191441 -167.382164) (xy 51.241029 -167.359524) (xy 51.293334 -167.344173) (xy 51.347292 -167.336422)
			(xy 51.374548 -167.335962) (xy 51.402122 -167.336442) (xy 51.456695 -167.344388) (xy 51.509556 -167.360109)
			(xy 51.559603 -167.383276) (xy 51.605792 -167.413408) (xy 51.647163 -167.449875) (xy 51.665378 -167.470582)
			(xy 51.675276 -167.48148) (xy 51.699926 -167.497555) (xy 51.728134 -167.505939) (xy 51.757562 -167.505939)
			(xy 51.78577 -167.497555) (xy 51.81042 -167.48148) (xy 51.820318 -167.470582) (xy 51.838512 -167.449855)
			(xy 51.879885 -167.413387) (xy 51.926079 -167.383257) (xy 51.97613 -167.360094) (xy 52.028995 -167.344381)
			(xy 52.083572 -167.336445) (xy 52.111148 -167.335962) (xy 52.137649 -167.336415) (xy 52.19014 -167.343762)
			(xy 52.241107 -167.358307) (xy 52.289569 -167.37977) (xy 52.334592 -167.407737) (xy 52.355242 -167.424354)
			(xy 52.367396 -167.433784) (xy 52.395794 -167.445573) (xy 52.426411 -167.448397) (xy 52.456486 -167.442003)
			(xy 52.483306 -167.426967) (xy 52.504451 -167.404645) (xy 52.511706 -167.39108) (xy 52.523817 -167.367395)
			(xy 52.553737 -167.323413) (xy 52.589605 -167.28413) (xy 52.630693 -167.250345) (xy 52.653184 -167.23614)
			(xy 52.665431 -167.228248) (xy 52.685104 -167.206769) (xy 52.697907 -167.180607) (xy 52.702796 -167.151894)
			(xy 52.699373 -167.122969) (xy 52.694078 -167.109394) (xy 52.684593 -167.086182) (xy 52.671241 -167.03785)
			(xy 52.664511 -166.988161) (xy 52.664106 -166.96309) (xy 52.66454 -166.938021) (xy 52.671286 -166.888338)
			(xy 52.684614 -166.840004) (xy 52.694078 -166.816786) (xy 52.699333 -166.803207) (xy 52.702713 -166.774299)
			(xy 52.697811 -166.74561) (xy 52.685024 -166.719464) (xy 52.665389 -166.69798) (xy 52.653184 -166.69004)
			(xy 52.630024 -166.675514) (xy 52.587899 -166.640668) (xy 52.551317 -166.600041) (xy 52.521063 -166.554506)
			(xy 52.497786 -166.505039) (xy 52.481986 -166.452703) (xy 52.474001 -166.398619) (xy 52.474003 -166.34395)
			(xy 52.481993 -166.289867) (xy 52.497797 -166.237532) (xy 52.521079 -166.188067) (xy 52.551336 -166.142534)
			(xy 52.587922 -166.101911) (xy 52.630049 -166.067068) (xy 52.653184 -166.0525) (xy 52.66539 -166.044551)
			(xy 52.685063 -166.023088) (xy 52.697871 -165.996941) (xy 52.702771 -165.968241) (xy 52.699363 -165.939326)
			(xy 52.694078 -165.925754) (xy 52.684581 -165.902547) (xy 52.671233 -165.854213) (xy 52.664508 -165.804522)
			(xy 52.664106 -165.77945) (xy 52.664627 -165.751565) (xy 52.672939 -165.696418) (xy 52.689377 -165.643126)
			(xy 52.713575 -165.59288) (xy 52.744991 -165.546801) (xy 52.782924 -165.505919) (xy 52.826526 -165.471147)
			(xy 52.874824 -165.443262) (xy 52.926739 -165.422887) (xy 52.98111 -165.410477) (xy 53.036724 -165.40631)
			(xy 53.092338 -165.410477) (xy 53.146709 -165.422887) (xy 53.198624 -165.443262) (xy 53.246922 -165.471147)
			(xy 53.290524 -165.505919) (xy 53.328457 -165.546801) (xy 53.359873 -165.59288) (xy 53.384071 -165.643126)
			(xy 53.400509 -165.696418) (xy 53.408821 -165.751565) (xy 53.409342 -165.77945) (xy 53.408875 -165.806782)
			(xy 53.400906 -165.860863) (xy 53.385118 -165.913198) (xy 53.36185 -165.962662) (xy 53.331601 -166.008195)
			(xy 53.295022 -166.048817) (xy 53.252897 -166.083655) (xy 53.229764 -166.09822) (xy 53.217537 -166.106138)
			(xy 53.19787 -166.127612) (xy 53.185068 -166.153767) (xy 53.180173 -166.182472) (xy 53.183584 -166.211392)
			(xy 53.18887 -166.224966) (xy 53.198345 -166.248181) (xy 53.211701 -166.296512) (xy 53.218435 -166.346199)
			(xy 53.218842 -166.37127) (xy 53.218431 -166.39634) (xy 53.211677 -166.446023) (xy 53.198339 -166.494357)
			(xy 53.18887 -166.517574) (xy 53.183624 -166.531151) (xy 53.180262 -166.560051) (xy 53.185173 -166.588729)
			(xy 53.197961 -166.614863) (xy 53.217591 -166.636338) (xy 53.229764 -166.64432) (xy 53.252885 -166.658903)
			(xy 53.295003 -166.693747) (xy 53.331579 -166.734369) (xy 53.361829 -166.779898) (xy 53.385103 -166.829358)
			(xy 53.400902 -166.881688) (xy 53.408888 -166.935764) (xy 53.408889 -166.990426) (xy 53.400905 -167.044502)
			(xy 53.385107 -167.096832) (xy 53.361834 -167.146292) (xy 53.331585 -167.191823) (xy 53.29501 -167.232446)
			(xy 53.252893 -167.267291) (xy 53.229764 -167.28186) (xy 53.217509 -167.289739) (xy 53.197842 -167.311225)
			(xy 53.185043 -167.33739) (xy 53.180156 -167.366104) (xy 53.183577 -167.39503) (xy 53.18887 -167.408606)
			(xy 53.198357 -167.431817) (xy 53.211708 -167.480149) (xy 53.218438 -167.529838) (xy 53.218842 -167.55491)
			(xy 53.21837 -167.581752) (xy 53.210665 -167.634881) (xy 53.195416 -167.686354) (xy 53.172938 -167.735106)
			(xy 53.143697 -167.780127) (xy 53.108298 -167.820487) (xy 53.067473 -167.855349) (xy 53.022069 -167.883993)
			(xy 52.973024 -167.905824) (xy 52.947316 -167.913558) (xy 52.932841 -167.918276) (xy 52.907286 -167.934788)
			(xy 52.887726 -167.958092) (xy 52.875894 -167.986122) (xy 52.87284 -168.016393) (xy 52.878835 -168.046222)
			(xy 52.885594 -168.059862) (xy 52.900228 -168.088008) (xy 52.920955 -168.147959) (xy 52.931453 -168.210517)
			(xy 52.932076 -168.242234) (xy 52.931855 -168.260253) (xy 52.928421 -168.296128) (xy 52.925218 -168.313862)
			(xy 52.922936 -168.329077) (xy 52.926453 -168.359622) (xy 52.938901 -168.387736) (xy 52.959153 -168.410871)
			(xy 52.985373 -168.426931) (xy 53.000148 -168.43121) (xy 53.027191 -168.438611) (xy 53.078917 -168.460241)
			(xy 53.126922 -168.489205) (xy 53.170174 -168.52488) (xy 53.207741 -168.566499) (xy 53.238815 -168.613165)
			(xy 53.262728 -168.663876) (xy 53.278965 -168.71754) (xy 53.287177 -168.773001) (xy 53.287676 -168.801034)
			(xy 53.287254 -168.828288) (xy 53.279492 -168.882239) (xy 53.264131 -168.934537) (xy 53.241483 -168.984117)
			(xy 53.21201 -169.029968) (xy 53.176312 -169.071159) (xy 53.135115 -169.10685) (xy 53.089259 -169.136315)
			(xy 53.039675 -169.158954) (xy 52.987375 -169.174306) (xy 52.933422 -169.182058) (xy 52.906168 -169.182542)
			(xy 52.878594 -169.18205) (xy 52.824022 -169.174105) (xy 52.771161 -169.158387) (xy 52.721115 -169.135222)
			(xy 52.674925 -169.105093) (xy 52.633554 -169.068628) (xy 52.615338 -169.047922) (xy 52.60544 -169.037024)
			(xy 52.58079 -169.020949) (xy 52.552582 -169.012565) (xy 52.523154 -169.012565) (xy 52.494946 -169.020949)
			(xy 52.470296 -169.037024) (xy 52.460398 -169.047922) (xy 52.442183 -169.068628) (xy 52.400812 -169.105093)
			(xy 52.354622 -169.13522) (xy 52.304575 -169.158383) (xy 52.251714 -169.174099) (xy 52.197142 -169.182039)
			(xy 52.141994 -169.182039) (xy 52.087422 -169.174099) (xy 52.034561 -169.158383) (xy 51.984514 -169.13522)
			(xy 51.938324 -169.105093) (xy 51.896953 -169.068628) (xy 51.878738 -169.047922) (xy 51.86884 -169.037024)
			(xy 51.84419 -169.020949) (xy 51.815982 -169.012565) (xy 51.786554 -169.012565) (xy 51.758346 -169.020949)
			(xy 51.733696 -169.037024) (xy 51.723798 -169.047922) (xy 51.705596 -169.068642) (xy 51.664225 -169.10511)
			(xy 51.618033 -169.135241) (xy 51.567983 -169.158405) (xy 51.515119 -169.17412) (xy 51.460543 -169.182058)
			(xy 51.432968 -169.182542) (xy 51.405718 -169.182052) (xy 51.351772 -169.174292) (xy 51.299479 -169.158935)
			(xy 51.249904 -169.136292) (xy 51.204055 -169.106826) (xy 51.162866 -169.071135) (xy 51.127175 -169.029946)
			(xy 51.097709 -168.984098) (xy 51.075066 -168.934523) (xy 51.059708 -168.88223) (xy 51.051948 -168.828284)
			(xy 51.05146 -168.801034) (xy 51.052043 -168.773181) (xy 51.060161 -168.71807) (xy 51.0762 -168.664722)
			(xy 51.09982 -168.614272) (xy 51.130519 -168.567788) (xy 51.167647 -168.526258) (xy 51.210414 -168.490563)
			(xy 51.257914 -168.461461) (xy 51.309138 -168.439569) (xy 51.33594 -168.431972) (xy 51.350063 -168.427719)
			(xy 51.375204 -168.41232) (xy 51.394916 -168.390396) (xy 51.407566 -168.363764) (xy 51.412104 -168.334632)
			(xy 51.410616 -168.319958) (xy 51.408945 -168.306942) (xy 51.407166 -168.280757) (xy 51.40706 -168.267634)
			(xy 51.407158 -168.253485) (xy 51.409189 -168.225262) (xy 51.411124 -168.211246) (xy 51.412683 -168.197896)
			(xy 51.409585 -168.171209) (xy 51.39962 -168.146259) (xy 51.38348 -168.124781) (xy 51.362288 -168.108267)
			(xy 51.337516 -168.097867) (xy 51.324256 -168.095676) (xy 51.297113 -168.09153) (xy 51.244287 -168.076561)
			(xy 51.194152 -168.054174) (xy 51.147744 -168.024832) (xy 51.106021 -167.989141) (xy 51.069844 -167.947838)
			(xy 51.039961 -167.901777) (xy 51.016989 -167.851907) (xy 51.001402 -167.79926) (xy 50.993522 -167.744923)
			(xy 50.99304 -167.71747) (xy 36.37534 -167.71747) (xy 36.37534 -169.778934) (xy 36.398201 -169.801794)
			(xy 43.431209 -169.801794) (xy 43.435245 -169.718347) (xy 43.447317 -169.635679) (xy 43.46731 -169.554562)
			(xy 43.495039 -169.475753) (xy 43.530245 -169.399988) (xy 43.572599 -169.327975) (xy 43.621705 -169.260386)
			(xy 43.677106 -169.197852) (xy 43.738283 -169.140957) (xy 43.804666 -169.090231) (xy 43.875634 -169.04615)
			(xy 43.950526 -169.009124) (xy 44.028642 -168.979498) (xy 44.109252 -168.95755) (xy 44.191604 -168.943485)
			(xy 44.27493 -168.937433) (xy 44.35845 -168.939452) (xy 44.441386 -168.949522) (xy 44.522962 -168.96755)
			(xy 44.602418 -168.993367) (xy 44.679011 -169.026732) (xy 44.752027 -169.067333) (xy 44.820783 -169.114792)
			(xy 44.884637 -169.168665) (xy 44.942994 -169.22845) (xy 44.995309 -169.293587) (xy 45.041092 -169.36347)
			(xy 45.079917 -169.437445) (xy 45.111422 -169.514822) (xy 45.135311 -169.594879) (xy 45.151362 -169.676867)
			(xy 45.159425 -169.760022) (xy 45.15993 -169.801794) (xy 45.159425 -169.843566) (xy 45.151362 -169.926721)
			(xy 45.135311 -170.008709) (xy 45.111422 -170.088766) (xy 45.079917 -170.166143) (xy 45.041092 -170.240118)
			(xy 44.995309 -170.310001) (xy 44.942994 -170.375138) (xy 44.884637 -170.434923) (xy 44.820783 -170.488796)
			(xy 44.752027 -170.536255) (xy 44.679011 -170.576856) (xy 44.602418 -170.610221) (xy 44.522962 -170.636038)
			(xy 44.441386 -170.654066) (xy 44.35845 -170.664136) (xy 44.27493 -170.666155) (xy 44.191604 -170.660103)
			(xy 44.109252 -170.646038) (xy 44.028642 -170.62409) (xy 43.950526 -170.594464) (xy 43.875634 -170.557438)
			(xy 43.804666 -170.513357) (xy 43.738283 -170.462631) (xy 43.677106 -170.405736) (xy 43.621705 -170.343202)
			(xy 43.572599 -170.275613) (xy 43.530245 -170.2036) (xy 43.495039 -170.127835) (xy 43.46731 -170.049026)
			(xy 43.447317 -169.967909) (xy 43.435245 -169.885241) (xy 43.431209 -169.801794) (xy 36.398201 -169.801794)
			(xy 37.452611 -170.856148) (xy 50.017172 -170.856148) (xy 50.017649 -170.828574) (xy 50.025597 -170.774002)
			(xy 50.041318 -170.721142) (xy 50.064486 -170.671096) (xy 50.094617 -170.624907) (xy 50.131084 -170.583538)
			(xy 50.173128 -170.54785) (xy 50.196242 -170.532806) (xy 50.208147 -170.524733) (xy 50.227333 -170.503326)
			(xy 50.239787 -170.477417) (xy 50.244521 -170.449062) (xy 50.24116 -170.420513) (xy 50.229971 -170.394033)
			(xy 50.21184 -170.371725) (xy 50.200306 -170.363134) (xy 50.178981 -170.347755) (xy 50.140292 -170.312157)
			(xy 50.10686 -170.27158) (xy 50.079321 -170.226795) (xy 50.058196 -170.178651) (xy 50.043886 -170.128062)
			(xy 50.036663 -170.075985) (xy 50.036222 -170.049698) (xy 50.036708 -170.022447) (xy 50.044464 -169.968499)
			(xy 50.059819 -169.916204) (xy 50.082461 -169.866627) (xy 50.111927 -169.820777) (xy 50.147618 -169.779586)
			(xy 50.188809 -169.743895) (xy 50.234659 -169.714429) (xy 50.284236 -169.691787) (xy 50.336531 -169.676432)
			(xy 50.390479 -169.668676) (xy 50.444981 -169.668676) (xy 50.498929 -169.676432) (xy 50.551224 -169.691787)
			(xy 50.600801 -169.714429) (xy 50.646651 -169.743895) (xy 50.687842 -169.779586) (xy 50.723533 -169.820777)
			(xy 50.752999 -169.866627) (xy 50.775641 -169.916204) (xy 50.790996 -169.968499) (xy 50.798752 -170.022447)
			(xy 50.799238 -170.049698) (xy 50.798792 -170.077273) (xy 50.790838 -170.131847) (xy 50.775111 -170.184707)
			(xy 50.751938 -170.234752) (xy 50.721802 -170.280941) (xy 50.685331 -170.32231) (xy 50.643284 -170.357997)
			(xy 50.620168 -170.37304) (xy 50.608219 -170.381053) (xy 50.58903 -170.402473) (xy 50.576576 -170.428395)
			(xy 50.571846 -170.456762) (xy 50.575216 -170.485322) (xy 50.586418 -170.51181) (xy 50.604562 -170.534121)
			(xy 50.616104 -170.542712) (xy 50.637453 -170.558059) (xy 50.676141 -170.593663) (xy 50.709571 -170.634245)
			(xy 50.737107 -170.679036) (xy 50.758228 -170.727185) (xy 50.772533 -170.777779) (xy 50.779751 -170.829859)
			(xy 50.780188 -170.856148) (xy 50.779702 -170.883399) (xy 50.771946 -170.937347) (xy 50.756591 -170.989642)
			(xy 50.733949 -171.039219) (xy 50.704483 -171.085069) (xy 50.668792 -171.12626) (xy 50.627601 -171.161951)
			(xy 50.581751 -171.191417) (xy 50.532174 -171.214059) (xy 50.479879 -171.229414) (xy 50.425931 -171.23717)
			(xy 50.371429 -171.23717) (xy 50.317481 -171.229414) (xy 50.265186 -171.214059) (xy 50.215609 -171.191417)
			(xy 50.169759 -171.161951) (xy 50.128568 -171.12626) (xy 50.092877 -171.085069) (xy 50.063411 -171.039219)
			(xy 50.040769 -170.989642) (xy 50.025414 -170.937347) (xy 50.017658 -170.883399) (xy 50.017172 -170.856148)
			(xy 37.452611 -170.856148) (xy 38.940806 -172.344264) (xy 43.406818 -172.344264) (xy 43.406818 -172.259568)
			(xy 43.414869 -172.175254) (xy 43.430898 -172.092088) (xy 43.454759 -172.010821) (xy 43.486238 -171.932191)
			(xy 43.525049 -171.85691) (xy 43.570839 -171.785658) (xy 43.623195 -171.719082) (xy 43.681643 -171.657784)
			(xy 43.745653 -171.602319) (xy 43.814645 -171.55319) (xy 43.887995 -171.510841) (xy 43.965038 -171.475657)
			(xy 44.045077 -171.447955) (xy 44.127386 -171.427987) (xy 44.211221 -171.415934) (xy 44.295822 -171.411904)
			(xy 44.380423 -171.415934) (xy 44.464258 -171.427987) (xy 44.546567 -171.447955) (xy 44.626606 -171.475657)
			(xy 44.703649 -171.510841) (xy 44.776999 -171.55319) (xy 44.845991 -171.602319) (xy 44.910001 -171.657784)
			(xy 44.968449 -171.719082) (xy 45.020805 -171.785658) (xy 45.066595 -171.85691) (xy 45.105406 -171.932191)
			(xy 45.136885 -172.010821) (xy 45.160746 -172.092088) (xy 45.176775 -172.175254) (xy 45.184826 -172.259568)
			(xy 45.185173 -172.288752) (xy 48.725285 -172.288752) (xy 48.725285 -172.234248) (xy 48.733042 -172.180299)
			(xy 48.748399 -172.128003) (xy 48.771041 -172.078425) (xy 48.80051 -172.032574) (xy 48.836204 -171.991384)
			(xy 48.877396 -171.955693) (xy 48.923249 -171.926228) (xy 48.972829 -171.903589) (xy 49.025126 -171.888236)
			(xy 49.079076 -171.880483) (xy 49.106328 -171.880022) (xy 49.136703 -171.88062) (xy 49.196685 -171.89025)
			(xy 49.254384 -171.909263) (xy 49.308341 -171.937178) (xy 49.357193 -171.97329) (xy 49.37887 -171.994576)
			(xy 49.388621 -172.003887) (xy 49.411894 -172.017482) (xy 49.437911 -172.024524) (xy 49.464863 -172.024524)
			(xy 49.49088 -172.017482) (xy 49.514153 -172.003887) (xy 49.523904 -171.994576) (xy 49.54556 -171.973266)
			(xy 49.594415 -171.937152) (xy 49.648377 -171.909238) (xy 49.706081 -171.890229) (xy 49.766069 -171.880607)
			(xy 49.796446 -171.880022) (xy 49.823697 -171.880451) (xy 49.877644 -171.888213) (xy 49.929938 -171.903574)
			(xy 49.979513 -171.926219) (xy 50.025361 -171.955689) (xy 50.066549 -171.991383) (xy 50.102238 -172.032576)
			(xy 50.131703 -172.078428) (xy 50.154342 -172.128006) (xy 50.169696 -172.180301) (xy 50.177452 -172.234249)
			(xy 50.177452 -172.288751) (xy 50.169696 -172.342699) (xy 50.154342 -172.394994) (xy 50.131703 -172.444572)
			(xy 50.102238 -172.490424) (xy 50.066549 -172.531617) (xy 50.025361 -172.567311) (xy 49.979513 -172.596781)
			(xy 49.929938 -172.619426) (xy 49.877644 -172.634787) (xy 49.823697 -172.642549) (xy 49.796446 -172.643038)
			(xy 49.76607 -172.642468) (xy 49.706086 -172.632833) (xy 49.648386 -172.613814) (xy 49.59443 -172.585893)
			(xy 49.545579 -172.549774) (xy 49.523904 -172.528484) (xy 49.514176 -172.519126) (xy 49.490915 -172.50545)
			(xy 49.464879 -172.498363) (xy 49.437895 -172.498363) (xy 49.411859 -172.50545) (xy 49.388598 -172.519126)
			(xy 49.37887 -172.528484) (xy 49.357174 -172.549751) (xy 49.30833 -172.585872) (xy 49.254379 -172.613795)
			(xy 49.196683 -172.632814) (xy 49.136703 -172.642447) (xy 49.106328 -172.643038) (xy 49.079076 -172.642517)
			(xy 49.025126 -172.634764) (xy 48.972829 -172.619411) (xy 48.923249 -172.596772) (xy 48.877396 -172.567307)
			(xy 48.836204 -172.531616) (xy 48.80051 -172.490426) (xy 48.771041 -172.444575) (xy 48.748399 -172.394997)
			(xy 48.733042 -172.342701) (xy 48.725285 -172.288752) (xy 45.185173 -172.288752) (xy 45.18533 -172.301916)
			(xy 45.184826 -172.344264) (xy 45.176775 -172.428578) (xy 45.160746 -172.511744) (xy 45.136885 -172.593011)
			(xy 45.105406 -172.671641) (xy 45.066595 -172.746922) (xy 45.020805 -172.818174) (xy 44.968449 -172.88475)
			(xy 44.910001 -172.946048) (xy 44.845991 -173.001513) (xy 44.776999 -173.050642) (xy 44.703649 -173.092991)
			(xy 44.626606 -173.128175) (xy 44.546567 -173.155877) (xy 44.464258 -173.175845) (xy 44.380423 -173.187898)
			(xy 44.295822 -173.191929) (xy 44.211221 -173.187898) (xy 44.127386 -173.175845) (xy 44.045077 -173.155877)
			(xy 43.965038 -173.128175) (xy 43.887995 -173.092991) (xy 43.814645 -173.050642) (xy 43.745653 -173.001513)
			(xy 43.681643 -172.946048) (xy 43.623195 -172.88475) (xy 43.570839 -172.818174) (xy 43.525049 -172.746922)
			(xy 43.486238 -172.671641) (xy 43.454759 -172.593011) (xy 43.430898 -172.511744) (xy 43.414869 -172.428578)
			(xy 43.406818 -172.344264) (xy 38.940806 -172.344264) (xy 41.15562 -174.55896) (xy 45.250608 -174.55896)
			(xy 47.01159 -172.797978) (xy 47.037139 -172.773094) (xy 47.09289 -172.72861) (xy 47.153273 -172.69065)
			(xy 47.217528 -172.659693) (xy 47.284846 -172.636128) (xy 47.35438 -172.620252) (xy 47.425254 -172.612264)
			(xy 47.460916 -172.611796) (xy 47.497325 -172.612296) (xy 47.569667 -172.620612) (xy 47.640583 -172.637145)
			(xy 47.709145 -172.661677) (xy 47.774451 -172.693888) (xy 47.835647 -172.733354) (xy 47.891929 -172.779558)
			(xy 47.942559 -172.831894) (xy 47.986874 -172.889675) (xy 48.006 -172.92066) (xy 50.439066 -172.92066)
			(xy 50.842926 -172.5168) (xy 50.800508 -172.474128) (xy 50.791872 -172.470318) (xy 50.784683 -172.467295)
			(xy 50.769631 -172.463217) (xy 50.7619 -172.46219) (xy 50.734288 -172.458577) (xy 50.680444 -172.444375)
			(xy 50.629237 -172.422494) (xy 50.581757 -172.393398) (xy 50.539013 -172.357707) (xy 50.501914 -172.316179)
			(xy 50.471249 -172.269697) (xy 50.44767 -172.21925) (xy 50.431678 -172.16591) (xy 50.423613 -172.110811)
			(xy 50.423064 -172.082968) (xy 50.423552 -172.055718) (xy 50.431312 -172.001772) (xy 50.44667 -171.949479)
			(xy 50.469312 -171.899904) (xy 50.498779 -171.854056) (xy 50.53447 -171.812867) (xy 50.575659 -171.777177)
			(xy 50.621508 -171.74771) (xy 50.671083 -171.725068) (xy 50.723376 -171.709711) (xy 50.777322 -171.701952)
			(xy 50.804572 -171.70146) (xy 50.832321 -171.701964) (xy 50.887232 -171.710012) (xy 50.940398 -171.72593)
			(xy 50.990698 -171.74938) (xy 51.037071 -171.779868) (xy 51.078539 -171.816751) (xy 51.114228 -171.859252)
			(xy 51.143384 -171.906474) (xy 51.165393 -171.957421) (xy 51.179791 -172.011019) (xy 51.18354 -172.038518)
			(xy 51.184482 -172.046717) (xy 51.188691 -172.062674) (xy 51.191922 -172.070268) (xy 51.195732 -172.078904)
			(xy 51.23815 -172.121576) (xy 51.571652 -171.788074) (xy 51.571652 -171.282868) (xy 51.572205 -171.252886)
			(xy 51.581579 -171.193659) (xy 51.600107 -171.136628) (xy 51.627331 -171.083201) (xy 51.662583 -171.034692)
			(xy 51.683412 -171.01312) (xy 52.458874 -170.237658) (xy 52.459382 -170.23715) (xy 52.479664 -170.21665)
			(xy 52.525293 -170.18139) (xy 52.575711 -170.153402) (xy 52.629768 -170.133326) (xy 52.686232 -170.121619)
			(xy 52.743816 -170.118548) (xy 52.772564 -170.120818) (xy 52.779676 -170.121834) (xy 52.77993 -170.121834)
			(xy 52.809528 -170.125874) (xy 52.867054 -170.141969) (xy 52.921366 -170.166836) (xy 52.971136 -170.199868)
			(xy 52.993544 -170.219624) (xy 53.000402 -170.225974) (xy 53.006244 -170.231816) (xy 53.015816 -170.240893)
			(xy 53.03855 -170.25425) (xy 53.06395 -170.261331) (xy 53.090317 -170.261661) (xy 53.115886 -170.255219)
			(xy 53.138949 -170.242435) (xy 53.148738 -170.233594) (xy 53.170415 -170.212307) (xy 53.219267 -170.176195)
			(xy 53.273224 -170.14828) (xy 53.330922 -170.129267) (xy 53.390905 -170.119638) (xy 53.42128 -170.11904)
			(xy 53.448533 -170.119502) (xy 53.502483 -170.127257) (xy 53.554781 -170.142612) (xy 53.60436 -170.165254)
			(xy 53.650212 -170.194722) (xy 53.691403 -170.230416) (xy 53.727095 -170.27161) (xy 53.75656 -170.317464)
			(xy 53.779198 -170.367046) (xy 53.794549 -170.419344) (xy 53.8023 -170.473295) (xy 53.802788 -170.500548)
			(xy 53.802306 -170.527709) (xy 53.794597 -170.581481) (xy 53.779343 -170.633617) (xy 53.756851 -170.683064)
			(xy 53.727576 -170.728822) (xy 53.692108 -170.769967) (xy 53.651166 -170.805668) (xy 53.605575 -170.835204)
			(xy 53.556258 -170.857978) (xy 53.50421 -170.873529) (xy 53.477414 -170.877992) (xy 53.462055 -170.880854)
			(xy 53.434 -170.894566) (xy 53.422296 -170.904916) (xy 53.421788 -170.905424) (xy 53.385466 -170.941746)
			(xy 53.479954 -171.03598) (xy 54.8005 -171.03598) (xy 54.833788 -171.036515) (xy 54.899792 -171.045234)
			(xy 54.964092 -171.062497) (xy 55.025587 -171.088008) (xy 55.083225 -171.12133) (xy 55.136018 -171.161892)
			(xy 55.15991 -171.185078) (xy 55.87873 -171.903898) (xy 55.901888 -171.927812) (xy 55.94243 -171.980612)
			(xy 55.975739 -172.038249) (xy 56.001245 -172.099739) (xy 56.018512 -172.16403) (xy 56.027247 -172.230024)
			(xy 56.027828 -172.263308) (xy 56.027828 -176.34966) (xy 56.027296 -176.382949) (xy 56.018581 -176.448955)
			(xy 56.001323 -176.513259) (xy 55.975816 -176.574758) (xy 55.942497 -176.6324) (xy 55.901936 -176.685198)
			(xy 55.87873 -176.70907) (xy 55.120794 -177.467006) (xy 55.12435 -177.492152) (xy 55.127332 -177.514447)
			(xy 55.13051 -177.559321) (xy 55.1307 -177.581814) (xy 55.130235 -177.617469) (xy 55.122282 -177.688332)
			(xy 55.106444 -177.75786) (xy 55.08292 -177.825177) (xy 55.052006 -177.889436) (xy 55.014091 -177.94983)
			(xy 54.969652 -178.005598) (xy 54.944772 -178.03114) (xy 50.153629 -182.822088) (xy 57.385202 -182.822088)
			(xy 57.389273 -182.766466) (xy 57.401399 -182.712029) (xy 57.421322 -182.659938) (xy 57.448618 -182.611303)
			(xy 57.482704 -182.56716) (xy 57.522853 -182.528451) (xy 57.568211 -182.496) (xy 57.617811 -182.470499)
			(xy 57.670595 -182.452492) (xy 57.725438 -182.442362) (xy 57.781172 -182.440325) (xy 57.836609 -182.446425)
			(xy 57.890566 -182.460531) (xy 57.941895 -182.482343) (xy 57.989501 -182.511397) (xy 58.032369 -182.547072)
			(xy 58.069586 -182.588609) (xy 58.100359 -182.635122) (xy 58.124031 -182.685619) (xy 58.140099 -182.739026)
			(xy 58.148219 -182.794202) (xy 58.148728 -182.822088) (xy 58.148219 -182.849974) (xy 58.140099 -182.90515)
			(xy 58.124031 -182.958557) (xy 58.100359 -183.009054) (xy 58.069586 -183.055567) (xy 58.032369 -183.097104)
			(xy 57.989501 -183.132779) (xy 57.941895 -183.161833) (xy 57.890566 -183.183645) (xy 57.836609 -183.197751)
			(xy 57.781172 -183.203851) (xy 57.725438 -183.201814) (xy 57.670595 -183.191684) (xy 57.617811 -183.173677)
			(xy 57.568211 -183.148176) (xy 57.522853 -183.115725) (xy 57.482704 -183.077016) (xy 57.448618 -183.032873)
			(xy 57.421322 -182.984238) (xy 57.401399 -182.932147) (xy 57.389273 -182.87771) (xy 57.385202 -182.822088)
			(xy 50.153629 -182.822088) (xy 48.702976 -184.272682) (xy 48.692735 -184.283663) (xy 48.678575 -184.310124)
			(xy 48.67271 -184.339557) (xy 48.675645 -184.369425) (xy 48.687129 -184.397152) (xy 48.706171 -184.420349)
			(xy 48.731129 -184.437016) (xy 48.759852 -184.445716) (xy 48.774858 -184.446164) (xy 57.73166 -184.446164)
		)
		(stroke
			(width 0)
			(type solid)
		)
		(fill yes)
		(layer "In15.Cu")
		(net "GND")
	)
	(gr_poly
		(pts
			(xy 68.522596 -32.140144) (xy 68.543444 -32.120015) (xy 68.590292 -32.085906) (xy 68.641901 -32.059548)
			(xy 68.696997 -32.041591) (xy 68.754226 -32.032476) (xy 68.7832 -32.03194) (xy 70.337934 -32.03194)
			(xy 70.361047 -32.032347) (xy 70.406902 -32.038202) (xy 70.429374 -32.043624) (xy 70.43547 -32.045148)
			(xy 70.51548 -32.045148) (xy 71.683626 -33.21304) (xy 84.892134 -33.21304) (xy 85.52688 -32.578548)
			(xy 85.52688 -14.087348) (xy 85.133434 -13.694156) (xy 82.17408 -13.694156) (xy 82.149631 -13.693706)
			(xy 82.101309 -13.686214) (xy 82.054705 -13.67141) (xy 82.010918 -13.649644) (xy 81.970981 -13.621428)
			(xy 81.9531 -13.604748) (xy 76.797916 -13.604748) (xy 76.778435 -13.622962) (xy 76.735301 -13.654328)
			(xy 76.688219 -13.679381) (xy 76.638108 -13.697633) (xy 76.585942 -13.708729) (xy 76.53274 -13.712452)
			(xy 76.479538 -13.708729) (xy 76.427372 -13.697633) (xy 76.377261 -13.679381) (xy 76.330179 -13.654328)
			(xy 76.287045 -13.622962) (xy 76.267564 -13.604748) (xy 75.141582 -13.604748) (xy 75.136756 -13.605764)
			(xy 75.118526 -13.609114) (xy 75.08163 -13.612676) (xy 75.063096 -13.612876) (xy 75.044562 -13.612668)
			(xy 75.007666 -13.609109) (xy 74.989436 -13.605764) (xy 74.98461 -13.604748) (xy 74.800968 -13.604748)
			(xy 74.78756 -13.605158) (xy 74.761671 -13.612146) (xy 74.738493 -13.625633) (xy 74.719624 -13.644687)
			(xy 74.706366 -13.667996) (xy 74.699631 -13.693953) (xy 74.699368 -13.707364) (xy 74.699368 -13.711428)
			(xy 74.698903 -13.738679) (xy 74.691142 -13.792624) (xy 74.675783 -13.844916) (xy 74.653139 -13.894491)
			(xy 74.623669 -13.940337) (xy 74.587975 -13.981523) (xy 74.546783 -14.01721) (xy 74.500931 -14.046671)
			(xy 74.451353 -14.069307) (xy 74.399058 -14.084657) (xy 74.345111 -14.092408) (xy 74.31786 -14.092936)
			(xy 74.288458 -14.092398) (xy 74.230348 -14.083385) (xy 74.17431 -14.065562) (xy 74.121669 -14.039353)
			(xy 74.073674 -14.005377) (xy 74.031459 -13.96444) (xy 74.013314 -13.941298) (xy 74.004199 -13.929984)
			(xy 73.980883 -13.912667) (xy 73.95363 -13.902631) (xy 73.924652 -13.90069) (xy 73.896303 -13.907002)
			(xy 73.870886 -13.921055) (xy 73.850466 -13.941707) (xy 73.843134 -13.954252) (xy 73.828695 -13.979744)
			(xy 73.793217 -14.026365) (xy 73.751032 -14.067018) (xy 73.703132 -14.100749) (xy 73.65064 -14.126765)
			(xy 73.59479 -14.144456) (xy 73.536893 -14.153407) (xy 73.5076 -14.153896) (xy 73.480347 -14.153433)
			(xy 73.426397 -14.145676) (xy 73.3741 -14.130319) (xy 73.324521 -14.107677) (xy 73.278668 -14.078209)
			(xy 73.237477 -14.042515) (xy 73.201784 -14.001322) (xy 73.172317 -13.955469) (xy 73.149676 -13.905889)
			(xy 73.134322 -13.853591) (xy 73.126566 -13.799641) (xy 73.126092 -13.772388) (xy 73.126205 -13.759329)
			(xy 73.127985 -13.733271) (xy 73.129648 -13.720318) (xy 73.131127 -13.705901) (xy 73.126879 -13.677247)
			(xy 73.114756 -13.650938) (xy 73.095735 -13.629091) (xy 73.071344 -13.613464) (xy 73.043547 -13.605313)
			(xy 73.029064 -13.604748) (xy 72.992488 -13.604748) (xy 72.979026 -13.6144) (xy 72.956164 -13.630197)
			(xy 72.906567 -13.655254) (xy 72.853678 -13.672299) (xy 72.798784 -13.680918) (xy 72.771 -13.681456)
			(xy 72.74122 -13.680854) (xy 72.682489 -13.67094) (xy 72.626228 -13.65139) (xy 72.574006 -13.622748)
			(xy 72.550274 -13.604748) (xy 70.54088 -13.604748) (xy 67.92722 -10.991088) (xy 67.900042 -10.997438)
			(xy 67.879176 -11.00185) (xy 67.836786 -11.006563) (xy 67.81546 -11.006836) (xy 67.78821 -11.006348)
			(xy 67.734265 -10.998587) (xy 67.681973 -10.983228) (xy 67.632399 -10.960585) (xy 67.586552 -10.931118)
			(xy 67.545364 -10.895427) (xy 67.509675 -10.854238) (xy 67.480209 -10.80839) (xy 67.457568 -10.758815)
			(xy 67.442211 -10.706523) (xy 67.434452 -10.652578) (xy 67.433952 -10.625328) (xy 67.434216 -10.604001)
			(xy 67.438921 -10.561609) (xy 67.44335 -10.540746) (xy 67.4497 -10.513568) (xy 67.31508 -10.378948)
			(xy 64.637412 -10.378948) (xy 64.630808 -10.380726) (xy 64.605786 -10.387246) (xy 64.554554 -10.394249)
			(xy 64.5287 -10.394696) (xy 64.502846 -10.394249) (xy 64.451615 -10.387243) (xy 64.426592 -10.380726)
			(xy 64.419988 -10.378948) (xy 63.574422 -10.378948) (xy 63.55588 -10.379456) (xy 63.537338 -10.378948)
			(xy 62.89548 -10.378948) (xy 62.41288 -10.861548) (xy 62.41288 -12.436348) (xy 62.818772 -12.436348)
			(xy 62.819258 -12.409097) (xy 62.827014 -12.355149) (xy 62.842369 -12.302854) (xy 62.865011 -12.253277)
			(xy 62.894477 -12.207427) (xy 62.930168 -12.166236) (xy 62.971359 -12.130545) (xy 63.017209 -12.101079)
			(xy 63.066786 -12.078437) (xy 63.119081 -12.063082) (xy 63.173029 -12.055326) (xy 63.227531 -12.055326)
			(xy 63.281479 -12.063082) (xy 63.333774 -12.078437) (xy 63.383351 -12.101079) (xy 63.429201 -12.130545)
			(xy 63.470392 -12.166236) (xy 63.506083 -12.207427) (xy 63.535549 -12.253277) (xy 63.558191 -12.302854)
			(xy 63.573546 -12.355149) (xy 63.581302 -12.409097) (xy 63.581788 -12.436348) (xy 63.581296 -12.463562)
			(xy 63.573551 -12.517437) (xy 63.558226 -12.569663) (xy 63.535631 -12.61918) (xy 63.521336 -12.642342)
			(xy 63.51639 -12.650818) (xy 63.512664 -12.670066) (xy 63.51644 -12.689304) (xy 63.527164 -12.705715)
			(xy 63.543267 -12.716898) (xy 63.562391 -12.721214) (xy 63.572136 -12.720066) (xy 63.58702 -12.717816)
			(xy 63.617028 -12.715404) (xy 63.63208 -12.71524) (xy 63.638176 -12.71524) (xy 63.652463 -12.71498)
			(xy 63.680038 -12.70754) (xy 63.704476 -12.692757) (xy 63.723866 -12.671786) (xy 63.736692 -12.646267)
			(xy 63.741952 -12.618194) (xy 63.739236 -12.589763) (xy 63.734442 -12.576302) (xy 63.726025 -12.553938)
			(xy 63.714162 -12.507648) (xy 63.708163 -12.46024) (xy 63.707772 -12.436348) (xy 63.708258 -12.409097)
			(xy 63.716014 -12.355149) (xy 63.731369 -12.302854) (xy 63.754011 -12.253277) (xy 63.783477 -12.207427)
			(xy 63.819168 -12.166236) (xy 63.860359 -12.130545) (xy 63.906209 -12.101079) (xy 63.955786 -12.078437)
			(xy 64.008081 -12.063082) (xy 64.062029 -12.055326) (xy 64.116531 -12.055326) (xy 64.170479 -12.063082)
			(xy 64.222774 -12.078437) (xy 64.272351 -12.101079) (xy 64.318201 -12.130545) (xy 64.359392 -12.166236)
			(xy 64.395083 -12.207427) (xy 64.424549 -12.253277) (xy 64.447191 -12.302854) (xy 64.462546 -12.355149)
			(xy 64.470302 -12.409097) (xy 64.470788 -12.436348) (xy 64.470296 -12.463562) (xy 64.462551 -12.517437)
			(xy 64.447226 -12.569663) (xy 64.424631 -12.61918) (xy 64.410336 -12.642342) (xy 64.40539 -12.650818)
			(xy 64.401664 -12.670066) (xy 64.40544 -12.689304) (xy 64.416164 -12.705715) (xy 64.432267 -12.716898)
			(xy 64.451391 -12.721214) (xy 64.461136 -12.720066) (xy 64.47602 -12.717816) (xy 64.506028 -12.715404)
			(xy 64.52108 -12.71524) (xy 64.527176 -12.71524) (xy 64.541463 -12.71498) (xy 64.569038 -12.70754)
			(xy 64.593476 -12.692757) (xy 64.612866 -12.671786) (xy 64.625692 -12.646267) (xy 64.630952 -12.618194)
			(xy 64.628236 -12.589763) (xy 64.623442 -12.576302) (xy 64.615025 -12.553938) (xy 64.603162 -12.507648)
			(xy 64.597163 -12.46024) (xy 64.596772 -12.436348) (xy 64.597258 -12.409097) (xy 64.605014 -12.355149)
			(xy 64.620369 -12.302854) (xy 64.643011 -12.253277) (xy 64.672477 -12.207427) (xy 64.708168 -12.166236)
			(xy 64.749359 -12.130545) (xy 64.795209 -12.101079) (xy 64.844786 -12.078437) (xy 64.897081 -12.063082)
			(xy 64.951029 -12.055326) (xy 65.005531 -12.055326) (xy 65.059479 -12.063082) (xy 65.111774 -12.078437)
			(xy 65.161351 -12.101079) (xy 65.207201 -12.130545) (xy 65.248392 -12.166236) (xy 65.284083 -12.207427)
			(xy 65.313549 -12.253277) (xy 65.336191 -12.302854) (xy 65.351546 -12.355149) (xy 65.359302 -12.409097)
			(xy 65.359788 -12.436348) (xy 65.359296 -12.463562) (xy 65.351551 -12.517437) (xy 65.336226 -12.569663)
			(xy 65.313631 -12.61918) (xy 65.299336 -12.642342) (xy 65.29439 -12.650818) (xy 65.290664 -12.670066)
			(xy 65.29444 -12.689304) (xy 65.305164 -12.705715) (xy 65.321267 -12.716898) (xy 65.340391 -12.721214)
			(xy 65.350136 -12.720066) (xy 65.36502 -12.717816) (xy 65.395028 -12.715404) (xy 65.41008 -12.71524)
			(xy 65.416176 -12.71524) (xy 65.430463 -12.71498) (xy 65.458038 -12.70754) (xy 65.482476 -12.692757)
			(xy 65.501866 -12.671786) (xy 65.514692 -12.646267) (xy 65.519952 -12.618194) (xy 65.517236 -12.589763)
			(xy 65.512442 -12.576302) (xy 65.504025 -12.553938) (xy 65.492162 -12.507648) (xy 65.486163 -12.46024)
			(xy 65.485772 -12.436348) (xy 65.4863 -12.409097) (xy 65.49405 -12.35515) (xy 65.509399 -12.302854)
			(xy 65.532034 -12.253276) (xy 65.561495 -12.207423) (xy 65.597182 -12.16623) (xy 65.638369 -12.130536)
			(xy 65.684216 -12.101067) (xy 65.73379 -12.078423) (xy 65.786083 -12.063064) (xy 65.840029 -12.055305)
			(xy 65.86728 -12.05484) (xy 65.89465 -12.055308) (xy 65.94883 -12.063124) (xy 66.001333 -12.078612)
			(xy 66.05108 -12.101454) (xy 66.097047 -12.131178) (xy 66.117978 -12.14882) (xy 66.129306 -12.158056)
			(xy 66.155863 -12.170232) (xy 66.18478 -12.174405) (xy 66.213697 -12.170232) (xy 66.240254 -12.158056)
			(xy 66.251582 -12.14882) (xy 66.272513 -12.131179) (xy 66.318485 -12.101467) (xy 66.368233 -12.078631)
			(xy 66.420734 -12.06314) (xy 66.474911 -12.055313) (xy 66.50228 -12.05484) (xy 66.528282 -12.05526)
			(xy 66.579801 -12.062334) (xy 66.629883 -12.076338) (xy 66.6776 -12.097014) (xy 66.722066 -12.123979)
			(xy 66.762458 -12.156733) (xy 66.798027 -12.194669) (xy 66.81343 -12.215622) (xy 66.822536 -12.227428)
			(xy 66.846063 -12.245714) (xy 66.873866 -12.25643) (xy 66.903578 -12.258665) (xy 66.932672 -12.252228)
			(xy 66.958669 -12.237668) (xy 66.969386 -12.227306) (xy 66.987433 -12.209216) (xy 67.02751 -12.177516)
			(xy 67.071458 -12.151446) (xy 67.118492 -12.131473) (xy 67.16777 -12.117955) (xy 67.218411 -12.111132)
			(xy 67.24396 -12.11072) (xy 67.271213 -12.111193) (xy 67.325165 -12.118945) (xy 67.377465 -12.134297)
			(xy 67.427046 -12.156937) (xy 67.472901 -12.186404) (xy 67.514095 -12.222097) (xy 67.549789 -12.263289)
			(xy 67.579257 -12.309143) (xy 67.601899 -12.358724) (xy 67.617253 -12.411023) (xy 67.625007 -12.464975)
			(xy 67.625468 -12.492228) (xy 67.624996 -12.518803) (xy 67.617628 -12.571438) (xy 67.603023 -12.622541)
			(xy 67.581466 -12.671122) (xy 67.553373 -12.71624) (xy 67.519288 -12.75702) (xy 67.479873 -12.792674)
			(xy 67.435889 -12.822511) (xy 67.388189 -12.845952) (xy 67.363086 -12.854686) (xy 67.350653 -12.859187)
			(xy 67.32849 -12.873593) (xy 67.310773 -12.89321) (xy 67.298691 -12.91672) (xy 67.293055 -12.942546)
			(xy 67.294244 -12.968952) (xy 67.297808 -12.981686) (xy 67.306137 -13.009718) (xy 67.31506 -13.06751)
			(xy 67.315588 -13.096748) (xy 67.315167 -13.124001) (xy 67.307403 -13.177952) (xy 67.292041 -13.23025)
			(xy 67.269393 -13.279828) (xy 67.23992 -13.325679) (xy 67.204221 -13.36687) (xy 67.163025 -13.40256)
			(xy 67.117169 -13.432025) (xy 67.067586 -13.454665) (xy 67.015286 -13.470018) (xy 66.961333 -13.477772)
			(xy 66.93408 -13.478256) (xy 66.906709 -13.477812) (xy 66.852528 -13.469991) (xy 66.800025 -13.454497)
			(xy 66.750278 -13.43165) (xy 66.704313 -13.40192) (xy 66.683382 -13.384276) (xy 66.672054 -13.37504)
			(xy 66.645497 -13.362864) (xy 66.61658 -13.358691) (xy 66.587663 -13.362864) (xy 66.561106 -13.37504)
			(xy 66.549778 -13.384276) (xy 66.528824 -13.401888) (xy 66.482858 -13.431605) (xy 66.433116 -13.454446)
			(xy 66.38062 -13.469944) (xy 66.326448 -13.477779) (xy 66.29908 -13.478256) (xy 66.27183 -13.477741)
			(xy 66.217886 -13.469983) (xy 66.165595 -13.454628) (xy 66.116021 -13.431988) (xy 66.070173 -13.402524)
			(xy 66.028984 -13.366836) (xy 65.993293 -13.32565) (xy 65.963826 -13.279804) (xy 65.941182 -13.230231)
			(xy 65.925823 -13.177941) (xy 65.918061 -13.123998) (xy 65.917572 -13.096748) (xy 65.918053 -13.069533)
			(xy 65.925799 -13.015658) (xy 65.941128 -12.963432) (xy 65.963726 -12.913915) (xy 65.978024 -12.890754)
			(xy 65.982915 -12.882253) (xy 65.98663 -12.863022) (xy 65.982857 -12.843802) (xy 65.972146 -12.827403)
			(xy 65.956064 -12.816222) (xy 65.936962 -12.811894) (xy 65.927224 -12.81303) (xy 65.912339 -12.815273)
			(xy 65.882332 -12.81769) (xy 65.86728 -12.817856) (xy 65.861184 -12.817856) (xy 65.846898 -12.81817)
			(xy 65.819324 -12.825596) (xy 65.794885 -12.840367) (xy 65.775493 -12.86133) (xy 65.762665 -12.886842)
			(xy 65.757405 -12.91491) (xy 65.760123 -12.943337) (xy 65.764918 -12.956794) (xy 65.773337 -12.979158)
			(xy 65.785198 -13.025448) (xy 65.791197 -13.072855) (xy 65.791588 -13.096748) (xy 65.791102 -13.123999)
			(xy 65.783346 -13.177947) (xy 65.767991 -13.230242) (xy 65.745349 -13.279819) (xy 65.715883 -13.325669)
			(xy 65.680192 -13.36686) (xy 65.639001 -13.402551) (xy 65.593151 -13.432017) (xy 65.543574 -13.454659)
			(xy 65.491279 -13.470014) (xy 65.437331 -13.47777) (xy 65.382829 -13.47777) (xy 65.328881 -13.470014)
			(xy 65.276586 -13.454659) (xy 65.227009 -13.432017) (xy 65.181159 -13.402551) (xy 65.139968 -13.36686)
			(xy 65.104277 -13.325669) (xy 65.074811 -13.279819) (xy 65.052169 -13.230242) (xy 65.036814 -13.177947)
			(xy 65.029058 -13.123999) (xy 65.028572 -13.096748) (xy 65.029053 -13.069533) (xy 65.036799 -13.015658)
			(xy 65.052128 -12.963432) (xy 65.074726 -12.913915) (xy 65.089024 -12.890754) (xy 65.093915 -12.882253)
			(xy 65.09763 -12.863022) (xy 65.093857 -12.843802) (xy 65.083146 -12.827403) (xy 65.067064 -12.816222)
			(xy 65.047962 -12.811894) (xy 65.038224 -12.81303) (xy 65.023339 -12.815273) (xy 64.993332 -12.81769)
			(xy 64.97828 -12.817856) (xy 64.972184 -12.817856) (xy 64.957898 -12.81817) (xy 64.930324 -12.825596)
			(xy 64.905885 -12.840367) (xy 64.886493 -12.86133) (xy 64.873665 -12.886842) (xy 64.868405 -12.91491)
			(xy 64.871123 -12.943337) (xy 64.875918 -12.956794) (xy 64.884337 -12.979158) (xy 64.896198 -13.025448)
			(xy 64.902197 -13.072855) (xy 64.902588 -13.096748) (xy 64.902102 -13.123999) (xy 64.894346 -13.177947)
			(xy 64.878991 -13.230242) (xy 64.856349 -13.279819) (xy 64.826883 -13.325669) (xy 64.791192 -13.36686)
			(xy 64.750001 -13.402551) (xy 64.704151 -13.432017) (xy 64.654574 -13.454659) (xy 64.602279 -13.470014)
			(xy 64.548331 -13.47777) (xy 64.493829 -13.47777) (xy 64.439881 -13.470014) (xy 64.387586 -13.454659)
			(xy 64.338009 -13.432017) (xy 64.292159 -13.402551) (xy 64.250968 -13.36686) (xy 64.215277 -13.325669)
			(xy 64.185811 -13.279819) (xy 64.163169 -13.230242) (xy 64.147814 -13.177947) (xy 64.140058 -13.123999)
			(xy 64.139572 -13.096748) (xy 64.140053 -13.069533) (xy 64.147799 -13.015658) (xy 64.163128 -12.963432)
			(xy 64.185726 -12.913915) (xy 64.200024 -12.890754) (xy 64.204915 -12.882253) (xy 64.20863 -12.863022)
			(xy 64.204857 -12.843802) (xy 64.194146 -12.827403) (xy 64.178064 -12.816222) (xy 64.158962 -12.811894)
			(xy 64.149224 -12.81303) (xy 64.134339 -12.815273) (xy 64.104332 -12.81769) (xy 64.08928 -12.817856)
			(xy 64.083184 -12.817856) (xy 64.068898 -12.81817) (xy 64.041324 -12.825596) (xy 64.016885 -12.840367)
			(xy 63.997493 -12.86133) (xy 63.984665 -12.886842) (xy 63.979405 -12.91491) (xy 63.982123 -12.943337)
			(xy 63.986918 -12.956794) (xy 63.995337 -12.979158) (xy 64.007198 -13.025448) (xy 64.013197 -13.072855)
			(xy 64.013588 -13.096748) (xy 64.013102 -13.123999) (xy 64.005346 -13.177947) (xy 63.989991 -13.230242)
			(xy 63.967349 -13.279819) (xy 63.937883 -13.325669) (xy 63.902192 -13.36686) (xy 63.861001 -13.402551)
			(xy 63.815151 -13.432017) (xy 63.765574 -13.454659) (xy 63.713279 -13.470014) (xy 63.659331 -13.47777)
			(xy 63.604829 -13.47777) (xy 63.550881 -13.470014) (xy 63.498586 -13.454659) (xy 63.449009 -13.432017)
			(xy 63.403159 -13.402551) (xy 63.361968 -13.36686) (xy 63.326277 -13.325669) (xy 63.296811 -13.279819)
			(xy 63.274169 -13.230242) (xy 63.258814 -13.177947) (xy 63.251058 -13.123999) (xy 63.250572 -13.096748)
			(xy 63.250934 -13.072811) (xy 63.256904 -13.025311) (xy 63.26878 -12.978934) (xy 63.277242 -12.95654)
			(xy 63.281898 -12.943447) (xy 63.284793 -12.915824) (xy 63.280132 -12.888444) (xy 63.26826 -12.863335)
			(xy 63.250058 -12.842356) (xy 63.226874 -12.827063) (xy 63.200424 -12.818588) (xy 63.186564 -12.817602)
			(xy 63.159965 -12.816259) (xy 63.107525 -12.806957) (xy 63.056887 -12.790451) (xy 63.009038 -12.767063)
			(xy 62.964907 -12.737248) (xy 62.925351 -12.701584) (xy 62.89114 -12.660765) (xy 62.862939 -12.615585)
			(xy 62.841296 -12.566921) (xy 62.826632 -12.51572) (xy 62.819232 -12.462978) (xy 62.818772 -12.436348)
			(xy 62.41288 -12.436348) (xy 62.41288 -14.315948) (xy 66.856862 -14.315948) (xy 66.860933 -14.260326)
			(xy 66.873059 -14.205889) (xy 66.892982 -14.153798) (xy 66.920278 -14.105163) (xy 66.954364 -14.06102)
			(xy 66.994513 -14.022311) (xy 67.039871 -13.98986) (xy 67.089471 -13.964359) (xy 67.142255 -13.946352)
			(xy 67.197098 -13.936222) (xy 67.252832 -13.934185) (xy 67.308269 -13.940285) (xy 67.362226 -13.954391)
			(xy 67.413555 -13.976203) (xy 67.461161 -14.005257) (xy 67.504029 -14.040932) (xy 67.541246 -14.082469)
			(xy 67.572019 -14.128982) (xy 67.595691 -14.179479) (xy 67.611759 -14.232886) (xy 67.619879 -14.288062)
			(xy 67.620388 -14.315948) (xy 67.619879 -14.343834) (xy 67.611759 -14.39901) (xy 67.595691 -14.452417)
			(xy 67.572019 -14.502914) (xy 67.541246 -14.549427) (xy 67.504029 -14.590964) (xy 67.461161 -14.626639)
			(xy 67.413555 -14.655693) (xy 67.362226 -14.677505) (xy 67.308269 -14.691611) (xy 67.252832 -14.697711)
			(xy 67.197098 -14.695674) (xy 67.142255 -14.685544) (xy 67.089471 -14.667537) (xy 67.039871 -14.642036)
			(xy 66.994513 -14.609585) (xy 66.954364 -14.570876) (xy 66.920278 -14.526733) (xy 66.892982 -14.478098)
			(xy 66.873059 -14.426007) (xy 66.860933 -14.37157) (xy 66.856862 -14.315948) (xy 62.41288 -14.315948)
			(xy 62.41288 -15.331948) (xy 66.856862 -15.331948) (xy 66.860933 -15.276326) (xy 66.873059 -15.221889)
			(xy 66.892982 -15.169798) (xy 66.920278 -15.121163) (xy 66.954364 -15.07702) (xy 66.994513 -15.038311)
			(xy 67.039871 -15.00586) (xy 67.089471 -14.980359) (xy 67.142255 -14.962352) (xy 67.197098 -14.952222)
			(xy 67.252832 -14.950185) (xy 67.308269 -14.956285) (xy 67.362226 -14.970391) (xy 67.413555 -14.992203)
			(xy 67.461161 -15.021257) (xy 67.504029 -15.056932) (xy 67.541246 -15.098469) (xy 67.572019 -15.144982)
			(xy 67.595691 -15.195479) (xy 67.611759 -15.248886) (xy 67.619879 -15.304062) (xy 67.620388 -15.331948)
			(xy 67.619879 -15.359834) (xy 67.611759 -15.41501) (xy 67.595691 -15.468417) (xy 67.572019 -15.518914)
			(xy 67.541246 -15.565427) (xy 67.504029 -15.606964) (xy 67.461161 -15.642639) (xy 67.413555 -15.671693)
			(xy 67.362226 -15.693505) (xy 67.308269 -15.707611) (xy 67.252832 -15.713711) (xy 67.197098 -15.711674)
			(xy 67.142255 -15.701544) (xy 67.089471 -15.683537) (xy 67.039871 -15.658036) (xy 66.994513 -15.625585)
			(xy 66.954364 -15.586876) (xy 66.920278 -15.542733) (xy 66.892982 -15.494098) (xy 66.873059 -15.442007)
			(xy 66.860933 -15.38757) (xy 66.856862 -15.331948) (xy 62.41288 -15.331948) (xy 62.41288 -16.347948)
			(xy 66.856862 -16.347948) (xy 66.860933 -16.292326) (xy 66.873059 -16.237889) (xy 66.892982 -16.185798)
			(xy 66.920278 -16.137163) (xy 66.954364 -16.09302) (xy 66.994513 -16.054311) (xy 67.039871 -16.02186)
			(xy 67.089471 -15.996359) (xy 67.142255 -15.978352) (xy 67.197098 -15.968222) (xy 67.252832 -15.966185)
			(xy 67.308269 -15.972285) (xy 67.362226 -15.986391) (xy 67.413555 -16.008203) (xy 67.461161 -16.037257)
			(xy 67.504029 -16.072932) (xy 67.541246 -16.114469) (xy 67.572019 -16.160982) (xy 67.595691 -16.211479)
			(xy 67.610079 -16.259302) (xy 77.27823 -16.259302) (xy 77.278687 -16.231727) (xy 77.286639 -16.177153)
			(xy 77.302366 -16.124293) (xy 77.325537 -16.074247) (xy 77.355672 -16.028057) (xy 77.392142 -15.986687)
			(xy 77.41285 -15.968472) (xy 77.423749 -15.958574) (xy 77.439829 -15.933925) (xy 77.448218 -15.905716)
			(xy 77.448218 -15.876286) (xy 77.439831 -15.848077) (xy 77.423751 -15.823428) (xy 77.41285 -15.813532)
			(xy 77.392141 -15.795319) (xy 77.355673 -15.753949) (xy 77.325542 -15.707759) (xy 77.302376 -15.657712)
			(xy 77.286658 -15.60485) (xy 77.278717 -15.550276) (xy 77.27823 -15.522702) (xy 77.278716 -15.495451)
			(xy 77.286472 -15.441503) (xy 77.301827 -15.389208) (xy 77.324469 -15.339631) (xy 77.353935 -15.293781)
			(xy 77.389626 -15.25259) (xy 77.430817 -15.216899) (xy 77.476667 -15.187433) (xy 77.526244 -15.164791)
			(xy 77.578539 -15.149436) (xy 77.632487 -15.14168) (xy 77.686989 -15.14168) (xy 77.740937 -15.149436)
			(xy 77.793232 -15.164791) (xy 77.842809 -15.187433) (xy 77.888659 -15.216899) (xy 77.92985 -15.25259)
			(xy 77.965541 -15.293781) (xy 77.995007 -15.339631) (xy 78.017649 -15.389208) (xy 78.033004 -15.441503)
			(xy 78.04076 -15.495451) (xy 78.041246 -15.522702) (xy 78.040801 -15.550277) (xy 78.032847 -15.604852)
			(xy 78.017119 -15.657713) (xy 77.993945 -15.707759) (xy 77.963808 -15.753948) (xy 77.927336 -15.795318)
			(xy 77.906626 -15.813532) (xy 77.895725 -15.823427) (xy 77.879649 -15.848078) (xy 77.871263 -15.876287)
			(xy 77.871264 -15.905716) (xy 77.87965 -15.933925) (xy 77.895727 -15.958574) (xy 77.906626 -15.968472)
			(xy 77.927332 -15.986689) (xy 77.963802 -16.028057) (xy 77.993934 -16.074246) (xy 78.0171 -16.124293)
			(xy 78.032818 -16.177154) (xy 78.04076 -16.231728) (xy 78.041246 -16.259302) (xy 78.04076 -16.286553)
			(xy 78.033004 -16.340501) (xy 78.017649 -16.392796) (xy 77.995007 -16.442373) (xy 77.965541 -16.488223)
			(xy 77.92985 -16.529414) (xy 77.888659 -16.565105) (xy 77.842809 -16.594571) (xy 77.793232 -16.617213)
			(xy 77.740937 -16.632568) (xy 77.686989 -16.640324) (xy 77.632487 -16.640324) (xy 77.578539 -16.632568)
			(xy 77.526244 -16.617213) (xy 77.476667 -16.594571) (xy 77.430817 -16.565105) (xy 77.389626 -16.529414)
			(xy 77.353935 -16.488223) (xy 77.324469 -16.442373) (xy 77.301827 -16.392796) (xy 77.286472 -16.340501)
			(xy 77.278716 -16.286553) (xy 77.27823 -16.259302) (xy 67.610079 -16.259302) (xy 67.611759 -16.264886)
			(xy 67.619879 -16.320062) (xy 67.620388 -16.347948) (xy 67.619879 -16.375834) (xy 67.611759 -16.43101)
			(xy 67.595691 -16.484417) (xy 67.572019 -16.534914) (xy 67.541246 -16.581427) (xy 67.504029 -16.622964)
			(xy 67.461161 -16.658639) (xy 67.413555 -16.687693) (xy 67.362226 -16.709505) (xy 67.308269 -16.723611)
			(xy 67.252832 -16.729711) (xy 67.197098 -16.727674) (xy 67.142255 -16.717544) (xy 67.089471 -16.699537)
			(xy 67.039871 -16.674036) (xy 66.994513 -16.641585) (xy 66.954364 -16.602876) (xy 66.920278 -16.558733)
			(xy 66.892982 -16.510098) (xy 66.873059 -16.458007) (xy 66.860933 -16.40357) (xy 66.856862 -16.347948)
			(xy 62.41288 -16.347948) (xy 62.41288 -16.87576) (xy 62.442852 -16.889222) (xy 62.46759 -16.900906)
			(xy 62.513727 -16.930309) (xy 62.55519 -16.966001) (xy 62.591128 -17.00725) (xy 62.620805 -17.053211)
			(xy 62.643612 -17.10294) (xy 62.659081 -17.155417) (xy 62.666894 -17.209565) (xy 62.666891 -17.264274)
			(xy 62.659072 -17.318422) (xy 62.643598 -17.370897) (xy 62.620786 -17.420624) (xy 62.591105 -17.466581)
			(xy 62.555162 -17.507827) (xy 62.513695 -17.543515) (xy 62.467555 -17.572913) (xy 62.442852 -17.584674)
			(xy 62.41288 -17.598136) (xy 62.41288 -17.684242) (xy 63.088772 -17.684242) (xy 63.092843 -17.62862)
			(xy 63.104969 -17.574183) (xy 63.124892 -17.522092) (xy 63.152188 -17.473457) (xy 63.186274 -17.429314)
			(xy 63.226423 -17.390605) (xy 63.271781 -17.358154) (xy 63.321381 -17.332653) (xy 63.374165 -17.314646)
			(xy 63.429008 -17.304516) (xy 63.484742 -17.302479) (xy 63.540179 -17.308579) (xy 63.594136 -17.322685)
			(xy 63.645465 -17.344497) (xy 63.693071 -17.373551) (xy 63.735939 -17.409226) (xy 63.773156 -17.450763)
			(xy 63.803929 -17.497276) (xy 63.827601 -17.547773) (xy 63.843669 -17.60118) (xy 63.851789 -17.656356)
			(xy 63.852298 -17.684242) (xy 63.851789 -17.712128) (xy 63.843669 -17.767304) (xy 63.827601 -17.820711)
			(xy 63.803929 -17.871208) (xy 63.773156 -17.917721) (xy 63.735939 -17.959258) (xy 63.693071 -17.994933)
			(xy 63.645465 -18.023987) (xy 63.594136 -18.045799) (xy 63.540179 -18.059905) (xy 63.484742 -18.066005)
			(xy 63.429008 -18.063968) (xy 63.374165 -18.053838) (xy 63.321381 -18.035831) (xy 63.271781 -18.01033)
			(xy 63.226423 -17.977879) (xy 63.186274 -17.93917) (xy 63.152188 -17.895027) (xy 63.124892 -17.846392)
			(xy 63.104969 -17.794301) (xy 63.092843 -17.739864) (xy 63.088772 -17.684242) (xy 62.41288 -17.684242)
			(xy 62.41288 -18.297144) (xy 67.30873 -18.297144) (xy 67.309215 -18.269774) (xy 67.317027 -18.215596)
			(xy 67.332511 -18.163093) (xy 67.355349 -18.113345) (xy 67.38507 -18.067378) (xy 67.40271 -18.046446)
			(xy 67.411904 -18.035087) (xy 67.424085 -18.00854) (xy 67.428265 -17.979633) (xy 67.424104 -17.950724)
			(xy 67.41194 -17.924169) (xy 67.40271 -17.912842) (xy 67.385079 -17.891904) (xy 67.355365 -17.845933)
			(xy 67.332528 -17.796187) (xy 67.317035 -17.743687) (xy 67.309205 -17.689513) (xy 67.30873 -17.662144)
			(xy 67.309216 -17.634893) (xy 67.316972 -17.580945) (xy 67.332327 -17.52865) (xy 67.354969 -17.479073)
			(xy 67.384435 -17.433223) (xy 67.420126 -17.392032) (xy 67.461317 -17.356341) (xy 67.507167 -17.326875)
			(xy 67.556744 -17.304233) (xy 67.609039 -17.288878) (xy 67.662987 -17.281122) (xy 67.717489 -17.281122)
			(xy 67.771437 -17.288878) (xy 67.823732 -17.304233) (xy 67.873309 -17.326875) (xy 67.919159 -17.356341)
			(xy 67.96035 -17.392032) (xy 67.996041 -17.433223) (xy 68.025507 -17.479073) (xy 68.048149 -17.52865)
			(xy 68.063504 -17.580945) (xy 68.07126 -17.634893) (xy 68.071746 -17.662144) (xy 68.07126 -17.689514)
			(xy 68.063449 -17.743692) (xy 68.047965 -17.796196) (xy 68.025128 -17.845943) (xy 67.995406 -17.89191)
			(xy 67.977766 -17.912842) (xy 67.968489 -17.924139) (xy 67.956321 -17.950708) (xy 67.952159 -17.979633)
			(xy 67.95634 -18.008556) (xy 67.968526 -18.035117) (xy 67.977766 -18.046446) (xy 67.995388 -18.067392)
			(xy 68.025104 -18.11336) (xy 68.04686 -18.160746) (xy 74.02525 -18.160746) (xy 74.029321 -18.105124)
			(xy 74.041447 -18.050687) (xy 74.06137 -17.998596) (xy 74.088666 -17.949961) (xy 74.122752 -17.905818)
			(xy 74.162901 -17.867109) (xy 74.208259 -17.834658) (xy 74.257859 -17.809157) (xy 74.310643 -17.79115)
			(xy 74.365486 -17.78102) (xy 74.42122 -17.778983) (xy 74.476657 -17.785083) (xy 74.530614 -17.799189)
			(xy 74.581943 -17.821001) (xy 74.629549 -17.850055) (xy 74.672417 -17.88573) (xy 74.709634 -17.927267)
			(xy 74.740407 -17.97378) (xy 74.764079 -18.024277) (xy 74.780147 -18.077684) (xy 74.788267 -18.13286)
			(xy 74.788776 -18.160746) (xy 74.788461 -18.178018) (xy 77.15072 -18.178018) (xy 77.154791 -18.122396)
			(xy 77.166917 -18.067959) (xy 77.18684 -18.015868) (xy 77.214136 -17.967233) (xy 77.248222 -17.92309)
			(xy 77.288371 -17.884381) (xy 77.333729 -17.85193) (xy 77.383329 -17.826429) (xy 77.436113 -17.808422)
			(xy 77.490956 -17.798292) (xy 77.54669 -17.796255) (xy 77.602127 -17.802355) (xy 77.656084 -17.816461)
			(xy 77.707413 -17.838273) (xy 77.755019 -17.867327) (xy 77.797887 -17.903002) (xy 77.835104 -17.944539)
			(xy 77.865877 -17.991052) (xy 77.889549 -18.041549) (xy 77.905617 -18.094956) (xy 77.913737 -18.150132)
			(xy 77.914246 -18.178018) (xy 77.913737 -18.205904) (xy 77.909019 -18.237962) (xy 79.54137 -18.237962)
			(xy 79.541889 -18.210389) (xy 79.549832 -18.155819) (xy 79.565547 -18.102961) (xy 79.588707 -18.052915)
			(xy 79.61883 -18.006724) (xy 79.655288 -17.96535) (xy 79.67599 -17.947132) (xy 79.686926 -17.937272)
			(xy 79.702998 -17.912611) (xy 79.711378 -17.884393) (xy 79.711371 -17.854958) (xy 79.702977 -17.826744)
			(xy 79.686893 -17.802091) (xy 79.67599 -17.792192) (xy 79.65527 -17.773991) (xy 79.618801 -17.73262)
			(xy 79.58867 -17.686428) (xy 79.565506 -17.636378) (xy 79.549791 -17.583514) (xy 79.541854 -17.528937)
			(xy 79.54137 -17.501362) (xy 79.541856 -17.474111) (xy 79.549612 -17.420163) (xy 79.564967 -17.367868)
			(xy 79.587609 -17.318291) (xy 79.617075 -17.272441) (xy 79.652766 -17.23125) (xy 79.693957 -17.195559)
			(xy 79.739807 -17.166093) (xy 79.789384 -17.143451) (xy 79.841679 -17.128096) (xy 79.895627 -17.12034)
			(xy 79.950129 -17.12034) (xy 80.004077 -17.128096) (xy 80.056372 -17.143451) (xy 80.105949 -17.166093)
			(xy 80.151799 -17.195559) (xy 80.19299 -17.23125) (xy 80.228681 -17.272441) (xy 80.258147 -17.318291)
			(xy 80.280789 -17.367868) (xy 80.296144 -17.420163) (xy 80.3039 -17.474111) (xy 80.304386 -17.501362)
			(xy 80.303899 -17.528936) (xy 80.295952 -17.583508) (xy 80.280231 -17.636368) (xy 80.257065 -17.686414)
			(xy 80.226936 -17.732604) (xy 80.190472 -17.773976) (xy 80.169766 -17.792192) (xy 80.15891 -17.802131)
			(xy 80.142842 -17.826771) (xy 80.134458 -17.854967) (xy 80.13445 -17.884384) (xy 80.142822 -17.912584)
			(xy 80.158878 -17.937232) (xy 80.169766 -17.947132) (xy 80.190489 -17.96533) (xy 80.22696 -18.006701)
			(xy 80.257091 -18.052893) (xy 80.280255 -18.102944) (xy 80.295969 -18.155809) (xy 80.303904 -18.210386)
			(xy 80.304386 -18.237962) (xy 80.3039 -18.265213) (xy 80.296144 -18.319161) (xy 80.280789 -18.371456)
			(xy 80.258147 -18.421033) (xy 80.228681 -18.466883) (xy 80.19299 -18.508074) (xy 80.151799 -18.543765)
			(xy 80.106327 -18.572988) (xy 81.670142 -18.572988) (xy 81.674213 -18.517366) (xy 81.686339 -18.462929)
			(xy 81.706262 -18.410838) (xy 81.733558 -18.362203) (xy 81.767644 -18.31806) (xy 81.807793 -18.279351)
			(xy 81.853151 -18.2469) (xy 81.902751 -18.221399) (xy 81.955535 -18.203392) (xy 82.010378 -18.193262)
			(xy 82.066112 -18.191225) (xy 82.121549 -18.197325) (xy 82.175506 -18.211431) (xy 82.226835 -18.233243)
			(xy 82.274441 -18.262297) (xy 82.317309 -18.297972) (xy 82.354526 -18.339509) (xy 82.385299 -18.386022)
			(xy 82.408971 -18.436519) (xy 82.425039 -18.489926) (xy 82.433159 -18.545102) (xy 82.433668 -18.572988)
			(xy 82.433159 -18.600874) (xy 82.425039 -18.65605) (xy 82.408971 -18.709457) (xy 82.385299 -18.759954)
			(xy 82.354526 -18.806467) (xy 82.317309 -18.848004) (xy 82.274441 -18.883679) (xy 82.226835 -18.912733)
			(xy 82.175506 -18.934545) (xy 82.121549 -18.948651) (xy 82.066112 -18.954751) (xy 82.010378 -18.952714)
			(xy 81.955535 -18.942584) (xy 81.902751 -18.924577) (xy 81.853151 -18.899076) (xy 81.807793 -18.866625)
			(xy 81.767644 -18.827916) (xy 81.733558 -18.783773) (xy 81.706262 -18.735138) (xy 81.686339 -18.683047)
			(xy 81.674213 -18.62861) (xy 81.670142 -18.572988) (xy 80.106327 -18.572988) (xy 80.105949 -18.573231)
			(xy 80.056372 -18.595873) (xy 80.004077 -18.611228) (xy 79.950129 -18.618984) (xy 79.895627 -18.618984)
			(xy 79.841679 -18.611228) (xy 79.789384 -18.595873) (xy 79.739807 -18.573231) (xy 79.693957 -18.543765)
			(xy 79.652766 -18.508074) (xy 79.617075 -18.466883) (xy 79.587609 -18.421033) (xy 79.564967 -18.371456)
			(xy 79.549612 -18.319161) (xy 79.541856 -18.265213) (xy 79.54137 -18.237962) (xy 77.909019 -18.237962)
			(xy 77.905617 -18.26108) (xy 77.889549 -18.314487) (xy 77.865877 -18.364984) (xy 77.835104 -18.411497)
			(xy 77.797887 -18.453034) (xy 77.755019 -18.488709) (xy 77.707413 -18.517763) (xy 77.656084 -18.539575)
			(xy 77.602127 -18.553681) (xy 77.54669 -18.559781) (xy 77.490956 -18.557744) (xy 77.436113 -18.547614)
			(xy 77.383329 -18.529607) (xy 77.333729 -18.504106) (xy 77.288371 -18.471655) (xy 77.248222 -18.432946)
			(xy 77.214136 -18.388803) (xy 77.18684 -18.340168) (xy 77.166917 -18.288077) (xy 77.154791 -18.23364)
			(xy 77.15072 -18.178018) (xy 74.788461 -18.178018) (xy 74.788267 -18.188632) (xy 74.780147 -18.243808)
			(xy 74.764079 -18.297215) (xy 74.740407 -18.347712) (xy 74.709634 -18.394225) (xy 74.672417 -18.435762)
			(xy 74.629549 -18.471437) (xy 74.581943 -18.500491) (xy 74.530614 -18.522303) (xy 74.476657 -18.536409)
			(xy 74.42122 -18.542509) (xy 74.365486 -18.540472) (xy 74.310643 -18.530342) (xy 74.257859 -18.512335)
			(xy 74.208259 -18.486834) (xy 74.162901 -18.454383) (xy 74.122752 -18.415674) (xy 74.088666 -18.371531)
			(xy 74.06137 -18.322896) (xy 74.041447 -18.270805) (xy 74.029321 -18.216368) (xy 74.02525 -18.160746)
			(xy 68.04686 -18.160746) (xy 68.047943 -18.163104) (xy 68.063438 -18.215602) (xy 68.07127 -18.269776)
			(xy 68.071746 -18.297144) (xy 68.07126 -18.324395) (xy 68.063504 -18.378343) (xy 68.048149 -18.430638)
			(xy 68.025507 -18.480215) (xy 67.996041 -18.526065) (xy 67.96035 -18.567256) (xy 67.919159 -18.602947)
			(xy 67.873309 -18.632413) (xy 67.823732 -18.655055) (xy 67.771437 -18.67041) (xy 67.717489 -18.678166)
			(xy 67.662987 -18.678166) (xy 67.609039 -18.67041) (xy 67.556744 -18.655055) (xy 67.507167 -18.632413)
			(xy 67.461317 -18.602947) (xy 67.420126 -18.567256) (xy 67.384435 -18.526065) (xy 67.354969 -18.480215)
			(xy 67.332327 -18.430638) (xy 67.316972 -18.378343) (xy 67.309216 -18.324395) (xy 67.30873 -18.297144)
			(xy 62.41288 -18.297144) (xy 62.41288 -19.220942) (xy 76.404722 -19.220942) (xy 76.408793 -19.16532)
			(xy 76.420919 -19.110883) (xy 76.440842 -19.058792) (xy 76.468138 -19.010157) (xy 76.502224 -18.966014)
			(xy 76.542373 -18.927305) (xy 76.587731 -18.894854) (xy 76.637331 -18.869353) (xy 76.690115 -18.851346)
			(xy 76.744958 -18.841216) (xy 76.800692 -18.839179) (xy 76.856129 -18.845279) (xy 76.910086 -18.859385)
			(xy 76.961415 -18.881197) (xy 77.009021 -18.910251) (xy 77.051889 -18.945926) (xy 77.089106 -18.987463)
			(xy 77.119879 -19.033976) (xy 77.143551 -19.084473) (xy 77.159619 -19.13788) (xy 77.167739 -19.193056)
			(xy 77.168248 -19.220942) (xy 77.167739 -19.248828) (xy 77.163657 -19.276568) (xy 78.474568 -19.276568)
			(xy 78.478639 -19.220946) (xy 78.490765 -19.166509) (xy 78.510688 -19.114418) (xy 78.537984 -19.065783)
			(xy 78.57207 -19.02164) (xy 78.612219 -18.982931) (xy 78.657577 -18.95048) (xy 78.707177 -18.924979)
			(xy 78.759961 -18.906972) (xy 78.814804 -18.896842) (xy 78.870538 -18.894805) (xy 78.925975 -18.900905)
			(xy 78.979932 -18.915011) (xy 79.031261 -18.936823) (xy 79.078867 -18.965877) (xy 79.121735 -19.001552)
			(xy 79.158952 -19.043089) (xy 79.189725 -19.089602) (xy 79.213397 -19.140099) (xy 79.229465 -19.193506)
			(xy 79.237585 -19.248682) (xy 79.238094 -19.276568) (xy 79.237585 -19.304454) (xy 79.229465 -19.35963)
			(xy 79.213397 -19.413037) (xy 79.189725 -19.463534) (xy 79.158952 -19.510047) (xy 79.121735 -19.551584)
			(xy 79.078867 -19.587259) (xy 79.031261 -19.616313) (xy 78.979932 -19.638125) (xy 78.925975 -19.652231)
			(xy 78.870538 -19.658331) (xy 78.814804 -19.656294) (xy 78.759961 -19.646164) (xy 78.707177 -19.628157)
			(xy 78.657577 -19.602656) (xy 78.612219 -19.570205) (xy 78.57207 -19.531496) (xy 78.537984 -19.487353)
			(xy 78.510688 -19.438718) (xy 78.490765 -19.386627) (xy 78.478639 -19.33219) (xy 78.474568 -19.276568)
			(xy 77.163657 -19.276568) (xy 77.159619 -19.304004) (xy 77.143551 -19.357411) (xy 77.119879 -19.407908)
			(xy 77.089106 -19.454421) (xy 77.051889 -19.495958) (xy 77.009021 -19.531633) (xy 76.961415 -19.560687)
			(xy 76.910086 -19.582499) (xy 76.856129 -19.596605) (xy 76.800692 -19.602705) (xy 76.744958 -19.600668)
			(xy 76.690115 -19.590538) (xy 76.637331 -19.572531) (xy 76.587731 -19.54703) (xy 76.542373 -19.514579)
			(xy 76.502224 -19.47587) (xy 76.468138 -19.431727) (xy 76.440842 -19.383092) (xy 76.420919 -19.331001)
			(xy 76.408793 -19.276564) (xy 76.404722 -19.220942) (xy 62.41288 -19.220942) (xy 62.41288 -20.326604)
			(xy 67.33413 -20.326604) (xy 67.334591 -20.299234) (xy 67.342409 -20.245054) (xy 67.357899 -20.19255)
			(xy 67.380742 -20.142804) (xy 67.410468 -20.096837) (xy 67.42811 -20.075906) (xy 67.437342 -20.064576)
			(xy 67.449519 -20.038019) (xy 67.453692 -20.009103) (xy 67.449521 -19.980187) (xy 67.437345 -19.95363)
			(xy 67.42811 -19.942302) (xy 67.41046 -19.921379) (xy 67.380749 -19.875404) (xy 67.357915 -19.825654)
			(xy 67.342427 -19.773151) (xy 67.334602 -19.718974) (xy 67.33413 -19.691604) (xy 67.334616 -19.664353)
			(xy 67.342372 -19.610405) (xy 67.357727 -19.55811) (xy 67.380369 -19.508533) (xy 67.409835 -19.462683)
			(xy 67.445526 -19.421492) (xy 67.486717 -19.385801) (xy 67.532567 -19.356335) (xy 67.582144 -19.333693)
			(xy 67.634439 -19.318338) (xy 67.688387 -19.310582) (xy 67.742889 -19.310582) (xy 67.796837 -19.318338)
			(xy 67.849132 -19.333693) (xy 67.898709 -19.356335) (xy 67.944559 -19.385801) (xy 67.98575 -19.421492)
			(xy 68.021441 -19.462683) (xy 68.050907 -19.508533) (xy 68.073549 -19.55811) (xy 68.088904 -19.610405)
			(xy 68.09666 -19.664353) (xy 68.097146 -19.691604) (xy 68.096695 -19.718975) (xy 68.088876 -19.773155)
			(xy 68.073384 -19.825659) (xy 68.066911 -19.839753) (xy 81.008163 -19.839753) (xy 81.008163 -19.785247)
			(xy 81.015921 -19.731295) (xy 81.031277 -19.678997) (xy 81.053921 -19.629417) (xy 81.08339 -19.583563)
			(xy 81.119085 -19.542371) (xy 81.160279 -19.506678) (xy 81.206134 -19.477211) (xy 81.255716 -19.45457)
			(xy 81.308015 -19.439216) (xy 81.361967 -19.431462) (xy 81.38922 -19.431) (xy 81.420118 -19.431619)
			(xy 81.481103 -19.441596) (xy 81.539679 -19.461284) (xy 81.567274 -19.475196) (xy 81.58046 -19.481564)
			(xy 81.609164 -19.487283) (xy 81.638314 -19.484641) (xy 81.665523 -19.473856) (xy 81.688566 -19.45581)
			(xy 81.705558 -19.431978) (xy 81.710784 -19.4183) (xy 81.71975 -19.393576) (xy 81.743518 -19.346661)
			(xy 81.773502 -19.303454) (xy 81.809135 -19.264773) (xy 81.849741 -19.231351) (xy 81.894552 -19.203821)
			(xy 81.942718 -19.182704) (xy 81.993328 -19.168401) (xy 82.045422 -19.161183) (xy 82.071718 -19.160744)
			(xy 82.098965 -19.161327) (xy 82.152904 -19.169085) (xy 82.20519 -19.18444) (xy 82.254758 -19.207079)
			(xy 82.300601 -19.236542) (xy 82.341784 -19.272229) (xy 82.377469 -19.313414) (xy 82.40693 -19.359257)
			(xy 82.429567 -19.408827) (xy 82.444919 -19.461114) (xy 82.452674 -19.515053) (xy 82.452674 -19.569547)
			(xy 82.444919 -19.623486) (xy 82.429567 -19.675773) (xy 82.40693 -19.725343) (xy 82.377469 -19.771186)
			(xy 82.341784 -19.812371) (xy 82.300601 -19.848058) (xy 82.254758 -19.877521) (xy 82.20519 -19.90016)
			(xy 82.152904 -19.915515) (xy 82.098965 -19.923273) (xy 82.071718 -19.92376) (xy 82.040819 -19.923169)
			(xy 81.979833 -19.913181) (xy 81.921258 -19.893482) (xy 81.893664 -19.879564) (xy 81.88045 -19.873264)
			(xy 81.851758 -19.867541) (xy 81.82262 -19.870174) (xy 81.795419 -19.880946) (xy 81.772379 -19.898976)
			(xy 81.755384 -19.92279) (xy 81.750154 -19.93646) (xy 81.741218 -19.961196) (xy 81.71745 -20.008115)
			(xy 81.687464 -20.051325) (xy 81.651828 -20.090007) (xy 81.611218 -20.123429) (xy 81.566402 -20.150958)
			(xy 81.518231 -20.172071) (xy 81.467616 -20.18637) (xy 81.415518 -20.193581) (xy 81.38922 -20.194016)
			(xy 81.361967 -20.193538) (xy 81.308015 -20.185784) (xy 81.255716 -20.17043) (xy 81.206134 -20.147789)
			(xy 81.160279 -20.118322) (xy 81.119085 -20.082629) (xy 81.08339 -20.041437) (xy 81.053921 -19.995583)
			(xy 81.031277 -19.946003) (xy 81.015921 -19.893705) (xy 81.008163 -19.839753) (xy 68.066911 -19.839753)
			(xy 68.050538 -19.875406) (xy 68.02081 -19.921371) (xy 68.003166 -19.942302) (xy 67.993928 -19.953628)
			(xy 67.981755 -19.980187) (xy 67.977585 -20.009103) (xy 67.981757 -20.038019) (xy 67.993931 -20.064578)
			(xy 68.003166 -20.075906) (xy 68.020816 -20.096829) (xy 68.050527 -20.142804) (xy 68.073362 -20.192554)
			(xy 68.08885 -20.245056) (xy 68.096674 -20.299234) (xy 68.097146 -20.326604) (xy 68.09666 -20.353855)
			(xy 68.088904 -20.407803) (xy 68.073549 -20.460098) (xy 68.050907 -20.509675) (xy 68.021441 -20.555525)
			(xy 67.98575 -20.596716) (xy 67.944559 -20.632407) (xy 67.898709 -20.661873) (xy 67.849132 -20.684515)
			(xy 67.796837 -20.69987) (xy 67.742889 -20.707626) (xy 67.688387 -20.707626) (xy 67.634439 -20.69987)
			(xy 67.582144 -20.684515) (xy 67.532567 -20.661873) (xy 67.486717 -20.632407) (xy 67.445526 -20.596716)
			(xy 67.409835 -20.555525) (xy 67.380369 -20.509675) (xy 67.357727 -20.460098) (xy 67.342372 -20.407803)
			(xy 67.334616 -20.353855) (xy 67.33413 -20.326604) (xy 62.41288 -20.326604) (xy 62.41288 -20.944078)
			(xy 76.224382 -20.944078) (xy 76.228453 -20.888456) (xy 76.240579 -20.834019) (xy 76.260502 -20.781928)
			(xy 76.287798 -20.733293) (xy 76.321884 -20.68915) (xy 76.362033 -20.650441) (xy 76.407391 -20.61799)
			(xy 76.456991 -20.592489) (xy 76.509775 -20.574482) (xy 76.564618 -20.564352) (xy 76.620352 -20.562315)
			(xy 76.675789 -20.568415) (xy 76.729746 -20.582521) (xy 76.781075 -20.604333) (xy 76.828681 -20.633387)
			(xy 76.871549 -20.669062) (xy 76.908766 -20.710599) (xy 76.939539 -20.757112) (xy 76.963211 -20.807609)
			(xy 76.979279 -20.861016) (xy 76.987399 -20.916192) (xy 76.987908 -20.944078) (xy 76.987399 -20.971964)
			(xy 76.979279 -21.02714) (xy 76.963211 -21.080547) (xy 76.939539 -21.131044) (xy 76.908766 -21.177557)
			(xy 76.871549 -21.219094) (xy 76.828681 -21.254769) (xy 76.781075 -21.283823) (xy 76.729746 -21.305635)
			(xy 76.675789 -21.319741) (xy 76.620352 -21.325841) (xy 76.564618 -21.323804) (xy 76.509775 -21.313674)
			(xy 76.456991 -21.295667) (xy 76.407391 -21.270166) (xy 76.362033 -21.237715) (xy 76.321884 -21.199006)
			(xy 76.287798 -21.154863) (xy 76.260502 -21.106228) (xy 76.240579 -21.054137) (xy 76.228453 -20.9997)
			(xy 76.224382 -20.944078) (xy 62.41288 -20.944078) (xy 62.41288 -21.416772) (xy 81.628742 -21.416772)
			(xy 81.62926 -21.387965) (xy 81.637934 -21.331007) (xy 81.655066 -21.275999) (xy 81.680266 -21.224189)
			(xy 81.712965 -21.176752) (xy 81.752418 -21.134766) (xy 81.79773 -21.099183) (xy 81.822544 -21.08454)
			(xy 81.834696 -21.07709) (xy 81.854691 -21.056799) (xy 81.86829 -21.031767) (xy 81.874431 -21.003949)
			(xy 81.872634 -20.975518) (xy 81.86304 -20.948695) (xy 81.846397 -20.925574) (xy 81.835498 -20.916392)
			(xy 81.813248 -20.898197) (xy 81.773976 -20.856231) (xy 81.741439 -20.808852) (xy 81.716371 -20.757131)
			(xy 81.699339 -20.702237) (xy 81.690727 -20.64541) (xy 81.69021 -20.616672) (xy 81.690696 -20.589421)
			(xy 81.698452 -20.535473) (xy 81.713807 -20.483178) (xy 81.736449 -20.433601) (xy 81.765915 -20.387751)
			(xy 81.801606 -20.34656) (xy 81.842797 -20.310869) (xy 81.888647 -20.281403) (xy 81.938224 -20.258761)
			(xy 81.990519 -20.243406) (xy 82.044467 -20.23565) (xy 82.098969 -20.23565) (xy 82.152917 -20.243406)
			(xy 82.205212 -20.258761) (xy 82.254789 -20.281403) (xy 82.300639 -20.310869) (xy 82.34183 -20.34656)
			(xy 82.377521 -20.387751) (xy 82.406987 -20.433601) (xy 82.429629 -20.483178) (xy 82.444984 -20.535473)
			(xy 82.45274 -20.589421) (xy 82.453226 -20.616672) (xy 82.452709 -20.645478) (xy 82.44403 -20.702435)
			(xy 82.426896 -20.757441) (xy 82.401694 -20.80925) (xy 82.368997 -20.856686) (xy 82.329546 -20.898674)
			(xy 82.284236 -20.934259) (xy 82.259424 -20.948904) (xy 82.247234 -20.956295) (xy 82.227242 -20.976601)
			(xy 82.213648 -21.001645) (xy 82.207513 -21.029473) (xy 82.209317 -21.057911) (xy 82.218918 -21.084741)
			(xy 82.235567 -21.107867) (xy 82.24647 -21.117052) (xy 82.268707 -21.135261) (xy 82.307977 -21.177227)
			(xy 82.340514 -21.224603) (xy 82.365583 -21.276321) (xy 82.382619 -21.331212) (xy 82.391237 -21.388035)
			(xy 82.391758 -21.416772) (xy 82.391272 -21.444023) (xy 82.383516 -21.497971) (xy 82.368161 -21.550266)
			(xy 82.345519 -21.599843) (xy 82.316053 -21.645693) (xy 82.280362 -21.686884) (xy 82.239171 -21.722575)
			(xy 82.193321 -21.752041) (xy 82.143744 -21.774683) (xy 82.091449 -21.790038) (xy 82.037501 -21.797794)
			(xy 81.982999 -21.797794) (xy 81.929051 -21.790038) (xy 81.876756 -21.774683) (xy 81.827179 -21.752041)
			(xy 81.781329 -21.722575) (xy 81.740138 -21.686884) (xy 81.704447 -21.645693) (xy 81.674981 -21.599843)
			(xy 81.652339 -21.550266) (xy 81.636984 -21.497971) (xy 81.629228 -21.444023) (xy 81.628742 -21.416772)
			(xy 62.41288 -21.416772) (xy 62.41288 -22.266148) (xy 66.501262 -22.266148) (xy 66.505333 -22.210526)
			(xy 66.517459 -22.156089) (xy 66.537382 -22.103998) (xy 66.564678 -22.055363) (xy 66.598764 -22.01122)
			(xy 66.638913 -21.972511) (xy 66.684271 -21.94006) (xy 66.733871 -21.914559) (xy 66.786655 -21.896552)
			(xy 66.841498 -21.886422) (xy 66.897232 -21.884385) (xy 66.952669 -21.890485) (xy 67.006626 -21.904591)
			(xy 67.057955 -21.926403) (xy 67.105561 -21.955457) (xy 67.148429 -21.991132) (xy 67.185646 -22.032669)
			(xy 67.216419 -22.079182) (xy 67.240091 -22.129679) (xy 67.256159 -22.183086) (xy 67.264279 -22.238262)
			(xy 67.264788 -22.266148) (xy 67.264279 -22.294034) (xy 67.256159 -22.34921) (xy 67.240091 -22.402617)
			(xy 67.216419 -22.453114) (xy 67.185646 -22.499627) (xy 67.148429 -22.541164) (xy 67.105561 -22.576839)
			(xy 67.09815 -22.581362) (xy 74.63866 -22.581362) (xy 74.642731 -22.52574) (xy 74.654857 -22.471303)
			(xy 74.67478 -22.419212) (xy 74.702076 -22.370577) (xy 74.736162 -22.326434) (xy 74.776311 -22.287725)
			(xy 74.821669 -22.255274) (xy 74.871269 -22.229773) (xy 74.924053 -22.211766) (xy 74.978896 -22.201636)
			(xy 75.03463 -22.199599) (xy 75.090067 -22.205699) (xy 75.144024 -22.219805) (xy 75.195353 -22.241617)
			(xy 75.242959 -22.270671) (xy 75.285827 -22.306346) (xy 75.323044 -22.347883) (xy 75.353817 -22.394396)
			(xy 75.377489 -22.444893) (xy 75.393557 -22.4983) (xy 75.401677 -22.553476) (xy 75.402186 -22.581362)
			(xy 75.401677 -22.609248) (xy 75.393557 -22.664424) (xy 75.377489 -22.717831) (xy 75.357227 -22.761053)
			(xy 79.21164 -22.761053) (xy 79.21164 -22.706547) (xy 79.219397 -22.652596) (xy 79.234752 -22.600298)
			(xy 79.257394 -22.550717) (xy 79.286861 -22.504863) (xy 79.322554 -22.463669) (xy 79.363745 -22.427974)
			(xy 79.409598 -22.398504) (xy 79.459177 -22.37586) (xy 79.511474 -22.360501) (xy 79.565425 -22.352741)
			(xy 79.592678 -22.352254) (xy 79.618793 -22.352689) (xy 79.670533 -22.35983) (xy 79.720814 -22.373967)
			(xy 79.768694 -22.394835) (xy 79.813277 -22.422045) (xy 79.853729 -22.455085) (xy 79.871824 -22.47392)
			(xy 79.881243 -22.483397) (xy 79.903906 -22.497534) (xy 79.929458 -22.505316) (xy 79.956154 -22.506211)
			(xy 79.98217 -22.500157) (xy 80.005729 -22.487569) (xy 80.025221 -22.469307) (xy 80.032606 -22.458172)
			(xy 80.047649 -22.43498) (xy 80.083338 -22.392766) (xy 80.124745 -22.356144) (xy 80.171003 -22.325881)
			(xy 80.221144 -22.302609) (xy 80.274118 -22.286817) (xy 80.328817 -22.278834) (xy 80.356456 -22.27834)
			(xy 80.383714 -22.278704) (xy 80.437677 -22.286457) (xy 80.489987 -22.301811) (xy 80.539579 -22.324454)
			(xy 80.585443 -22.353924) (xy 80.626646 -22.389623) (xy 80.662349 -22.430822) (xy 80.691825 -22.476683)
			(xy 80.714474 -22.526272) (xy 80.729834 -22.57858) (xy 80.737593 -22.632542) (xy 80.737593 -22.687058)
			(xy 80.729834 -22.74102) (xy 80.714474 -22.793328) (xy 80.691825 -22.842917) (xy 80.662349 -22.888778)
			(xy 80.626646 -22.929977) (xy 80.585443 -22.965676) (xy 80.539579 -22.995146) (xy 80.489987 -23.017789)
			(xy 80.437677 -23.033143) (xy 80.383714 -23.040896) (xy 80.356456 -23.041356) (xy 80.33034 -23.040961)
			(xy 80.278598 -23.033812) (xy 80.228317 -23.019667) (xy 80.180437 -22.998791) (xy 80.135854 -22.971575)
			(xy 80.095404 -22.938528) (xy 80.07731 -22.91969) (xy 80.067857 -22.910248) (xy 80.045203 -22.896108)
			(xy 80.019659 -22.888321) (xy 79.992969 -22.887421) (xy 79.966958 -22.893469) (xy 79.943403 -22.90605)
			(xy 79.923913 -22.924307) (xy 79.916528 -22.935438) (xy 79.901532 -22.958663) (xy 79.865835 -23.000875)
			(xy 79.82442 -23.037495) (xy 79.778154 -23.067754) (xy 79.728005 -23.091021) (xy 79.675024 -23.106806)
			(xy 79.620319 -23.114781) (xy 79.592678 -23.11527) (xy 79.565425 -23.114859) (xy 79.511474 -23.107099)
			(xy 79.459177 -23.09174) (xy 79.409598 -23.069096) (xy 79.363745 -23.039626) (xy 79.322554 -23.003931)
			(xy 79.286861 -22.962737) (xy 79.257394 -22.916883) (xy 79.234752 -22.867302) (xy 79.219397 -22.815004)
			(xy 79.21164 -22.761053) (xy 75.357227 -22.761053) (xy 75.353817 -22.768328) (xy 75.323044 -22.814841)
			(xy 75.285827 -22.856378) (xy 75.242959 -22.892053) (xy 75.195353 -22.921107) (xy 75.144024 -22.942919)
			(xy 75.090067 -22.957025) (xy 75.03463 -22.963125) (xy 74.978896 -22.961088) (xy 74.924053 -22.950958)
			(xy 74.871269 -22.932951) (xy 74.821669 -22.90745) (xy 74.776311 -22.874999) (xy 74.736162 -22.83629)
			(xy 74.702076 -22.792147) (xy 74.67478 -22.743512) (xy 74.654857 -22.691421) (xy 74.642731 -22.636984)
			(xy 74.63866 -22.581362) (xy 67.09815 -22.581362) (xy 67.057955 -22.605893) (xy 67.006626 -22.627705)
			(xy 66.952669 -22.641811) (xy 66.897232 -22.647911) (xy 66.841498 -22.645874) (xy 66.786655 -22.635744)
			(xy 66.733871 -22.617737) (xy 66.684271 -22.592236) (xy 66.638913 -22.559785) (xy 66.598764 -22.521076)
			(xy 66.564678 -22.476933) (xy 66.537382 -22.428298) (xy 66.517459 -22.376207) (xy 66.505333 -22.32177)
			(xy 66.501262 -22.266148) (xy 62.41288 -22.266148) (xy 62.41288 -23.404322) (xy 62.63462 -23.404322)
			(xy 62.638691 -23.3487) (xy 62.650817 -23.294263) (xy 62.67074 -23.242172) (xy 62.698036 -23.193537)
			(xy 62.732122 -23.149394) (xy 62.772271 -23.110685) (xy 62.817629 -23.078234) (xy 62.867229 -23.052733)
			(xy 62.920013 -23.034726) (xy 62.974856 -23.024596) (xy 63.03059 -23.022559) (xy 63.086027 -23.028659)
			(xy 63.139984 -23.042765) (xy 63.191313 -23.064577) (xy 63.238919 -23.093631) (xy 63.281787 -23.129306)
			(xy 63.319004 -23.170843) (xy 63.349777 -23.217356) (xy 63.373449 -23.267853) (xy 63.389517 -23.32126)
			(xy 63.397637 -23.376436) (xy 63.398146 -23.404322) (xy 63.397637 -23.432208) (xy 63.389517 -23.487384)
			(xy 63.373449 -23.540791) (xy 63.349777 -23.591288) (xy 63.319004 -23.637801) (xy 63.281787 -23.679338)
			(xy 63.238919 -23.715013) (xy 63.191313 -23.744067) (xy 63.139984 -23.765879) (xy 63.086027 -23.779985)
			(xy 63.03059 -23.786085) (xy 62.974856 -23.784048) (xy 62.920013 -23.773918) (xy 62.867229 -23.755911)
			(xy 62.817629 -23.73041) (xy 62.772271 -23.697959) (xy 62.732122 -23.65925) (xy 62.698036 -23.615107)
			(xy 62.67074 -23.566472) (xy 62.650817 -23.514381) (xy 62.638691 -23.459944) (xy 62.63462 -23.404322)
			(xy 62.41288 -23.404322) (xy 62.41288 -23.688548) (xy 60.563506 -25.537922) (xy 62.58382 -25.537922)
			(xy 62.587891 -25.4823) (xy 62.600017 -25.427863) (xy 62.61994 -25.375772) (xy 62.647236 -25.327137)
			(xy 62.681322 -25.282994) (xy 62.721471 -25.244285) (xy 62.766829 -25.211834) (xy 62.816429 -25.186333)
			(xy 62.869213 -25.168326) (xy 62.924056 -25.158196) (xy 62.97979 -25.156159) (xy 63.035227 -25.162259)
			(xy 63.089184 -25.176365) (xy 63.140513 -25.198177) (xy 63.188119 -25.227231) (xy 63.230987 -25.262906)
			(xy 63.268204 -25.304443) (xy 63.298977 -25.350956) (xy 63.322649 -25.401453) (xy 63.338717 -25.45486)
			(xy 63.346837 -25.510036) (xy 63.347346 -25.537922) (xy 63.346837 -25.565808) (xy 63.346493 -25.568148)
			(xy 66.019172 -25.568148) (xy 66.019706 -25.540386) (xy 66.027747 -25.485449) (xy 66.043668 -25.432258)
			(xy 66.067132 -25.381936) (xy 66.097642 -25.335547) (xy 66.134555 -25.294072) (xy 66.17709 -25.258385)
			(xy 66.224349 -25.229241) (xy 66.275334 -25.207256) (xy 66.328968 -25.192894) (xy 66.356484 -25.18918)
			(xy 66.370108 -25.187096) (xy 66.395616 -25.176695) (xy 66.417412 -25.159849) (xy 66.433905 -25.137784)
			(xy 66.443893 -25.112112) (xy 66.446647 -25.084702) (xy 66.441968 -25.057556) (xy 66.436494 -25.044908)
			(xy 66.425012 -25.019366) (xy 66.408841 -24.96575) (xy 66.400665 -24.910349) (xy 66.400172 -24.882348)
			(xy 66.400658 -24.855097) (xy 66.408414 -24.801149) (xy 66.423769 -24.748854) (xy 66.446411 -24.699277)
			(xy 66.475877 -24.653427) (xy 66.511568 -24.612236) (xy 66.552759 -24.576545) (xy 66.598609 -24.547079)
			(xy 66.648186 -24.524437) (xy 66.700481 -24.509082) (xy 66.754429 -24.501326) (xy 66.808931 -24.501326)
			(xy 66.862879 -24.509082) (xy 66.915174 -24.524437) (xy 66.964751 -24.547079) (xy 67.010601 -24.576545)
			(xy 67.051792 -24.612236) (xy 67.087483 -24.653427) (xy 67.116949 -24.699277) (xy 67.139591 -24.748854)
			(xy 67.154946 -24.801149) (xy 67.162702 -24.855097) (xy 67.163188 -24.882348) (xy 67.162706 -24.910674)
			(xy 67.154363 -24.966709) (xy 67.137823 -25.020893) (xy 67.126104 -25.046686) (xy 67.120615 -25.059312)
			(xy 67.115846 -25.086415) (xy 67.118487 -25.113808) (xy 67.128346 -25.139501) (xy 67.144706 -25.161629)
			(xy 67.166381 -25.178585) (xy 67.191796 -25.189139) (xy 67.219106 -25.192524) (xy 67.232784 -25.190958)
			(xy 67.245484 -25.18918) (xy 67.259108 -25.187096) (xy 67.284616 -25.176695) (xy 67.306412 -25.159849)
			(xy 67.322905 -25.137784) (xy 67.332893 -25.112112) (xy 67.335647 -25.084702) (xy 67.330968 -25.057556)
			(xy 67.325494 -25.044908) (xy 67.314012 -25.019366) (xy 67.297841 -24.96575) (xy 67.289665 -24.910349)
			(xy 67.289172 -24.882348) (xy 67.289658 -24.855097) (xy 67.297414 -24.801149) (xy 67.312769 -24.748854)
			(xy 67.335411 -24.699277) (xy 67.364877 -24.653427) (xy 67.400568 -24.612236) (xy 67.441759 -24.576545)
			(xy 67.487609 -24.547079) (xy 67.537186 -24.524437) (xy 67.589481 -24.509082) (xy 67.643429 -24.501326)
			(xy 67.697931 -24.501326) (xy 67.751879 -24.509082) (xy 67.804174 -24.524437) (xy 67.853751 -24.547079)
			(xy 67.899601 -24.576545) (xy 67.940792 -24.612236) (xy 67.976483 -24.653427) (xy 68.005949 -24.699277)
			(xy 68.028591 -24.748854) (xy 68.043946 -24.801149) (xy 68.051702 -24.855097) (xy 68.052188 -24.882348)
			(xy 68.051706 -24.910674) (xy 68.043363 -24.966709) (xy 68.026823 -25.020893) (xy 68.015104 -25.046686)
			(xy 68.009615 -25.059312) (xy 68.004846 -25.086415) (xy 68.007487 -25.113808) (xy 68.017346 -25.139501)
			(xy 68.033706 -25.161629) (xy 68.055381 -25.178585) (xy 68.080796 -25.189139) (xy 68.108106 -25.192524)
			(xy 68.121784 -25.190958) (xy 68.134484 -25.18918) (xy 68.148108 -25.187096) (xy 68.173616 -25.176695)
			(xy 68.195412 -25.159849) (xy 68.211905 -25.137784) (xy 68.221893 -25.112112) (xy 68.224647 -25.084702)
			(xy 68.219968 -25.057556) (xy 68.214494 -25.044908) (xy 68.203012 -25.019366) (xy 68.186841 -24.96575)
			(xy 68.178665 -24.910349) (xy 68.178172 -24.882348) (xy 68.178658 -24.855097) (xy 68.186414 -24.801149)
			(xy 68.201769 -24.748854) (xy 68.224411 -24.699277) (xy 68.253877 -24.653427) (xy 68.289568 -24.612236)
			(xy 68.330759 -24.576545) (xy 68.376609 -24.547079) (xy 68.426186 -24.524437) (xy 68.478481 -24.509082)
			(xy 68.532429 -24.501326) (xy 68.586931 -24.501326) (xy 68.640879 -24.509082) (xy 68.693174 -24.524437)
			(xy 68.742751 -24.547079) (xy 68.750639 -24.552148) (xy 69.117462 -24.552148) (xy 69.121533 -24.496526)
			(xy 69.133659 -24.442089) (xy 69.153582 -24.389998) (xy 69.180878 -24.341363) (xy 69.214964 -24.29722)
			(xy 69.255113 -24.258511) (xy 69.300471 -24.22606) (xy 69.350071 -24.200559) (xy 69.402855 -24.182552)
			(xy 69.457698 -24.172422) (xy 69.513432 -24.170385) (xy 69.568869 -24.176485) (xy 69.622826 -24.190591)
			(xy 69.674155 -24.212403) (xy 69.721761 -24.241457) (xy 69.764629 -24.277132) (xy 69.797569 -24.313896)
			(xy 77.804262 -24.313896) (xy 77.808333 -24.258274) (xy 77.820459 -24.203837) (xy 77.840382 -24.151746)
			(xy 77.867678 -24.103111) (xy 77.901764 -24.058968) (xy 77.941913 -24.020259) (xy 77.987271 -23.987808)
			(xy 78.036871 -23.962307) (xy 78.089655 -23.9443) (xy 78.144498 -23.93417) (xy 78.200232 -23.932133)
			(xy 78.255669 -23.938233) (xy 78.309626 -23.952339) (xy 78.360955 -23.974151) (xy 78.408561 -24.003205)
			(xy 78.451429 -24.03888) (xy 78.488646 -24.080417) (xy 78.519419 -24.12693) (xy 78.543091 -24.177427)
			(xy 78.559159 -24.230834) (xy 78.567279 -24.28601) (xy 78.567788 -24.313896) (xy 78.567279 -24.341782)
			(xy 78.559159 -24.396958) (xy 78.543091 -24.450365) (xy 78.519419 -24.500862) (xy 78.488646 -24.547375)
			(xy 78.45228 -24.587962) (xy 79.23606 -24.587962) (xy 79.240131 -24.53234) (xy 79.252257 -24.477903)
			(xy 79.27218 -24.425812) (xy 79.299476 -24.377177) (xy 79.333562 -24.333034) (xy 79.373711 -24.294325)
			(xy 79.419069 -24.261874) (xy 79.468669 -24.236373) (xy 79.521453 -24.218366) (xy 79.576296 -24.208236)
			(xy 79.63203 -24.206199) (xy 79.687467 -24.212299) (xy 79.741424 -24.226405) (xy 79.792753 -24.248217)
			(xy 79.840359 -24.277271) (xy 79.883227 -24.312946) (xy 79.920444 -24.354483) (xy 79.951217 -24.400996)
			(xy 79.974889 -24.451493) (xy 79.990957 -24.5049) (xy 79.999077 -24.560076) (xy 79.999586 -24.587962)
			(xy 79.999077 -24.615848) (xy 79.990957 -24.671024) (xy 79.974889 -24.724431) (xy 79.951217 -24.774928)
			(xy 79.920444 -24.821441) (xy 79.883227 -24.862978) (xy 79.840359 -24.898653) (xy 79.792753 -24.927707)
			(xy 79.741424 -24.949519) (xy 79.687467 -24.963625) (xy 79.63203 -24.969725) (xy 79.576296 -24.967688)
			(xy 79.521453 -24.957558) (xy 79.468669 -24.939551) (xy 79.419069 -24.91405) (xy 79.373711 -24.881599)
			(xy 79.333562 -24.84289) (xy 79.299476 -24.798747) (xy 79.27218 -24.750112) (xy 79.252257 -24.698021)
			(xy 79.240131 -24.643584) (xy 79.23606 -24.587962) (xy 78.45228 -24.587962) (xy 78.451429 -24.588912)
			(xy 78.408561 -24.624587) (xy 78.360955 -24.653641) (xy 78.309626 -24.675453) (xy 78.255669 -24.689559)
			(xy 78.200232 -24.695659) (xy 78.144498 -24.693622) (xy 78.089655 -24.683492) (xy 78.036871 -24.665485)
			(xy 77.987271 -24.639984) (xy 77.941913 -24.607533) (xy 77.901764 -24.568824) (xy 77.867678 -24.524681)
			(xy 77.840382 -24.476046) (xy 77.820459 -24.423955) (xy 77.808333 -24.369518) (xy 77.804262 -24.313896)
			(xy 69.797569 -24.313896) (xy 69.801846 -24.318669) (xy 69.832619 -24.365182) (xy 69.856291 -24.415679)
			(xy 69.872359 -24.469086) (xy 69.880479 -24.524262) (xy 69.880988 -24.552148) (xy 69.880479 -24.580034)
			(xy 69.872359 -24.63521) (xy 69.856291 -24.688617) (xy 69.832619 -24.739114) (xy 69.801846 -24.785627)
			(xy 69.764629 -24.827164) (xy 69.721761 -24.862839) (xy 69.674155 -24.891893) (xy 69.622826 -24.913705)
			(xy 69.568869 -24.927811) (xy 69.513432 -24.933911) (xy 69.457698 -24.931874) (xy 69.402855 -24.921744)
			(xy 69.350071 -24.903737) (xy 69.300471 -24.878236) (xy 69.255113 -24.845785) (xy 69.214964 -24.807076)
			(xy 69.180878 -24.762933) (xy 69.153582 -24.714298) (xy 69.133659 -24.662207) (xy 69.121533 -24.60777)
			(xy 69.117462 -24.552148) (xy 68.750639 -24.552148) (xy 68.788601 -24.576545) (xy 68.829792 -24.612236)
			(xy 68.865483 -24.653427) (xy 68.894949 -24.699277) (xy 68.917591 -24.748854) (xy 68.932946 -24.801149)
			(xy 68.940702 -24.855097) (xy 68.941188 -24.882348) (xy 68.940686 -24.910111) (xy 68.932644 -24.965052)
			(xy 68.916721 -25.018246) (xy 68.893255 -25.068569) (xy 68.862742 -25.11496) (xy 68.825825 -25.156436)
			(xy 68.783285 -25.192122) (xy 68.736021 -25.221264) (xy 68.685032 -25.243246) (xy 68.631394 -25.257604)
			(xy 68.603876 -25.261316) (xy 68.590232 -25.263308) (xy 68.564703 -25.273709) (xy 68.542892 -25.290567)
			(xy 68.526392 -25.31265) (xy 68.516408 -25.338345) (xy 68.513669 -25.365775) (xy 68.518376 -25.392937)
			(xy 68.523866 -25.405588) (xy 68.535351 -25.431129) (xy 68.551519 -25.484746) (xy 68.559695 -25.540147)
			(xy 68.560188 -25.568148) (xy 68.559702 -25.595399) (xy 68.551946 -25.649347) (xy 68.536591 -25.701642)
			(xy 68.513949 -25.751219) (xy 68.484483 -25.797069) (xy 68.448792 -25.83826) (xy 68.407601 -25.873951)
			(xy 68.361751 -25.903417) (xy 68.312174 -25.926059) (xy 68.259879 -25.941414) (xy 68.205931 -25.94917)
			(xy 68.151429 -25.94917) (xy 68.097481 -25.941414) (xy 68.045186 -25.926059) (xy 67.995609 -25.903417)
			(xy 67.949759 -25.873951) (xy 67.908568 -25.83826) (xy 67.872877 -25.797069) (xy 67.843411 -25.751219)
			(xy 67.820769 -25.701642) (xy 67.805414 -25.649347) (xy 67.797658 -25.595399) (xy 67.797172 -25.568148)
			(xy 67.797656 -25.539822) (xy 67.805999 -25.483787) (xy 67.822537 -25.429603) (xy 67.834256 -25.40381)
			(xy 67.839791 -25.391201) (xy 67.844563 -25.364089) (xy 67.841922 -25.336687) (xy 67.832058 -25.310986)
			(xy 67.81569 -25.288853) (xy 67.794005 -25.271895) (xy 67.768578 -25.261344) (xy 67.741258 -25.257966)
			(xy 67.727576 -25.259538) (xy 67.714876 -25.261316) (xy 67.701232 -25.263308) (xy 67.675703 -25.273709)
			(xy 67.653892 -25.290567) (xy 67.637392 -25.31265) (xy 67.627408 -25.338345) (xy 67.624669 -25.365775)
			(xy 67.629376 -25.392937) (xy 67.634866 -25.405588) (xy 67.646351 -25.431129) (xy 67.662519 -25.484746)
			(xy 67.670695 -25.540147) (xy 67.671188 -25.568148) (xy 67.670702 -25.595399) (xy 67.662946 -25.649347)
			(xy 67.647591 -25.701642) (xy 67.624949 -25.751219) (xy 67.595483 -25.797069) (xy 67.559792 -25.83826)
			(xy 67.518601 -25.873951) (xy 67.472751 -25.903417) (xy 67.423174 -25.926059) (xy 67.370879 -25.941414)
			(xy 67.316931 -25.94917) (xy 67.262429 -25.94917) (xy 67.208481 -25.941414) (xy 67.156186 -25.926059)
			(xy 67.106609 -25.903417) (xy 67.060759 -25.873951) (xy 67.019568 -25.83826) (xy 66.983877 -25.797069)
			(xy 66.954411 -25.751219) (xy 66.931769 -25.701642) (xy 66.916414 -25.649347) (xy 66.908658 -25.595399)
			(xy 66.908172 -25.568148) (xy 66.908656 -25.539822) (xy 66.916999 -25.483787) (xy 66.933537 -25.429603)
			(xy 66.945256 -25.40381) (xy 66.950791 -25.391201) (xy 66.955563 -25.364089) (xy 66.952922 -25.336687)
			(xy 66.943058 -25.310986) (xy 66.92669 -25.288853) (xy 66.905005 -25.271895) (xy 66.879578 -25.261344)
			(xy 66.852258 -25.257966) (xy 66.838576 -25.259538) (xy 66.825876 -25.261316) (xy 66.812232 -25.263308)
			(xy 66.786703 -25.273709) (xy 66.764892 -25.290567) (xy 66.748392 -25.31265) (xy 66.738408 -25.338345)
			(xy 66.735669 -25.365775) (xy 66.740376 -25.392937) (xy 66.745866 -25.405588) (xy 66.757351 -25.431129)
			(xy 66.773519 -25.484746) (xy 66.781695 -25.540147) (xy 66.782188 -25.568148) (xy 66.781702 -25.595399)
			(xy 66.773946 -25.649347) (xy 66.758591 -25.701642) (xy 66.735949 -25.751219) (xy 66.706483 -25.797069)
			(xy 66.670792 -25.83826) (xy 66.629601 -25.873951) (xy 66.583751 -25.903417) (xy 66.534174 -25.926059)
			(xy 66.481879 -25.941414) (xy 66.427931 -25.94917) (xy 66.373429 -25.94917) (xy 66.319481 -25.941414)
			(xy 66.267186 -25.926059) (xy 66.217609 -25.903417) (xy 66.171759 -25.873951) (xy 66.130568 -25.83826)
			(xy 66.094877 -25.797069) (xy 66.065411 -25.751219) (xy 66.042769 -25.701642) (xy 66.027414 -25.649347)
			(xy 66.019658 -25.595399) (xy 66.019172 -25.568148) (xy 63.346493 -25.568148) (xy 63.338717 -25.620984)
			(xy 63.322649 -25.674391) (xy 63.298977 -25.724888) (xy 63.268204 -25.771401) (xy 63.230987 -25.812938)
			(xy 63.188119 -25.848613) (xy 63.140513 -25.877667) (xy 63.089184 -25.899479) (xy 63.035227 -25.913585)
			(xy 62.97979 -25.919685) (xy 62.924056 -25.917648) (xy 62.869213 -25.907518) (xy 62.816429 -25.889511)
			(xy 62.766829 -25.86401) (xy 62.721471 -25.831559) (xy 62.681322 -25.79285) (xy 62.647236 -25.748707)
			(xy 62.61994 -25.700072) (xy 62.600017 -25.647981) (xy 62.587891 -25.593544) (xy 62.58382 -25.537922)
			(xy 60.563506 -25.537922) (xy 59.403375 -26.698053) (xy 72.09964 -26.698053) (xy 72.09964 -26.643547)
			(xy 72.107397 -26.589596) (xy 72.122752 -26.537298) (xy 72.145394 -26.487717) (xy 72.174861 -26.441863)
			(xy 72.210554 -26.400669) (xy 72.251745 -26.364974) (xy 72.297598 -26.335504) (xy 72.347177 -26.31286)
			(xy 72.399474 -26.297501) (xy 72.453425 -26.289741) (xy 72.480678 -26.289254) (xy 72.507935 -26.289747)
			(xy 72.561894 -26.297511) (xy 72.6142 -26.312871) (xy 72.66379 -26.335513) (xy 72.709656 -26.364978)
			(xy 72.750865 -26.400666) (xy 72.786579 -26.441853) (xy 72.801734 -26.464514) (xy 72.810015 -26.476441)
			(xy 72.831951 -26.495445) (xy 72.858351 -26.5075) (xy 72.887078 -26.51163) (xy 72.915805 -26.5075)
			(xy 72.942205 -26.495445) (xy 72.964141 -26.476441) (xy 72.972422 -26.464514) (xy 72.987539 -26.441825)
			(xy 73.023252 -26.400629) (xy 73.064464 -26.364935) (xy 73.110336 -26.335469) (xy 73.159935 -26.312831)
			(xy 73.21225 -26.297482) (xy 73.266218 -26.289735) (xy 73.293478 -26.289254) (xy 73.320729 -26.289792)
			(xy 73.374677 -26.297545) (xy 73.426972 -26.312898) (xy 73.47655 -26.335537) (xy 73.522402 -26.365001)
			(xy 73.563593 -26.400692) (xy 73.599285 -26.441881) (xy 73.628752 -26.48773) (xy 73.651394 -26.537307)
			(xy 73.66675 -26.589601) (xy 73.674507 -26.643549) (xy 73.674507 -26.698051) (xy 73.66675 -26.751999)
			(xy 73.651394 -26.804293) (xy 73.628752 -26.85387) (xy 73.599285 -26.899719) (xy 73.563593 -26.940908)
			(xy 73.522402 -26.976599) (xy 73.47655 -27.006063) (xy 73.426972 -27.028702) (xy 73.374677 -27.044055)
			(xy 73.320729 -27.051808) (xy 73.293478 -27.05227) (xy 73.26622 -27.0518) (xy 73.212261 -27.044031)
			(xy 73.159954 -27.028666) (xy 73.110365 -27.00602) (xy 73.064499 -26.976552) (xy 73.023291 -26.940861)
			(xy 72.987577 -26.899672) (xy 72.972422 -26.87701) (xy 72.964141 -26.865083) (xy 72.942205 -26.846079)
			(xy 72.915805 -26.834024) (xy 72.887078 -26.829894) (xy 72.858351 -26.834024) (xy 72.831951 -26.846079)
			(xy 72.810015 -26.865083) (xy 72.801734 -26.87701) (xy 72.786588 -26.899679) (xy 72.750879 -26.940873)
			(xy 72.709671 -26.976568) (xy 72.663804 -27.006036) (xy 72.614211 -27.028677) (xy 72.5619 -27.044031)
			(xy 72.507937 -27.051786) (xy 72.480678 -27.05227) (xy 72.453425 -27.051859) (xy 72.399474 -27.044099)
			(xy 72.347177 -27.02874) (xy 72.297598 -27.006096) (xy 72.251745 -26.976626) (xy 72.210554 -26.940931)
			(xy 72.174861 -26.899737) (xy 72.145394 -26.853883) (xy 72.122752 -26.804302) (xy 72.107397 -26.752004)
			(xy 72.09964 -26.698053) (xy 59.403375 -26.698053) (xy 58.88228 -27.219148) (xy 58.88228 -28.331922)
			(xy 61.80277 -28.331922) (xy 61.806841 -28.2763) (xy 61.818967 -28.221863) (xy 61.83889 -28.169772)
			(xy 61.866186 -28.121137) (xy 61.900272 -28.076994) (xy 61.940421 -28.038285) (xy 61.985779 -28.005834)
			(xy 62.035379 -27.980333) (xy 62.088163 -27.962326) (xy 62.143006 -27.952196) (xy 62.19874 -27.950159)
			(xy 62.254177 -27.956259) (xy 62.308134 -27.970365) (xy 62.359463 -27.992177) (xy 62.407069 -28.021231)
			(xy 62.449937 -28.056906) (xy 62.487154 -28.098443) (xy 62.517927 -28.144956) (xy 62.541599 -28.195453)
			(xy 62.557667 -28.24886) (xy 62.565787 -28.304036) (xy 62.566296 -28.331922) (xy 62.565787 -28.359808)
			(xy 62.561368 -28.389834) (xy 64.102994 -28.389834) (xy 64.107065 -28.334212) (xy 64.119191 -28.279775)
			(xy 64.139114 -28.227684) (xy 64.16641 -28.179049) (xy 64.200496 -28.134906) (xy 64.240645 -28.096197)
			(xy 64.286003 -28.063746) (xy 64.335603 -28.038245) (xy 64.388387 -28.020238) (xy 64.44323 -28.010108)
			(xy 64.498964 -28.008071) (xy 64.554401 -28.014171) (xy 64.608358 -28.028277) (xy 64.659687 -28.050089)
			(xy 64.707293 -28.079143) (xy 64.750161 -28.114818) (xy 64.787378 -28.156355) (xy 64.818151 -28.202868)
			(xy 64.820305 -28.207462) (xy 66.166238 -28.207462) (xy 66.166725 -28.18014) (xy 66.17507 -28.126136)
			(xy 66.191558 -28.074039) (xy 66.215804 -28.025068) (xy 66.247239 -27.980371) (xy 66.265806 -27.96032)
			(xy 66.276244 -27.94873) (xy 66.290071 -27.920786) (xy 66.294822 -27.889972) (xy 66.290054 -27.859161)
			(xy 66.276212 -27.831225) (xy 66.265806 -27.819604) (xy 66.247204 -27.799581) (xy 66.215746 -27.754891)
			(xy 66.191495 -27.705914) (xy 66.175021 -27.653805) (xy 66.166712 -27.599788) (xy 66.166238 -27.572462)
			(xy 66.166736 -27.545813) (xy 66.174679 -27.493109) (xy 66.190389 -27.442179) (xy 66.213515 -27.394158)
			(xy 66.243539 -27.350121) (xy 66.279791 -27.31105) (xy 66.321462 -27.277819) (xy 66.36762 -27.25117)
			(xy 66.417234 -27.231698) (xy 66.469196 -27.219838) (xy 66.522346 -27.215855) (xy 66.575496 -27.219838)
			(xy 66.627458 -27.231698) (xy 66.677072 -27.25117) (xy 66.72323 -27.277819) (xy 66.764901 -27.31105)
			(xy 66.801153 -27.350121) (xy 66.831177 -27.394158) (xy 66.854303 -27.442179) (xy 66.870013 -27.493109)
			(xy 66.877956 -27.545813) (xy 66.878454 -27.572462) (xy 66.877922 -27.599782) (xy 66.869589 -27.653784)
			(xy 66.853111 -27.705881) (xy 66.828875 -27.754853) (xy 66.797449 -27.799552) (xy 66.778886 -27.819604)
			(xy 66.768524 -27.831256) (xy 66.75469 -27.859178) (xy 66.749926 -27.889972) (xy 66.754674 -27.92077)
			(xy 66.768492 -27.948699) (xy 66.778886 -27.96032) (xy 66.797498 -27.980334) (xy 66.828955 -28.025027)
			(xy 66.853205 -28.074005) (xy 66.869676 -28.126117) (xy 66.877982 -28.180135) (xy 66.878454 -28.207462)
			(xy 67.06616 -28.207462) (xy 67.066669 -28.180141) (xy 67.075011 -28.126139) (xy 67.091496 -28.074043)
			(xy 67.115736 -28.025072) (xy 67.147164 -27.980372) (xy 67.165728 -27.96032) (xy 67.176164 -27.948729)
			(xy 67.189988 -27.920785) (xy 67.194738 -27.889972) (xy 67.189971 -27.859162) (xy 67.176132 -27.831226)
			(xy 67.165728 -27.819604) (xy 67.14713 -27.799577) (xy 67.115671 -27.754889) (xy 67.091418 -27.705913)
			(xy 67.074943 -27.653804) (xy 67.066634 -27.599788) (xy 67.06616 -27.572462) (xy 67.066658 -27.545813)
			(xy 67.074601 -27.493109) (xy 67.090311 -27.442179) (xy 67.113437 -27.394158) (xy 67.143461 -27.350121)
			(xy 67.179713 -27.31105) (xy 67.221384 -27.277819) (xy 67.267542 -27.25117) (xy 67.317156 -27.231698)
			(xy 67.369118 -27.219838) (xy 67.422268 -27.215855) (xy 67.475418 -27.219838) (xy 67.52738 -27.231698)
			(xy 67.576994 -27.25117) (xy 67.623152 -27.277819) (xy 67.664823 -27.31105) (xy 67.701075 -27.350121)
			(xy 67.731099 -27.394158) (xy 67.754225 -27.442179) (xy 67.769935 -27.493109) (xy 67.777878 -27.545813)
			(xy 67.778376 -27.572462) (xy 67.777838 -27.599782) (xy 67.769505 -27.653783) (xy 67.753029 -27.70588)
			(xy 67.728794 -27.754852) (xy 67.69737 -27.799552) (xy 67.678808 -27.819604) (xy 67.668452 -27.831259)
			(xy 67.65463 -27.859181) (xy 67.649869 -27.889972) (xy 67.654613 -27.920766) (xy 67.668421 -27.948696)
			(xy 67.678808 -27.96032) (xy 67.697423 -27.980331) (xy 67.728879 -28.025025) (xy 67.753128 -28.074004)
			(xy 67.769599 -28.126116) (xy 67.777904 -28.180135) (xy 67.778376 -28.207462) (xy 67.966082 -28.207462)
			(xy 67.966585 -28.180141) (xy 67.974928 -28.126139) (xy 67.991414 -28.074042) (xy 68.015655 -28.025071)
			(xy 68.047085 -27.980372) (xy 68.06565 -27.96032) (xy 68.076084 -27.948728) (xy 68.089905 -27.920784)
			(xy 68.094654 -27.889972) (xy 68.089888 -27.859163) (xy 68.076052 -27.831226) (xy 68.06565 -27.819604)
			(xy 68.047056 -27.799574) (xy 68.015595 -27.754887) (xy 67.991341 -27.705912) (xy 67.974866 -27.653804)
			(xy 67.966556 -27.599788) (xy 67.966082 -27.572462) (xy 67.96658 -27.545813) (xy 67.974523 -27.493109)
			(xy 67.990233 -27.442179) (xy 68.013359 -27.394158) (xy 68.043383 -27.350121) (xy 68.079635 -27.31105)
			(xy 68.121306 -27.277819) (xy 68.167464 -27.25117) (xy 68.217078 -27.231698) (xy 68.26904 -27.219838)
			(xy 68.32219 -27.215855) (xy 68.37534 -27.219838) (xy 68.427302 -27.231698) (xy 68.476916 -27.25117)
			(xy 68.523074 -27.277819) (xy 68.564745 -27.31105) (xy 68.600997 -27.350121) (xy 68.631021 -27.394158)
			(xy 68.654147 -27.442179) (xy 68.669857 -27.493109) (xy 68.6778 -27.545813) (xy 68.678298 -27.572462)
			(xy 68.677754 -27.599782) (xy 68.669422 -27.653782) (xy 68.652946 -27.705879) (xy 68.628713 -27.754851)
			(xy 68.597291 -27.799551) (xy 68.57873 -27.819604) (xy 68.568372 -27.831258) (xy 68.554547 -27.85918)
			(xy 68.549785 -27.889972) (xy 68.55453 -27.920767) (xy 68.568341 -27.948697) (xy 68.57873 -27.96032)
			(xy 68.597349 -27.980328) (xy 68.628804 -28.025023) (xy 68.653051 -28.074003) (xy 68.669521 -28.126116)
			(xy 68.677826 -28.180135) (xy 68.678298 -28.207462) (xy 68.866258 -28.207462) (xy 68.86674 -28.18014)
			(xy 68.875085 -28.126136) (xy 68.891574 -28.074038) (xy 68.915821 -28.025067) (xy 68.947258 -27.98037)
			(xy 68.965826 -27.96032) (xy 68.976262 -27.948729) (xy 68.990086 -27.920785) (xy 68.994836 -27.889972)
			(xy 68.99007 -27.859162) (xy 68.976231 -27.831225) (xy 68.965826 -27.819604) (xy 68.947228 -27.799578)
			(xy 68.915768 -27.754889) (xy 68.891516 -27.705913) (xy 68.875041 -27.653804) (xy 68.866732 -27.599788)
			(xy 68.866258 -27.572462) (xy 68.866756 -27.545813) (xy 68.874699 -27.493109) (xy 68.890409 -27.442179)
			(xy 68.913535 -27.394158) (xy 68.943559 -27.350121) (xy 68.979811 -27.31105) (xy 69.021482 -27.277819)
			(xy 69.06764 -27.25117) (xy 69.117254 -27.231698) (xy 69.169216 -27.219838) (xy 69.222366 -27.215855)
			(xy 69.275516 -27.219838) (xy 69.327478 -27.231698) (xy 69.377092 -27.25117) (xy 69.42325 -27.277819)
			(xy 69.464921 -27.31105) (xy 69.501173 -27.350121) (xy 69.531197 -27.394158) (xy 69.554323 -27.442179)
			(xy 69.570033 -27.493109) (xy 69.577976 -27.545813) (xy 69.578474 -27.572462) (xy 69.577937 -27.599782)
			(xy 69.569604 -27.653783) (xy 69.553127 -27.70588) (xy 69.528893 -27.754852) (xy 69.497468 -27.799552)
			(xy 69.478906 -27.819604) (xy 69.468551 -27.831259) (xy 69.454728 -27.859181) (xy 69.449967 -27.889972)
			(xy 69.453879 -27.915362) (xy 70.95617 -27.915362) (xy 70.956679 -27.886623) (xy 70.965306 -27.829795)
			(xy 70.98236 -27.774904) (xy 71.007455 -27.723193) (xy 71.040022 -27.675831) (xy 71.059294 -27.654504)
			(xy 71.069401 -27.642999) (xy 71.082736 -27.615442) (xy 71.087312 -27.585172) (xy 71.082719 -27.554905)
			(xy 71.069369 -27.527355) (xy 71.059294 -27.51582) (xy 71.040015 -27.4945) (xy 71.007448 -27.447137)
			(xy 70.982356 -27.395424) (xy 70.965308 -27.340531) (xy 70.956689 -27.283702) (xy 70.95617 -27.254962)
			(xy 70.956656 -27.227711) (xy 70.964412 -27.173763) (xy 70.979767 -27.121468) (xy 71.002409 -27.071891)
			(xy 71.031875 -27.026041) (xy 71.067566 -26.98485) (xy 71.108757 -26.949159) (xy 71.154607 -26.919693)
			(xy 71.204184 -26.897051) (xy 71.256479 -26.881696) (xy 71.310427 -26.87394) (xy 71.364929 -26.87394)
			(xy 71.418877 -26.881696) (xy 71.471172 -26.897051) (xy 71.520749 -26.919693) (xy 71.566599 -26.949159)
			(xy 71.60779 -26.98485) (xy 71.643481 -27.026041) (xy 71.672947 -27.071891) (xy 71.695589 -27.121468)
			(xy 71.710944 -27.173763) (xy 71.7187 -27.227711) (xy 71.719186 -27.254962) (xy 71.718677 -27.283701)
			(xy 71.710047 -27.340528) (xy 71.692992 -27.395418) (xy 71.667898 -27.44713) (xy 71.635332 -27.494492)
			(xy 71.616062 -27.51582) (xy 71.606025 -27.527383) (xy 71.592674 -27.554918) (xy 71.588081 -27.585172)
			(xy 71.592658 -27.615429) (xy 71.605993 -27.642971) (xy 71.616062 -27.654504) (xy 71.635315 -27.675847)
			(xy 71.667883 -27.723204) (xy 71.692979 -27.774912) (xy 71.710034 -27.829799) (xy 71.718662 -27.886624)
			(xy 71.719186 -27.915362) (xy 71.7187 -27.942613) (xy 71.710944 -27.996561) (xy 71.695589 -28.048856)
			(xy 71.672947 -28.098433) (xy 71.643481 -28.144283) (xy 71.60779 -28.185474) (xy 71.566599 -28.221165)
			(xy 71.520749 -28.250631) (xy 71.471172 -28.273273) (xy 71.418877 -28.288628) (xy 71.364929 -28.296384)
			(xy 71.310427 -28.296384) (xy 71.256479 -28.288628) (xy 71.204184 -28.273273) (xy 71.154607 -28.250631)
			(xy 71.108757 -28.221165) (xy 71.067566 -28.185474) (xy 71.031875 -28.144283) (xy 71.002409 -28.098433)
			(xy 70.979767 -28.048856) (xy 70.964412 -27.996561) (xy 70.956656 -27.942613) (xy 70.95617 -27.915362)
			(xy 69.453879 -27.915362) (xy 69.454712 -27.920766) (xy 69.468519 -27.948696) (xy 69.478906 -27.96032)
			(xy 69.497521 -27.980331) (xy 69.528977 -28.025025) (xy 69.553226 -28.074004) (xy 69.569697 -28.126116)
			(xy 69.578002 -28.180135) (xy 69.578474 -28.207462) (xy 69.577976 -28.234111) (xy 69.570033 -28.286815)
			(xy 69.554323 -28.337745) (xy 69.531197 -28.385766) (xy 69.501173 -28.429803) (xy 69.464921 -28.468874)
			(xy 69.42325 -28.502105) (xy 69.377092 -28.528754) (xy 69.327478 -28.548226) (xy 69.275516 -28.560086)
			(xy 69.222366 -28.56407) (xy 69.169216 -28.560086) (xy 69.117254 -28.548226) (xy 69.06764 -28.528754)
			(xy 69.021482 -28.502105) (xy 68.979811 -28.468874) (xy 68.943559 -28.429803) (xy 68.913535 -28.385766)
			(xy 68.890409 -28.337745) (xy 68.874699 -28.286815) (xy 68.866756 -28.234111) (xy 68.866258 -28.207462)
			(xy 68.678298 -28.207462) (xy 68.6778 -28.234111) (xy 68.669857 -28.286815) (xy 68.654147 -28.337745)
			(xy 68.631021 -28.385766) (xy 68.600997 -28.429803) (xy 68.564745 -28.468874) (xy 68.523074 -28.502105)
			(xy 68.476916 -28.528754) (xy 68.427302 -28.548226) (xy 68.37534 -28.560086) (xy 68.32219 -28.56407)
			(xy 68.26904 -28.560086) (xy 68.217078 -28.548226) (xy 68.167464 -28.528754) (xy 68.121306 -28.502105)
			(xy 68.079635 -28.468874) (xy 68.043383 -28.429803) (xy 68.013359 -28.385766) (xy 67.990233 -28.337745)
			(xy 67.974523 -28.286815) (xy 67.96658 -28.234111) (xy 67.966082 -28.207462) (xy 67.778376 -28.207462)
			(xy 67.777878 -28.234111) (xy 67.769935 -28.286815) (xy 67.754225 -28.337745) (xy 67.731099 -28.385766)
			(xy 67.701075 -28.429803) (xy 67.664823 -28.468874) (xy 67.623152 -28.502105) (xy 67.576994 -28.528754)
			(xy 67.52738 -28.548226) (xy 67.475418 -28.560086) (xy 67.422268 -28.56407) (xy 67.369118 -28.560086)
			(xy 67.317156 -28.548226) (xy 67.267542 -28.528754) (xy 67.221384 -28.502105) (xy 67.179713 -28.468874)
			(xy 67.143461 -28.429803) (xy 67.113437 -28.385766) (xy 67.090311 -28.337745) (xy 67.074601 -28.286815)
			(xy 67.066658 -28.234111) (xy 67.06616 -28.207462) (xy 66.878454 -28.207462) (xy 66.877956 -28.234111)
			(xy 66.870013 -28.286815) (xy 66.854303 -28.337745) (xy 66.831177 -28.385766) (xy 66.801153 -28.429803)
			(xy 66.764901 -28.468874) (xy 66.72323 -28.502105) (xy 66.677072 -28.528754) (xy 66.627458 -28.548226)
			(xy 66.575496 -28.560086) (xy 66.522346 -28.56407) (xy 66.469196 -28.560086) (xy 66.417234 -28.548226)
			(xy 66.36762 -28.528754) (xy 66.321462 -28.502105) (xy 66.279791 -28.468874) (xy 66.243539 -28.429803)
			(xy 66.213515 -28.385766) (xy 66.190389 -28.337745) (xy 66.174679 -28.286815) (xy 66.166736 -28.234111)
			(xy 66.166238 -28.207462) (xy 64.820305 -28.207462) (xy 64.841823 -28.253365) (xy 64.857891 -28.306772)
			(xy 64.866011 -28.361948) (xy 64.86652 -28.389834) (xy 64.866011 -28.41772) (xy 64.857891 -28.472896)
			(xy 64.841823 -28.526303) (xy 64.818151 -28.5768) (xy 64.787378 -28.623313) (xy 64.761709 -28.651962)
			(xy 76.118974 -28.651962) (xy 76.11943 -28.625646) (xy 76.126651 -28.573513) (xy 76.140964 -28.522865)
			(xy 76.162098 -28.474663) (xy 76.189652 -28.429821) (xy 76.223104 -28.389189) (xy 76.242164 -28.371038)
			(xy 76.252225 -28.361264) (xy 76.266926 -28.337381) (xy 76.274562 -28.310397) (xy 76.274555 -28.282352)
			(xy 76.266905 -28.255371) (xy 76.252193 -28.231497) (xy 76.242164 -28.221686) (xy 76.22309 -28.203546)
			(xy 76.189609 -28.162928) (xy 76.162036 -28.118089) (xy 76.140896 -28.069882) (xy 76.126591 -28.019225)
			(xy 76.119394 -27.967081) (xy 76.118974 -27.940762) (xy 76.119492 -27.913189) (xy 76.127435 -27.858619)
			(xy 76.14315 -27.805761) (xy 76.16631 -27.755715) (xy 76.196433 -27.709524) (xy 76.232891 -27.66815)
			(xy 76.253594 -27.649932) (xy 76.264529 -27.640072) (xy 76.280601 -27.615411) (xy 76.28898 -27.587193)
			(xy 76.288973 -27.557758) (xy 76.28058 -27.529544) (xy 76.264497 -27.504891) (xy 76.253594 -27.494992)
			(xy 76.232875 -27.47679) (xy 76.196405 -27.435419) (xy 76.166274 -27.389227) (xy 76.14311 -27.339177)
			(xy 76.127395 -27.286313) (xy 76.119458 -27.231737) (xy 76.118974 -27.204162) (xy 76.11946 -27.176911)
			(xy 76.127216 -27.122963) (xy 76.142571 -27.070668) (xy 76.165213 -27.021091) (xy 76.194679 -26.975241)
			(xy 76.23037 -26.93405) (xy 76.271561 -26.898359) (xy 76.317411 -26.868893) (xy 76.366988 -26.846251)
			(xy 76.419283 -26.830896) (xy 76.473231 -26.82314) (xy 76.527733 -26.82314) (xy 76.581681 -26.830896)
			(xy 76.633976 -26.846251) (xy 76.683553 -26.868893) (xy 76.729403 -26.898359) (xy 76.770594 -26.93405)
			(xy 76.806285 -26.975241) (xy 76.835751 -27.021091) (xy 76.858393 -27.070668) (xy 76.873748 -27.122963)
			(xy 76.881504 -27.176911) (xy 76.88199 -27.204162) (xy 76.881502 -27.231736) (xy 76.873554 -27.286308)
			(xy 76.857834 -27.339167) (xy 76.834668 -27.389213) (xy 76.804539 -27.435404) (xy 76.768076 -27.476776)
			(xy 76.74737 -27.494992) (xy 76.736514 -27.504931) (xy 76.720445 -27.529571) (xy 76.71206 -27.557767)
			(xy 76.712053 -27.587184) (xy 76.720425 -27.615384) (xy 76.736481 -27.640032) (xy 76.74737 -27.649932)
			(xy 76.768094 -27.66813) (xy 76.804564 -27.7095) (xy 76.834696 -27.755693) (xy 76.85786 -27.805744)
			(xy 76.873573 -27.858609) (xy 76.881508 -27.913186) (xy 76.88199 -27.940762) (xy 76.881561 -27.967079)
			(xy 76.874337 -28.019214) (xy 76.860019 -28.069863) (xy 76.83888 -28.118065) (xy 76.81132 -28.162906)
			(xy 76.777862 -28.203537) (xy 76.7588 -28.221686) (xy 76.748818 -28.231534) (xy 76.734119 -28.255397)
			(xy 76.726476 -28.282361) (xy 76.726469 -28.310388) (xy 76.734098 -28.337356) (xy 76.748785 -28.361226)
			(xy 76.7588 -28.371038) (xy 76.777898 -28.389154) (xy 76.811374 -28.429779) (xy 76.838942 -28.474623)
			(xy 76.860078 -28.522834) (xy 76.874378 -28.573495) (xy 76.881572 -28.625641) (xy 76.88199 -28.651962)
			(xy 78.62697 -28.651962) (xy 78.627428 -28.625646) (xy 78.634648 -28.573513) (xy 78.648961 -28.522865)
			(xy 78.670095 -28.474663) (xy 78.697649 -28.429821) (xy 78.731101 -28.389189) (xy 78.75016 -28.371038)
			(xy 78.760222 -28.361264) (xy 78.774923 -28.337381) (xy 78.782559 -28.310397) (xy 78.782552 -28.282352)
			(xy 78.774902 -28.255371) (xy 78.760189 -28.231496) (xy 78.75016 -28.221686) (xy 78.731085 -28.203546)
			(xy 78.697605 -28.162928) (xy 78.670032 -28.118089) (xy 78.648892 -28.069883) (xy 78.634587 -28.019225)
			(xy 78.62739 -27.967081) (xy 78.62697 -27.940762) (xy 78.627489 -27.913189) (xy 78.635432 -27.858619)
			(xy 78.651147 -27.805761) (xy 78.674307 -27.755715) (xy 78.70443 -27.709524) (xy 78.740888 -27.66815)
			(xy 78.76159 -27.649932) (xy 78.772526 -27.640072) (xy 78.788598 -27.615411) (xy 78.796978 -27.587193)
			(xy 78.796971 -27.557758) (xy 78.788577 -27.529544) (xy 78.772493 -27.504891) (xy 78.76159 -27.494992)
			(xy 78.74087 -27.476791) (xy 78.704401 -27.43542) (xy 78.67427 -27.389228) (xy 78.651106 -27.339178)
			(xy 78.635391 -27.286314) (xy 78.627454 -27.231737) (xy 78.62697 -27.204162) (xy 78.627456 -27.176911)
			(xy 78.635212 -27.122963) (xy 78.650567 -27.070668) (xy 78.673209 -27.021091) (xy 78.702675 -26.975241)
			(xy 78.738366 -26.93405) (xy 78.779557 -26.898359) (xy 78.825407 -26.868893) (xy 78.874984 -26.846251)
			(xy 78.927279 -26.830896) (xy 78.981227 -26.82314) (xy 79.035729 -26.82314) (xy 79.089677 -26.830896)
			(xy 79.141972 -26.846251) (xy 79.191549 -26.868893) (xy 79.237399 -26.898359) (xy 79.27859 -26.93405)
			(xy 79.314281 -26.975241) (xy 79.343747 -27.021091) (xy 79.366389 -27.070668) (xy 79.381744 -27.122963)
			(xy 79.3895 -27.176911) (xy 79.389986 -27.204162) (xy 79.389499 -27.231736) (xy 79.381552 -27.286308)
			(xy 79.365831 -27.339168) (xy 79.342665 -27.389214) (xy 79.312536 -27.435404) (xy 79.276072 -27.476776)
			(xy 79.255366 -27.494992) (xy 79.24451 -27.504931) (xy 79.228442 -27.529571) (xy 79.220058 -27.557767)
			(xy 79.22005 -27.587184) (xy 79.228422 -27.615384) (xy 79.244478 -27.640032) (xy 79.255366 -27.649932)
			(xy 79.276089 -27.66813) (xy 79.31256 -27.709501) (xy 79.342691 -27.755693) (xy 79.365855 -27.805744)
			(xy 79.381569 -27.858609) (xy 79.389504 -27.913186) (xy 79.389986 -27.940762) (xy 79.389559 -27.967079)
			(xy 79.382334 -28.019214) (xy 79.368016 -28.069863) (xy 79.346877 -28.118065) (xy 79.319317 -28.162906)
			(xy 79.285858 -28.203537) (xy 79.266796 -28.221686) (xy 79.256814 -28.231534) (xy 79.242116 -28.255397)
			(xy 79.234473 -28.282361) (xy 79.234466 -28.310388) (xy 79.242095 -28.337356) (xy 79.256782 -28.361226)
			(xy 79.266796 -28.371038) (xy 79.285893 -28.389155) (xy 79.31937 -28.429779) (xy 79.346938 -28.474623)
			(xy 79.368073 -28.522834) (xy 79.382374 -28.573495) (xy 79.389568 -28.625641) (xy 79.389986 -28.651962)
			(xy 79.3895 -28.679213) (xy 79.381744 -28.733161) (xy 79.366389 -28.785456) (xy 79.343747 -28.835033)
			(xy 79.314281 -28.880883) (xy 79.27859 -28.922074) (xy 79.237399 -28.957765) (xy 79.191549 -28.987231)
			(xy 79.141972 -29.009873) (xy 79.089677 -29.025228) (xy 79.035729 -29.032984) (xy 78.981227 -29.032984)
			(xy 78.927279 -29.025228) (xy 78.874984 -29.009873) (xy 78.825407 -28.987231) (xy 78.779557 -28.957765)
			(xy 78.738366 -28.922074) (xy 78.702675 -28.880883) (xy 78.673209 -28.835033) (xy 78.650567 -28.785456)
			(xy 78.635212 -28.733161) (xy 78.627456 -28.679213) (xy 78.62697 -28.651962) (xy 76.88199 -28.651962)
			(xy 76.881504 -28.679213) (xy 76.873748 -28.733161) (xy 76.858393 -28.785456) (xy 76.835751 -28.835033)
			(xy 76.806285 -28.880883) (xy 76.770594 -28.922074) (xy 76.729403 -28.957765) (xy 76.683553 -28.987231)
			(xy 76.633976 -29.009873) (xy 76.581681 -29.025228) (xy 76.527733 -29.032984) (xy 76.473231 -29.032984)
			(xy 76.419283 -29.025228) (xy 76.366988 -29.009873) (xy 76.317411 -28.987231) (xy 76.271561 -28.957765)
			(xy 76.23037 -28.922074) (xy 76.194679 -28.880883) (xy 76.165213 -28.835033) (xy 76.142571 -28.785456)
			(xy 76.127216 -28.733161) (xy 76.11946 -28.679213) (xy 76.118974 -28.651962) (xy 64.761709 -28.651962)
			(xy 64.750161 -28.66485) (xy 64.707293 -28.700525) (xy 64.659687 -28.729579) (xy 64.608358 -28.751391)
			(xy 64.554401 -28.765497) (xy 64.498964 -28.771597) (xy 64.44323 -28.76956) (xy 64.388387 -28.75943)
			(xy 64.335603 -28.741423) (xy 64.286003 -28.715922) (xy 64.240645 -28.683471) (xy 64.200496 -28.644762)
			(xy 64.16641 -28.600619) (xy 64.139114 -28.551984) (xy 64.119191 -28.499893) (xy 64.107065 -28.445456)
			(xy 64.102994 -28.389834) (xy 62.561368 -28.389834) (xy 62.557667 -28.414984) (xy 62.541599 -28.468391)
			(xy 62.517927 -28.518888) (xy 62.487154 -28.565401) (xy 62.449937 -28.606938) (xy 62.407069 -28.642613)
			(xy 62.359463 -28.671667) (xy 62.308134 -28.693479) (xy 62.254177 -28.707585) (xy 62.19874 -28.713685)
			(xy 62.143006 -28.711648) (xy 62.088163 -28.701518) (xy 62.035379 -28.683511) (xy 61.985779 -28.65801)
			(xy 61.940421 -28.625559) (xy 61.900272 -28.58685) (xy 61.866186 -28.542707) (xy 61.83889 -28.494072)
			(xy 61.818967 -28.441981) (xy 61.806841 -28.387544) (xy 61.80277 -28.331922) (xy 58.88228 -28.331922)
			(xy 58.88228 -29.347922) (xy 61.80277 -29.347922) (xy 61.806841 -29.2923) (xy 61.818967 -29.237863)
			(xy 61.83889 -29.185772) (xy 61.866186 -29.137137) (xy 61.900272 -29.092994) (xy 61.940421 -29.054285)
			(xy 61.985779 -29.021834) (xy 62.035379 -28.996333) (xy 62.088163 -28.978326) (xy 62.143006 -28.968196)
			(xy 62.19874 -28.966159) (xy 62.254177 -28.972259) (xy 62.308134 -28.986365) (xy 62.359463 -29.008177)
			(xy 62.407069 -29.037231) (xy 62.449937 -29.072906) (xy 62.487154 -29.114443) (xy 62.517927 -29.160956)
			(xy 62.541599 -29.211453) (xy 62.557667 -29.26486) (xy 62.565787 -29.320036) (xy 62.566296 -29.347922)
			(xy 62.565787 -29.375808) (xy 62.5632 -29.393388) (xy 64.111122 -29.393388) (xy 64.115193 -29.337766)
			(xy 64.127319 -29.283329) (xy 64.147242 -29.231238) (xy 64.174538 -29.182603) (xy 64.208624 -29.13846)
			(xy 64.248773 -29.099751) (xy 64.294131 -29.0673) (xy 64.343731 -29.041799) (xy 64.396515 -29.023792)
			(xy 64.451358 -29.013662) (xy 64.507092 -29.011625) (xy 64.562529 -29.017725) (xy 64.616486 -29.031831)
			(xy 64.667815 -29.053643) (xy 64.715421 -29.082697) (xy 64.758289 -29.118372) (xy 64.795506 -29.159909)
			(xy 64.826279 -29.206422) (xy 64.849951 -29.256919) (xy 64.866019 -29.310326) (xy 64.874139 -29.365502)
			(xy 64.874594 -29.390453) (xy 71.46464 -29.390453) (xy 71.46464 -29.335947) (xy 71.472397 -29.281996)
			(xy 71.487752 -29.229698) (xy 71.510394 -29.180117) (xy 71.539861 -29.134263) (xy 71.575554 -29.093069)
			(xy 71.616745 -29.057374) (xy 71.662598 -29.027904) (xy 71.712177 -29.00526) (xy 71.764474 -28.989901)
			(xy 71.818425 -28.982141) (xy 71.845678 -28.981654) (xy 71.874595 -28.982168) (xy 71.931768 -28.990895)
			(xy 71.986967 -29.008152) (xy 72.03893 -29.033545) (xy 72.086463 -29.06649) (xy 72.128479 -29.106233)
			(xy 72.146668 -29.12872) (xy 72.156565 -29.140525) (xy 72.181889 -29.158044) (xy 72.211282 -29.16722)
			(xy 72.242074 -29.16722) (xy 72.271467 -29.158044) (xy 72.296791 -29.140525) (xy 72.306688 -29.12872)
			(xy 72.324891 -29.106246) (xy 72.366908 -29.06651) (xy 72.41444 -29.033569) (xy 72.466399 -29.008179)
			(xy 72.521595 -28.990921) (xy 72.578763 -28.98219) (xy 72.607678 -28.981654) (xy 72.634929 -28.982192)
			(xy 72.688877 -28.989945) (xy 72.741172 -29.005298) (xy 72.79075 -29.027937) (xy 72.836602 -29.057401)
			(xy 72.877793 -29.093092) (xy 72.913485 -29.134281) (xy 72.942952 -29.18013) (xy 72.965594 -29.229707)
			(xy 72.98095 -29.282001) (xy 72.988707 -29.335949) (xy 72.988707 -29.390451) (xy 72.98095 -29.444399)
			(xy 72.965594 -29.496693) (xy 72.942952 -29.54627) (xy 72.913485 -29.592119) (xy 72.877793 -29.633308)
			(xy 72.836602 -29.668999) (xy 72.79075 -29.698463) (xy 72.741172 -29.721102) (xy 72.688877 -29.736455)
			(xy 72.634929 -29.744208) (xy 72.607678 -29.74467) (xy 72.578763 -29.744107) (xy 72.521593 -29.735389)
			(xy 72.466395 -29.71814) (xy 72.414433 -29.692757) (xy 72.366898 -29.659821) (xy 72.324879 -29.620086)
			(xy 72.306688 -29.597604) (xy 72.296791 -29.585799) (xy 72.271467 -29.56828) (xy 72.242074 -29.559104)
			(xy 72.211282 -29.559104) (xy 72.181889 -29.56828) (xy 72.156565 -29.585799) (xy 72.146668 -29.597604)
			(xy 72.128496 -29.620104) (xy 72.086472 -29.659838) (xy 72.038933 -29.692775) (xy 71.986968 -29.71816)
			(xy 71.931767 -29.735413) (xy 71.874595 -29.744137) (xy 71.845678 -29.74467) (xy 71.818425 -29.744259)
			(xy 71.764474 -29.736499) (xy 71.712177 -29.72114) (xy 71.662598 -29.698496) (xy 71.616745 -29.669026)
			(xy 71.575554 -29.633331) (xy 71.539861 -29.592137) (xy 71.510394 -29.546283) (xy 71.487752 -29.496702)
			(xy 71.472397 -29.444404) (xy 71.46464 -29.390453) (xy 64.874594 -29.390453) (xy 64.874648 -29.393388)
			(xy 64.874139 -29.421274) (xy 64.866019 -29.47645) (xy 64.849951 -29.529857) (xy 64.826279 -29.580354)
			(xy 64.795506 -29.626867) (xy 64.758289 -29.668404) (xy 64.715421 -29.704079) (xy 64.667815 -29.733133)
			(xy 64.616486 -29.754945) (xy 64.562529 -29.769051) (xy 64.507092 -29.775151) (xy 64.451358 -29.773114)
			(xy 64.396515 -29.762984) (xy 64.343731 -29.744977) (xy 64.294131 -29.719476) (xy 64.248773 -29.687025)
			(xy 64.208624 -29.648316) (xy 64.174538 -29.604173) (xy 64.147242 -29.555538) (xy 64.127319 -29.503447)
			(xy 64.115193 -29.44901) (xy 64.111122 -29.393388) (xy 62.5632 -29.393388) (xy 62.557667 -29.430984)
			(xy 62.541599 -29.484391) (xy 62.517927 -29.534888) (xy 62.487154 -29.581401) (xy 62.449937 -29.622938)
			(xy 62.407069 -29.658613) (xy 62.359463 -29.687667) (xy 62.308134 -29.709479) (xy 62.254177 -29.723585)
			(xy 62.19874 -29.729685) (xy 62.143006 -29.727648) (xy 62.088163 -29.717518) (xy 62.035379 -29.699511)
			(xy 61.985779 -29.67401) (xy 61.940421 -29.641559) (xy 61.900272 -29.60285) (xy 61.866186 -29.558707)
			(xy 61.83889 -29.510072) (xy 61.818967 -29.457981) (xy 61.806841 -29.403544) (xy 61.80277 -29.347922)
			(xy 58.88228 -29.347922) (xy 58.88228 -30.714188) (xy 66.559682 -30.714188) (xy 66.563753 -30.658566)
			(xy 66.575879 -30.604129) (xy 66.595802 -30.552038) (xy 66.623098 -30.503403) (xy 66.657184 -30.45926)
			(xy 66.697333 -30.420551) (xy 66.742691 -30.3881) (xy 66.792291 -30.362599) (xy 66.845075 -30.344592)
			(xy 66.899918 -30.334462) (xy 66.955652 -30.332425) (xy 67.011089 -30.338525) (xy 67.065046 -30.352631)
			(xy 67.116375 -30.374443) (xy 67.163981 -30.403497) (xy 67.206849 -30.439172) (xy 67.244066 -30.480709)
			(xy 67.274839 -30.527222) (xy 67.298511 -30.577719) (xy 67.314579 -30.631126) (xy 67.322699 -30.686302)
			(xy 67.323208 -30.714188) (xy 67.322699 -30.742074) (xy 67.320448 -30.757368) (xy 67.992496 -30.757368)
			(xy 67.996567 -30.701746) (xy 68.008693 -30.647309) (xy 68.028616 -30.595218) (xy 68.055912 -30.546583)
			(xy 68.089998 -30.50244) (xy 68.130147 -30.463731) (xy 68.175505 -30.43128) (xy 68.225105 -30.405779)
			(xy 68.277889 -30.387772) (xy 68.332732 -30.377642) (xy 68.388466 -30.375605) (xy 68.443903 -30.381705)
			(xy 68.49786 -30.395811) (xy 68.549189 -30.417623) (xy 68.596795 -30.446677) (xy 68.639663 -30.482352)
			(xy 68.67688 -30.523889) (xy 68.689014 -30.54223) (xy 69.67042 -30.54223) (xy 69.674491 -30.486608)
			(xy 69.686617 -30.432171) (xy 69.70654 -30.38008) (xy 69.733836 -30.331445) (xy 69.767922 -30.287302)
			(xy 69.808071 -30.248593) (xy 69.853429 -30.216142) (xy 69.903029 -30.190641) (xy 69.955813 -30.172634)
			(xy 70.010656 -30.162504) (xy 70.06639 -30.160467) (xy 70.121827 -30.166567) (xy 70.175784 -30.180673)
			(xy 70.227113 -30.202485) (xy 70.274719 -30.231539) (xy 70.317587 -30.267214) (xy 70.354804 -30.308751)
			(xy 70.385577 -30.355264) (xy 70.409249 -30.405761) (xy 70.425317 -30.459168) (xy 70.433437 -30.514344)
			(xy 70.433946 -30.54223) (xy 70.433437 -30.570116) (xy 70.425317 -30.625292) (xy 70.409249 -30.678699)
			(xy 70.385577 -30.729196) (xy 70.354804 -30.775709) (xy 70.317587 -30.817246) (xy 70.274719 -30.852921)
			(xy 70.227113 -30.881975) (xy 70.175784 -30.903787) (xy 70.121827 -30.917893) (xy 70.06639 -30.923993)
			(xy 70.010656 -30.921956) (xy 69.955813 -30.911826) (xy 69.903029 -30.893819) (xy 69.853429 -30.868318)
			(xy 69.808071 -30.835867) (xy 69.767922 -30.797158) (xy 69.733836 -30.753015) (xy 69.70654 -30.70438)
			(xy 69.686617 -30.652289) (xy 69.674491 -30.597852) (xy 69.67042 -30.54223) (xy 68.689014 -30.54223)
			(xy 68.707653 -30.570402) (xy 68.731325 -30.620899) (xy 68.747393 -30.674306) (xy 68.755513 -30.729482)
			(xy 68.756022 -30.757368) (xy 68.755513 -30.785254) (xy 68.747393 -30.84043) (xy 68.731325 -30.893837)
			(xy 68.707653 -30.944334) (xy 68.67688 -30.990847) (xy 68.639663 -31.032384) (xy 68.596795 -31.068059)
			(xy 68.549189 -31.097113) (xy 68.49786 -31.118925) (xy 68.443903 -31.133031) (xy 68.388466 -31.139131)
			(xy 68.332732 -31.137094) (xy 68.277889 -31.126964) (xy 68.225105 -31.108957) (xy 68.175505 -31.083456)
			(xy 68.130147 -31.051005) (xy 68.089998 -31.012296) (xy 68.055912 -30.968153) (xy 68.028616 -30.919518)
			(xy 68.008693 -30.867427) (xy 67.996567 -30.81299) (xy 67.992496 -30.757368) (xy 67.320448 -30.757368)
			(xy 67.314579 -30.79725) (xy 67.298511 -30.850657) (xy 67.274839 -30.901154) (xy 67.244066 -30.947667)
			(xy 67.206849 -30.989204) (xy 67.163981 -31.024879) (xy 67.116375 -31.053933) (xy 67.065046 -31.075745)
			(xy 67.011089 -31.089851) (xy 66.955652 -31.095951) (xy 66.899918 -31.093914) (xy 66.845075 -31.083784)
			(xy 66.792291 -31.065777) (xy 66.742691 -31.040276) (xy 66.697333 -31.007825) (xy 66.657184 -30.969116)
			(xy 66.623098 -30.924973) (xy 66.595802 -30.876338) (xy 66.575879 -30.824247) (xy 66.563753 -30.76981)
			(xy 66.559682 -30.714188) (xy 58.88228 -30.714188) (xy 58.88228 -31.874968) (xy 67.159122 -31.874968)
			(xy 67.163193 -31.819346) (xy 67.175319 -31.764909) (xy 67.195242 -31.712818) (xy 67.222538 -31.664183)
			(xy 67.256624 -31.62004) (xy 67.296773 -31.581331) (xy 67.342131 -31.54888) (xy 67.391731 -31.523379)
			(xy 67.444515 -31.505372) (xy 67.499358 -31.495242) (xy 67.555092 -31.493205) (xy 67.610529 -31.499305)
			(xy 67.664486 -31.513411) (xy 67.715815 -31.535223) (xy 67.763421 -31.564277) (xy 67.806289 -31.599952)
			(xy 67.843506 -31.641489) (xy 67.874279 -31.688002) (xy 67.897951 -31.738499) (xy 67.914019 -31.791906)
			(xy 67.922139 -31.847082) (xy 67.922648 -31.874968) (xy 67.922139 -31.902854) (xy 67.914019 -31.95803)
			(xy 67.897951 -32.011437) (xy 67.874279 -32.061934) (xy 67.843506 -32.108447) (xy 67.806289 -32.149984)
			(xy 67.763421 -32.185659) (xy 67.715815 -32.214713) (xy 67.664486 -32.236525) (xy 67.610529 -32.250631)
			(xy 67.555092 -32.256731) (xy 67.499358 -32.254694) (xy 67.444515 -32.244564) (xy 67.391731 -32.226557)
			(xy 67.342131 -32.201056) (xy 67.296773 -32.168605) (xy 67.256624 -32.129896) (xy 67.222538 -32.085753)
			(xy 67.195242 -32.037118) (xy 67.175319 -31.985027) (xy 67.163193 -31.93059) (xy 67.159122 -31.874968)
			(xy 58.88228 -31.874968) (xy 58.88228 -32.944562) (xy 60.14542 -32.944562) (xy 60.149491 -32.88894)
			(xy 60.161617 -32.834503) (xy 60.18154 -32.782412) (xy 60.208836 -32.733777) (xy 60.242922 -32.689634)
			(xy 60.283071 -32.650925) (xy 60.328429 -32.618474) (xy 60.378029 -32.592973) (xy 60.430813 -32.574966)
			(xy 60.485656 -32.564836) (xy 60.54139 -32.562799) (xy 60.596827 -32.568899) (xy 60.650784 -32.583005)
			(xy 60.702113 -32.604817) (xy 60.749719 -32.633871) (xy 60.792587 -32.669546) (xy 60.829804 -32.711083)
			(xy 60.860577 -32.757596) (xy 60.884249 -32.808093) (xy 60.900317 -32.8615) (xy 60.908437 -32.916676)
			(xy 60.908946 -32.944562) (xy 60.908437 -32.972448) (xy 60.900317 -33.027624) (xy 60.884249 -33.081031)
			(xy 60.860577 -33.131528) (xy 60.829804 -33.178041) (xy 60.792587 -33.219578) (xy 60.749719 -33.255253)
			(xy 60.702113 -33.284307) (xy 60.650784 -33.306119) (xy 60.596827 -33.320225) (xy 60.54139 -33.326325)
			(xy 60.485656 -33.324288) (xy 60.430813 -33.314158) (xy 60.378029 -33.296151) (xy 60.328429 -33.27065)
			(xy 60.283071 -33.238199) (xy 60.242922 -33.19949) (xy 60.208836 -33.155347) (xy 60.18154 -33.106712)
			(xy 60.161617 -33.054621) (xy 60.149491 -33.000184) (xy 60.14542 -32.944562) (xy 58.88228 -32.944562)
			(xy 58.88228 -33.823148) (xy 59.148726 -34.08934) (xy 64.1858 -34.08934) (xy 64.210721 -34.089771)
			(xy 64.260105 -34.096519) (xy 64.308131 -34.109852) (xy 64.353925 -34.129528) (xy 64.396655 -34.155188)
			(xy 64.435543 -34.186366) (xy 64.453008 -34.204148) (xy 66.458338 -34.204148)
		)
		(stroke
			(width 0)
			(type solid)
		)
		(fill yes)
		(layer "In15.Cu")
		(net "GND")
	)
	(gr_poly
		(pts
			(xy 190.2968 -365.216948) (xy 190.2968 -333.822548) (xy 188.976 -332.501748) (xy 166.37 -332.501748)
			(xy 165.877748 -332.994) (xy 165.877748 -335.51996) (xy 170.076618 -335.51996) (xy 170.076618 -335.435264)
			(xy 170.084669 -335.35095) (xy 170.100698 -335.267784) (xy 170.124559 -335.186517) (xy 170.156038 -335.107887)
			(xy 170.194849 -335.032606) (xy 170.240639 -334.961354) (xy 170.292995 -334.894778) (xy 170.351443 -334.83348)
			(xy 170.415453 -334.778015) (xy 170.484445 -334.728886) (xy 170.557795 -334.686537) (xy 170.634838 -334.651353)
			(xy 170.714877 -334.623651) (xy 170.797186 -334.603683) (xy 170.881021 -334.59163) (xy 170.965622 -334.5876)
			(xy 171.050223 -334.59163) (xy 171.134058 -334.603683) (xy 171.216367 -334.623651) (xy 171.296406 -334.651353)
			(xy 171.373449 -334.686537) (xy 171.446799 -334.728886) (xy 171.515791 -334.778015) (xy 171.579801 -334.83348)
			(xy 171.638249 -334.894778) (xy 171.690605 -334.961354) (xy 171.736395 -335.032606) (xy 171.775206 -335.107887)
			(xy 171.806685 -335.186517) (xy 171.830546 -335.267784) (xy 171.846575 -335.35095) (xy 171.854626 -335.435264)
			(xy 171.85513 -335.477612) (xy 171.854626 -335.51996) (xy 171.85402 -335.52631) (xy 176.26736 -335.52631)
			(xy 176.26736 -335.441614) (xy 176.275411 -335.3573) (xy 176.29144 -335.274134) (xy 176.315301 -335.192867)
			(xy 176.34678 -335.114237) (xy 176.385591 -335.038956) (xy 176.431381 -334.967704) (xy 176.483737 -334.901128)
			(xy 176.542185 -334.83983) (xy 176.606195 -334.784365) (xy 176.675187 -334.735236) (xy 176.748537 -334.692887)
			(xy 176.82558 -334.657703) (xy 176.905619 -334.630001) (xy 176.987928 -334.610033) (xy 177.071763 -334.59798)
			(xy 177.156364 -334.59395) (xy 177.240965 -334.59798) (xy 177.3248 -334.610033) (xy 177.407109 -334.630001)
			(xy 177.487148 -334.657703) (xy 177.564191 -334.692887) (xy 177.637541 -334.735236) (xy 177.706533 -334.784365)
			(xy 177.770543 -334.83983) (xy 177.828991 -334.901128) (xy 177.881347 -334.967704) (xy 177.927137 -335.038956)
			(xy 177.965948 -335.114237) (xy 177.997427 -335.192867) (xy 178.021288 -335.274134) (xy 178.037317 -335.3573)
			(xy 178.045368 -335.441614) (xy 178.045872 -335.483962) (xy 178.045368 -335.52631) (xy 182.46496 -335.52631)
			(xy 182.46496 -335.441614) (xy 182.473011 -335.3573) (xy 182.48904 -335.274134) (xy 182.512901 -335.192867)
			(xy 182.54438 -335.114237) (xy 182.583191 -335.038956) (xy 182.628981 -334.967704) (xy 182.681337 -334.901128)
			(xy 182.739785 -334.83983) (xy 182.803795 -334.784365) (xy 182.872787 -334.735236) (xy 182.946137 -334.692887)
			(xy 183.02318 -334.657703) (xy 183.103219 -334.630001) (xy 183.185528 -334.610033) (xy 183.269363 -334.59798)
			(xy 183.353964 -334.59395) (xy 183.438565 -334.59798) (xy 183.5224 -334.610033) (xy 183.604709 -334.630001)
			(xy 183.684748 -334.657703) (xy 183.761791 -334.692887) (xy 183.835141 -334.735236) (xy 183.904133 -334.784365)
			(xy 183.968143 -334.83983) (xy 184.026591 -334.901128) (xy 184.078947 -334.967704) (xy 184.124737 -335.038956)
			(xy 184.163548 -335.114237) (xy 184.195027 -335.192867) (xy 184.218888 -335.274134) (xy 184.234917 -335.3573)
			(xy 184.242968 -335.441614) (xy 184.243472 -335.483962) (xy 184.242968 -335.52631) (xy 184.234917 -335.610624)
			(xy 184.218888 -335.69379) (xy 184.195027 -335.775057) (xy 184.163548 -335.853687) (xy 184.124737 -335.928968)
			(xy 184.078947 -336.00022) (xy 184.026591 -336.066796) (xy 183.968143 -336.128094) (xy 183.904133 -336.183559)
			(xy 183.835141 -336.232688) (xy 183.761791 -336.275037) (xy 183.684748 -336.310221) (xy 183.604709 -336.337923)
			(xy 183.5224 -336.357891) (xy 183.438565 -336.369944) (xy 183.353964 -336.373975) (xy 183.269363 -336.369944)
			(xy 183.185528 -336.357891) (xy 183.103219 -336.337923) (xy 183.02318 -336.310221) (xy 182.946137 -336.275037)
			(xy 182.872787 -336.232688) (xy 182.803795 -336.183559) (xy 182.739785 -336.128094) (xy 182.681337 -336.066796)
			(xy 182.628981 -336.00022) (xy 182.583191 -335.928968) (xy 182.54438 -335.853687) (xy 182.512901 -335.775057)
			(xy 182.48904 -335.69379) (xy 182.473011 -335.610624) (xy 182.46496 -335.52631) (xy 178.045368 -335.52631)
			(xy 178.037317 -335.610624) (xy 178.021288 -335.69379) (xy 177.997427 -335.775057) (xy 177.965948 -335.853687)
			(xy 177.927137 -335.928968) (xy 177.881347 -336.00022) (xy 177.828991 -336.066796) (xy 177.770543 -336.128094)
			(xy 177.706533 -336.183559) (xy 177.637541 -336.232688) (xy 177.564191 -336.275037) (xy 177.487148 -336.310221)
			(xy 177.407109 -336.337923) (xy 177.3248 -336.357891) (xy 177.240965 -336.369944) (xy 177.156364 -336.373975)
			(xy 177.071763 -336.369944) (xy 176.987928 -336.357891) (xy 176.905619 -336.337923) (xy 176.82558 -336.310221)
			(xy 176.748537 -336.275037) (xy 176.675187 -336.232688) (xy 176.606195 -336.183559) (xy 176.542185 -336.128094)
			(xy 176.483737 -336.066796) (xy 176.431381 -336.00022) (xy 176.385591 -335.928968) (xy 176.34678 -335.853687)
			(xy 176.315301 -335.775057) (xy 176.29144 -335.69379) (xy 176.275411 -335.610624) (xy 176.26736 -335.52631)
			(xy 171.85402 -335.52631) (xy 171.846575 -335.604274) (xy 171.830546 -335.68744) (xy 171.806685 -335.768707)
			(xy 171.775206 -335.847337) (xy 171.736395 -335.922618) (xy 171.690605 -335.99387) (xy 171.638249 -336.060446)
			(xy 171.579801 -336.121744) (xy 171.515791 -336.177209) (xy 171.446799 -336.226338) (xy 171.373449 -336.268687)
			(xy 171.296406 -336.303871) (xy 171.216367 -336.331573) (xy 171.134058 -336.351541) (xy 171.050223 -336.363594)
			(xy 170.965622 -336.367625) (xy 170.881021 -336.363594) (xy 170.797186 -336.351541) (xy 170.714877 -336.331573)
			(xy 170.634838 -336.303871) (xy 170.557795 -336.268687) (xy 170.484445 -336.226338) (xy 170.415453 -336.177209)
			(xy 170.351443 -336.121744) (xy 170.292995 -336.060446) (xy 170.240639 -335.99387) (xy 170.194849 -335.922618)
			(xy 170.156038 -335.847337) (xy 170.124559 -335.768707) (xy 170.100698 -335.68744) (xy 170.084669 -335.604274)
			(xy 170.076618 -335.51996) (xy 165.877748 -335.51996) (xy 165.877748 -337.477608) (xy 170.050211 -337.477608)
			(xy 170.054233 -337.391888) (xy 170.066264 -337.30692) (xy 170.0862 -337.223453) (xy 170.113863 -337.142219)
			(xy 170.149012 -337.063933) (xy 170.191338 -336.989282) (xy 170.240467 -336.918923) (xy 170.29597 -336.853473)
			(xy 170.357357 -336.793509) (xy 170.42409 -336.739556) (xy 170.495582 -336.692089) (xy 170.571204 -336.651525)
			(xy 170.650293 -336.618221) (xy 170.732153 -336.592469) (xy 170.816064 -336.574496) (xy 170.90129 -336.56446)
			(xy 170.987082 -336.562448) (xy 171.072684 -336.568479) (xy 171.157346 -336.582499) (xy 171.240323 -336.604385)
			(xy 171.320886 -336.633946) (xy 171.398326 -336.67092) (xy 171.471965 -336.714984) (xy 171.541153 -336.76575)
			(xy 171.605284 -336.822771) (xy 171.663793 -336.885547) (xy 171.716166 -336.953527) (xy 171.761944 -337.026112)
			(xy 171.800724 -337.102664) (xy 171.832165 -337.182512) (xy 171.855991 -337.264953) (xy 171.871992 -337.349263)
			(xy 171.880027 -337.434701) (xy 171.88053 -337.477608) (xy 171.880456 -337.483958) (xy 176.240953 -337.483958)
			(xy 176.244975 -337.398238) (xy 176.257006 -337.31327) (xy 176.276942 -337.229803) (xy 176.304605 -337.148569)
			(xy 176.339754 -337.070283) (xy 176.38208 -336.995632) (xy 176.431209 -336.925273) (xy 176.486712 -336.859823)
			(xy 176.548099 -336.799859) (xy 176.614832 -336.745906) (xy 176.686324 -336.698439) (xy 176.761946 -336.657875)
			(xy 176.841035 -336.624571) (xy 176.922895 -336.598819) (xy 177.006806 -336.580846) (xy 177.092032 -336.57081)
			(xy 177.177824 -336.568798) (xy 177.263426 -336.574829) (xy 177.348088 -336.588849) (xy 177.431065 -336.610735)
			(xy 177.511628 -336.640296) (xy 177.589068 -336.67727) (xy 177.662707 -336.721334) (xy 177.731895 -336.7721)
			(xy 177.796026 -336.829121) (xy 177.854535 -336.891897) (xy 177.906908 -336.959877) (xy 177.952686 -337.032462)
			(xy 177.991466 -337.109014) (xy 178.022907 -337.188862) (xy 178.046733 -337.271303) (xy 178.062734 -337.355613)
			(xy 178.070769 -337.441051) (xy 178.071272 -337.483958) (xy 182.439056 -337.483958) (xy 182.439544 -337.441682)
			(xy 182.447346 -337.35749) (xy 182.462882 -337.274377) (xy 182.486021 -337.193053) (xy 182.516565 -337.11421)
			(xy 182.554253 -337.038522) (xy 182.598764 -336.966634) (xy 182.649718 -336.89916) (xy 182.706681 -336.836675)
			(xy 182.769166 -336.779712) (xy 182.83664 -336.728758) (xy 182.908528 -336.684247) (xy 182.984216 -336.646559)
			(xy 183.063059 -336.616015) (xy 183.144383 -336.592876) (xy 183.227496 -336.57734) (xy 183.311688 -336.569538)
			(xy 183.39624 -336.569538) (xy 183.480432 -336.57734) (xy 183.563545 -336.592876) (xy 183.644869 -336.616015)
			(xy 183.723712 -336.646559) (xy 183.7994 -336.684247) (xy 183.871288 -336.728758) (xy 183.938762 -336.779712)
			(xy 184.001247 -336.836675) (xy 184.05821 -336.89916) (xy 184.109164 -336.966634) (xy 184.153675 -337.038522)
			(xy 184.191363 -337.11421) (xy 184.221907 -337.193053) (xy 184.245046 -337.274377) (xy 184.260582 -337.35749)
			(xy 184.268384 -337.441682) (xy 184.268872 -337.483958) (xy 184.268338 -337.527902) (xy 184.259914 -337.615385)
			(xy 184.243138 -337.701657) (xy 184.218167 -337.785923) (xy 184.185229 -337.867405) (xy 184.144629 -337.945353)
			(xy 184.096741 -338.019048) (xy 184.042007 -338.087812) (xy 183.98093 -338.151009) (xy 183.914074 -338.208057)
			(xy 183.842055 -338.258431) (xy 183.804052 -338.280502) (xy 183.792022 -338.28775) (xy 183.772209 -338.307642)
			(xy 183.758568 -338.332181) (xy 183.752134 -338.35951) (xy 183.753394 -338.387557) (xy 183.762252 -338.414199)
			(xy 183.778037 -338.437416) (xy 183.799554 -338.455452) (xy 183.81218 -338.461604) (xy 183.839112 -338.474322)
			(xy 183.889 -338.506852) (xy 183.911494 -338.526374) (xy 183.922936 -338.536019) (xy 183.949979 -338.548799)
			(xy 183.979566 -338.553185) (xy 184.009153 -338.548799) (xy 184.036196 -338.536019) (xy 184.047638 -338.526374)
			(xy 184.068792 -338.507958) (xy 184.115469 -338.476864) (xy 184.166199 -338.452947) (xy 184.219887 -338.436726)
			(xy 184.275373 -338.428551) (xy 184.303416 -338.428076) (xy 184.330787 -338.428514) (xy 184.384968 -338.436336)
			(xy 184.437473 -338.45183) (xy 184.487219 -338.474679) (xy 184.533184 -338.504411) (xy 184.554114 -338.522056)
			(xy 184.565442 -338.531292) (xy 184.591999 -338.543468) (xy 184.620916 -338.547641) (xy 184.649833 -338.543468)
			(xy 184.67639 -338.531292) (xy 184.687718 -338.522056) (xy 184.708664 -338.504435) (xy 184.754634 -338.474722)
			(xy 184.804378 -338.451883) (xy 184.856875 -338.436387) (xy 184.911048 -338.428553) (xy 184.938416 -338.428076)
			(xy 184.965667 -338.428563) (xy 185.019614 -338.436321) (xy 185.071908 -338.451677) (xy 185.121484 -338.474319)
			(xy 185.167333 -338.503786) (xy 185.208523 -338.539477) (xy 185.244214 -338.580667) (xy 185.273681 -338.626516)
			(xy 185.296323 -338.676092) (xy 185.311679 -338.728386) (xy 185.319437 -338.782333) (xy 185.319924 -338.809584)
			(xy 185.319467 -338.836955) (xy 185.31165 -338.891135) (xy 185.29616 -338.943639) (xy 185.273315 -338.993386)
			(xy 185.243587 -339.039351) (xy 185.225944 -339.060282) (xy 185.216727 -339.071623) (xy 185.204555 -339.098177)
			(xy 185.200381 -339.127088) (xy 185.204548 -339.156) (xy 185.216714 -339.182557) (xy 185.225944 -339.193886)
			(xy 185.24357 -339.214831) (xy 185.273298 -339.260796) (xy 185.296146 -339.31054) (xy 185.311645 -339.36304)
			(xy 185.319475 -339.417218) (xy 185.319477 -339.471958) (xy 185.31165 -339.526136) (xy 185.296154 -339.578637)
			(xy 185.273309 -339.628383) (xy 185.243585 -339.67435) (xy 185.225944 -339.695282) (xy 185.216727 -339.706623)
			(xy 185.204555 -339.733177) (xy 185.200381 -339.762088) (xy 185.204548 -339.791) (xy 185.216714 -339.817557)
			(xy 185.225944 -339.828886) (xy 185.24357 -339.849831) (xy 185.273298 -339.895796) (xy 185.296146 -339.94554)
			(xy 185.311645 -339.99804) (xy 185.319475 -340.052218) (xy 185.319477 -340.106958) (xy 185.31165 -340.161136)
			(xy 185.296154 -340.213637) (xy 185.273309 -340.263383) (xy 185.243585 -340.30935) (xy 185.225944 -340.330282)
			(xy 185.216727 -340.341623) (xy 185.204555 -340.368177) (xy 185.200381 -340.397088) (xy 185.204548 -340.426)
			(xy 185.216714 -340.452557) (xy 185.225944 -340.463886) (xy 185.24357 -340.484831) (xy 185.273298 -340.530796)
			(xy 185.296146 -340.58054) (xy 185.311645 -340.63304) (xy 185.319475 -340.687218) (xy 185.319477 -340.741958)
			(xy 185.31165 -340.796136) (xy 185.296154 -340.848637) (xy 185.273309 -340.898383) (xy 185.243585 -340.94435)
			(xy 185.225944 -340.965282) (xy 185.216727 -340.976623) (xy 185.204555 -341.003177) (xy 185.200381 -341.032088)
			(xy 185.204548 -341.061) (xy 185.216714 -341.087557) (xy 185.225944 -341.098886) (xy 185.24357 -341.119831)
			(xy 185.273298 -341.165796) (xy 185.296146 -341.21554) (xy 185.311645 -341.26804) (xy 185.319475 -341.322218)
			(xy 185.319477 -341.376958) (xy 185.31165 -341.431136) (xy 185.296154 -341.483637) (xy 185.273309 -341.533383)
			(xy 185.243585 -341.57935) (xy 185.225944 -341.600282) (xy 185.216727 -341.611623) (xy 185.204555 -341.638177)
			(xy 185.200381 -341.667088) (xy 185.204548 -341.696) (xy 185.216714 -341.722557) (xy 185.225944 -341.733886)
			(xy 185.24357 -341.754831) (xy 185.273298 -341.800796) (xy 185.296146 -341.85054) (xy 185.311645 -341.90304)
			(xy 185.319475 -341.957218) (xy 185.319477 -342.011958) (xy 185.31165 -342.066136) (xy 185.296154 -342.118637)
			(xy 185.273309 -342.168383) (xy 185.243585 -342.21435) (xy 185.225944 -342.235282) (xy 185.216727 -342.246623)
			(xy 185.204555 -342.273177) (xy 185.200381 -342.302088) (xy 185.204548 -342.331) (xy 185.216714 -342.357557)
			(xy 185.225944 -342.368886) (xy 185.243597 -342.389807) (xy 185.273306 -342.435783) (xy 185.296138 -342.485534)
			(xy 185.311626 -342.538037) (xy 185.319452 -342.592214) (xy 185.319924 -342.619584) (xy 185.319407 -342.646834)
			(xy 185.311653 -342.70078) (xy 185.296301 -342.753073) (xy 185.273663 -342.802649) (xy 185.2442 -342.848499)
			(xy 185.208511 -342.889689) (xy 185.167324 -342.92538) (xy 185.121477 -342.954847) (xy 185.071903 -342.97749)
			(xy 185.019611 -342.992846) (xy 184.965666 -343.000605) (xy 184.938416 -343.001092) (xy 184.911046 -343.000619)
			(xy 184.856867 -342.992803) (xy 184.804364 -342.977316) (xy 184.754617 -342.954475) (xy 184.70865 -342.924752)
			(xy 184.687718 -342.907112) (xy 184.67639 -342.897876) (xy 184.649833 -342.8857) (xy 184.620916 -342.881527)
			(xy 184.591999 -342.8857) (xy 184.565442 -342.897876) (xy 184.554114 -342.907112) (xy 184.533189 -342.92476)
			(xy 184.487214 -342.95447) (xy 184.437465 -342.977304) (xy 184.384963 -342.992793) (xy 184.330786 -343.000619)
			(xy 184.303416 -343.001092) (xy 184.275376 -343.000597) (xy 184.219898 -342.992398) (xy 184.166215 -342.976172)
			(xy 184.115483 -342.952271) (xy 184.068792 -342.921207) (xy 184.047638 -342.902794) (xy 184.036196 -342.893149)
			(xy 184.009153 -342.880369) (xy 183.979566 -342.875983) (xy 183.949979 -342.880369) (xy 183.922936 -342.893149)
			(xy 183.911494 -342.902794) (xy 183.890362 -342.921237) (xy 183.84368 -342.952329) (xy 183.792944 -342.97624)
			(xy 183.739251 -342.992455) (xy 183.683761 -343.000622) (xy 183.655716 -343.001092) (xy 183.628463 -343.00063)
			(xy 183.574511 -342.992875) (xy 183.522212 -342.97752) (xy 183.472631 -342.954878) (xy 183.426777 -342.92541)
			(xy 183.385584 -342.889716) (xy 183.34989 -342.848523) (xy 183.320422 -342.802669) (xy 183.29778 -342.753088)
			(xy 183.282425 -342.700789) (xy 183.27467 -342.646837) (xy 183.274208 -342.619584) (xy 183.274663 -342.592213)
			(xy 183.282483 -342.538034) (xy 183.297975 -342.48553) (xy 183.320819 -342.435784) (xy 183.350546 -342.389817)
			(xy 183.368188 -342.368886) (xy 183.377441 -342.357571) (xy 183.389618 -342.331009) (xy 183.393788 -342.302088)
			(xy 183.389611 -342.273168) (xy 183.377428 -342.246609) (xy 183.368188 -342.235282) (xy 183.350533 -342.214361)
			(xy 183.320812 -342.16839) (xy 183.29797 -342.118642) (xy 183.282477 -342.066138) (xy 183.27465 -342.011959)
			(xy 183.274652 -341.957217) (xy 183.282482 -341.903038) (xy 183.297979 -341.850535) (xy 183.320824 -341.800788)
			(xy 183.350548 -341.75482) (xy 183.368188 -341.733886) (xy 183.377441 -341.722571) (xy 183.389618 -341.696009)
			(xy 183.393788 -341.667088) (xy 183.389611 -341.638168) (xy 183.377428 -341.611609) (xy 183.368188 -341.600282)
			(xy 183.350533 -341.579361) (xy 183.320812 -341.53339) (xy 183.29797 -341.483642) (xy 183.282477 -341.431138)
			(xy 183.27465 -341.376959) (xy 183.274652 -341.322217) (xy 183.282482 -341.268038) (xy 183.297979 -341.215535)
			(xy 183.320824 -341.165788) (xy 183.350548 -341.11982) (xy 183.368188 -341.098886) (xy 183.377441 -341.087571)
			(xy 183.389618 -341.061009) (xy 183.393788 -341.032088) (xy 183.389611 -341.003168) (xy 183.377428 -340.976609)
			(xy 183.368188 -340.965282) (xy 183.350533 -340.944361) (xy 183.320812 -340.89839) (xy 183.29797 -340.848642)
			(xy 183.282477 -340.796138) (xy 183.27465 -340.741959) (xy 183.274652 -340.687217) (xy 183.282482 -340.633038)
			(xy 183.297979 -340.580535) (xy 183.320824 -340.530788) (xy 183.350548 -340.48482) (xy 183.368188 -340.463886)
			(xy 183.377441 -340.452571) (xy 183.389618 -340.426009) (xy 183.393788 -340.397088) (xy 183.389611 -340.368168)
			(xy 183.377428 -340.341609) (xy 183.368188 -340.330282) (xy 183.350533 -340.309361) (xy 183.320812 -340.26339)
			(xy 183.29797 -340.213642) (xy 183.282477 -340.161138) (xy 183.27465 -340.106959) (xy 183.274652 -340.052217)
			(xy 183.282482 -339.998038) (xy 183.297979 -339.945535) (xy 183.320824 -339.895788) (xy 183.350548 -339.84982)
			(xy 183.368188 -339.828886) (xy 183.377441 -339.817571) (xy 183.389618 -339.791009) (xy 183.393788 -339.762088)
			(xy 183.389611 -339.733168) (xy 183.377428 -339.706609) (xy 183.368188 -339.695282) (xy 183.350533 -339.674361)
			(xy 183.320812 -339.62839) (xy 183.29797 -339.578642) (xy 183.282477 -339.526138) (xy 183.27465 -339.471959)
			(xy 183.274652 -339.417217) (xy 183.282482 -339.363038) (xy 183.297979 -339.310535) (xy 183.320824 -339.260788)
			(xy 183.350548 -339.21482) (xy 183.368188 -339.193886) (xy 183.377441 -339.182571) (xy 183.389618 -339.156009)
			(xy 183.393788 -339.127088) (xy 183.389611 -339.098168) (xy 183.377428 -339.071609) (xy 183.368188 -339.060282)
			(xy 183.350572 -339.039331) (xy 183.320857 -338.993363) (xy 183.298017 -338.943621) (xy 183.28252 -338.891124)
			(xy 183.274686 -338.836952) (xy 183.274208 -338.809584) (xy 183.274668 -338.782851) (xy 183.282177 -338.729914)
			(xy 183.296991 -338.67854) (xy 183.318821 -338.629732) (xy 183.347239 -338.584443) (xy 183.364124 -338.563712)
			(xy 183.372832 -338.552699) (xy 183.384366 -338.527111) (xy 183.388505 -338.499351) (xy 183.384937 -338.471511)
			(xy 183.373932 -338.445692) (xy 183.356318 -338.423839) (xy 183.333425 -338.407602) (xy 183.306978 -338.398203)
			(xy 183.293004 -338.396834) (xy 183.250113 -338.393549) (xy 183.165193 -338.379781) (xy 183.081941 -338.358103)
			(xy 183.001091 -338.328705) (xy 182.923357 -338.291848) (xy 182.849427 -338.247857) (xy 182.779952 -338.19712)
			(xy 182.715547 -338.140086) (xy 182.65678 -338.077258) (xy 182.604169 -338.009191) (xy 182.558181 -337.936486)
			(xy 182.51922 -337.859785) (xy 182.487632 -337.779766) (xy 182.463694 -337.697135) (xy 182.447618 -337.612622)
			(xy 182.439547 -337.526972) (xy 182.439056 -337.483958) (xy 178.071272 -337.483958) (xy 178.070769 -337.526865)
			(xy 178.062734 -337.612303) (xy 178.046733 -337.696613) (xy 178.022907 -337.779054) (xy 177.991466 -337.858902)
			(xy 177.952686 -337.935454) (xy 177.906908 -338.008039) (xy 177.854535 -338.076019) (xy 177.796026 -338.138795)
			(xy 177.731895 -338.195816) (xy 177.662707 -338.246582) (xy 177.589068 -338.290646) (xy 177.511628 -338.32762)
			(xy 177.431065 -338.357181) (xy 177.348088 -338.379067) (xy 177.263426 -338.393087) (xy 177.177824 -338.399118)
			(xy 177.092032 -338.397106) (xy 177.006806 -338.38707) (xy 176.922895 -338.369097) (xy 176.841035 -338.343345)
			(xy 176.761946 -338.310041) (xy 176.686324 -338.269477) (xy 176.614832 -338.22201) (xy 176.548099 -338.168057)
			(xy 176.486712 -338.108093) (xy 176.431209 -338.042643) (xy 176.38208 -337.972284) (xy 176.339754 -337.897633)
			(xy 176.304605 -337.819347) (xy 176.276942 -337.738113) (xy 176.257006 -337.654646) (xy 176.244975 -337.569678)
			(xy 176.240953 -337.483958) (xy 171.880456 -337.483958) (xy 171.880027 -337.520515) (xy 171.871992 -337.605953)
			(xy 171.855991 -337.690263) (xy 171.832165 -337.772704) (xy 171.800724 -337.852552) (xy 171.761944 -337.929104)
			(xy 171.716166 -338.001689) (xy 171.663793 -338.069669) (xy 171.605284 -338.132445) (xy 171.541153 -338.189466)
			(xy 171.471965 -338.240232) (xy 171.398326 -338.284296) (xy 171.320886 -338.32127) (xy 171.240323 -338.350831)
			(xy 171.157346 -338.372717) (xy 171.072684 -338.386737) (xy 170.987082 -338.392768) (xy 170.90129 -338.390756)
			(xy 170.816064 -338.38072) (xy 170.732153 -338.362747) (xy 170.650293 -338.336995) (xy 170.571204 -338.303691)
			(xy 170.495582 -338.263127) (xy 170.42409 -338.21566) (xy 170.357357 -338.161707) (xy 170.29597 -338.101743)
			(xy 170.240467 -338.036293) (xy 170.191338 -337.965934) (xy 170.149012 -337.891283) (xy 170.113863 -337.812997)
			(xy 170.0862 -337.731763) (xy 170.066264 -337.648296) (xy 170.054233 -337.563328) (xy 170.050211 -337.477608)
			(xy 165.877748 -337.477608) (xy 165.877748 -338.866734) (xy 165.879272 -338.868004) (xy 166.019226 -341.038942)
			(xy 166.02075 -341.069168) (xy 166.02075 -341.073486) (xy 166.021512 -341.102188) (xy 166.021512 -341.102696)
			(xy 166.021258 -341.113872) (xy 166.021258 -341.117682) (xy 166.010336 -341.827104) (xy 166.044626 -342.021668)
			(xy 166.150019 -342.619584) (xy 168.52519 -342.619584) (xy 168.525649 -342.592214) (xy 168.533469 -342.538034)
			(xy 168.54896 -342.485531) (xy 168.571803 -342.435784) (xy 168.601528 -342.389818) (xy 168.61917 -342.368886)
			(xy 168.628425 -342.357571) (xy 168.640604 -342.33101) (xy 168.644775 -342.302088) (xy 168.640597 -342.273167)
			(xy 168.628412 -342.246608) (xy 168.61917 -342.235282) (xy 168.601512 -342.214363) (xy 168.571784 -342.168394)
			(xy 168.548937 -342.118645) (xy 168.53344 -342.066141) (xy 168.525612 -342.01196) (xy 168.525614 -341.957216)
			(xy 168.533446 -341.903035) (xy 168.548946 -341.850532) (xy 168.571796 -341.800785) (xy 168.601526 -341.754818)
			(xy 168.61917 -341.733886) (xy 168.628425 -341.722571) (xy 168.640604 -341.69601) (xy 168.644775 -341.667088)
			(xy 168.640597 -341.638167) (xy 168.628412 -341.611608) (xy 168.61917 -341.600282) (xy 168.601512 -341.579363)
			(xy 168.571784 -341.533394) (xy 168.548937 -341.483645) (xy 168.53344 -341.431141) (xy 168.525612 -341.37696)
			(xy 168.525614 -341.322216) (xy 168.533446 -341.268035) (xy 168.548946 -341.215532) (xy 168.571796 -341.165785)
			(xy 168.601526 -341.119818) (xy 168.61917 -341.098886) (xy 168.628425 -341.087571) (xy 168.640604 -341.06101)
			(xy 168.644775 -341.032088) (xy 168.640597 -341.003167) (xy 168.628412 -340.976608) (xy 168.61917 -340.965282)
			(xy 168.601512 -340.944363) (xy 168.571784 -340.898394) (xy 168.548937 -340.848645) (xy 168.53344 -340.796141)
			(xy 168.525612 -340.74196) (xy 168.525614 -340.687216) (xy 168.533446 -340.633035) (xy 168.548946 -340.580532)
			(xy 168.571796 -340.530785) (xy 168.601526 -340.484818) (xy 168.61917 -340.463886) (xy 168.628425 -340.452571)
			(xy 168.640604 -340.42601) (xy 168.644775 -340.397088) (xy 168.640597 -340.368167) (xy 168.628412 -340.341608)
			(xy 168.61917 -340.330282) (xy 168.601512 -340.309363) (xy 168.571784 -340.263394) (xy 168.548937 -340.213645)
			(xy 168.53344 -340.161141) (xy 168.525612 -340.10696) (xy 168.525614 -340.052216) (xy 168.533446 -339.998035)
			(xy 168.548946 -339.945532) (xy 168.571796 -339.895785) (xy 168.601526 -339.849818) (xy 168.61917 -339.828886)
			(xy 168.628425 -339.817571) (xy 168.640604 -339.79101) (xy 168.644775 -339.762088) (xy 168.640597 -339.733167)
			(xy 168.628412 -339.706608) (xy 168.61917 -339.695282) (xy 168.601512 -339.674363) (xy 168.571784 -339.628394)
			(xy 168.548937 -339.578645) (xy 168.53344 -339.526141) (xy 168.525612 -339.47196) (xy 168.525614 -339.417216)
			(xy 168.533446 -339.363035) (xy 168.548946 -339.310532) (xy 168.571796 -339.260785) (xy 168.601526 -339.214818)
			(xy 168.61917 -339.193886) (xy 168.628425 -339.182571) (xy 168.640604 -339.15601) (xy 168.644775 -339.127088)
			(xy 168.640597 -339.098167) (xy 168.628412 -339.071608) (xy 168.61917 -339.060282) (xy 168.601551 -339.039334)
			(xy 168.571837 -338.993365) (xy 168.548998 -338.943621) (xy 168.533502 -338.891125) (xy 168.525668 -338.836952)
			(xy 168.52519 -338.809584) (xy 168.525663 -338.782332) (xy 168.533422 -338.728384) (xy 168.548779 -338.676089)
			(xy 168.571421 -338.626512) (xy 168.600889 -338.580662) (xy 168.636582 -338.539472) (xy 168.677773 -338.503781)
			(xy 168.723625 -338.474315) (xy 168.773203 -338.451674) (xy 168.825498 -338.436319) (xy 168.879446 -338.428562)
			(xy 168.906698 -338.428076) (xy 168.934069 -338.428525) (xy 168.98825 -338.436344) (xy 169.040754 -338.451836)
			(xy 169.0905 -338.474682) (xy 169.136466 -338.504412) (xy 169.157396 -338.522056) (xy 169.168724 -338.531292)
			(xy 169.195281 -338.543468) (xy 169.224198 -338.547641) (xy 169.253115 -338.543468) (xy 169.279672 -338.531292)
			(xy 169.291 -338.522056) (xy 169.311915 -338.504396) (xy 169.357893 -338.474689) (xy 169.407645 -338.451858)
			(xy 169.460149 -338.436371) (xy 169.514328 -338.428547) (xy 169.541698 -338.428076) (xy 169.569738 -338.428571)
			(xy 169.625216 -338.436772) (xy 169.678898 -338.452997) (xy 169.72963 -338.476899) (xy 169.776322 -338.507962)
			(xy 169.797476 -338.526374) (xy 169.808918 -338.536019) (xy 169.835961 -338.548799) (xy 169.865548 -338.553185)
			(xy 169.895135 -338.548799) (xy 169.922178 -338.536019) (xy 169.93362 -338.526374) (xy 169.954781 -338.507967)
			(xy 170.001456 -338.476871) (xy 170.052184 -338.452953) (xy 170.105871 -338.43673) (xy 170.161356 -338.428552)
			(xy 170.189398 -338.428076) (xy 170.216648 -338.42858) (xy 170.270595 -338.436335) (xy 170.322888 -338.451689)
			(xy 170.372464 -338.474329) (xy 170.418314 -338.503794) (xy 170.459504 -338.539483) (xy 170.495195 -338.580672)
			(xy 170.524662 -338.62652) (xy 170.547304 -338.676095) (xy 170.562661 -338.728388) (xy 170.570419 -338.782334)
			(xy 170.570906 -338.809584) (xy 170.570429 -338.836954) (xy 170.562614 -338.891132) (xy 170.547127 -338.943635)
			(xy 170.524288 -338.993382) (xy 170.494566 -339.03935) (xy 170.476926 -339.060282) (xy 170.467702 -339.07162)
			(xy 170.45552 -339.098173) (xy 170.451343 -339.127088) (xy 170.455513 -339.156003) (xy 170.467689 -339.18256)
			(xy 170.476926 -339.193886) (xy 170.494553 -339.214831) (xy 170.524282 -339.260795) (xy 170.547131 -339.310539)
			(xy 170.562631 -339.36304) (xy 170.570462 -339.417218) (xy 170.570464 -339.471958) (xy 170.562636 -339.526137)
			(xy 170.54714 -339.578638) (xy 170.524294 -339.628384) (xy 170.494568 -339.67435) (xy 170.476926 -339.695282)
			(xy 170.467702 -339.70662) (xy 170.45552 -339.733173) (xy 170.451343 -339.762088) (xy 170.455513 -339.791003)
			(xy 170.467689 -339.81756) (xy 170.476926 -339.828886) (xy 170.494553 -339.849831) (xy 170.524282 -339.895795)
			(xy 170.547131 -339.945539) (xy 170.562631 -339.99804) (xy 170.570462 -340.052218) (xy 170.570464 -340.106958)
			(xy 170.562636 -340.161137) (xy 170.54714 -340.213638) (xy 170.524294 -340.263384) (xy 170.494568 -340.30935)
			(xy 170.476926 -340.330282) (xy 170.467702 -340.34162) (xy 170.45552 -340.368173) (xy 170.451343 -340.397088)
			(xy 170.455513 -340.426003) (xy 170.467689 -340.45256) (xy 170.476926 -340.463886) (xy 170.494553 -340.484831)
			(xy 170.524282 -340.530795) (xy 170.547131 -340.580539) (xy 170.562631 -340.63304) (xy 170.570462 -340.687218)
			(xy 170.570464 -340.741958) (xy 170.562636 -340.796137) (xy 170.54714 -340.848638) (xy 170.524294 -340.898384)
			(xy 170.494568 -340.94435) (xy 170.476926 -340.965282) (xy 170.467702 -340.97662) (xy 170.45552 -341.003173)
			(xy 170.451343 -341.032088) (xy 170.455513 -341.061003) (xy 170.467689 -341.08756) (xy 170.476926 -341.098886)
			(xy 170.494553 -341.119831) (xy 170.524282 -341.165795) (xy 170.547131 -341.215539) (xy 170.562631 -341.26804)
			(xy 170.570462 -341.322218) (xy 170.570464 -341.376958) (xy 170.562636 -341.431137) (xy 170.54714 -341.483638)
			(xy 170.524294 -341.533384) (xy 170.494568 -341.57935) (xy 170.476926 -341.600282) (xy 170.467702 -341.61162)
			(xy 170.45552 -341.638173) (xy 170.451343 -341.667088) (xy 170.455513 -341.696003) (xy 170.467689 -341.72256)
			(xy 170.476926 -341.733886) (xy 170.494553 -341.754831) (xy 170.524282 -341.800795) (xy 170.547131 -341.850539)
			(xy 170.562631 -341.90304) (xy 170.570462 -341.957218) (xy 170.570464 -342.011958) (xy 170.562636 -342.066137)
			(xy 170.54714 -342.118638) (xy 170.524294 -342.168384) (xy 170.494568 -342.21435) (xy 170.476926 -342.235282)
			(xy 170.467702 -342.24662) (xy 170.45552 -342.273173) (xy 170.451343 -342.302088) (xy 170.455513 -342.331003)
			(xy 170.467689 -342.35756) (xy 170.476926 -342.368886) (xy 170.494576 -342.389809) (xy 170.524285 -342.435785)
			(xy 170.547119 -342.485535) (xy 170.562607 -342.538037) (xy 170.570433 -342.592214) (xy 170.570906 -342.619584)
			(xy 173.495462 -342.619584) (xy 173.495904 -342.592213) (xy 173.503725 -342.538032) (xy 173.519219 -342.485528)
			(xy 173.542067 -342.435781) (xy 173.571797 -342.389816) (xy 173.589442 -342.368886) (xy 173.598691 -342.357569)
			(xy 173.610861 -342.331007) (xy 173.615029 -342.302088) (xy 173.610854 -342.27317) (xy 173.598678 -342.246611)
			(xy 173.589442 -342.235282) (xy 173.571785 -342.214362) (xy 173.54206 -342.168393) (xy 173.519214 -342.118644)
			(xy 173.503719 -342.06614) (xy 173.495891 -342.011959) (xy 173.495893 -341.957216) (xy 173.503724 -341.903036)
			(xy 173.519223 -341.850533) (xy 173.542071 -341.800786) (xy 173.5718 -341.754818) (xy 173.589442 -341.733886)
			(xy 173.598691 -341.722569) (xy 173.610861 -341.696007) (xy 173.615029 -341.667088) (xy 173.610854 -341.63817)
			(xy 173.598678 -341.611611) (xy 173.589442 -341.600282) (xy 173.571785 -341.579362) (xy 173.54206 -341.533393)
			(xy 173.519214 -341.483644) (xy 173.503719 -341.43114) (xy 173.495891 -341.376959) (xy 173.495893 -341.322216)
			(xy 173.503724 -341.268036) (xy 173.519223 -341.215533) (xy 173.542071 -341.165786) (xy 173.5718 -341.119818)
			(xy 173.589442 -341.098886) (xy 173.598691 -341.087569) (xy 173.610861 -341.061007) (xy 173.615029 -341.032088)
			(xy 173.610854 -341.00317) (xy 173.598678 -340.976611) (xy 173.589442 -340.965282) (xy 173.571785 -340.944362)
			(xy 173.54206 -340.898393) (xy 173.519214 -340.848644) (xy 173.503719 -340.79614) (xy 173.495891 -340.741959)
			(xy 173.495893 -340.687216) (xy 173.503724 -340.633036) (xy 173.519223 -340.580533) (xy 173.542071 -340.530786)
			(xy 173.5718 -340.484818) (xy 173.589442 -340.463886) (xy 173.598691 -340.452569) (xy 173.610861 -340.426007)
			(xy 173.615029 -340.397088) (xy 173.610854 -340.36817) (xy 173.598678 -340.341611) (xy 173.589442 -340.330282)
			(xy 173.571785 -340.309362) (xy 173.54206 -340.263393) (xy 173.519214 -340.213644) (xy 173.503719 -340.16114)
			(xy 173.495891 -340.106959) (xy 173.495893 -340.052216) (xy 173.503724 -339.998036) (xy 173.519223 -339.945533)
			(xy 173.542071 -339.895786) (xy 173.5718 -339.849818) (xy 173.589442 -339.828886) (xy 173.598691 -339.817569)
			(xy 173.610861 -339.791007) (xy 173.615029 -339.762088) (xy 173.610854 -339.73317) (xy 173.598678 -339.706611)
			(xy 173.589442 -339.695282) (xy 173.571785 -339.674362) (xy 173.54206 -339.628393) (xy 173.519214 -339.578644)
			(xy 173.503719 -339.52614) (xy 173.495891 -339.471959) (xy 173.495893 -339.417216) (xy 173.503724 -339.363036)
			(xy 173.519223 -339.310533) (xy 173.542071 -339.260786) (xy 173.5718 -339.214818) (xy 173.589442 -339.193886)
			(xy 173.598691 -339.182569) (xy 173.610861 -339.156007) (xy 173.615029 -339.127088) (xy 173.610854 -339.09817)
			(xy 173.598678 -339.071611) (xy 173.589442 -339.060282) (xy 173.571834 -339.039324) (xy 173.542116 -338.993359)
			(xy 173.519274 -338.943618) (xy 173.503775 -338.891123) (xy 173.49594 -338.836952) (xy 173.495462 -338.809584)
			(xy 173.495963 -338.782334) (xy 173.503721 -338.728388) (xy 173.519076 -338.676095) (xy 173.541717 -338.62652)
			(xy 173.571182 -338.580671) (xy 173.606872 -338.539482) (xy 173.64806 -338.503791) (xy 173.693908 -338.474324)
			(xy 173.743482 -338.451681) (xy 173.795774 -338.436324) (xy 173.84972 -338.428564) (xy 173.87697 -338.428076)
			(xy 173.90501 -338.428587) (xy 173.960487 -338.436784) (xy 174.014169 -338.453006) (xy 174.064901 -338.476904)
			(xy 174.111593 -338.507964) (xy 174.132748 -338.526374) (xy 174.14419 -338.536019) (xy 174.171233 -338.548799)
			(xy 174.20082 -338.553185) (xy 174.230407 -338.548799) (xy 174.25745 -338.536019) (xy 174.268892 -338.526374)
			(xy 174.290025 -338.507932) (xy 174.336707 -338.476842) (xy 174.387443 -338.45293) (xy 174.441136 -338.436715)
			(xy 174.496626 -338.428547) (xy 174.52467 -338.428076) (xy 174.55204 -338.428541) (xy 174.60622 -338.436356)
			(xy 174.658724 -338.451845) (xy 174.708471 -338.474687) (xy 174.754437 -338.504413) (xy 174.775368 -338.522056)
			(xy 174.786696 -338.531292) (xy 174.813253 -338.543468) (xy 174.84217 -338.547641) (xy 174.871087 -338.543468)
			(xy 174.897644 -338.531292) (xy 174.908972 -338.522056) (xy 174.929898 -338.504409) (xy 174.975873 -338.4747)
			(xy 175.025622 -338.451866) (xy 175.078124 -338.436377) (xy 175.132301 -338.428549) (xy 175.15967 -338.428076)
			(xy 175.186921 -338.428583) (xy 175.24087 -338.436336) (xy 175.293166 -338.451687) (xy 175.342745 -338.474325)
			(xy 175.388597 -338.503788) (xy 175.42979 -338.539477) (xy 175.465484 -338.580666) (xy 175.494953 -338.626515)
			(xy 175.517597 -338.676091) (xy 175.532955 -338.728385) (xy 175.540714 -338.782333) (xy 175.541178 -338.809584)
			(xy 175.540708 -338.836954) (xy 175.532892 -338.891133) (xy 175.517404 -338.943637) (xy 175.494563 -338.993383)
			(xy 175.464839 -339.03935) (xy 175.447198 -339.060282) (xy 175.437977 -339.071621) (xy 175.425798 -339.098174)
			(xy 175.421622 -339.127088) (xy 175.425791 -339.156002) (xy 175.437964 -339.182559) (xy 175.447198 -339.193886)
			(xy 175.464822 -339.214832) (xy 175.494546 -339.260798) (xy 175.51739 -339.310542) (xy 175.532887 -339.363042)
			(xy 175.540716 -339.417218) (xy 175.540718 -339.471958) (xy 175.532892 -339.526134) (xy 175.517399 -339.578635)
			(xy 175.494557 -339.628381) (xy 175.464837 -339.674349) (xy 175.447198 -339.695282) (xy 175.437977 -339.706621)
			(xy 175.425798 -339.733174) (xy 175.421622 -339.762088) (xy 175.425791 -339.791002) (xy 175.437964 -339.817559)
			(xy 175.447198 -339.828886) (xy 175.464822 -339.849832) (xy 175.494546 -339.895798) (xy 175.51739 -339.945542)
			(xy 175.532887 -339.998042) (xy 175.540716 -340.052218) (xy 175.540718 -340.106958) (xy 175.532892 -340.161134)
			(xy 175.517399 -340.213635) (xy 175.494557 -340.263381) (xy 175.464837 -340.309349) (xy 175.447198 -340.330282)
			(xy 175.437977 -340.341621) (xy 175.425798 -340.368174) (xy 175.421622 -340.397088) (xy 175.425791 -340.426002)
			(xy 175.437964 -340.452559) (xy 175.447198 -340.463886) (xy 175.464822 -340.484832) (xy 175.494546 -340.530798)
			(xy 175.51739 -340.580542) (xy 175.532887 -340.633042) (xy 175.540716 -340.687218) (xy 175.540718 -340.741958)
			(xy 175.532892 -340.796134) (xy 175.517399 -340.848635) (xy 175.494557 -340.898381) (xy 175.464837 -340.944349)
			(xy 175.447198 -340.965282) (xy 175.437977 -340.976621) (xy 175.425798 -341.003174) (xy 175.421622 -341.032088)
			(xy 175.425791 -341.061002) (xy 175.437964 -341.087559) (xy 175.447198 -341.098886) (xy 175.464822 -341.119832)
			(xy 175.494546 -341.165798) (xy 175.51739 -341.215542) (xy 175.532887 -341.268042) (xy 175.540716 -341.322218)
			(xy 175.540718 -341.376958) (xy 175.532892 -341.431134) (xy 175.517399 -341.483635) (xy 175.494557 -341.533381)
			(xy 175.464837 -341.579349) (xy 175.447198 -341.600282) (xy 175.437977 -341.611621) (xy 175.425798 -341.638174)
			(xy 175.421622 -341.667088) (xy 175.425791 -341.696002) (xy 175.437964 -341.722559) (xy 175.447198 -341.733886)
			(xy 175.464822 -341.754832) (xy 175.494546 -341.800798) (xy 175.51739 -341.850542) (xy 175.532887 -341.903042)
			(xy 175.540716 -341.957218) (xy 175.540718 -342.011958) (xy 175.532892 -342.066134) (xy 175.517399 -342.118635)
			(xy 175.494557 -342.168381) (xy 175.464837 -342.214349) (xy 175.447198 -342.235282) (xy 175.437977 -342.246621)
			(xy 175.425798 -342.273174) (xy 175.421622 -342.302088) (xy 175.425791 -342.331002) (xy 175.437964 -342.357559)
			(xy 175.447198 -342.368886) (xy 175.464844 -342.389813) (xy 175.494555 -342.435787) (xy 175.517389 -342.485536)
			(xy 175.532879 -342.538038) (xy 175.540705 -342.592214) (xy 175.541178 -342.619584) (xy 178.20259 -342.619584)
			(xy 178.203049 -342.592214) (xy 178.210869 -342.538034) (xy 178.22636 -342.485531) (xy 178.249203 -342.435784)
			(xy 178.278928 -342.389818) (xy 178.29657 -342.368886) (xy 178.305825 -342.357571) (xy 178.318004 -342.33101)
			(xy 178.322175 -342.302088) (xy 178.317997 -342.273167) (xy 178.305812 -342.246608) (xy 178.29657 -342.235282)
			(xy 178.278912 -342.214363) (xy 178.249184 -342.168394) (xy 178.226337 -342.118645) (xy 178.21084 -342.066141)
			(xy 178.203012 -342.01196) (xy 178.203014 -341.957216) (xy 178.210846 -341.903035) (xy 178.226346 -341.850532)
			(xy 178.249196 -341.800785) (xy 178.278926 -341.754818) (xy 178.29657 -341.733886) (xy 178.305825 -341.722571)
			(xy 178.318004 -341.69601) (xy 178.322175 -341.667088) (xy 178.317997 -341.638167) (xy 178.305812 -341.611608)
			(xy 178.29657 -341.600282) (xy 178.278912 -341.579363) (xy 178.249184 -341.533394) (xy 178.226337 -341.483645)
			(xy 178.21084 -341.431141) (xy 178.203012 -341.37696) (xy 178.203014 -341.322216) (xy 178.210846 -341.268035)
			(xy 178.226346 -341.215532) (xy 178.249196 -341.165785) (xy 178.278926 -341.119818) (xy 178.29657 -341.098886)
			(xy 178.305825 -341.087571) (xy 178.318004 -341.06101) (xy 178.322175 -341.032088) (xy 178.317997 -341.003167)
			(xy 178.305812 -340.976608) (xy 178.29657 -340.965282) (xy 178.278912 -340.944363) (xy 178.249184 -340.898394)
			(xy 178.226337 -340.848645) (xy 178.21084 -340.796141) (xy 178.203012 -340.74196) (xy 178.203014 -340.687216)
			(xy 178.210846 -340.633035) (xy 178.226346 -340.580532) (xy 178.249196 -340.530785) (xy 178.278926 -340.484818)
			(xy 178.29657 -340.463886) (xy 178.305825 -340.452571) (xy 178.318004 -340.42601) (xy 178.322175 -340.397088)
			(xy 178.317997 -340.368167) (xy 178.305812 -340.341608) (xy 178.29657 -340.330282) (xy 178.278912 -340.309363)
			(xy 178.249184 -340.263394) (xy 178.226337 -340.213645) (xy 178.21084 -340.161141) (xy 178.203012 -340.10696)
			(xy 178.203014 -340.052216) (xy 178.210846 -339.998035) (xy 178.226346 -339.945532) (xy 178.249196 -339.895785)
			(xy 178.278926 -339.849818) (xy 178.29657 -339.828886) (xy 178.305825 -339.817571) (xy 178.318004 -339.79101)
			(xy 178.322175 -339.762088) (xy 178.317997 -339.733167) (xy 178.305812 -339.706608) (xy 178.29657 -339.695282)
			(xy 178.278912 -339.674363) (xy 178.249184 -339.628394) (xy 178.226337 -339.578645) (xy 178.21084 -339.526141)
			(xy 178.203012 -339.47196) (xy 178.203014 -339.417216) (xy 178.210846 -339.363035) (xy 178.226346 -339.310532)
			(xy 178.249196 -339.260785) (xy 178.278926 -339.214818) (xy 178.29657 -339.193886) (xy 178.305825 -339.182571)
			(xy 178.318004 -339.15601) (xy 178.322175 -339.127088) (xy 178.317997 -339.098167) (xy 178.305812 -339.071608)
			(xy 178.29657 -339.060282) (xy 178.278951 -339.039334) (xy 178.249237 -338.993365) (xy 178.226398 -338.943621)
			(xy 178.210902 -338.891125) (xy 178.203068 -338.836952) (xy 178.20259 -338.809584) (xy 178.203063 -338.782332)
			(xy 178.210822 -338.728384) (xy 178.226179 -338.676089) (xy 178.248821 -338.626512) (xy 178.278289 -338.580662)
			(xy 178.313982 -338.539472) (xy 178.355173 -338.503781) (xy 178.401025 -338.474315) (xy 178.450603 -338.451674)
			(xy 178.502898 -338.436319) (xy 178.556846 -338.428562) (xy 178.584098 -338.428076) (xy 178.611469 -338.428525)
			(xy 178.66565 -338.436344) (xy 178.718154 -338.451836) (xy 178.7679 -338.474682) (xy 178.813866 -338.504412)
			(xy 178.834796 -338.522056) (xy 178.846124 -338.531292) (xy 178.872681 -338.543468) (xy 178.901598 -338.547641)
			(xy 178.930515 -338.543468) (xy 178.957072 -338.531292) (xy 178.9684 -338.522056) (xy 178.989315 -338.504396)
			(xy 179.035293 -338.474689) (xy 179.085045 -338.451858) (xy 179.137549 -338.436371) (xy 179.191728 -338.428547)
			(xy 179.219098 -338.428076) (xy 179.247138 -338.428571) (xy 179.302616 -338.436772) (xy 179.356298 -338.452997)
			(xy 179.40703 -338.476899) (xy 179.453722 -338.507962) (xy 179.474876 -338.526374) (xy 179.486318 -338.536019)
			(xy 179.513361 -338.548799) (xy 179.542948 -338.553185) (xy 179.572535 -338.548799) (xy 179.599578 -338.536019)
			(xy 179.61102 -338.526374) (xy 179.632181 -338.507967) (xy 179.678856 -338.476871) (xy 179.729584 -338.452953)
			(xy 179.783271 -338.43673) (xy 179.838756 -338.428552) (xy 179.866798 -338.428076) (xy 179.894048 -338.42858)
			(xy 179.947995 -338.436335) (xy 180.000288 -338.451689) (xy 180.049864 -338.474329) (xy 180.095714 -338.503794)
			(xy 180.136904 -338.539483) (xy 180.172595 -338.580672) (xy 180.202062 -338.62652) (xy 180.224704 -338.676095)
			(xy 180.240061 -338.728388) (xy 180.247819 -338.782334) (xy 180.248306 -338.809584) (xy 180.247829 -338.836954)
			(xy 180.240014 -338.891132) (xy 180.224527 -338.943635) (xy 180.201688 -338.993382) (xy 180.171966 -339.03935)
			(xy 180.154326 -339.060282) (xy 180.145102 -339.07162) (xy 180.13292 -339.098173) (xy 180.128743 -339.127088)
			(xy 180.132913 -339.156003) (xy 180.145089 -339.18256) (xy 180.154326 -339.193886) (xy 180.171953 -339.214831)
			(xy 180.201682 -339.260795) (xy 180.224531 -339.310539) (xy 180.240031 -339.36304) (xy 180.247862 -339.417218)
			(xy 180.247864 -339.471958) (xy 180.240036 -339.526137) (xy 180.22454 -339.578638) (xy 180.201694 -339.628384)
			(xy 180.171968 -339.67435) (xy 180.154326 -339.695282) (xy 180.145102 -339.70662) (xy 180.13292 -339.733173)
			(xy 180.128743 -339.762088) (xy 180.132913 -339.791003) (xy 180.145089 -339.81756) (xy 180.154326 -339.828886)
			(xy 180.171953 -339.849831) (xy 180.201682 -339.895795) (xy 180.224531 -339.945539) (xy 180.240031 -339.99804)
			(xy 180.247862 -340.052218) (xy 180.247864 -340.106958) (xy 180.240036 -340.161137) (xy 180.22454 -340.213638)
			(xy 180.201694 -340.263384) (xy 180.171968 -340.30935) (xy 180.154326 -340.330282) (xy 180.145102 -340.34162)
			(xy 180.13292 -340.368173) (xy 180.128743 -340.397088) (xy 180.132913 -340.426003) (xy 180.145089 -340.45256)
			(xy 180.154326 -340.463886) (xy 180.171953 -340.484831) (xy 180.201682 -340.530795) (xy 180.224531 -340.580539)
			(xy 180.240031 -340.63304) (xy 180.247862 -340.687218) (xy 180.247864 -340.741958) (xy 180.240036 -340.796137)
			(xy 180.22454 -340.848638) (xy 180.201694 -340.898384) (xy 180.171968 -340.94435) (xy 180.154326 -340.965282)
			(xy 180.145102 -340.97662) (xy 180.13292 -341.003173) (xy 180.128743 -341.032088) (xy 180.132913 -341.061003)
			(xy 180.145089 -341.08756) (xy 180.154326 -341.098886) (xy 180.171953 -341.119831) (xy 180.201682 -341.165795)
			(xy 180.224531 -341.215539) (xy 180.240031 -341.26804) (xy 180.247862 -341.322218) (xy 180.247864 -341.376958)
			(xy 180.240036 -341.431137) (xy 180.22454 -341.483638) (xy 180.201694 -341.533384) (xy 180.171968 -341.57935)
			(xy 180.154326 -341.600282) (xy 180.145102 -341.61162) (xy 180.13292 -341.638173) (xy 180.128743 -341.667088)
			(xy 180.132913 -341.696003) (xy 180.145089 -341.72256) (xy 180.154326 -341.733886) (xy 180.171953 -341.754831)
			(xy 180.201682 -341.800795) (xy 180.224531 -341.850539) (xy 180.240031 -341.90304) (xy 180.247862 -341.957218)
			(xy 180.247864 -342.011958) (xy 180.240036 -342.066137) (xy 180.22454 -342.118638) (xy 180.201694 -342.168384)
			(xy 180.171968 -342.21435) (xy 180.154326 -342.235282) (xy 180.145102 -342.24662) (xy 180.13292 -342.273173)
			(xy 180.128743 -342.302088) (xy 180.132913 -342.331003) (xy 180.145089 -342.35756) (xy 180.154326 -342.368886)
			(xy 180.171976 -342.389809) (xy 180.201685 -342.435785) (xy 180.224519 -342.485535) (xy 180.240007 -342.538037)
			(xy 180.247833 -342.592214) (xy 180.248306 -342.619584) (xy 180.24783 -342.646837) (xy 180.240075 -342.700787)
			(xy 180.224721 -342.753085) (xy 180.20208 -342.802665) (xy 180.172614 -342.848518) (xy 180.136921 -342.889711)
			(xy 180.09573 -342.925405) (xy 180.049877 -342.954873) (xy 180.000298 -342.977516) (xy 179.948001 -342.992872)
			(xy 179.894051 -343.000629) (xy 179.866798 -343.001092) (xy 179.838757 -343.000608) (xy 179.783279 -342.992406)
			(xy 179.729596 -342.976178) (xy 179.678864 -342.952274) (xy 179.632173 -342.921208) (xy 179.61102 -342.902794)
			(xy 179.599578 -342.893149) (xy 179.572535 -342.880369) (xy 179.542948 -342.875983) (xy 179.513361 -342.880369)
			(xy 179.486318 -342.893149) (xy 179.474876 -342.902794) (xy 179.453712 -342.921198) (xy 179.407039 -342.952296)
			(xy 179.356311 -342.976215) (xy 179.302625 -342.992438) (xy 179.24714 -343.000616) (xy 179.219098 -343.001092)
			(xy 179.191728 -343.000629) (xy 179.137548 -342.992811) (xy 179.085045 -342.977321) (xy 179.035298 -342.954479)
			(xy 178.989332 -342.924753) (xy 178.9684 -342.907112) (xy 178.957072 -342.897876) (xy 178.930515 -342.8857)
			(xy 178.901598 -342.881527) (xy 178.872681 -342.8857) (xy 178.846124 -342.897876) (xy 178.834796 -342.907112)
			(xy 178.813878 -342.924768) (xy 178.767901 -342.954477) (xy 178.71815 -342.97731) (xy 178.665646 -342.992797)
			(xy 178.611468 -343.00062) (xy 178.584098 -343.001092) (xy 178.556844 -343.000646) (xy 178.502892 -342.992889)
			(xy 178.450593 -342.977532) (xy 178.401012 -342.954888) (xy 178.355158 -342.925418) (xy 178.313965 -342.889723)
			(xy 178.278271 -342.848528) (xy 178.248804 -342.802673) (xy 178.226162 -342.75309) (xy 178.210807 -342.70079)
			(xy 178.203052 -342.646838) (xy 178.20259 -342.619584) (xy 175.541178 -342.619584) (xy 175.54073 -342.646838)
			(xy 175.532974 -342.700791) (xy 175.517619 -342.753091) (xy 175.494976 -342.802673) (xy 175.465507 -342.848528)
			(xy 175.429811 -342.889721) (xy 175.388616 -342.925415) (xy 175.342761 -342.954883) (xy 175.293178 -342.977524)
			(xy 175.240877 -342.992877) (xy 175.186924 -343.000631) (xy 175.15967 -343.001092) (xy 175.132299 -343.000645)
			(xy 175.078119 -342.992823) (xy 175.025616 -342.97733) (xy 174.975869 -342.954484) (xy 174.929903 -342.924755)
			(xy 174.908972 -342.907112) (xy 174.897644 -342.897876) (xy 174.871087 -342.8857) (xy 174.84217 -342.881527)
			(xy 174.813253 -342.8857) (xy 174.786696 -342.897876) (xy 174.775368 -342.907112) (xy 174.754423 -342.924735)
			(xy 174.708453 -342.954448) (xy 174.658709 -342.977287) (xy 174.606211 -342.992782) (xy 174.552038 -343.000615)
			(xy 174.52467 -343.001092) (xy 174.496629 -343.000624) (xy 174.441149 -342.992418) (xy 174.387467 -342.976187)
			(xy 174.336735 -342.952279) (xy 174.290045 -342.921209) (xy 174.268892 -342.902794) (xy 174.25745 -342.893149)
			(xy 174.230407 -342.880369) (xy 174.20082 -342.875983) (xy 174.171233 -342.880369) (xy 174.14419 -342.893149)
			(xy 174.132748 -342.902794) (xy 174.111595 -342.921212) (xy 174.064919 -342.952307) (xy 174.014188 -342.976223)
			(xy 173.9605 -342.992444) (xy 173.905013 -343.000618) (xy 173.87697 -343.001092) (xy 173.849717 -343.00065)
			(xy 173.795767 -342.992889) (xy 173.743471 -342.977529) (xy 173.693892 -342.954883) (xy 173.648041 -342.925413)
			(xy 173.606851 -342.889717) (xy 173.57116 -342.848522) (xy 173.541694 -342.802667) (xy 173.519055 -342.753086)
			(xy 173.503701 -342.700788) (xy 173.495947 -342.646837) (xy 173.495462 -342.619584) (xy 170.570906 -342.619584)
			(xy 170.57043 -342.646837) (xy 170.562675 -342.700787) (xy 170.547321 -342.753085) (xy 170.52468 -342.802665)
			(xy 170.495214 -342.848518) (xy 170.459521 -342.889711) (xy 170.41833 -342.925405) (xy 170.372477 -342.954873)
			(xy 170.322898 -342.977516) (xy 170.270601 -342.992872) (xy 170.216651 -343.000629) (xy 170.189398 -343.001092)
			(xy 170.161357 -343.000608) (xy 170.105879 -342.992406) (xy 170.052196 -342.976178) (xy 170.001464 -342.952274)
			(xy 169.954773 -342.921208) (xy 169.93362 -342.902794) (xy 169.922178 -342.893149) (xy 169.895135 -342.880369)
			(xy 169.865548 -342.875983) (xy 169.835961 -342.880369) (xy 169.808918 -342.893149) (xy 169.797476 -342.902794)
			(xy 169.776312 -342.921198) (xy 169.729639 -342.952296) (xy 169.678911 -342.976215) (xy 169.625225 -342.992438)
			(xy 169.56974 -343.000616) (xy 169.541698 -343.001092) (xy 169.514328 -343.000629) (xy 169.460148 -342.992811)
			(xy 169.407645 -342.977321) (xy 169.357898 -342.954479) (xy 169.311932 -342.924753) (xy 169.291 -342.907112)
			(xy 169.279672 -342.897876) (xy 169.253115 -342.8857) (xy 169.224198 -342.881527) (xy 169.195281 -342.8857)
			(xy 169.168724 -342.897876) (xy 169.157396 -342.907112) (xy 169.136478 -342.924768) (xy 169.090501 -342.954477)
			(xy 169.04075 -342.97731) (xy 168.988246 -342.992797) (xy 168.934068 -343.00062) (xy 168.906698 -343.001092)
			(xy 168.879444 -343.000646) (xy 168.825492 -342.992889) (xy 168.773193 -342.977532) (xy 168.723612 -342.954888)
			(xy 168.677758 -342.925418) (xy 168.636565 -342.889723) (xy 168.600871 -342.848528) (xy 168.571404 -342.802673)
			(xy 168.548762 -342.75309) (xy 168.533407 -342.70079) (xy 168.525652 -342.646838) (xy 168.52519 -342.619584)
			(xy 166.150019 -342.619584) (xy 166.71544 -345.82735) (xy 166.718792 -345.846745) (xy 166.724129 -345.885745)
			(xy 166.726108 -345.905328) (xy 166.728225 -345.928702) (xy 166.730509 -345.975585) (xy 166.73068 -345.999054)
			(xy 166.730512 -346.022523) (xy 166.728226 -346.069406) (xy 166.726108 -346.09278) (xy 166.724117 -346.112361)
			(xy 166.718779 -346.151361) (xy 166.71544 -346.170758) (xy 166.252906 -348.794324) (xy 166.127176 -350.23298)
			(xy 166.018464 -351.47631) (xy 166.079932 -353.278694) (xy 166.11854 -353.287076) (xy 166.145839 -353.293523)
			(xy 166.19831 -353.313349) (xy 166.24731 -353.34065) (xy 166.291781 -353.374836) (xy 166.330762 -353.415168)
			(xy 166.363413 -353.460778) (xy 166.389028 -353.510679) (xy 166.407055 -353.563795) (xy 166.417104 -353.618979)
			(xy 166.418514 -353.646994) (xy 166.427034 -353.675385) (xy 166.436218 -353.733944) (xy 166.436802 -353.76358)
			(xy 166.436308 -353.791627) (xy 166.428097 -353.847116) (xy 166.411849 -353.900806) (xy 166.387914 -353.951537)
			(xy 166.356809 -353.998216) (xy 166.319203 -354.039838) (xy 166.275909 -354.075504) (xy 166.227858 -354.104446)
			(xy 166.176087 -354.12604) (xy 166.14902 -354.133404) (xy 166.109396 -354.143564) (xy 166.114222 -354.281232)
			(xy 166.150798 -354.290884) (xy 166.177725 -354.298356) (xy 166.229203 -354.320096) (xy 166.276959 -354.349111)
			(xy 166.319974 -354.384781) (xy 166.357326 -354.426343) (xy 166.388217 -354.472908) (xy 166.411986 -354.523481)
			(xy 166.428126 -354.57698) (xy 166.43629 -354.63226) (xy 166.436802 -354.6602) (xy 166.436354 -354.686698)
			(xy 166.429028 -354.739186) (xy 166.414505 -354.790153) (xy 166.393063 -354.838618) (xy 166.365117 -354.883647)
			(xy 166.331204 -354.924372) (xy 166.291977 -354.960008) (xy 166.248194 -354.989868) (xy 166.200698 -355.013378)
			(xy 166.179311 -355.02088) (xy 168.06799 -355.02088) (xy 168.068468 -354.992839) (xy 168.076672 -354.93736)
			(xy 168.092902 -354.883678) (xy 168.116807 -354.832946) (xy 168.147874 -354.786255) (xy 168.166288 -354.765102)
			(xy 168.175903 -354.753637) (xy 168.188686 -354.726603) (xy 168.193077 -354.697022) (xy 168.188699 -354.66744)
			(xy 168.175928 -354.6404) (xy 168.166288 -354.628958) (xy 168.147872 -354.607803) (xy 168.116777 -354.561127)
			(xy 168.092861 -354.510397) (xy 168.07664 -354.456709) (xy 168.068464 -354.401223) (xy 168.06799 -354.37318)
			(xy 168.068476 -354.345929) (xy 168.076232 -354.291981) (xy 168.091587 -354.239686) (xy 168.114229 -354.190109)
			(xy 168.143695 -354.144259) (xy 168.179386 -354.103068) (xy 168.220577 -354.067377) (xy 168.266427 -354.037911)
			(xy 168.316004 -354.015269) (xy 168.368299 -353.999914) (xy 168.422247 -353.992158) (xy 168.476749 -353.992158)
			(xy 168.530697 -353.999914) (xy 168.582992 -354.015269) (xy 168.632569 -354.037911) (xy 168.678419 -354.067377)
			(xy 168.71961 -354.103068) (xy 168.755301 -354.144259) (xy 168.784767 -354.190109) (xy 168.807409 -354.239686)
			(xy 168.822764 -354.291981) (xy 168.83052 -354.345929) (xy 168.831006 -354.37318) (xy 168.830505 -354.40122)
			(xy 168.822306 -354.456698) (xy 168.806083 -354.51038) (xy 168.782182 -354.561112) (xy 168.75112 -354.607804)
			(xy 168.732708 -354.628958) (xy 168.728189 -354.634292) (xy 176.045366 -354.634292) (xy 176.049437 -354.57867)
			(xy 176.061563 -354.524233) (xy 176.081486 -354.472142) (xy 176.108782 -354.423507) (xy 176.142868 -354.379364)
			(xy 176.183017 -354.340655) (xy 176.228375 -354.308204) (xy 176.277975 -354.282703) (xy 176.330759 -354.264696)
			(xy 176.385602 -354.254566) (xy 176.441336 -354.252529) (xy 176.496773 -354.258629) (xy 176.55073 -354.272735)
			(xy 176.602059 -354.294547) (xy 176.649665 -354.323601) (xy 176.692533 -354.359276) (xy 176.72975 -354.400813)
			(xy 176.760523 -354.447326) (xy 176.784195 -354.497823) (xy 176.800263 -354.55123) (xy 176.808383 -354.606406)
			(xy 176.808892 -354.634292) (xy 176.808383 -354.662178) (xy 176.800263 -354.717354) (xy 176.784195 -354.770761)
			(xy 176.760523 -354.821258) (xy 176.72975 -354.867771) (xy 176.692533 -354.909308) (xy 176.649665 -354.944983)
			(xy 176.602059 -354.974037) (xy 176.55073 -354.995849) (xy 176.496773 -355.009955) (xy 176.455195 -355.01453)
			(xy 177.756312 -355.01453) (xy 177.756793 -354.98716) (xy 177.764607 -354.932982) (xy 177.780092 -354.880479)
			(xy 177.802931 -354.830732) (xy 177.832652 -354.784764) (xy 177.850292 -354.763832) (xy 177.859501 -354.752483)
			(xy 177.871683 -354.725934) (xy 177.875861 -354.697023) (xy 177.871695 -354.66811) (xy 177.859525 -354.641555)
			(xy 177.850292 -354.630228) (xy 177.832651 -354.609297) (xy 177.80294 -354.563324) (xy 177.780104 -354.513576)
			(xy 177.764614 -354.461075) (xy 177.756786 -354.406899) (xy 177.756312 -354.37953) (xy 177.756798 -354.352279)
			(xy 177.764554 -354.298331) (xy 177.779909 -354.246036) (xy 177.802551 -354.196459) (xy 177.832017 -354.150609)
			(xy 177.867708 -354.109418) (xy 177.908899 -354.073727) (xy 177.954749 -354.044261) (xy 178.004326 -354.021619)
			(xy 178.056621 -354.006264) (xy 178.110569 -353.998508) (xy 178.165071 -353.998508) (xy 178.219019 -354.006264)
			(xy 178.271314 -354.021619) (xy 178.320891 -354.044261) (xy 178.366741 -354.073727) (xy 178.407932 -354.109418)
			(xy 178.443623 -354.150609) (xy 178.473089 -354.196459) (xy 178.495731 -354.246036) (xy 178.511086 -354.298331)
			(xy 178.518842 -354.352279) (xy 178.519328 -354.37953) (xy 178.518897 -354.406902) (xy 178.511073 -354.461083)
			(xy 178.495577 -354.513587) (xy 178.472727 -354.563334) (xy 178.442994 -354.609298) (xy 178.425348 -354.630228)
			(xy 178.419106 -354.637848) (xy 185.603386 -354.637848) (xy 185.607457 -354.582226) (xy 185.619583 -354.527789)
			(xy 185.639506 -354.475698) (xy 185.666802 -354.427063) (xy 185.700888 -354.38292) (xy 185.741037 -354.344211)
			(xy 185.786395 -354.31176) (xy 185.835995 -354.286259) (xy 185.888779 -354.268252) (xy 185.943622 -354.258122)
			(xy 185.999356 -354.256085) (xy 186.054793 -354.262185) (xy 186.10875 -354.276291) (xy 186.160079 -354.298103)
			(xy 186.207685 -354.327157) (xy 186.250553 -354.362832) (xy 186.28777 -354.404369) (xy 186.318543 -354.450882)
			(xy 186.342215 -354.501379) (xy 186.358283 -354.554786) (xy 186.366403 -354.609962) (xy 186.366912 -354.637848)
			(xy 186.366403 -354.665734) (xy 186.358283 -354.72091) (xy 186.342215 -354.774317) (xy 186.318543 -354.824814)
			(xy 186.28777 -354.871327) (xy 186.250553 -354.912864) (xy 186.207685 -354.948539) (xy 186.160079 -354.977593)
			(xy 186.10875 -354.999405) (xy 186.054793 -355.013511) (xy 185.999356 -355.019611) (xy 185.943622 -355.017574)
			(xy 185.888779 -355.007444) (xy 185.835995 -354.989437) (xy 185.786395 -354.963936) (xy 185.741037 -354.931485)
			(xy 185.700888 -354.892776) (xy 185.666802 -354.848633) (xy 185.639506 -354.799998) (xy 185.619583 -354.747907)
			(xy 185.607457 -354.69347) (xy 185.603386 -354.637848) (xy 178.419106 -354.637848) (xy 178.416086 -354.641535)
			(xy 178.403918 -354.668101) (xy 178.399754 -354.697023) (xy 178.403931 -354.725942) (xy 178.416111 -354.752503)
			(xy 178.425348 -354.763832) (xy 178.442961 -354.784786) (xy 178.472678 -354.830752) (xy 178.49552 -354.880494)
			(xy 178.511017 -354.93299) (xy 178.518851 -354.987162) (xy 178.519328 -355.01453) (xy 178.518842 -355.041781)
			(xy 178.511086 -355.095729) (xy 178.495731 -355.148024) (xy 178.473089 -355.197601) (xy 178.443623 -355.243451)
			(xy 178.407932 -355.284642) (xy 178.366741 -355.320333) (xy 178.320891 -355.349799) (xy 178.271314 -355.372441)
			(xy 178.219019 -355.387796) (xy 178.165071 -355.395552) (xy 178.110569 -355.395552) (xy 178.056621 -355.387796)
			(xy 178.004326 -355.372441) (xy 177.954749 -355.349799) (xy 177.908899 -355.320333) (xy 177.867708 -355.284642)
			(xy 177.832017 -355.243451) (xy 177.802551 -355.197601) (xy 177.779909 -355.148024) (xy 177.764554 -355.095729)
			(xy 177.756798 -355.041781) (xy 177.756312 -355.01453) (xy 176.455195 -355.01453) (xy 176.441336 -355.016055)
			(xy 176.385602 -355.014018) (xy 176.330759 -355.003888) (xy 176.277975 -354.985881) (xy 176.228375 -354.96038)
			(xy 176.183017 -354.927929) (xy 176.142868 -354.88922) (xy 176.108782 -354.845077) (xy 176.081486 -354.796442)
			(xy 176.061563 -354.744351) (xy 176.049437 -354.689914) (xy 176.045366 -354.634292) (xy 168.728189 -354.634292)
			(xy 168.723034 -354.640377) (xy 168.710259 -354.667429) (xy 168.705879 -354.697022) (xy 168.710272 -354.726614)
			(xy 168.723059 -354.75366) (xy 168.732708 -354.765102) (xy 168.751151 -354.786234) (xy 168.782243 -354.832916)
			(xy 168.806154 -354.883652) (xy 168.822368 -354.937345) (xy 168.830536 -354.992835) (xy 168.831006 -355.02088)
			(xy 168.83052 -355.048131) (xy 168.822764 -355.102079) (xy 168.807409 -355.154374) (xy 168.784767 -355.203951)
			(xy 168.755301 -355.249801) (xy 168.71961 -355.290992) (xy 168.678419 -355.326683) (xy 168.632569 -355.356149)
			(xy 168.582992 -355.378791) (xy 168.530697 -355.394146) (xy 168.476749 -355.401902) (xy 168.422247 -355.401902)
			(xy 168.368299 -355.394146) (xy 168.316004 -355.378791) (xy 168.266427 -355.356149) (xy 168.220577 -355.326683)
			(xy 168.179386 -355.290992) (xy 168.143695 -355.249801) (xy 168.114229 -355.203951) (xy 168.091587 -355.154374)
			(xy 168.076232 -355.102079) (xy 168.068476 -355.048131) (xy 168.06799 -355.02088) (xy 166.179311 -355.02088)
			(xy 166.17569 -355.02215) (xy 166.139876 -355.034088) (xy 166.152929 -355.4171) (xy 172.316679 -355.4171)
			(xy 172.320847 -355.361492) (xy 172.333255 -355.307126) (xy 172.353627 -355.255216) (xy 172.381508 -355.206922)
			(xy 172.416275 -355.163323) (xy 172.457152 -355.125392) (xy 172.503225 -355.093977) (xy 172.553465 -355.069779)
			(xy 172.606751 -355.053339) (xy 172.661892 -355.045025) (xy 172.689774 -355.044502) (xy 172.717106 -355.044977)
			(xy 172.771185 -355.052948) (xy 172.823518 -355.068736) (xy 172.872982 -355.092004) (xy 172.918514 -355.122251)
			(xy 172.959137 -355.158828) (xy 172.993977 -355.200949) (xy 173.008544 -355.22408) (xy 173.016453 -355.236315)
			(xy 173.037926 -355.255989) (xy 173.064084 -355.268794) (xy 173.092794 -355.273686) (xy 173.121716 -355.270266)
			(xy 173.13529 -355.264974) (xy 173.158503 -355.255494) (xy 173.206835 -355.24214) (xy 173.256523 -355.235408)
			(xy 173.281594 -355.235002) (xy 173.306663 -355.235442) (xy 173.356345 -355.242185) (xy 173.40468 -355.255511)
			(xy 173.427898 -355.264974) (xy 173.441482 -355.270214) (xy 173.470388 -355.273597) (xy 173.499075 -355.268699)
			(xy 173.52522 -355.255916) (xy 173.546704 -355.236283) (xy 173.554644 -355.22408) (xy 173.569213 -355.200949)
			(xy 173.604056 -355.158828) (xy 173.644679 -355.122249) (xy 173.69021 -355.091998) (xy 173.739672 -355.068722)
			(xy 173.792003 -355.052922) (xy 173.846082 -355.044936) (xy 173.900746 -355.044936) (xy 173.954825 -355.052922)
			(xy 174.007156 -355.068722) (xy 174.056618 -355.091998) (xy 174.102149 -355.122249) (xy 174.142772 -355.158828)
			(xy 174.177615 -355.200949) (xy 174.192184 -355.22408) (xy 174.20015 -355.236274) (xy 174.221608 -355.255948)
			(xy 174.24775 -355.268758) (xy 174.276446 -355.273661) (xy 174.305358 -355.270257) (xy 174.31893 -355.264974)
			(xy 174.342139 -355.255482) (xy 174.390472 -355.242132) (xy 174.440162 -355.235405) (xy 174.465234 -355.235002)
			(xy 174.492078 -355.23542) (xy 174.545211 -355.24313) (xy 174.596686 -355.258385) (xy 174.64544 -355.280868)
			(xy 174.690463 -355.310116) (xy 174.730823 -355.345522) (xy 174.765683 -355.386354) (xy 174.794323 -355.431765)
			(xy 174.81615 -355.480817) (xy 174.823882 -355.506528) (xy 174.828594 -355.521008) (xy 174.845101 -355.546571)
			(xy 174.868405 -355.566137) (xy 174.896439 -355.577971) (xy 174.926716 -355.58102) (xy 174.956547 -355.575016)
			(xy 174.970186 -355.56825) (xy 174.998325 -355.553603) (xy 175.05828 -355.532881) (xy 175.120841 -355.522389)
			(xy 175.152558 -355.521768) (xy 175.170577 -355.521985) (xy 175.206452 -355.525422) (xy 175.224186 -355.528626)
			(xy 175.239394 -355.530974) (xy 175.269951 -355.527449) (xy 175.298072 -355.514987) (xy 175.321208 -355.494718)
			(xy 175.337261 -355.46848) (xy 175.341534 -355.453696) (xy 175.348943 -355.426655) (xy 175.370568 -355.374927)
			(xy 175.399529 -355.32692) (xy 175.435203 -355.283666) (xy 175.476821 -355.246098) (xy 175.523487 -355.215023)
			(xy 175.574199 -355.191111) (xy 175.627863 -355.174875) (xy 175.683325 -355.166666) (xy 175.711358 -355.166168)
			(xy 175.738609 -355.166694) (xy 175.792556 -355.174445) (xy 175.844851 -355.189794) (xy 175.89443 -355.21243)
			(xy 175.940282 -355.241892) (xy 175.981474 -355.277579) (xy 176.017169 -355.318765) (xy 176.046638 -355.364612)
			(xy 176.069282 -355.414187) (xy 176.070138 -355.4171) (xy 182.004979 -355.4171) (xy 182.009147 -355.36149)
			(xy 182.021556 -355.307122) (xy 182.04193 -355.25521) (xy 182.069813 -355.206915) (xy 182.104582 -355.163315)
			(xy 182.145461 -355.125384) (xy 182.191537 -355.09397) (xy 182.241781 -355.069773) (xy 182.29507 -355.053335)
			(xy 182.350213 -355.045023) (xy 182.378096 -355.044502) (xy 182.405428 -355.044959) (xy 182.459508 -355.052933)
			(xy 182.511842 -355.068725) (xy 182.561306 -355.091995) (xy 182.606838 -355.122245) (xy 182.64746 -355.158824)
			(xy 182.6823 -355.200947) (xy 182.696866 -355.22408) (xy 182.704754 -355.23633) (xy 182.726233 -355.256004)
			(xy 182.752397 -355.268807) (xy 182.781111 -355.273695) (xy 182.810037 -355.27027) (xy 182.823612 -355.264974)
			(xy 182.846823 -355.255487) (xy 182.895155 -355.242135) (xy 182.944844 -355.235406) (xy 182.969916 -355.235002)
			(xy 182.994985 -355.235435) (xy 183.044668 -355.242181) (xy 183.093002 -355.25551) (xy 183.11622 -355.264974)
			(xy 183.129796 -355.270237) (xy 183.158706 -355.273615) (xy 183.187396 -355.268712) (xy 183.213543 -355.255923)
			(xy 183.235026 -355.236286) (xy 183.242966 -355.22408) (xy 183.257535 -355.200949) (xy 183.292378 -355.158828)
			(xy 183.333001 -355.122249) (xy 183.378532 -355.091998) (xy 183.427994 -355.068722) (xy 183.480325 -355.052922)
			(xy 183.534404 -355.044936) (xy 183.589068 -355.044936) (xy 183.643147 -355.052922) (xy 183.695478 -355.068722)
			(xy 183.74494 -355.091998) (xy 183.790471 -355.122249) (xy 183.831094 -355.158828) (xy 183.865937 -355.200949)
			(xy 183.880506 -355.22408) (xy 183.888451 -355.236289) (xy 183.909915 -355.255963) (xy 183.936063 -355.268771)
			(xy 183.964764 -355.27367) (xy 183.99368 -355.270261) (xy 184.007252 -355.264974) (xy 184.030458 -355.255475)
			(xy 184.078793 -355.242128) (xy 184.128484 -355.235403) (xy 184.153556 -355.235002) (xy 184.180398 -355.23549)
			(xy 184.233527 -355.243189) (xy 184.285002 -355.258433) (xy 184.333755 -355.280907) (xy 184.378778 -355.310146)
			(xy 184.419139 -355.345544) (xy 184.454001 -355.386368) (xy 184.482643 -355.431774) (xy 184.504471 -355.48082)
			(xy 184.512204 -355.506528) (xy 184.516888 -355.521018) (xy 184.533399 -355.546585) (xy 184.55671 -355.566152)
			(xy 184.58475 -355.577984) (xy 184.615032 -355.58103) (xy 184.644867 -355.575019) (xy 184.658508 -355.56825)
			(xy 184.686661 -355.553631) (xy 184.746609 -355.5329) (xy 184.809164 -355.522395) (xy 184.84088 -355.521768)
			(xy 184.8589 -355.521982) (xy 184.894774 -355.525421) (xy 184.912508 -355.528626) (xy 184.927714 -355.530997)
			(xy 184.958273 -355.527466) (xy 184.986395 -355.514998) (xy 185.009532 -355.494724) (xy 185.025584 -355.468482)
			(xy 185.029856 -355.453696) (xy 185.037245 -355.426649) (xy 185.058872 -355.374919) (xy 185.087835 -355.326911)
			(xy 185.123511 -355.283658) (xy 185.165131 -355.24609) (xy 185.211801 -355.215015) (xy 185.262515 -355.191104)
			(xy 185.316182 -355.174871) (xy 185.371646 -355.166664) (xy 185.39968 -355.166168) (xy 185.42693 -355.166697)
			(xy 185.480875 -355.17445) (xy 185.533167 -355.189801) (xy 185.582742 -355.212438) (xy 185.628592 -355.2419)
			(xy 185.669782 -355.277587) (xy 185.705473 -355.318773) (xy 185.734941 -355.364619) (xy 185.757583 -355.414192)
			(xy 185.772941 -355.466482) (xy 185.7807 -355.520426) (xy 185.781188 -355.547676) (xy 185.78071 -355.57525)
			(xy 185.772761 -355.629823) (xy 185.757038 -355.682682) (xy 185.733871 -355.732729) (xy 185.70374 -355.778918)
			(xy 185.667274 -355.82029) (xy 185.646568 -355.838506) (xy 185.635698 -355.848431) (xy 185.61963 -355.873075)
			(xy 185.611247 -355.901275) (xy 185.611243 -355.930694) (xy 185.619617 -355.958897) (xy 185.635678 -355.983546)
			(xy 185.646568 -355.993446) (xy 185.667251 -356.011687) (xy 185.703717 -356.053054) (xy 185.733847 -356.09924)
			(xy 185.757012 -356.149284) (xy 185.77273 -356.202142) (xy 185.780673 -356.256712) (xy 185.780675 -356.311857)
			(xy 185.772737 -356.366428) (xy 185.757023 -356.419287) (xy 185.733862 -356.469333) (xy 185.703736 -356.515521)
			(xy 185.667273 -356.556891) (xy 185.646568 -356.575106) (xy 185.635698 -356.585031) (xy 185.61963 -356.609675)
			(xy 185.611247 -356.637875) (xy 185.611243 -356.667294) (xy 185.619617 -356.695497) (xy 185.635678 -356.720146)
			(xy 185.646568 -356.730046) (xy 185.66725 -356.748289) (xy 185.703724 -356.78965) (xy 185.73386 -356.835833)
			(xy 185.757032 -356.885875) (xy 185.772754 -356.938732) (xy 185.7807 -356.993303) (xy 185.781188 -357.020876)
			(xy 185.780722 -357.048129) (xy 185.772968 -357.102081) (xy 185.757614 -357.15438) (xy 185.734973 -357.203961)
			(xy 185.705506 -357.249816) (xy 185.669812 -357.291009) (xy 185.628619 -357.326703) (xy 185.582765 -357.356171)
			(xy 185.533184 -357.378813) (xy 185.480885 -357.394167) (xy 185.426933 -357.401922) (xy 185.39968 -357.402384)
			(xy 185.371824 -357.401891) (xy 185.316706 -357.393764) (xy 185.263355 -357.377715) (xy 185.212901 -357.354085)
			(xy 185.166416 -357.323374) (xy 185.124887 -357.286235) (xy 185.089195 -357.243456) (xy 185.060097 -357.195945)
			(xy 185.038211 -357.144711) (xy 185.030618 -357.117904) (xy 185.026394 -357.10377) (xy 185.010993 -357.078621)
			(xy 184.989063 -357.058905) (xy 184.962422 -357.046259) (xy 184.933281 -357.041732) (xy 184.918604 -357.043228)
			(xy 184.905587 -357.044895) (xy 184.879403 -357.046676) (xy 184.86628 -357.046784) (xy 184.852131 -357.046693)
			(xy 184.823908 -357.044657) (xy 184.809892 -357.04272) (xy 184.79654 -357.041169) (xy 184.769851 -357.044258)
			(xy 184.744897 -357.054218) (xy 184.723417 -357.070357) (xy 184.706905 -357.091552) (xy 184.696509 -357.116327)
			(xy 184.694322 -357.129588) (xy 184.690263 -357.156746) (xy 184.675284 -357.209576) (xy 184.652888 -357.259714)
			(xy 184.623536 -357.306124) (xy 184.587835 -357.347847) (xy 184.546523 -357.384023) (xy 184.500452 -357.413903)
			(xy 184.450573 -357.436871) (xy 184.397918 -357.452452) (xy 184.343572 -357.460326) (xy 184.316116 -357.460804)
			(xy 184.288863 -357.46033) (xy 184.234913 -357.452575) (xy 184.182615 -357.437221) (xy 184.133034 -357.41458)
			(xy 184.087181 -357.385113) (xy 184.045988 -357.34942) (xy 184.010294 -357.308229) (xy 183.980826 -357.262376)
			(xy 183.958184 -357.212797) (xy 183.942828 -357.160499) (xy 183.935071 -357.106549) (xy 183.934608 -357.079296)
			(xy 183.935068 -357.051721) (xy 183.943021 -356.997148) (xy 183.958747 -356.944288) (xy 183.981918 -356.894242)
			(xy 184.012052 -356.848052) (xy 184.04852 -356.806682) (xy 184.069228 -356.788466) (xy 184.080126 -356.77857)
			(xy 184.096194 -356.753918) (xy 184.104574 -356.72571) (xy 184.104573 -356.696284) (xy 184.096191 -356.668078)
			(xy 184.080123 -356.643426) (xy 184.069228 -356.633526) (xy 184.048532 -356.615298) (xy 184.012059 -356.573934)
			(xy 183.981924 -356.527748) (xy 183.958756 -356.477703) (xy 183.943037 -356.424843) (xy 183.935094 -356.37027)
			(xy 183.934608 -356.342696) (xy 183.935076 -356.316195) (xy 183.942417 -356.263705) (xy 183.956958 -356.212737)
			(xy 183.978418 -356.164275) (xy 184.006384 -356.119251) (xy 184.023 -356.098602) (xy 184.032398 -356.086423)
			(xy 184.0442 -356.058034) (xy 184.047035 -356.027421) (xy 184.040647 -355.997347) (xy 184.025613 -355.970529)
			(xy 184.003291 -355.949389) (xy 183.989726 -355.942138) (xy 183.96604 -355.93003) (xy 183.922058 -355.900108)
			(xy 183.882776 -355.864239) (xy 183.848991 -355.823151) (xy 183.834786 -355.80066) (xy 183.826864 -355.788436)
			(xy 183.80539 -355.76877) (xy 183.779237 -355.755968) (xy 183.750533 -355.751072) (xy 183.721614 -355.754481)
			(xy 183.70804 -355.759766) (xy 183.684836 -355.76927) (xy 183.6365 -355.782615) (xy 183.586808 -355.789337)
			(xy 183.561736 -355.789738) (xy 183.536666 -355.789326) (xy 183.486983 -355.782572) (xy 183.438649 -355.769235)
			(xy 183.415432 -355.759766) (xy 183.401852 -355.754528) (xy 183.372954 -355.751164) (xy 183.344277 -355.756074)
			(xy 183.318144 -355.76886) (xy 183.296668 -355.788488) (xy 183.288686 -355.80066) (xy 183.274117 -355.823791)
			(xy 183.239274 -355.865912) (xy 183.198651 -355.902491) (xy 183.15312 -355.932742) (xy 183.103658 -355.956018)
			(xy 183.051327 -355.971818) (xy 182.997248 -355.979804) (xy 182.942584 -355.979804) (xy 182.888505 -355.971818)
			(xy 182.836174 -355.956018) (xy 182.786712 -355.932742) (xy 182.741181 -355.902491) (xy 182.700558 -355.865912)
			(xy 182.665715 -355.823791) (xy 182.651146 -355.80066) (xy 182.643262 -355.788408) (xy 182.621778 -355.768742)
			(xy 182.595614 -355.755943) (xy 182.566901 -355.751055) (xy 182.537976 -355.754474) (xy 182.5244 -355.759766)
			(xy 182.501189 -355.769251) (xy 182.452856 -355.782603) (xy 182.403167 -355.789333) (xy 182.378096 -355.789738)
			(xy 182.350213 -355.789177) (xy 182.29507 -355.780865) (xy 182.241781 -355.764427) (xy 182.191537 -355.74023)
			(xy 182.145461 -355.708816) (xy 182.104582 -355.670885) (xy 182.069813 -355.627285) (xy 182.04193 -355.57899)
			(xy 182.021556 -355.527078) (xy 182.009147 -355.47271) (xy 182.004979 -355.4171) (xy 176.070138 -355.4171)
			(xy 176.084641 -355.466479) (xy 176.092401 -355.520425) (xy 176.092866 -355.547676) (xy 176.092396 -355.575251)
			(xy 176.084446 -355.629824) (xy 176.068722 -355.682684) (xy 176.045553 -355.73273) (xy 176.015421 -355.77892)
			(xy 175.978953 -355.820291) (xy 175.958246 -355.838506) (xy 175.947369 -355.848427) (xy 175.931289 -355.873069)
			(xy 175.922898 -355.901272) (xy 175.922894 -355.930697) (xy 175.931276 -355.958903) (xy 175.947348 -355.98355)
			(xy 175.958246 -355.993446) (xy 175.97893 -356.011686) (xy 176.015398 -356.053052) (xy 176.04553 -356.099239)
			(xy 176.068696 -356.149282) (xy 176.084415 -356.202141) (xy 176.092358 -356.256712) (xy 176.092361 -356.311857)
			(xy 176.084422 -356.366429) (xy 176.068707 -356.419288) (xy 176.045545 -356.469334) (xy 176.036694 -356.482904)
			(xy 178.547266 -356.482904) (xy 178.551337 -356.427282) (xy 178.563463 -356.372845) (xy 178.583386 -356.320754)
			(xy 178.610682 -356.272119) (xy 178.644768 -356.227976) (xy 178.684917 -356.189267) (xy 178.730275 -356.156816)
			(xy 178.779875 -356.131315) (xy 178.832659 -356.113308) (xy 178.887502 -356.103178) (xy 178.943236 -356.101141)
			(xy 178.998673 -356.107241) (xy 179.05263 -356.121347) (xy 179.103959 -356.143159) (xy 179.151565 -356.172213)
			(xy 179.194433 -356.207888) (xy 179.23165 -356.249425) (xy 179.262423 -356.295938) (xy 179.286095 -356.346435)
			(xy 179.302163 -356.399842) (xy 179.310283 -356.455018) (xy 179.310792 -356.482904) (xy 179.310283 -356.51079)
			(xy 179.302163 -356.565966) (xy 179.286095 -356.619373) (xy 179.262423 -356.66987) (xy 179.23165 -356.716383)
			(xy 179.194433 -356.75792) (xy 179.151565 -356.793595) (xy 179.103959 -356.822649) (xy 179.05263 -356.844461)
			(xy 178.998673 -356.858567) (xy 178.943236 -356.864667) (xy 178.887502 -356.86263) (xy 178.832659 -356.8525)
			(xy 178.779875 -356.834493) (xy 178.730275 -356.808992) (xy 178.684917 -356.776541) (xy 178.644768 -356.737832)
			(xy 178.610682 -356.693689) (xy 178.583386 -356.645054) (xy 178.563463 -356.592963) (xy 178.551337 -356.538526)
			(xy 178.547266 -356.482904) (xy 176.036694 -356.482904) (xy 176.015417 -356.515523) (xy 175.978952 -356.556892)
			(xy 175.958246 -356.575106) (xy 175.947369 -356.585027) (xy 175.931289 -356.609669) (xy 175.922898 -356.637872)
			(xy 175.922894 -356.667297) (xy 175.931276 -356.695503) (xy 175.947348 -356.72015) (xy 175.958246 -356.730046)
			(xy 175.978943 -356.748272) (xy 176.015413 -356.789639) (xy 176.045546 -356.835826) (xy 176.068713 -356.885871)
			(xy 176.084433 -356.93873) (xy 176.092378 -356.993302) (xy 176.092866 -357.020876) (xy 176.092422 -357.04813)
			(xy 176.084667 -357.102084) (xy 176.069312 -357.154385) (xy 176.04667 -357.203968) (xy 176.0172 -357.249823)
			(xy 175.981504 -357.291017) (xy 175.940308 -357.326711) (xy 175.894452 -357.356178) (xy 175.844868 -357.378819)
			(xy 175.792566 -357.394171) (xy 175.738612 -357.401924) (xy 175.711358 -357.402384) (xy 175.683501 -357.401911)
			(xy 175.628383 -357.393781) (xy 175.575031 -357.377729) (xy 175.524577 -357.354095) (xy 175.478092 -357.323382)
			(xy 175.436563 -357.286241) (xy 175.400871 -357.24346) (xy 175.371774 -357.195948) (xy 175.349889 -357.144711)
			(xy 175.342296 -357.117904) (xy 175.337994 -357.103798) (xy 175.322609 -357.078656) (xy 175.300697 -357.058941)
			(xy 175.274076 -357.046287) (xy 175.244953 -357.041743) (xy 175.230282 -357.043228) (xy 175.217265 -357.044897)
			(xy 175.191081 -357.046677) (xy 175.177958 -357.046784) (xy 175.163809 -357.046695) (xy 175.135586 -357.044658)
			(xy 175.12157 -357.04272) (xy 175.10822 -357.041147) (xy 175.081529 -357.044241) (xy 175.056574 -357.054206)
			(xy 175.035094 -357.070349) (xy 175.018582 -357.091547) (xy 175.008187 -357.116326) (xy 175.006 -357.129588)
			(xy 175.001962 -357.15675) (xy 174.986983 -357.209582) (xy 174.964584 -357.259721) (xy 174.935231 -357.306132)
			(xy 174.899527 -357.347855) (xy 174.858212 -357.384031) (xy 174.812138 -357.41391) (xy 174.762257 -357.436877)
			(xy 174.709599 -357.452457) (xy 174.655251 -357.460327) (xy 174.627794 -357.460804) (xy 177.882802 -357.460804)
			(xy 177.886873 -357.405182) (xy 177.898999 -357.350745) (xy 177.918922 -357.298654) (xy 177.946218 -357.250019)
			(xy 177.980304 -357.205876) (xy 178.020453 -357.167167) (xy 178.065811 -357.134716) (xy 178.115411 -357.109215)
			(xy 178.168195 -357.091208) (xy 178.223038 -357.081078) (xy 178.278772 -357.079041) (xy 178.334209 -357.085141)
			(xy 178.388166 -357.099247) (xy 178.439495 -357.121059) (xy 178.487101 -357.150113) (xy 178.529969 -357.185788)
			(xy 178.567186 -357.227325) (xy 178.597959 -357.273838) (xy 178.621631 -357.324335) (xy 178.637699 -357.377742)
			(xy 178.645819 -357.432918) (xy 178.646328 -357.460804) (xy 178.645819 -357.48869) (xy 178.637699 -357.543866)
			(xy 178.621631 -357.597273) (xy 178.597959 -357.64777) (xy 178.567186 -357.694283) (xy 178.529969 -357.73582)
			(xy 178.487101 -357.771495) (xy 178.439495 -357.800549) (xy 178.388166 -357.822361) (xy 178.334209 -357.836467)
			(xy 178.278772 -357.842567) (xy 178.223038 -357.84053) (xy 178.168195 -357.8304) (xy 178.115411 -357.812393)
			(xy 178.065811 -357.786892) (xy 178.020453 -357.754441) (xy 177.980304 -357.715732) (xy 177.946218 -357.671589)
			(xy 177.918922 -357.622954) (xy 177.898999 -357.570863) (xy 177.886873 -357.516426) (xy 177.882802 -357.460804)
			(xy 174.627794 -357.460804) (xy 174.600542 -357.460328) (xy 174.546594 -357.45257) (xy 174.494299 -357.437214)
			(xy 174.444721 -357.414572) (xy 174.398871 -357.385105) (xy 174.357681 -357.349412) (xy 174.321989 -357.308221)
			(xy 174.292523 -357.26237) (xy 174.269882 -357.212792) (xy 174.254528 -357.160496) (xy 174.246772 -357.106548)
			(xy 174.246286 -357.079296) (xy 174.246754 -357.051722) (xy 174.254707 -356.997149) (xy 174.270432 -356.944289)
			(xy 174.293601 -356.894244) (xy 174.323733 -356.848054) (xy 174.3602 -356.806682) (xy 174.380906 -356.788466)
			(xy 174.391806 -356.778571) (xy 174.407877 -356.753919) (xy 174.41626 -356.725711) (xy 174.416259 -356.696284)
			(xy 174.407875 -356.668076) (xy 174.391803 -356.643425) (xy 174.380906 -356.633526) (xy 174.360205 -356.615303)
			(xy 174.323734 -356.573937) (xy 174.2936 -356.52775) (xy 174.270433 -356.477704) (xy 174.254714 -356.424843)
			(xy 174.246772 -356.37027) (xy 174.246286 -356.342696) (xy 174.246759 -356.316196) (xy 174.2541 -356.263705)
			(xy 174.26864 -356.212738) (xy 174.290099 -356.164275) (xy 174.318063 -356.119252) (xy 174.334678 -356.098602)
			(xy 174.344049 -356.086407) (xy 174.355839 -356.058023) (xy 174.35867 -356.027419) (xy 174.352287 -355.997354)
			(xy 174.337266 -355.97054) (xy 174.31496 -355.949395) (xy 174.301404 -355.942138) (xy 174.277714 -355.930037)
			(xy 174.233734 -355.900113) (xy 174.194453 -355.864242) (xy 174.160669 -355.823152) (xy 174.146464 -355.80066)
			(xy 174.138563 -355.788421) (xy 174.117083 -355.768755) (xy 174.090924 -355.755954) (xy 174.062215 -355.751063)
			(xy 174.033293 -355.754477) (xy 174.019718 -355.759766) (xy 173.996504 -355.769246) (xy 173.948173 -355.7826)
			(xy 173.898485 -355.789332) (xy 173.873414 -355.789738) (xy 173.848345 -355.7893) (xy 173.798662 -355.782557)
			(xy 173.750328 -355.76923) (xy 173.72711 -355.759766) (xy 173.713502 -355.75461) (xy 173.684618 -355.751229)
			(xy 173.655952 -355.756121) (xy 173.629823 -355.768887) (xy 173.608347 -355.788496) (xy 173.600364 -355.80066)
			(xy 173.585795 -355.823791) (xy 173.550952 -355.865912) (xy 173.510329 -355.902491) (xy 173.464798 -355.932742)
			(xy 173.415336 -355.956018) (xy 173.363005 -355.971818) (xy 173.308926 -355.979804) (xy 173.254262 -355.979804)
			(xy 173.200183 -355.971818) (xy 173.147852 -355.956018) (xy 173.09839 -355.932742) (xy 173.052859 -355.902491)
			(xy 173.012236 -355.865912) (xy 172.977393 -355.823791) (xy 172.962824 -355.80066) (xy 172.954866 -355.788462)
			(xy 172.933402 -355.768796) (xy 172.907258 -355.75599) (xy 172.878563 -355.751087) (xy 172.849651 -355.754487)
			(xy 172.836078 -355.759766) (xy 172.812869 -355.769258) (xy 172.764536 -355.782607) (xy 172.714846 -355.789335)
			(xy 172.689774 -355.789738) (xy 172.661892 -355.789175) (xy 172.606751 -355.780861) (xy 172.553465 -355.764421)
			(xy 172.503225 -355.740223) (xy 172.457152 -355.708808) (xy 172.416275 -355.670877) (xy 172.381508 -355.627278)
			(xy 172.353627 -355.578984) (xy 172.333255 -355.527074) (xy 172.320847 -355.472708) (xy 172.316679 -355.4171)
			(xy 166.152929 -355.4171) (xy 166.189252 -356.482904) (xy 168.858944 -356.482904) (xy 168.863015 -356.427282)
			(xy 168.875141 -356.372845) (xy 168.895064 -356.320754) (xy 168.92236 -356.272119) (xy 168.956446 -356.227976)
			(xy 168.996595 -356.189267) (xy 169.041953 -356.156816) (xy 169.091553 -356.131315) (xy 169.144337 -356.113308)
			(xy 169.19918 -356.103178) (xy 169.254914 -356.101141) (xy 169.310351 -356.107241) (xy 169.364308 -356.121347)
			(xy 169.415637 -356.143159) (xy 169.463243 -356.172213) (xy 169.506111 -356.207888) (xy 169.543328 -356.249425)
			(xy 169.574101 -356.295938) (xy 169.597773 -356.346435) (xy 169.613841 -356.399842) (xy 169.621961 -356.455018)
			(xy 169.62247 -356.482904) (xy 169.621961 -356.51079) (xy 169.613841 -356.565966) (xy 169.597773 -356.619373)
			(xy 169.574101 -356.66987) (xy 169.543328 -356.716383) (xy 169.506111 -356.75792) (xy 169.463243 -356.793595)
			(xy 169.415637 -356.822649) (xy 169.364308 -356.844461) (xy 169.310351 -356.858567) (xy 169.254914 -356.864667)
			(xy 169.19918 -356.86263) (xy 169.144337 -356.8525) (xy 169.091553 -356.834493) (xy 169.041953 -356.808992)
			(xy 168.996595 -356.776541) (xy 168.956446 -356.737832) (xy 168.92236 -356.693689) (xy 168.895064 -356.645054)
			(xy 168.875141 -356.592963) (xy 168.863015 -356.538526) (xy 168.858944 -356.482904) (xy 166.189252 -356.482904)
			(xy 166.222173 -357.448866) (xy 168.19448 -357.448866) (xy 168.198551 -357.393244) (xy 168.210677 -357.338807)
			(xy 168.2306 -357.286716) (xy 168.257896 -357.238081) (xy 168.291982 -357.193938) (xy 168.332131 -357.155229)
			(xy 168.377489 -357.122778) (xy 168.427089 -357.097277) (xy 168.479873 -357.07927) (xy 168.534716 -357.06914)
			(xy 168.59045 -357.067103) (xy 168.645887 -357.073203) (xy 168.699844 -357.087309) (xy 168.751173 -357.109121)
			(xy 168.798779 -357.138175) (xy 168.841647 -357.17385) (xy 168.878864 -357.215387) (xy 168.909637 -357.2619)
			(xy 168.933309 -357.312397) (xy 168.949377 -357.365804) (xy 168.957497 -357.42098) (xy 168.958006 -357.448866)
			(xy 168.957497 -357.476752) (xy 168.949377 -357.531928) (xy 168.933309 -357.585335) (xy 168.909637 -357.635832)
			(xy 168.878864 -357.682345) (xy 168.841647 -357.723882) (xy 168.798779 -357.759557) (xy 168.751173 -357.788611)
			(xy 168.699844 -357.810423) (xy 168.645887 -357.824529) (xy 168.59045 -357.830629) (xy 168.534716 -357.828592)
			(xy 168.479873 -357.818462) (xy 168.427089 -357.800455) (xy 168.377489 -357.774954) (xy 168.332131 -357.742503)
			(xy 168.291982 -357.703794) (xy 168.257896 -357.659651) (xy 168.2306 -357.611016) (xy 168.210677 -357.558925)
			(xy 168.198551 -357.504488) (xy 168.19448 -357.448866) (xy 166.222173 -357.448866) (xy 166.240663 -357.99141)
			(xy 169.66565 -357.99141) (xy 169.666086 -357.966072) (xy 169.672793 -357.915843) (xy 169.686091 -357.866943)
			(xy 169.705744 -357.820235) (xy 169.731409 -357.776539) (xy 169.762632 -357.736625) (xy 169.780458 -357.718614)
			(xy 169.789846 -357.708834) (xy 169.803642 -357.685512) (xy 169.810797 -357.659378) (xy 169.810805 -357.632282)
			(xy 169.803665 -357.606143) (xy 169.789883 -357.582814) (xy 169.780458 -357.573072) (xy 169.762627 -357.555065)
			(xy 169.731397 -357.515153) (xy 169.705728 -357.471458) (xy 169.68607 -357.424748) (xy 169.67277 -357.375847)
			(xy 169.666063 -357.325615) (xy 169.66565 -357.300276) (xy 169.666136 -357.273025) (xy 169.673892 -357.219077)
			(xy 169.689247 -357.166782) (xy 169.711889 -357.117205) (xy 169.741355 -357.071355) (xy 169.777046 -357.030164)
			(xy 169.818237 -356.994473) (xy 169.864087 -356.965007) (xy 169.913664 -356.942365) (xy 169.965959 -356.92701)
			(xy 170.019907 -356.919254) (xy 170.074409 -356.919254) (xy 170.128357 -356.92701) (xy 170.180652 -356.942365)
			(xy 170.230229 -356.965007) (xy 170.276079 -356.994473) (xy 170.31727 -357.030164) (xy 170.352961 -357.071355)
			(xy 170.382427 -357.117205) (xy 170.405069 -357.166782) (xy 170.420424 -357.219077) (xy 170.42818 -357.273025)
			(xy 170.428326 -357.281226) (xy 171.290996 -357.281226) (xy 171.291482 -357.253975) (xy 171.299238 -357.200027)
			(xy 171.314593 -357.147732) (xy 171.337235 -357.098155) (xy 171.366701 -357.052305) (xy 171.402392 -357.011114)
			(xy 171.443583 -356.975423) (xy 171.489433 -356.945957) (xy 171.53901 -356.923315) (xy 171.591305 -356.90796)
			(xy 171.645253 -356.900204) (xy 171.699755 -356.900204) (xy 171.753703 -356.90796) (xy 171.805998 -356.923315)
			(xy 171.855575 -356.945957) (xy 171.901425 -356.975423) (xy 171.942616 -357.011114) (xy 171.978307 -357.052305)
			(xy 172.007773 -357.098155) (xy 172.030415 -357.147732) (xy 172.04577 -357.200027) (xy 172.053526 -357.253975)
			(xy 172.054012 -357.281226) (xy 172.05377 -357.299893) (xy 172.050079 -357.337044) (xy 172.046646 -357.355394)
			(xy 172.044279 -357.369658) (xy 172.046811 -357.398451) (xy 172.057314 -357.425379) (xy 172.074943 -357.448283)
			(xy 172.098287 -357.465328) (xy 172.125472 -357.475145) (xy 172.139864 -357.476552) (xy 172.168516 -357.478943)
			(xy 172.224682 -357.491225) (xy 172.278369 -357.511796) (xy 172.328362 -357.54019) (xy 172.373528 -357.575762)
			(xy 172.412846 -357.61771) (xy 172.445425 -357.665081) (xy 172.470528 -357.716805) (xy 172.487586 -357.771709)
			(xy 172.496212 -357.828551) (xy 172.496734 -357.857298) (xy 172.496248 -357.884549) (xy 172.488492 -357.938497)
			(xy 172.473137 -357.990792) (xy 172.450495 -358.040369) (xy 172.441966 -358.05364) (xy 179.353972 -358.05364)
			(xy 179.35445 -358.025192) (xy 179.362913 -357.96893) (xy 179.379643 -357.91455) (xy 179.404268 -357.86326)
			(xy 179.436242 -357.816198) (xy 179.474853 -357.77441) (xy 179.49672 -357.756206) (xy 179.508238 -357.746308)
			(xy 179.525265 -357.721175) (xy 179.534167 -357.692153) (xy 179.534159 -357.661795) (xy 179.525242 -357.632777)
			(xy 179.508202 -357.607653) (xy 179.49672 -357.59771) (xy 179.474849 -357.579513) (xy 179.436246 -357.537721)
			(xy 179.404282 -357.490657) (xy 179.379667 -357.439365) (xy 179.362948 -357.384984) (xy 179.354497 -357.328722)
			(xy 179.353972 -357.300276) (xy 179.354458 -357.273025) (xy 179.362214 -357.219077) (xy 179.377569 -357.166782)
			(xy 179.400211 -357.117205) (xy 179.429677 -357.071355) (xy 179.465368 -357.030164) (xy 179.506559 -356.994473)
			(xy 179.552409 -356.965007) (xy 179.601986 -356.942365) (xy 179.654281 -356.92701) (xy 179.708229 -356.919254)
			(xy 179.762731 -356.919254) (xy 179.816679 -356.92701) (xy 179.868974 -356.942365) (xy 179.918551 -356.965007)
			(xy 179.964401 -356.994473) (xy 180.005592 -357.030164) (xy 180.041283 -357.071355) (xy 180.070749 -357.117205)
			(xy 180.093391 -357.166782) (xy 180.108746 -357.219077) (xy 180.116502 -357.273025) (xy 180.116648 -357.281226)
			(xy 180.979318 -357.281226) (xy 180.979804 -357.253975) (xy 180.98756 -357.200027) (xy 181.002915 -357.147732)
			(xy 181.025557 -357.098155) (xy 181.055023 -357.052305) (xy 181.090714 -357.011114) (xy 181.131905 -356.975423)
			(xy 181.177755 -356.945957) (xy 181.227332 -356.923315) (xy 181.279627 -356.90796) (xy 181.333575 -356.900204)
			(xy 181.388077 -356.900204) (xy 181.442025 -356.90796) (xy 181.49432 -356.923315) (xy 181.543897 -356.945957)
			(xy 181.589747 -356.975423) (xy 181.630938 -357.011114) (xy 181.666629 -357.052305) (xy 181.696095 -357.098155)
			(xy 181.718737 -357.147732) (xy 181.734092 -357.200027) (xy 181.741848 -357.253975) (xy 181.742334 -357.281226)
			(xy 181.742101 -357.299893) (xy 181.738409 -357.337045) (xy 181.734968 -357.355394) (xy 181.73258 -357.369656)
			(xy 181.735113 -357.398452) (xy 181.745618 -357.425384) (xy 181.763252 -357.44829) (xy 181.786601 -357.465334)
			(xy 181.813792 -357.475148) (xy 181.828186 -357.476552) (xy 181.85684 -357.478924) (xy 181.913006 -357.49121)
			(xy 181.966693 -357.511783) (xy 182.016686 -357.540179) (xy 182.061852 -357.575754) (xy 182.10117 -357.617703)
			(xy 182.133748 -357.665077) (xy 182.158851 -357.716802) (xy 182.175908 -357.771707) (xy 182.184534 -357.828551)
			(xy 182.185056 -357.857298) (xy 182.18457 -357.884549) (xy 182.176814 -357.938497) (xy 182.161459 -357.990792)
			(xy 182.138817 -358.040369) (xy 182.109351 -358.086219) (xy 182.07366 -358.12741) (xy 182.032469 -358.163101)
			(xy 181.986619 -358.192567) (xy 181.937042 -358.215209) (xy 181.884747 -358.230564) (xy 181.830799 -358.23832)
			(xy 181.776297 -358.23832) (xy 181.722349 -358.230564) (xy 181.670054 -358.215209) (xy 181.620477 -358.192567)
			(xy 181.574627 -358.163101) (xy 181.533436 -358.12741) (xy 181.497745 -358.086219) (xy 181.468279 -358.040369)
			(xy 181.445637 -357.990792) (xy 181.430282 -357.938497) (xy 181.422526 -357.884549) (xy 181.42204 -357.857298)
			(xy 181.422277 -357.838631) (xy 181.425967 -357.801479) (xy 181.429406 -357.78313) (xy 181.431793 -357.768867)
			(xy 181.429265 -357.740068) (xy 181.418763 -357.713134) (xy 181.401128 -357.690227) (xy 181.377777 -357.673184)
			(xy 181.350583 -357.663373) (xy 181.336188 -357.661972) (xy 181.307535 -357.659599) (xy 181.25137 -357.64731)
			(xy 181.197685 -357.626735) (xy 181.147693 -357.598338) (xy 181.102528 -357.562763) (xy 181.063211 -357.520815)
			(xy 181.030633 -357.473442) (xy 181.00553 -357.421719) (xy 180.98847 -357.366815) (xy 180.979841 -357.309973)
			(xy 180.979318 -357.281226) (xy 180.116648 -357.281226) (xy 180.116988 -357.300276) (xy 180.116428 -357.32872)
			(xy 180.107979 -357.384978) (xy 180.091264 -357.439356) (xy 180.066654 -357.490646) (xy 180.034696 -357.53771)
			(xy 179.9961 -357.579502) (xy 179.97424 -357.59771) (xy 179.96281 -357.6077) (xy 179.945787 -357.632808)
			(xy 179.93688 -357.661806) (xy 179.936872 -357.692141) (xy 179.945764 -357.721144) (xy 179.962774 -357.746261)
			(xy 179.97424 -357.756206) (xy 179.99611 -357.774404) (xy 180.034716 -357.816194) (xy 180.066681 -357.863258)
			(xy 180.091296 -357.914551) (xy 180.108014 -357.968932) (xy 180.110284 -357.984044) (xy 180.369462 -357.984044)
			(xy 180.373533 -357.928422) (xy 180.385659 -357.873985) (xy 180.405582 -357.821894) (xy 180.432878 -357.773259)
			(xy 180.466964 -357.729116) (xy 180.507113 -357.690407) (xy 180.552471 -357.657956) (xy 180.602071 -357.632455)
			(xy 180.654855 -357.614448) (xy 180.709698 -357.604318) (xy 180.765432 -357.602281) (xy 180.820869 -357.608381)
			(xy 180.874826 -357.622487) (xy 180.926155 -357.644299) (xy 180.973761 -357.673353) (xy 181.016629 -357.709028)
			(xy 181.053846 -357.750565) (xy 181.084619 -357.797078) (xy 181.108291 -357.847575) (xy 181.124359 -357.900982)
			(xy 181.132479 -357.956158) (xy 181.132988 -357.984044) (xy 181.132479 -358.01193) (xy 181.124359 -358.067106)
			(xy 181.108291 -358.120513) (xy 181.084619 -358.17101) (xy 181.053846 -358.217523) (xy 181.016629 -358.25906)
			(xy 180.973761 -358.294735) (xy 180.926155 -358.323789) (xy 180.874826 -358.345601) (xy 180.820869 -358.359707)
			(xy 180.765432 -358.365807) (xy 180.709698 -358.36377) (xy 180.654855 -358.35364) (xy 180.602071 -358.335633)
			(xy 180.552471 -358.310132) (xy 180.507113 -358.277681) (xy 180.466964 -358.238972) (xy 180.432878 -358.194829)
			(xy 180.405582 -358.146194) (xy 180.385659 -358.094103) (xy 180.373533 -358.039666) (xy 180.369462 -357.984044)
			(xy 180.110284 -357.984044) (xy 180.116464 -358.025193) (xy 180.116988 -358.05364) (xy 180.116502 -358.080891)
			(xy 180.108746 -358.134839) (xy 180.093391 -358.187134) (xy 180.070749 -358.236711) (xy 180.041283 -358.282561)
			(xy 180.005592 -358.323752) (xy 179.964401 -358.359443) (xy 179.918551 -358.388909) (xy 179.868974 -358.411551)
			(xy 179.816679 -358.426906) (xy 179.762731 -358.434662) (xy 179.708229 -358.434662) (xy 179.654281 -358.426906)
			(xy 179.601986 -358.411551) (xy 179.552409 -358.388909) (xy 179.506559 -358.359443) (xy 179.465368 -358.323752)
			(xy 179.429677 -358.282561) (xy 179.400211 -358.236711) (xy 179.377569 -358.187134) (xy 179.362214 -358.134839)
			(xy 179.354458 -358.080891) (xy 179.353972 -358.05364) (xy 172.441966 -358.05364) (xy 172.421029 -358.086219)
			(xy 172.385338 -358.12741) (xy 172.344147 -358.163101) (xy 172.298297 -358.192567) (xy 172.24872 -358.215209)
			(xy 172.196425 -358.230564) (xy 172.142477 -358.23832) (xy 172.087975 -358.23832) (xy 172.034027 -358.230564)
			(xy 171.981732 -358.215209) (xy 171.932155 -358.192567) (xy 171.886305 -358.163101) (xy 171.845114 -358.12741)
			(xy 171.809423 -358.086219) (xy 171.779957 -358.040369) (xy 171.757315 -357.990792) (xy 171.74196 -357.938497)
			(xy 171.734204 -357.884549) (xy 171.733718 -357.857298) (xy 171.733956 -357.838631) (xy 171.737645 -357.801479)
			(xy 171.741084 -357.78313) (xy 171.743398 -357.76886) (xy 171.740872 -357.740075) (xy 171.730379 -357.713153)
			(xy 171.71276 -357.690251) (xy 171.689428 -357.673205) (xy 171.662253 -357.663383) (xy 171.647866 -357.661972)
			(xy 171.619211 -357.659618) (xy 171.563046 -357.647326) (xy 171.50936 -357.626748) (xy 171.459369 -357.598348)
			(xy 171.414205 -357.562771) (xy 171.374888 -357.520821) (xy 171.34231 -357.473447) (xy 171.317207 -357.421722)
			(xy 171.300148 -357.366816) (xy 171.291519 -357.309973) (xy 171.290996 -357.281226) (xy 170.428326 -357.281226)
			(xy 170.428666 -357.300276) (xy 170.428216 -357.325613) (xy 170.421511 -357.375842) (xy 170.408216 -357.424741)
			(xy 170.388565 -357.47145) (xy 170.362903 -357.515146) (xy 170.331683 -357.555061) (xy 170.313858 -357.573072)
			(xy 170.30443 -357.582799) (xy 170.290719 -357.606154) (xy 170.283619 -357.632289) (xy 170.283627 -357.659371)
			(xy 170.290743 -357.685502) (xy 170.304467 -357.708849) (xy 170.313858 -357.718614) (xy 170.331685 -357.736625)
			(xy 170.362915 -357.776536) (xy 170.388585 -357.820231) (xy 170.408243 -357.86694) (xy 170.421543 -357.91584)
			(xy 170.428252 -357.966071) (xy 170.428546 -357.984044) (xy 170.68114 -357.984044) (xy 170.685211 -357.928422)
			(xy 170.697337 -357.873985) (xy 170.71726 -357.821894) (xy 170.744556 -357.773259) (xy 170.778642 -357.729116)
			(xy 170.818791 -357.690407) (xy 170.864149 -357.657956) (xy 170.913749 -357.632455) (xy 170.966533 -357.614448)
			(xy 171.021376 -357.604318) (xy 171.07711 -357.602281) (xy 171.132547 -357.608381) (xy 171.186504 -357.622487)
			(xy 171.237833 -357.644299) (xy 171.285439 -357.673353) (xy 171.328307 -357.709028) (xy 171.365524 -357.750565)
			(xy 171.396297 -357.797078) (xy 171.419969 -357.847575) (xy 171.436037 -357.900982) (xy 171.444157 -357.956158)
			(xy 171.444666 -357.984044) (xy 171.444157 -358.01193) (xy 171.436037 -358.067106) (xy 171.419969 -358.120513)
			(xy 171.396297 -358.17101) (xy 171.365524 -358.217523) (xy 171.328307 -358.25906) (xy 171.285439 -358.294735)
			(xy 171.237833 -358.323789) (xy 171.186504 -358.345601) (xy 171.132547 -358.359707) (xy 171.07711 -358.365807)
			(xy 171.021376 -358.36377) (xy 170.966533 -358.35364) (xy 170.913749 -358.335633) (xy 170.864149 -358.310132)
			(xy 170.818791 -358.277681) (xy 170.778642 -358.238972) (xy 170.744556 -358.194829) (xy 170.71726 -358.146194)
			(xy 170.697337 -358.094103) (xy 170.685211 -358.039666) (xy 170.68114 -357.984044) (xy 170.428546 -357.984044)
			(xy 170.428666 -357.99141) (xy 170.42818 -358.018661) (xy 170.420424 -358.072609) (xy 170.405069 -358.124904)
			(xy 170.382427 -358.174481) (xy 170.352961 -358.220331) (xy 170.31727 -358.261522) (xy 170.276079 -358.297213)
			(xy 170.230229 -358.326679) (xy 170.180652 -358.349321) (xy 170.128357 -358.364676) (xy 170.074409 -358.372432)
			(xy 170.019907 -358.372432) (xy 169.965959 -358.364676) (xy 169.913664 -358.349321) (xy 169.864087 -358.326679)
			(xy 169.818237 -358.297213) (xy 169.777046 -358.261522) (xy 169.741355 -358.220331) (xy 169.711889 -358.174481)
			(xy 169.689247 -358.124904) (xy 169.673892 -358.072609) (xy 169.666136 -358.018661) (xy 169.66565 -357.99141)
			(xy 166.240663 -357.99141) (xy 166.347648 -361.130596) (xy 166.3954 -361.178348) (xy 173.4312 -361.178348)
			(xy 173.7614 -361.508548) (xy 173.7614 -361.518962) (xy 175.165258 -361.518962) (xy 175.165781 -361.489792)
			(xy 175.174688 -361.432135) (xy 175.192271 -361.376507) (xy 175.218122 -361.324205) (xy 175.251636 -361.276451)
			(xy 175.292033 -361.234359) (xy 175.314864 -361.216194) (xy 175.325211 -361.207738) (xy 175.341501 -361.186567)
			(xy 175.351744 -361.161896) (xy 175.355241 -361.135413) (xy 175.351751 -361.10893) (xy 175.341514 -361.084257)
			(xy 175.32523 -361.063081) (xy 175.314864 -361.05465) (xy 175.292028 -361.036491) (xy 175.251629 -360.994402)
			(xy 175.218116 -360.946647) (xy 175.192271 -360.894343) (xy 175.1747 -360.838712) (xy 175.165812 -360.781052)
			(xy 175.165258 -360.751882) (xy 175.165761 -360.724632) (xy 175.173519 -360.670687) (xy 175.188875 -360.618394)
			(xy 175.211515 -360.568819) (xy 175.24098 -360.52297) (xy 175.27667 -360.481781) (xy 175.317858 -360.44609)
			(xy 175.363705 -360.416623) (xy 175.413279 -360.39398) (xy 175.465571 -360.378622) (xy 175.519516 -360.370862)
			(xy 175.546766 -360.370374) (xy 175.575683 -360.370889) (xy 175.632856 -360.379614) (xy 175.688056 -360.396871)
			(xy 175.740019 -360.422263) (xy 175.787552 -360.455209) (xy 175.829567 -360.494953) (xy 175.847756 -360.51744)
			(xy 175.857653 -360.529245) (xy 175.882977 -360.546764) (xy 175.91237 -360.55594) (xy 175.943162 -360.55594)
			(xy 175.972555 -360.546764) (xy 175.997879 -360.529245) (xy 176.007776 -360.51744) (xy 176.025991 -360.494976)
			(xy 176.068004 -360.455238) (xy 176.115534 -360.422296) (xy 176.167491 -360.396903) (xy 176.222685 -360.379643)
			(xy 176.279851 -360.370911) (xy 176.308766 -360.370374) (xy 176.337312 -360.37093) (xy 176.393765 -360.379443)
			(xy 176.44832 -360.396269) (xy 176.499761 -360.421033) (xy 176.52365 -360.436668) (xy 176.534772 -360.443765)
			(xy 176.559632 -360.452568) (xy 176.585919 -360.45469) (xy 176.61187 -360.449989) (xy 176.635742 -360.438781)
			(xy 176.655935 -360.421817) (xy 176.663858 -360.411268) (xy 176.679265 -360.390252) (xy 176.714864 -360.352198)
			(xy 176.75531 -360.31934) (xy 176.799849 -360.29229) (xy 176.847654 -360.27155) (xy 176.897835 -360.257507)
			(xy 176.949461 -360.25042) (xy 176.975516 -360.249978) (xy 177.004432 -360.250527) (xy 177.061603 -360.259246)
			(xy 177.116803 -360.276496) (xy 177.168765 -360.301881) (xy 177.2163 -360.334821) (xy 177.258316 -360.37456)
			(xy 177.276506 -360.397044) (xy 177.286403 -360.408849) (xy 177.311727 -360.426368) (xy 177.34112 -360.435544)
			(xy 177.371912 -360.435544) (xy 177.401305 -360.426368) (xy 177.426629 -360.408849) (xy 177.436526 -360.397044)
			(xy 177.454713 -360.374557) (xy 177.496733 -360.33482) (xy 177.544268 -360.30188) (xy 177.59623 -360.276492)
			(xy 177.651429 -360.259237) (xy 177.7086 -360.250511) (xy 177.737516 -360.249978) (xy 177.764767 -360.250463)
			(xy 177.818714 -360.258221) (xy 177.871008 -360.273578) (xy 177.920584 -360.29622) (xy 177.966434 -360.325686)
			(xy 178.007624 -360.361378) (xy 178.043315 -360.402568) (xy 178.072781 -360.448417) (xy 178.095423 -360.497994)
			(xy 178.110779 -360.550288) (xy 178.118537 -360.604235) (xy 178.119024 -360.631486) (xy 178.118573 -360.657529)
			(xy 178.111489 -360.70913) (xy 178.097451 -360.759287) (xy 178.076719 -360.807069) (xy 178.04968 -360.851586)
			(xy 178.016836 -360.89201) (xy 177.99812 -360.910124) (xy 177.988141 -360.920052) (xy 177.973673 -360.94419)
			(xy 177.966332 -360.971357) (xy 177.966673 -360.999497) (xy 177.97467 -361.026479) (xy 177.989718 -361.050259)
			(xy 177.999898 -361.059984) (xy 178.019495 -361.07813) (xy 178.053888 -361.118993) (xy 178.082244 -361.164254)
			(xy 178.104009 -361.213028) (xy 178.118757 -361.264362) (xy 178.1262 -361.317251) (xy 178.126644 -361.343956)
			(xy 178.126102 -361.371724) (xy 178.118056 -361.426674) (xy 178.102127 -361.479877) (xy 178.078653 -361.530208)
			(xy 178.048129 -361.576604) (xy 178.011201 -361.618083) (xy 177.990246 -361.63631) (xy 177.979642 -361.645881)
			(xy 177.963652 -361.66953) (xy 177.954852 -361.696687) (xy 177.953933 -361.725219) (xy 177.960967 -361.752886)
			(xy 177.975402 -361.777515) (xy 177.98542 -361.787694) (xy 178.003747 -361.805801) (xy 178.035923 -361.846035)
			(xy 178.062396 -361.890231) (xy 178.082685 -361.937585) (xy 178.096422 -361.987238) (xy 178.103357 -362.038287)
			(xy 178.103784 -362.064046) (xy 178.10329 -362.091415) (xy 178.09548 -362.145593) (xy 178.079997 -362.198096)
			(xy 178.057162 -362.247844) (xy 178.027443 -362.293812) (xy 178.009804 -362.314744) (xy 178.000523 -362.326038)
			(xy 177.98835 -362.352608) (xy 177.984186 -362.381535) (xy 177.98837 -362.410459) (xy 178.00056 -362.437021)
			(xy 178.009804 -362.448348) (xy 178.027488 -362.469245) (xy 178.057209 -362.51522) (xy 178.08005 -362.564972)
			(xy 178.095541 -362.617479) (xy 178.103365 -362.671662) (xy 178.10336 -362.726407) (xy 178.095526 -362.780589)
			(xy 178.080025 -362.833093) (xy 178.057176 -362.882841) (xy 178.027447 -362.928811) (xy 178.009804 -362.949744)
			(xy 178.000523 -362.961038) (xy 177.98835 -362.987608) (xy 177.984186 -363.016535) (xy 177.98837 -363.045459)
			(xy 178.00056 -363.072021) (xy 178.009804 -363.083348) (xy 178.027433 -363.104288) (xy 178.057146 -363.150259)
			(xy 178.059513 -363.155414) (xy 179.144926 -363.155414) (xy 179.144926 -363.070718) (xy 179.152977 -362.986404)
			(xy 179.169006 -362.903238) (xy 179.192867 -362.821971) (xy 179.224346 -362.743341) (xy 179.263157 -362.66806)
			(xy 179.308947 -362.596808) (xy 179.361303 -362.530232) (xy 179.419751 -362.468934) (xy 179.483761 -362.413469)
			(xy 179.552753 -362.36434) (xy 179.626103 -362.321991) (xy 179.703146 -362.286807) (xy 179.783185 -362.259105)
			(xy 179.865494 -362.239137) (xy 179.949329 -362.227084) (xy 180.03393 -362.223054) (xy 180.118531 -362.227084)
			(xy 180.202366 -362.239137) (xy 180.284675 -362.259105) (xy 180.364714 -362.286807) (xy 180.441757 -362.321991)
			(xy 180.515107 -362.36434) (xy 180.584099 -362.413469) (xy 180.648109 -362.468934) (xy 180.706557 -362.530232)
			(xy 180.758913 -362.596808) (xy 180.804703 -362.66806) (xy 180.843514 -362.743341) (xy 180.874993 -362.821971)
			(xy 180.898854 -362.903238) (xy 180.914883 -362.986404) (xy 180.922934 -363.070718) (xy 180.923438 -363.113066)
			(xy 181.669439 -363.113066) (xy 181.673475 -363.029619) (xy 181.685547 -362.946951) (xy 181.70554 -362.865834)
			(xy 181.733269 -362.787025) (xy 181.768475 -362.71126) (xy 181.810829 -362.639247) (xy 181.859935 -362.571658)
			(xy 181.915336 -362.509124) (xy 181.976513 -362.452229) (xy 182.042896 -362.401503) (xy 182.113864 -362.357422)
			(xy 182.188756 -362.320396) (xy 182.266872 -362.29077) (xy 182.347482 -362.268822) (xy 182.429834 -362.254757)
			(xy 182.51316 -362.248705) (xy 182.59668 -362.250724) (xy 182.679616 -362.260794) (xy 182.761192 -362.278822)
			(xy 182.840648 -362.304639) (xy 182.917241 -362.338004) (xy 182.990257 -362.378605) (xy 183.059013 -362.426064)
			(xy 183.122867 -362.479937) (xy 183.181224 -362.539722) (xy 183.233539 -362.604859) (xy 183.279322 -362.674742)
			(xy 183.318147 -362.748717) (xy 183.349652 -362.826094) (xy 183.373541 -362.906151) (xy 183.389592 -362.988139)
			(xy 183.397655 -363.071294) (xy 183.39816 -363.113066) (xy 183.397655 -363.154838) (xy 183.389592 -363.237993)
			(xy 183.373541 -363.319981) (xy 183.349652 -363.400038) (xy 183.318147 -363.477415) (xy 183.279322 -363.55139)
			(xy 183.233539 -363.621273) (xy 183.181224 -363.68641) (xy 183.122867 -363.746195) (xy 183.059013 -363.800068)
			(xy 182.990257 -363.847527) (xy 182.917241 -363.888128) (xy 182.840648 -363.921493) (xy 182.761192 -363.94731)
			(xy 182.679616 -363.965338) (xy 182.59668 -363.975408) (xy 182.51316 -363.977427) (xy 182.429834 -363.971375)
			(xy 182.347482 -363.95731) (xy 182.266872 -363.935362) (xy 182.188756 -363.905736) (xy 182.113864 -363.86871)
			(xy 182.042896 -363.824629) (xy 181.976513 -363.773903) (xy 181.915336 -363.717008) (xy 181.859935 -363.654474)
			(xy 181.810829 -363.586885) (xy 181.768475 -363.514872) (xy 181.733269 -363.439107) (xy 181.70554 -363.360298)
			(xy 181.685547 -363.279181) (xy 181.673475 -363.196513) (xy 181.669439 -363.113066) (xy 180.923438 -363.113066)
			(xy 180.922934 -363.155414) (xy 180.914883 -363.239728) (xy 180.898854 -363.322894) (xy 180.874993 -363.404161)
			(xy 180.843514 -363.482791) (xy 180.804703 -363.558072) (xy 180.758913 -363.629324) (xy 180.706557 -363.6959)
			(xy 180.648109 -363.757198) (xy 180.584099 -363.812663) (xy 180.515107 -363.861792) (xy 180.441757 -363.904141)
			(xy 180.364714 -363.939325) (xy 180.284675 -363.967027) (xy 180.202366 -363.986995) (xy 180.118531 -363.999048)
			(xy 180.03393 -364.003079) (xy 179.949329 -363.999048) (xy 179.865494 -363.986995) (xy 179.783185 -363.967027)
			(xy 179.703146 -363.939325) (xy 179.626103 -363.904141) (xy 179.552753 -363.861792) (xy 179.483761 -363.812663)
			(xy 179.419751 -363.757198) (xy 179.361303 -363.6959) (xy 179.308947 -363.629324) (xy 179.263157 -363.558072)
			(xy 179.224346 -363.482791) (xy 179.192867 -363.404161) (xy 179.169006 -363.322894) (xy 179.152977 -363.239728)
			(xy 179.144926 -363.155414) (xy 178.059513 -363.155414) (xy 178.079984 -363.200004) (xy 178.095477 -363.252503)
			(xy 178.103308 -363.306677) (xy 178.103784 -363.334046) (xy 178.103365 -363.361299) (xy 178.095601 -363.415251)
			(xy 178.080239 -363.467548) (xy 178.057591 -363.517127) (xy 178.028118 -363.562979) (xy 177.992419 -363.604169)
			(xy 177.951222 -363.63986) (xy 177.905366 -363.669325) (xy 177.855783 -363.691964) (xy 177.803482 -363.707316)
			(xy 177.74953 -363.71507) (xy 177.722276 -363.715554) (xy 177.69336 -363.714998) (xy 177.63619 -363.706279)
			(xy 177.580991 -363.68903) (xy 177.529029 -363.663645) (xy 177.481494 -363.630708) (xy 177.439477 -363.590971)
			(xy 177.421286 -363.568488) (xy 177.411389 -363.556683) (xy 177.386065 -363.539164) (xy 177.356672 -363.529988)
			(xy 177.32588 -363.529988) (xy 177.296487 -363.539164) (xy 177.271163 -363.556683) (xy 177.261266 -363.568488)
			(xy 177.243091 -363.590985) (xy 177.201068 -363.63072) (xy 177.15353 -363.663658) (xy 177.101566 -363.689044)
			(xy 177.046365 -363.706297) (xy 176.989193 -363.715022) (xy 176.960276 -363.715554) (xy 176.933026 -363.715045)
			(xy 176.879082 -363.707286) (xy 176.82679 -363.69193) (xy 176.777216 -363.66929) (xy 176.731368 -363.639825)
			(xy 176.690179 -363.604136) (xy 176.654488 -363.56295) (xy 176.625021 -363.517103) (xy 176.602377 -363.46753)
			(xy 176.587019 -363.41524) (xy 176.579257 -363.361296) (xy 176.578768 -363.334046) (xy 176.579244 -363.306676)
			(xy 176.587057 -363.252497) (xy 176.602543 -363.199993) (xy 176.625383 -363.150246) (xy 176.655107 -363.104279)
			(xy 176.672748 -363.083348) (xy 176.681937 -363.071986) (xy 176.694114 -363.04544) (xy 176.698293 -363.016535)
			(xy 176.694133 -362.987627) (xy 176.681975 -362.961073) (xy 176.672748 -362.949744) (xy 176.655151 -362.928775)
			(xy 176.625423 -362.882814) (xy 176.602574 -362.833074) (xy 176.587073 -362.780577) (xy 176.57924 -362.726403)
			(xy 176.579235 -362.671666) (xy 176.587058 -362.617491) (xy 176.60255 -362.564991) (xy 176.62539 -362.515247)
			(xy 176.65511 -362.46928) (xy 176.672748 -362.448348) (xy 176.681937 -362.436986) (xy 176.694114 -362.41044)
			(xy 176.698293 -362.381535) (xy 176.694133 -362.352627) (xy 176.681975 -362.326073) (xy 176.672748 -362.314744)
			(xy 176.655124 -362.2938) (xy 176.625408 -362.247831) (xy 176.602568 -362.198087) (xy 176.587074 -362.145589)
			(xy 176.579243 -362.091414) (xy 176.578768 -362.064046) (xy 176.578999 -362.044991) (xy 176.582819 -362.007073)
			(xy 176.586388 -361.988354) (xy 176.588705 -361.97488) (xy 176.586854 -361.947611) (xy 176.577837 -361.92181)
			(xy 176.562301 -361.899324) (xy 176.541357 -361.881763) (xy 176.516507 -361.870386) (xy 176.489529 -361.866007)
			(xy 176.462355 -361.868939) (xy 176.449482 -361.873546) (xy 176.427016 -361.882082) (xy 176.380475 -361.894068)
			(xy 176.332796 -361.900107) (xy 176.308766 -361.90047) (xy 176.27985 -361.899916) (xy 176.22268 -361.891196)
			(xy 176.167482 -361.873946) (xy 176.115519 -361.848561) (xy 176.067985 -361.815623) (xy 176.025967 -361.775887)
			(xy 176.007776 -361.753404) (xy 175.997879 -361.741599) (xy 175.972555 -361.72408) (xy 175.943162 -361.714904)
			(xy 175.91237 -361.714904) (xy 175.882977 -361.72408) (xy 175.857653 -361.741599) (xy 175.847756 -361.753404)
			(xy 175.829591 -361.775909) (xy 175.787566 -361.815643) (xy 175.740025 -361.848579) (xy 175.688059 -361.873964)
			(xy 175.632857 -361.891215) (xy 175.575684 -361.899938) (xy 175.546766 -361.90047) (xy 175.519511 -361.900077)
			(xy 175.465555 -361.892314) (xy 175.413254 -361.876952) (xy 175.363671 -361.854303) (xy 175.317816 -361.824827)
			(xy 175.276623 -361.789126) (xy 175.240929 -361.747926) (xy 175.211463 -361.702066) (xy 175.188823 -361.652479)
			(xy 175.173471 -361.600174) (xy 175.165718 -361.546218) (xy 175.165258 -361.518962) (xy 173.7614 -361.518962)
			(xy 173.7614 -365.547148) (xy 174.0408 -365.826548) (xy 189.6872 -365.826548)
		)
		(stroke
			(width 0)
			(type solid)
		)
		(fill yes)
		(layer "In15.Cu")
		(net "GND")
	)
	(gr_poly
		(pts
			(xy 55.483506 -366.872266) (xy 55.465218 -366.846866) (xy 55.448354 -366.822399) (xy 55.421604 -366.769339)
			(xy 55.4034 -366.712775) (xy 55.394182 -366.654073) (xy 55.39359 -366.624362) (xy 55.39359 -366.616742)
			(xy 55.394642 -366.588552) (xy 55.404022 -366.532927) (xy 55.42149 -366.479289) (xy 55.446664 -366.428808)
			(xy 55.478995 -366.382583) (xy 55.51778 -366.341621) (xy 55.562173 -366.306816) (xy 55.611206 -366.278926)
			(xy 55.663811 -366.258558) (xy 55.718842 -366.246158) (xy 55.775098 -366.241994) (xy 55.831354 -366.246158)
			(xy 55.886385 -366.258558) (xy 55.93899 -366.278926) (xy 55.988023 -366.306816) (xy 56.032416 -366.341621)
			(xy 56.071201 -366.382583) (xy 56.103532 -366.428808) (xy 56.128706 -366.479289) (xy 56.146174 -366.532927)
			(xy 56.155554 -366.588552) (xy 56.156606 -366.616742) (xy 56.156606 -366.624362) (xy 56.156041 -366.654075)
			(xy 56.146828 -366.712781) (xy 56.128619 -366.769348) (xy 56.101855 -366.822405) (xy 56.084978 -366.846866)
			(xy 56.06669 -366.872266) (xy 56.136286 -367.007648) (xy 56.23052 -367.007648) (xy 57.861708 -352.152204)
			(xy 57.861708 -347.933264) (xy 56.430926 -334.03921) (xy 56.430926 -334.038702) (xy 56.243982 -332.223364)
			(xy 56.241508 -332.1981) (xy 56.238839 -332.147402) (xy 56.238648 -332.122018) (xy 56.238648 -331.03185)
			(xy 55.1942 -329.987148) (xy 35.5854 -329.987148) (xy 34.902394 -330.670154) (xy 34.902394 -335.51361)
			(xy 39.617392 -335.51361) (xy 39.617392 -335.428914) (xy 39.625443 -335.3446) (xy 39.641472 -335.261434)
			(xy 39.665333 -335.180167) (xy 39.696812 -335.101537) (xy 39.735623 -335.026256) (xy 39.781413 -334.955004)
			(xy 39.833769 -334.888428) (xy 39.892217 -334.82713) (xy 39.956227 -334.771665) (xy 40.025219 -334.722536)
			(xy 40.098569 -334.680187) (xy 40.175612 -334.645003) (xy 40.255651 -334.617301) (xy 40.33796 -334.597333)
			(xy 40.421795 -334.58528) (xy 40.506396 -334.58125) (xy 40.590997 -334.58528) (xy 40.674832 -334.597333)
			(xy 40.757141 -334.617301) (xy 40.83718 -334.645003) (xy 40.914223 -334.680187) (xy 40.987573 -334.722536)
			(xy 41.056565 -334.771665) (xy 41.120575 -334.82713) (xy 41.179023 -334.888428) (xy 41.231379 -334.955004)
			(xy 41.277169 -335.026256) (xy 41.31598 -335.101537) (xy 41.347459 -335.180167) (xy 41.37132 -335.261434)
			(xy 41.387349 -335.3446) (xy 41.3954 -335.428914) (xy 41.395904 -335.471262) (xy 41.3954 -335.51361)
			(xy 41.394794 -335.51996) (xy 45.808134 -335.51996) (xy 45.808134 -335.435264) (xy 45.816185 -335.35095)
			(xy 45.832214 -335.267784) (xy 45.856075 -335.186517) (xy 45.887554 -335.107887) (xy 45.926365 -335.032606)
			(xy 45.972155 -334.961354) (xy 46.024511 -334.894778) (xy 46.082959 -334.83348) (xy 46.146969 -334.778015)
			(xy 46.215961 -334.728886) (xy 46.289311 -334.686537) (xy 46.366354 -334.651353) (xy 46.446393 -334.623651)
			(xy 46.528702 -334.603683) (xy 46.612537 -334.59163) (xy 46.697138 -334.5876) (xy 46.781739 -334.59163)
			(xy 46.865574 -334.603683) (xy 46.947883 -334.623651) (xy 47.027922 -334.651353) (xy 47.104965 -334.686537)
			(xy 47.178315 -334.728886) (xy 47.247307 -334.778015) (xy 47.311317 -334.83348) (xy 47.369765 -334.894778)
			(xy 47.422121 -334.961354) (xy 47.467911 -335.032606) (xy 47.506722 -335.107887) (xy 47.538201 -335.186517)
			(xy 47.562062 -335.267784) (xy 47.578091 -335.35095) (xy 47.586142 -335.435264) (xy 47.586646 -335.477612)
			(xy 47.586142 -335.51996) (xy 52.005734 -335.51996) (xy 52.005734 -335.435264) (xy 52.013785 -335.35095)
			(xy 52.029814 -335.267784) (xy 52.053675 -335.186517) (xy 52.085154 -335.107887) (xy 52.123965 -335.032606)
			(xy 52.169755 -334.961354) (xy 52.222111 -334.894778) (xy 52.280559 -334.83348) (xy 52.344569 -334.778015)
			(xy 52.413561 -334.728886) (xy 52.486911 -334.686537) (xy 52.563954 -334.651353) (xy 52.643993 -334.623651)
			(xy 52.726302 -334.603683) (xy 52.810137 -334.59163) (xy 52.894738 -334.5876) (xy 52.979339 -334.59163)
			(xy 53.063174 -334.603683) (xy 53.145483 -334.623651) (xy 53.225522 -334.651353) (xy 53.302565 -334.686537)
			(xy 53.375915 -334.728886) (xy 53.444907 -334.778015) (xy 53.508917 -334.83348) (xy 53.567365 -334.894778)
			(xy 53.619721 -334.961354) (xy 53.665511 -335.032606) (xy 53.704322 -335.107887) (xy 53.735801 -335.186517)
			(xy 53.759662 -335.267784) (xy 53.775691 -335.35095) (xy 53.783742 -335.435264) (xy 53.784246 -335.477612)
			(xy 53.783742 -335.51996) (xy 53.775691 -335.604274) (xy 53.759662 -335.68744) (xy 53.735801 -335.768707)
			(xy 53.704322 -335.847337) (xy 53.665511 -335.922618) (xy 53.619721 -335.99387) (xy 53.567365 -336.060446)
			(xy 53.508917 -336.121744) (xy 53.444907 -336.177209) (xy 53.375915 -336.226338) (xy 53.302565 -336.268687)
			(xy 53.225522 -336.303871) (xy 53.145483 -336.331573) (xy 53.063174 -336.351541) (xy 52.979339 -336.363594)
			(xy 52.894738 -336.367625) (xy 52.810137 -336.363594) (xy 52.726302 -336.351541) (xy 52.643993 -336.331573)
			(xy 52.563954 -336.303871) (xy 52.486911 -336.268687) (xy 52.413561 -336.226338) (xy 52.344569 -336.177209)
			(xy 52.280559 -336.121744) (xy 52.222111 -336.060446) (xy 52.169755 -335.99387) (xy 52.123965 -335.922618)
			(xy 52.085154 -335.847337) (xy 52.053675 -335.768707) (xy 52.029814 -335.68744) (xy 52.013785 -335.604274)
			(xy 52.005734 -335.51996) (xy 47.586142 -335.51996) (xy 47.578091 -335.604274) (xy 47.562062 -335.68744)
			(xy 47.538201 -335.768707) (xy 47.506722 -335.847337) (xy 47.467911 -335.922618) (xy 47.422121 -335.99387)
			(xy 47.369765 -336.060446) (xy 47.311317 -336.121744) (xy 47.247307 -336.177209) (xy 47.178315 -336.226338)
			(xy 47.104965 -336.268687) (xy 47.027922 -336.303871) (xy 46.947883 -336.331573) (xy 46.865574 -336.351541)
			(xy 46.781739 -336.363594) (xy 46.697138 -336.367625) (xy 46.612537 -336.363594) (xy 46.528702 -336.351541)
			(xy 46.446393 -336.331573) (xy 46.366354 -336.303871) (xy 46.289311 -336.268687) (xy 46.215961 -336.226338)
			(xy 46.146969 -336.177209) (xy 46.082959 -336.121744) (xy 46.024511 -336.060446) (xy 45.972155 -335.99387)
			(xy 45.926365 -335.922618) (xy 45.887554 -335.847337) (xy 45.856075 -335.768707) (xy 45.832214 -335.68744)
			(xy 45.816185 -335.604274) (xy 45.808134 -335.51996) (xy 41.394794 -335.51996) (xy 41.387349 -335.597924)
			(xy 41.37132 -335.68109) (xy 41.347459 -335.762357) (xy 41.31598 -335.840987) (xy 41.277169 -335.916268)
			(xy 41.231379 -335.98752) (xy 41.179023 -336.054096) (xy 41.120575 -336.115394) (xy 41.056565 -336.170859)
			(xy 40.987573 -336.219988) (xy 40.914223 -336.262337) (xy 40.83718 -336.297521) (xy 40.757141 -336.325223)
			(xy 40.674832 -336.345191) (xy 40.590997 -336.357244) (xy 40.506396 -336.361275) (xy 40.421795 -336.357244)
			(xy 40.33796 -336.345191) (xy 40.255651 -336.325223) (xy 40.175612 -336.297521) (xy 40.098569 -336.262337)
			(xy 40.025219 -336.219988) (xy 39.956227 -336.170859) (xy 39.892217 -336.115394) (xy 39.833769 -336.054096)
			(xy 39.781413 -335.98752) (xy 39.735623 -335.916268) (xy 39.696812 -335.840987) (xy 39.665333 -335.762357)
			(xy 39.641472 -335.68109) (xy 39.625443 -335.597924) (xy 39.617392 -335.51361) (xy 34.902394 -335.51361)
			(xy 34.902394 -337.471258) (xy 39.590985 -337.471258) (xy 39.595007 -337.385538) (xy 39.607038 -337.30057)
			(xy 39.626974 -337.217103) (xy 39.654637 -337.135869) (xy 39.689786 -337.057583) (xy 39.732112 -336.982932)
			(xy 39.781241 -336.912573) (xy 39.836744 -336.847123) (xy 39.898131 -336.787159) (xy 39.964864 -336.733206)
			(xy 40.036356 -336.685739) (xy 40.111978 -336.645175) (xy 40.191067 -336.611871) (xy 40.272927 -336.586119)
			(xy 40.356838 -336.568146) (xy 40.442064 -336.55811) (xy 40.527856 -336.556098) (xy 40.613458 -336.562129)
			(xy 40.69812 -336.576149) (xy 40.781097 -336.598035) (xy 40.86166 -336.627596) (xy 40.9391 -336.66457)
			(xy 41.012739 -336.708634) (xy 41.081927 -336.7594) (xy 41.146058 -336.816421) (xy 41.204567 -336.879197)
			(xy 41.25694 -336.947177) (xy 41.302718 -337.019762) (xy 41.341498 -337.096314) (xy 41.372939 -337.176162)
			(xy 41.396765 -337.258603) (xy 41.412766 -337.342913) (xy 41.420801 -337.428351) (xy 41.421304 -337.471258)
			(xy 41.42123 -337.477608) (xy 45.781727 -337.477608) (xy 45.785749 -337.391888) (xy 45.79778 -337.30692)
			(xy 45.817716 -337.223453) (xy 45.845379 -337.142219) (xy 45.880528 -337.063933) (xy 45.922854 -336.989282)
			(xy 45.971983 -336.918923) (xy 46.027486 -336.853473) (xy 46.088873 -336.793509) (xy 46.155606 -336.739556)
			(xy 46.227098 -336.692089) (xy 46.30272 -336.651525) (xy 46.381809 -336.618221) (xy 46.463669 -336.592469)
			(xy 46.54758 -336.574496) (xy 46.632806 -336.56446) (xy 46.718598 -336.562448) (xy 46.8042 -336.568479)
			(xy 46.888862 -336.582499) (xy 46.971839 -336.604385) (xy 47.052402 -336.633946) (xy 47.129842 -336.67092)
			(xy 47.203481 -336.714984) (xy 47.272669 -336.76575) (xy 47.3368 -336.822771) (xy 47.395309 -336.885547)
			(xy 47.447682 -336.953527) (xy 47.49346 -337.026112) (xy 47.53224 -337.102664) (xy 47.563681 -337.182512)
			(xy 47.587507 -337.264953) (xy 47.603508 -337.349263) (xy 47.611543 -337.434701) (xy 47.612046 -337.477608)
			(xy 51.97983 -337.477608) (xy 51.980318 -337.435332) (xy 51.98812 -337.35114) (xy 52.003656 -337.268027)
			(xy 52.026795 -337.186703) (xy 52.057339 -337.10786) (xy 52.095027 -337.032172) (xy 52.139538 -336.960284)
			(xy 52.190492 -336.89281) (xy 52.247455 -336.830325) (xy 52.30994 -336.773362) (xy 52.377414 -336.722408)
			(xy 52.449302 -336.677897) (xy 52.52499 -336.640209) (xy 52.603833 -336.609665) (xy 52.685157 -336.586526)
			(xy 52.76827 -336.57099) (xy 52.852462 -336.563188) (xy 52.937014 -336.563188) (xy 53.021206 -336.57099)
			(xy 53.104319 -336.586526) (xy 53.185643 -336.609665) (xy 53.264486 -336.640209) (xy 53.340174 -336.677897)
			(xy 53.412062 -336.722408) (xy 53.479536 -336.773362) (xy 53.542021 -336.830325) (xy 53.598984 -336.89281)
			(xy 53.649938 -336.960284) (xy 53.694449 -337.032172) (xy 53.732137 -337.10786) (xy 53.762681 -337.186703)
			(xy 53.78582 -337.268027) (xy 53.801356 -337.35114) (xy 53.809158 -337.435332) (xy 53.809646 -337.477608)
			(xy 53.809142 -337.519569) (xy 53.801456 -337.603139) (xy 53.786148 -337.685654) (xy 53.763347 -337.766421)
			(xy 53.733246 -337.844759) (xy 53.696097 -337.920012) (xy 53.652212 -337.991547) (xy 53.60196 -338.058761)
			(xy 53.545764 -338.121091) (xy 53.484096 -338.178013) (xy 53.417474 -338.229047) (xy 53.346458 -338.273766)
			(xy 53.309266 -338.293202) (xy 53.296167 -338.300524) (xy 53.274558 -338.321321) (xy 53.259912 -338.347494)
			(xy 53.25349 -338.37679) (xy 53.255844 -338.406689) (xy 53.266772 -338.434619) (xy 53.285333 -338.458177)
			(xy 53.297328 -338.467192) (xy 53.308811 -338.475301) (xy 53.330676 -338.492974) (xy 53.341016 -338.502498)
			(xy 53.35255 -338.51257) (xy 53.380096 -338.525912) (xy 53.410358 -338.530497) (xy 53.44062 -338.525912)
			(xy 53.468166 -338.51257) (xy 53.4797 -338.502498) (xy 53.501027 -338.483228) (xy 53.54839 -338.450663)
			(xy 53.600101 -338.425572) (xy 53.654992 -338.408522) (xy 53.711819 -338.3999) (xy 53.769297 -338.3999)
			(xy 53.826124 -338.408522) (xy 53.881015 -338.425572) (xy 53.932726 -338.450663) (xy 53.980089 -338.483228)
			(xy 54.001416 -338.502498) (xy 54.01295 -338.51257) (xy 54.040496 -338.525912) (xy 54.070758 -338.530497)
			(xy 54.10102 -338.525912) (xy 54.128566 -338.51257) (xy 54.1401 -338.502498) (xy 54.161412 -338.48321)
			(xy 54.208777 -338.450644) (xy 54.260493 -338.425554) (xy 54.315387 -338.408508) (xy 54.372218 -338.399891)
			(xy 54.400958 -338.399374) (xy 54.428209 -338.399894) (xy 54.482157 -338.407645) (xy 54.534453 -338.422995)
			(xy 54.584031 -338.445631) (xy 54.629884 -338.475093) (xy 54.671077 -338.510781) (xy 54.706771 -338.551968)
			(xy 54.73624 -338.597816) (xy 54.758884 -338.647391) (xy 54.774242 -338.699684) (xy 54.782001 -338.753631)
			(xy 54.782466 -338.780882) (xy 54.781914 -338.80962) (xy 54.773295 -338.866445) (xy 54.756251 -338.921335)
			(xy 54.731166 -338.973047) (xy 54.698609 -339.020411) (xy 54.679342 -339.04174) (xy 54.669287 -339.053288)
			(xy 54.655941 -339.080829) (xy 54.651353 -339.111087) (xy 54.655934 -339.141346) (xy 54.669272 -339.16889)
			(xy 54.679342 -339.180424) (xy 54.698601 -339.201761) (xy 54.73117 -339.24912) (xy 54.756265 -339.300829)
			(xy 54.773318 -339.355718) (xy 54.781944 -339.412544) (xy 54.782466 -339.441282) (xy 54.782015 -339.468272)
			(xy 54.774408 -339.521712) (xy 54.759344 -339.573547) (xy 54.737124 -339.622741) (xy 54.70819 -339.668311)
			(xy 54.673122 -339.709347) (xy 54.65318 -339.72754) (xy 54.642465 -339.737466) (xy 54.626852 -339.762143)
			(xy 54.618868 -339.790231) (xy 54.619166 -339.819431) (xy 54.627722 -339.84735) (xy 54.643835 -339.871703)
			(xy 54.654704 -339.881464) (xy 54.675503 -339.899686) (xy 54.712176 -339.941068) (xy 54.742483 -339.987316)
			(xy 54.765788 -340.037458) (xy 54.781602 -340.090442) (xy 54.789593 -340.145155) (xy 54.790086 -340.172802)
			(xy 54.789559 -340.202244) (xy 54.780511 -340.26043) (xy 54.76263 -340.316534) (xy 54.736341 -340.369224)
			(xy 54.702268 -340.417249) (xy 54.682136 -340.43874) (xy 54.671747 -340.450216) (xy 54.657858 -340.477865)
			(xy 54.652857 -340.508401) (xy 54.657201 -340.539036) (xy 54.670494 -340.566978) (xy 54.680612 -340.578694)
			(xy 54.699625 -340.600011) (xy 54.731799 -340.647204) (xy 54.75658 -340.698665) (xy 54.773417 -340.753245)
			(xy 54.781931 -340.809723) (xy 54.782466 -340.838282) (xy 54.781998 -340.865652) (xy 54.774182 -340.919832)
			(xy 54.758694 -340.972335) (xy 54.735852 -341.022082) (xy 54.706127 -341.068049) (xy 54.688486 -341.08898)
			(xy 54.679268 -341.100321) (xy 54.66709 -341.126874) (xy 54.662914 -341.155786) (xy 54.667082 -341.1847)
			(xy 54.679253 -341.211256) (xy 54.688486 -341.222584) (xy 54.706109 -341.243531) (xy 54.735833 -341.289497)
			(xy 54.758679 -341.339241) (xy 54.774176 -341.391741) (xy 54.782006 -341.445917) (xy 54.782008 -341.500656)
			(xy 54.774182 -341.554833) (xy 54.758688 -341.607334) (xy 54.735846 -341.657079) (xy 54.706125 -341.703047)
			(xy 54.688486 -341.72398) (xy 54.679268 -341.735321) (xy 54.66709 -341.761874) (xy 54.662914 -341.790786)
			(xy 54.667082 -341.8197) (xy 54.679253 -341.846256) (xy 54.688486 -341.857584) (xy 54.706109 -341.878531)
			(xy 54.735833 -341.924497) (xy 54.758679 -341.974241) (xy 54.774176 -342.026741) (xy 54.782006 -342.080917)
			(xy 54.782008 -342.135656) (xy 54.774182 -342.189833) (xy 54.758688 -342.242334) (xy 54.735846 -342.292079)
			(xy 54.706125 -342.338047) (xy 54.688486 -342.35898) (xy 54.679268 -342.370321) (xy 54.66709 -342.396874)
			(xy 54.662914 -342.425786) (xy 54.667082 -342.4547) (xy 54.679253 -342.481256) (xy 54.688486 -342.492584)
			(xy 54.706129 -342.513513) (xy 54.735841 -342.559486) (xy 54.758676 -342.609235) (xy 54.774166 -342.661736)
			(xy 54.781993 -342.715913) (xy 54.782466 -342.743282) (xy 54.782028 -342.770536) (xy 54.774272 -342.82449)
			(xy 54.758916 -342.876791) (xy 54.736273 -342.926374) (xy 54.706803 -342.972229) (xy 54.671106 -343.013423)
			(xy 54.62991 -343.049117) (xy 54.584053 -343.078584) (xy 54.534469 -343.101225) (xy 54.482167 -343.116577)
			(xy 54.428212 -343.12433) (xy 54.400958 -343.12479) (xy 54.372218 -343.124294) (xy 54.315389 -343.115665)
			(xy 54.260498 -343.098609) (xy 54.208787 -343.073511) (xy 54.161426 -343.04094) (xy 54.1401 -343.021666)
			(xy 54.128566 -343.011594) (xy 54.10102 -342.998252) (xy 54.070758 -342.993667) (xy 54.040496 -342.998252)
			(xy 54.01295 -343.011594) (xy 54.001416 -343.021666) (xy 53.980089 -343.040936) (xy 53.932726 -343.073501)
			(xy 53.881015 -343.098592) (xy 53.826124 -343.115642) (xy 53.769297 -343.124264) (xy 53.711819 -343.124264)
			(xy 53.654992 -343.115642) (xy 53.600101 -343.098592) (xy 53.54839 -343.073501) (xy 53.501027 -343.040936)
			(xy 53.4797 -343.021666) (xy 53.468166 -343.011594) (xy 53.44062 -342.998252) (xy 53.410358 -342.993667)
			(xy 53.380096 -342.998252) (xy 53.35255 -343.011594) (xy 53.341016 -343.021666) (xy 53.319707 -343.040957)
			(xy 53.27234 -343.073521) (xy 53.220624 -343.098609) (xy 53.165729 -343.115655) (xy 53.108898 -343.124272)
			(xy 53.080158 -343.12479) (xy 53.052905 -343.124361) (xy 52.998954 -343.116599) (xy 52.946657 -343.101237)
			(xy 52.897079 -343.07859) (xy 52.851228 -343.049117) (xy 52.810037 -343.01342) (xy 52.774347 -342.972224)
			(xy 52.744881 -342.926369) (xy 52.722242 -342.876786) (xy 52.706889 -342.824487) (xy 52.699135 -342.770535)
			(xy 52.69865 -342.743282) (xy 52.699093 -342.715911) (xy 52.706915 -342.66173) (xy 52.722408 -342.609226)
			(xy 52.745256 -342.55948) (xy 52.774986 -342.513514) (xy 52.79263 -342.492584) (xy 52.801882 -342.481269)
			(xy 52.814053 -342.454706) (xy 52.818221 -342.425786) (xy 52.814046 -342.396868) (xy 52.801867 -342.370308)
			(xy 52.79263 -342.35898) (xy 52.774972 -342.338062) (xy 52.745247 -342.292091) (xy 52.722403 -342.242343)
			(xy 52.706908 -342.189839) (xy 52.699081 -342.135658) (xy 52.699083 -342.080915) (xy 52.706914 -342.026735)
			(xy 52.722412 -341.974232) (xy 52.74526 -341.924485) (xy 52.774988 -341.878517) (xy 52.79263 -341.857584)
			(xy 52.801882 -341.846269) (xy 52.814053 -341.819706) (xy 52.818221 -341.790786) (xy 52.814046 -341.761868)
			(xy 52.801867 -341.735308) (xy 52.79263 -341.72398) (xy 52.774972 -341.703062) (xy 52.745247 -341.657091)
			(xy 52.722403 -341.607343) (xy 52.706908 -341.554839) (xy 52.699081 -341.500658) (xy 52.699083 -341.445915)
			(xy 52.706914 -341.391735) (xy 52.722412 -341.339232) (xy 52.74526 -341.289485) (xy 52.774988 -341.243517)
			(xy 52.79263 -341.222584) (xy 52.801882 -341.211269) (xy 52.814053 -341.184706) (xy 52.818221 -341.155786)
			(xy 52.814046 -341.126868) (xy 52.801867 -341.100308) (xy 52.79263 -341.08898) (xy 52.77502 -341.068025)
			(xy 52.745302 -341.022059) (xy 52.72246 -340.972317) (xy 52.706963 -340.919822) (xy 52.699128 -340.86565)
			(xy 52.69865 -340.838282) (xy 52.69922 -340.808841) (xy 52.708256 -340.750657) (xy 52.726126 -340.694554)
			(xy 52.752406 -340.641862) (xy 52.786471 -340.593836) (xy 52.8066 -340.572344) (xy 52.817009 -340.560883)
			(xy 52.830906 -340.53323) (xy 52.835907 -340.502688) (xy 52.831556 -340.472046) (xy 52.81825 -340.444104)
			(xy 52.808124 -340.43239) (xy 52.789093 -340.411088) (xy 52.756924 -340.36389) (xy 52.732147 -340.312425)
			(xy 52.715315 -340.257843) (xy 52.706803 -340.201361) (xy 52.70627 -340.172802) (xy 52.706698 -340.145811)
			(xy 52.714308 -340.092369) (xy 52.729376 -340.040533) (xy 52.7516 -339.99134) (xy 52.780538 -339.94577)
			(xy 52.815611 -339.904735) (xy 52.835556 -339.886544) (xy 52.846182 -339.876532) (xy 52.861793 -339.851879)
			(xy 52.869785 -339.823814) (xy 52.869503 -339.794635) (xy 52.86097 -339.766729) (xy 52.844886 -339.742382)
			(xy 52.834032 -339.73262) (xy 52.813233 -339.714399) (xy 52.776559 -339.673017) (xy 52.74625 -339.62677)
			(xy 52.722945 -339.576627) (xy 52.707131 -339.523643) (xy 52.699142 -339.468929) (xy 52.69865 -339.441282)
			(xy 52.699176 -339.412543) (xy 52.7078 -339.355717) (xy 52.72485 -339.300827) (xy 52.749941 -339.249115)
			(xy 52.782504 -339.201752) (xy 52.801774 -339.180424) (xy 52.811863 -339.168904) (xy 52.825203 -339.141353)
			(xy 52.829784 -339.111087) (xy 52.825195 -339.080822) (xy 52.811848 -339.053274) (xy 52.801774 -339.04174)
			(xy 52.782501 -339.020415) (xy 52.749933 -338.973053) (xy 52.724841 -338.921341) (xy 52.707791 -338.86645)
			(xy 52.69917 -338.809621) (xy 52.69865 -338.780882) (xy 52.699093 -338.754848) (xy 52.706182 -338.703265)
			(xy 52.720212 -338.653124) (xy 52.740924 -338.605353) (xy 52.767933 -338.560838) (xy 52.783994 -338.540344)
			(xy 52.792995 -338.528305) (xy 52.804369 -338.500505) (xy 52.807153 -338.470597) (xy 52.801105 -338.441174)
			(xy 52.78675 -338.414789) (xy 52.765333 -338.393729) (xy 52.73871 -338.37982) (xy 52.72405 -338.376514)
			(xy 52.682679 -338.368223) (xy 52.601583 -338.344902) (xy 52.522979 -338.314214) (xy 52.447534 -338.276419)
			(xy 52.375889 -338.231838) (xy 52.308653 -338.180851) (xy 52.246397 -338.12389) (xy 52.189649 -338.061439)
			(xy 52.138892 -337.994029) (xy 52.094557 -337.922232) (xy 52.05702 -337.846659) (xy 52.0266 -337.76795)
			(xy 52.003557 -337.686775) (xy 51.988084 -337.603823) (xy 51.980315 -337.519799) (xy 51.97983 -337.477608)
			(xy 47.612046 -337.477608) (xy 47.611543 -337.520515) (xy 47.603508 -337.605953) (xy 47.587507 -337.690263)
			(xy 47.563681 -337.772704) (xy 47.53224 -337.852552) (xy 47.49346 -337.929104) (xy 47.447682 -338.001689)
			(xy 47.395309 -338.069669) (xy 47.3368 -338.132445) (xy 47.272669 -338.189466) (xy 47.203481 -338.240232)
			(xy 47.129842 -338.284296) (xy 47.052402 -338.32127) (xy 46.971839 -338.350831) (xy 46.888862 -338.372717)
			(xy 46.8042 -338.386737) (xy 46.718598 -338.392768) (xy 46.632806 -338.390756) (xy 46.54758 -338.38072)
			(xy 46.463669 -338.362747) (xy 46.381809 -338.336995) (xy 46.30272 -338.303691) (xy 46.227098 -338.263127)
			(xy 46.155606 -338.21566) (xy 46.088873 -338.161707) (xy 46.027486 -338.101743) (xy 45.971983 -338.036293)
			(xy 45.922854 -337.965934) (xy 45.880528 -337.891283) (xy 45.845379 -337.812997) (xy 45.817716 -337.731763)
			(xy 45.79778 -337.648296) (xy 45.785749 -337.563328) (xy 45.781727 -337.477608) (xy 41.42123 -337.477608)
			(xy 41.420801 -337.514165) (xy 41.412766 -337.599603) (xy 41.396765 -337.683913) (xy 41.372939 -337.766354)
			(xy 41.341498 -337.846202) (xy 41.302718 -337.922754) (xy 41.25694 -337.995339) (xy 41.204567 -338.063319)
			(xy 41.146058 -338.126095) (xy 41.081927 -338.183116) (xy 41.012739 -338.233882) (xy 40.9391 -338.277946)
			(xy 40.86166 -338.31492) (xy 40.781097 -338.344481) (xy 40.69812 -338.366367) (xy 40.613458 -338.380387)
			(xy 40.527856 -338.386418) (xy 40.442064 -338.384406) (xy 40.356838 -338.37437) (xy 40.272927 -338.356397)
			(xy 40.191067 -338.330645) (xy 40.111978 -338.297341) (xy 40.036356 -338.256777) (xy 39.964864 -338.20931)
			(xy 39.898131 -338.155357) (xy 39.836744 -338.095393) (xy 39.781241 -338.029943) (xy 39.732112 -337.959584)
			(xy 39.689786 -337.884933) (xy 39.654637 -337.806647) (xy 39.626974 -337.725413) (xy 39.607038 -337.641946)
			(xy 39.595007 -337.556978) (xy 39.590985 -337.471258) (xy 34.902394 -337.471258) (xy 34.902394 -339.443822)
			(xy 38.02761 -339.443822) (xy 38.028087 -339.416452) (xy 38.035901 -339.362273) (xy 38.051388 -339.30977)
			(xy 38.074227 -339.260023) (xy 38.10395 -339.214056) (xy 38.12159 -339.193124) (xy 38.130806 -339.181781)
			(xy 38.142988 -339.155229) (xy 38.147165 -339.126317) (xy 38.142997 -339.097403) (xy 38.130825 -339.070847)
			(xy 38.12159 -339.05952) (xy 38.103945 -339.038593) (xy 38.074235 -338.992618) (xy 38.0514 -338.94287)
			(xy 38.03591 -338.890368) (xy 38.028083 -338.836191) (xy 38.02761 -338.808822) (xy 38.028076 -338.781569)
			(xy 38.03583 -338.727617) (xy 38.051184 -338.675318) (xy 38.073826 -338.625737) (xy 38.103293 -338.579883)
			(xy 38.138987 -338.538689) (xy 38.18018 -338.502995) (xy 38.226033 -338.473528) (xy 38.275614 -338.450886)
			(xy 38.327913 -338.435531) (xy 38.381865 -338.427776) (xy 38.409118 -338.427314) (xy 38.437856 -338.42785)
			(xy 38.494682 -338.436473) (xy 38.549572 -338.453521) (xy 38.601284 -338.47861) (xy 38.648648 -338.51117)
			(xy 38.669976 -338.530438) (xy 38.68151 -338.54051) (xy 38.709056 -338.553852) (xy 38.739318 -338.558437)
			(xy 38.76958 -338.553852) (xy 38.797126 -338.54051) (xy 38.80866 -338.530438) (xy 38.829987 -338.511168)
			(xy 38.87735 -338.478603) (xy 38.929061 -338.453512) (xy 38.983952 -338.436462) (xy 39.040779 -338.42784)
			(xy 39.098257 -338.42784) (xy 39.155084 -338.436462) (xy 39.209975 -338.453512) (xy 39.261686 -338.478603)
			(xy 39.309049 -338.511168) (xy 39.330376 -338.530438) (xy 39.341283 -338.539936) (xy 39.367057 -338.553021)
			(xy 39.395469 -338.558337) (xy 39.42423 -338.555455) (xy 39.437818 -338.550504) (xy 39.456048 -338.52959)
			(xy 39.497498 -338.492717) (xy 39.543854 -338.462239) (xy 39.594137 -338.4388) (xy 39.647286 -338.422894)
			(xy 39.702179 -338.414858) (xy 39.729918 -338.41436) (xy 39.75719 -338.414785) (xy 39.81118 -338.42255)
			(xy 39.863515 -338.43792) (xy 39.913129 -338.460581) (xy 39.959014 -338.490072) (xy 40.000234 -338.525794)
			(xy 40.035952 -338.567018) (xy 40.065438 -338.612906) (xy 40.088094 -338.662523) (xy 40.103459 -338.714859)
			(xy 40.111218 -338.768849) (xy 40.11168 -338.796122) (xy 40.111426 -338.810092) (xy 40.110907 -338.837335)
			(xy 40.102977 -338.891244) (xy 40.087449 -338.943474) (xy 40.06464 -338.99296) (xy 40.035015 -339.038692)
			(xy 40.017446 -339.05952) (xy 40.009031 -339.069826) (xy 39.997353 -339.093722) (xy 39.992231 -339.119822)
			(xy 39.994012 -339.146359) (xy 39.997888 -339.159088) (xy 40.019063 -339.180757) (xy 40.054942 -339.229573)
			(xy 40.082668 -339.283439) (xy 40.101546 -339.341006) (xy 40.111103 -339.40083) (xy 40.11168 -339.431122)
			(xy 40.111426 -339.445092) (xy 40.110952 -339.470505) (xy 40.104043 -339.520863) (xy 40.090504 -339.569857)
			(xy 40.070578 -339.616618) (xy 40.044616 -339.660317) (xy 40.013079 -339.70018) (xy 39.995094 -339.718142)
			(xy 39.985339 -339.728135) (xy 39.971307 -339.752272) (xy 39.964343 -339.779309) (xy 39.964969 -339.807221)
			(xy 39.973137 -339.833919) (xy 39.988236 -339.857403) (xy 39.998396 -339.866986) (xy 40.018206 -339.885169)
			(xy 40.052996 -339.926171) (xy 40.081692 -339.971647) (xy 40.103726 -340.020698) (xy 40.118662 -340.072355)
			(xy 40.126207 -340.125596) (xy 40.126666 -340.152482) (xy 40.126079 -340.182605) (xy 40.116601 -340.2421)
			(xy 40.097894 -340.299368) (xy 40.070422 -340.352985) (xy 40.034867 -340.40162) (xy 40.01389 -340.423246)
			(xy 40.004689 -340.432983) (xy 39.99124 -340.45614) (xy 39.984274 -340.481998) (xy 39.984271 -340.508777)
			(xy 39.99123 -340.534636) (xy 40.004673 -340.557797) (xy 40.01389 -340.567518) (xy 40.034854 -340.589158)
			(xy 40.070425 -340.637782) (xy 40.097908 -340.691395) (xy 40.11662 -340.748662) (xy 40.126095 -340.808159)
			(xy 40.126666 -340.838282) (xy 40.126198 -340.865652) (xy 40.118382 -340.919832) (xy 40.102894 -340.972335)
			(xy 40.080052 -341.022082) (xy 40.050327 -341.068049) (xy 40.032686 -341.08898) (xy 40.023468 -341.100321)
			(xy 40.01129 -341.126874) (xy 40.007114 -341.155786) (xy 40.011282 -341.1847) (xy 40.023453 -341.211256)
			(xy 40.032686 -341.222584) (xy 40.050309 -341.243531) (xy 40.080033 -341.289497) (xy 40.102879 -341.339241)
			(xy 40.118376 -341.391741) (xy 40.126206 -341.445917) (xy 40.126208 -341.500656) (xy 40.118382 -341.554833)
			(xy 40.102888 -341.607334) (xy 40.080046 -341.657079) (xy 40.050325 -341.703047) (xy 40.032686 -341.72398)
			(xy 40.023468 -341.735321) (xy 40.01129 -341.761874) (xy 40.007114 -341.790786) (xy 40.011282 -341.8197)
			(xy 40.023453 -341.846256) (xy 40.032686 -341.857584) (xy 40.050309 -341.878531) (xy 40.080033 -341.924497)
			(xy 40.102879 -341.974241) (xy 40.118376 -342.026741) (xy 40.126206 -342.080917) (xy 40.126208 -342.135656)
			(xy 40.118382 -342.189833) (xy 40.102888 -342.242334) (xy 40.080046 -342.292079) (xy 40.050325 -342.338047)
			(xy 40.032686 -342.35898) (xy 40.023468 -342.370321) (xy 40.01129 -342.396874) (xy 40.007114 -342.425786)
			(xy 40.011282 -342.4547) (xy 40.023453 -342.481256) (xy 40.032686 -342.492584) (xy 40.050329 -342.513513)
			(xy 40.080041 -342.559486) (xy 40.102876 -342.609235) (xy 40.118366 -342.661736) (xy 40.126193 -342.715913)
			(xy 40.126666 -342.743282) (xy 43.02125 -342.743282) (xy 43.021693 -342.715911) (xy 43.029515 -342.66173)
			(xy 43.045008 -342.609226) (xy 43.067856 -342.55948) (xy 43.097586 -342.513514) (xy 43.11523 -342.492584)
			(xy 43.124482 -342.481269) (xy 43.136653 -342.454706) (xy 43.140821 -342.425786) (xy 43.136646 -342.396868)
			(xy 43.124467 -342.370308) (xy 43.11523 -342.35898) (xy 43.097572 -342.338062) (xy 43.067847 -342.292091)
			(xy 43.045003 -342.242343) (xy 43.029508 -342.189839) (xy 43.021681 -342.135658) (xy 43.021683 -342.080915)
			(xy 43.029514 -342.026735) (xy 43.045012 -341.974232) (xy 43.06786 -341.924485) (xy 43.097588 -341.878517)
			(xy 43.11523 -341.857584) (xy 43.124482 -341.846269) (xy 43.136653 -341.819706) (xy 43.140821 -341.790786)
			(xy 43.136646 -341.761868) (xy 43.124467 -341.735308) (xy 43.11523 -341.72398) (xy 43.097572 -341.703062)
			(xy 43.067847 -341.657091) (xy 43.045003 -341.607343) (xy 43.029508 -341.554839) (xy 43.021681 -341.500658)
			(xy 43.021683 -341.445915) (xy 43.029514 -341.391735) (xy 43.045012 -341.339232) (xy 43.06786 -341.289485)
			(xy 43.097588 -341.243517) (xy 43.11523 -341.222584) (xy 43.124482 -341.211269) (xy 43.136653 -341.184706)
			(xy 43.140821 -341.155786) (xy 43.136646 -341.126868) (xy 43.124467 -341.100308) (xy 43.11523 -341.08898)
			(xy 43.09762 -341.068025) (xy 43.067902 -341.022059) (xy 43.04506 -340.972317) (xy 43.029563 -340.919822)
			(xy 43.021728 -340.86565) (xy 43.02125 -340.838282) (xy 43.02125 -340.838028) (xy 43.021846 -340.808195)
			(xy 43.031143 -340.749256) (xy 43.049499 -340.692483) (xy 43.076467 -340.639258) (xy 43.11139 -340.590879)
			(xy 43.131994 -340.569296) (xy 43.142625 -340.557741) (xy 43.157002 -340.529852) (xy 43.162226 -340.498914)
			(xy 43.157801 -340.467851) (xy 43.144146 -340.439601) (xy 43.133772 -340.427818) (xy 43.114184 -340.406442)
			(xy 43.081067 -340.358854) (xy 43.055538 -340.3068) (xy 43.038186 -340.25148) (xy 43.02941 -340.194171)
			(xy 43.02887 -340.165182) (xy 43.029319 -340.138581) (xy 43.036697 -340.085893) (xy 43.051322 -340.034741)
			(xy 43.07291 -339.986116) (xy 43.101043 -339.940961) (xy 43.135174 -339.900151) (xy 43.1546 -339.881972)
			(xy 43.164941 -339.872005) (xy 43.180033 -339.847581) (xy 43.187736 -339.819924) (xy 43.187444 -339.791215)
			(xy 43.179179 -339.76372) (xy 43.163593 -339.739609) (xy 43.153076 -339.729826) (xy 43.132762 -339.711618)
			(xy 43.097025 -339.670401) (xy 43.067521 -339.624515) (xy 43.044852 -339.574896) (xy 43.029478 -339.522555)
			(xy 43.021713 -339.468558) (xy 43.02125 -339.441282) (xy 43.021776 -339.412543) (xy 43.0304 -339.355717)
			(xy 43.04745 -339.300827) (xy 43.072541 -339.249115) (xy 43.105104 -339.201752) (xy 43.124374 -339.180424)
			(xy 43.134463 -339.168904) (xy 43.147803 -339.141353) (xy 43.152384 -339.111087) (xy 43.147795 -339.080822)
			(xy 43.134448 -339.053274) (xy 43.124374 -339.04174) (xy 43.105101 -339.020415) (xy 43.072533 -338.973053)
			(xy 43.047441 -338.921341) (xy 43.030391 -338.86645) (xy 43.02177 -338.809621) (xy 43.02125 -338.780882)
			(xy 43.021761 -338.753632) (xy 43.029519 -338.699688) (xy 43.044874 -338.647396) (xy 43.067514 -338.597821)
			(xy 43.096979 -338.551973) (xy 43.132667 -338.510784) (xy 43.173854 -338.475093) (xy 43.2197 -338.445626)
			(xy 43.269273 -338.422982) (xy 43.321564 -338.407624) (xy 43.375508 -338.399863) (xy 43.402758 -338.399374)
			(xy 43.431498 -338.399869) (xy 43.488326 -338.4085) (xy 43.543217 -338.425557) (xy 43.594928 -338.450655)
			(xy 43.64229 -338.483225) (xy 43.663616 -338.502498) (xy 43.67515 -338.51257) (xy 43.702696 -338.525912)
			(xy 43.732958 -338.530497) (xy 43.76322 -338.525912) (xy 43.790766 -338.51257) (xy 43.8023 -338.502498)
			(xy 43.823627 -338.483228) (xy 43.87099 -338.450663) (xy 43.922701 -338.425572) (xy 43.977592 -338.408522)
			(xy 44.034419 -338.3999) (xy 44.091897 -338.3999) (xy 44.148724 -338.408522) (xy 44.203615 -338.425572)
			(xy 44.255326 -338.450663) (xy 44.302689 -338.483228) (xy 44.324016 -338.502498) (xy 44.33555 -338.51257)
			(xy 44.363096 -338.525912) (xy 44.393358 -338.530497) (xy 44.42362 -338.525912) (xy 44.451166 -338.51257)
			(xy 44.4627 -338.502498) (xy 44.484012 -338.48321) (xy 44.531377 -338.450644) (xy 44.583093 -338.425554)
			(xy 44.637987 -338.408508) (xy 44.694818 -338.399891) (xy 44.723558 -338.399374) (xy 44.750809 -338.399894)
			(xy 44.804757 -338.407645) (xy 44.857053 -338.422995) (xy 44.906631 -338.445631) (xy 44.952484 -338.475093)
			(xy 44.993677 -338.510781) (xy 45.029371 -338.551968) (xy 45.05884 -338.597816) (xy 45.081484 -338.647391)
			(xy 45.096842 -338.699684) (xy 45.104601 -338.753631) (xy 45.105066 -338.780882) (xy 45.104514 -338.80962)
			(xy 45.095895 -338.866445) (xy 45.078851 -338.921335) (xy 45.053766 -338.973047) (xy 45.021209 -339.020411)
			(xy 45.001942 -339.04174) (xy 44.991887 -339.053288) (xy 44.978541 -339.080829) (xy 44.973953 -339.111087)
			(xy 44.978534 -339.141346) (xy 44.991872 -339.16889) (xy 45.001942 -339.180424) (xy 45.021201 -339.201761)
			(xy 45.05377 -339.24912) (xy 45.078865 -339.300829) (xy 45.095918 -339.355718) (xy 45.104544 -339.412544)
			(xy 45.105066 -339.441282) (xy 45.104581 -339.467882) (xy 45.097208 -339.520567) (xy 45.08259 -339.571718)
			(xy 45.061009 -339.620343) (xy 45.032883 -339.665499) (xy 44.998758 -339.706312) (xy 44.979336 -339.724492)
			(xy 44.969028 -339.734492) (xy 44.953929 -339.758905) (xy 44.946218 -339.786555) (xy 44.946504 -339.815258)
			(xy 44.954764 -339.842749) (xy 44.970345 -339.866857) (xy 44.98086 -339.876638) (xy 45.001164 -339.894857)
			(xy 45.0369 -339.936073) (xy 45.066404 -339.981956) (xy 45.089075 -340.031573) (xy 45.104452 -340.083912)
			(xy 45.112221 -340.137907) (xy 45.112686 -340.165182) (xy 45.112686 -340.165436) (xy 45.112546 -340.172802)
			(xy 47.71263 -340.172802) (xy 47.713127 -340.145156) (xy 47.721126 -340.090444) (xy 47.736942 -340.037461)
			(xy 47.760243 -339.987318) (xy 47.790542 -339.941065) (xy 47.827203 -339.899672) (xy 47.848012 -339.881464)
			(xy 47.858786 -339.871635) (xy 47.874807 -339.847284) (xy 47.883311 -339.819404) (xy 47.883608 -339.790257)
			(xy 47.875673 -339.762209) (xy 47.860151 -339.737538) (xy 47.849536 -339.72754) (xy 47.829588 -339.709355)
			(xy 47.794526 -339.668314) (xy 47.765598 -339.622741) (xy 47.743382 -339.573546) (xy 47.728321 -339.521712)
			(xy 47.720716 -339.468271) (xy 47.72025 -339.441282) (xy 47.720776 -339.412543) (xy 47.7294 -339.355717)
			(xy 47.74645 -339.300827) (xy 47.771541 -339.249115) (xy 47.804104 -339.201752) (xy 47.823374 -339.180424)
			(xy 47.833463 -339.168904) (xy 47.846803 -339.141353) (xy 47.851384 -339.111087) (xy 47.846795 -339.080822)
			(xy 47.833448 -339.053274) (xy 47.823374 -339.04174) (xy 47.804101 -339.020415) (xy 47.771533 -338.973053)
			(xy 47.746441 -338.921341) (xy 47.729391 -338.86645) (xy 47.72077 -338.809621) (xy 47.72025 -338.780882)
			(xy 47.720761 -338.753632) (xy 47.728519 -338.699688) (xy 47.743874 -338.647396) (xy 47.766514 -338.597821)
			(xy 47.795979 -338.551973) (xy 47.831667 -338.510784) (xy 47.872854 -338.475093) (xy 47.9187 -338.445626)
			(xy 47.968273 -338.422982) (xy 48.020564 -338.407624) (xy 48.074508 -338.399863) (xy 48.101758 -338.399374)
			(xy 48.130498 -338.399869) (xy 48.187326 -338.4085) (xy 48.242217 -338.425557) (xy 48.293928 -338.450655)
			(xy 48.34129 -338.483225) (xy 48.362616 -338.502498) (xy 48.37415 -338.51257) (xy 48.401696 -338.525912)
			(xy 48.431958 -338.530497) (xy 48.46222 -338.525912) (xy 48.489766 -338.51257) (xy 48.5013 -338.502498)
			(xy 48.522627 -338.483228) (xy 48.56999 -338.450663) (xy 48.621701 -338.425572) (xy 48.676592 -338.408522)
			(xy 48.733419 -338.3999) (xy 48.790897 -338.3999) (xy 48.847724 -338.408522) (xy 48.902615 -338.425572)
			(xy 48.954326 -338.450663) (xy 49.001689 -338.483228) (xy 49.023016 -338.502498) (xy 49.03455 -338.51257)
			(xy 49.062096 -338.525912) (xy 49.092358 -338.530497) (xy 49.12262 -338.525912) (xy 49.150166 -338.51257)
			(xy 49.1617 -338.502498) (xy 49.183012 -338.48321) (xy 49.230377 -338.450644) (xy 49.282093 -338.425554)
			(xy 49.336987 -338.408508) (xy 49.393818 -338.399891) (xy 49.422558 -338.399374) (xy 49.449809 -338.399894)
			(xy 49.503757 -338.407645) (xy 49.556053 -338.422995) (xy 49.605631 -338.445631) (xy 49.651484 -338.475093)
			(xy 49.692677 -338.510781) (xy 49.728371 -338.551968) (xy 49.75784 -338.597816) (xy 49.780484 -338.647391)
			(xy 49.795842 -338.699684) (xy 49.803601 -338.753631) (xy 49.804066 -338.780882) (xy 49.803514 -338.80962)
			(xy 49.794895 -338.866445) (xy 49.777851 -338.921335) (xy 49.752766 -338.973047) (xy 49.720209 -339.020411)
			(xy 49.700942 -339.04174) (xy 49.690887 -339.053288) (xy 49.677541 -339.080829) (xy 49.672953 -339.111087)
			(xy 49.677534 -339.141346) (xy 49.690872 -339.16889) (xy 49.700942 -339.180424) (xy 49.720201 -339.201761)
			(xy 49.75277 -339.24912) (xy 49.777865 -339.300829) (xy 49.794918 -339.355718) (xy 49.803544 -339.412544)
			(xy 49.804066 -339.441282) (xy 49.80356 -339.468928) (xy 49.795563 -339.523639) (xy 49.779749 -339.576622)
			(xy 49.756449 -339.626766) (xy 49.726152 -339.673019) (xy 49.689493 -339.714412) (xy 49.668684 -339.73262)
			(xy 49.657819 -339.742361) (xy 49.641786 -339.766732) (xy 49.633283 -339.794638) (xy 49.633002 -339.823809)
			(xy 49.640965 -339.851874) (xy 49.656525 -339.87655) (xy 49.66716 -339.886544) (xy 49.687099 -339.904738)
			(xy 49.722162 -339.945777) (xy 49.751091 -339.991348) (xy 49.773309 -340.040541) (xy 49.788372 -340.092374)
			(xy 49.795979 -340.145813) (xy 49.796446 -340.172802) (xy 49.795882 -340.20136) (xy 49.787374 -340.257838)
			(xy 49.770547 -340.312419) (xy 49.745777 -340.363885) (xy 49.713618 -340.411086) (xy 49.694592 -340.43239)
			(xy 49.684469 -340.444114) (xy 49.671114 -340.472041) (xy 49.666746 -340.502687) (xy 49.671766 -340.533234)
			(xy 49.685713 -340.56087) (xy 49.696116 -340.572344) (xy 49.71624 -340.593841) (xy 49.750307 -340.641867)
			(xy 49.776592 -340.694557) (xy 49.794471 -340.750658) (xy 49.803519 -340.808841) (xy 49.804066 -340.838282)
			(xy 49.803598 -340.865652) (xy 49.795782 -340.919832) (xy 49.780294 -340.972335) (xy 49.757452 -341.022082)
			(xy 49.727727 -341.068049) (xy 49.710086 -341.08898) (xy 49.700868 -341.100321) (xy 49.68869 -341.126874)
			(xy 49.684514 -341.155786) (xy 49.688682 -341.1847) (xy 49.700853 -341.211256) (xy 49.710086 -341.222584)
			(xy 49.727709 -341.243531) (xy 49.757433 -341.289497) (xy 49.780279 -341.339241) (xy 49.795776 -341.391741)
			(xy 49.803606 -341.445917) (xy 49.803608 -341.500656) (xy 49.795782 -341.554833) (xy 49.780288 -341.607334)
			(xy 49.757446 -341.657079) (xy 49.727725 -341.703047) (xy 49.710086 -341.72398) (xy 49.700868 -341.735321)
			(xy 49.68869 -341.761874) (xy 49.684514 -341.790786) (xy 49.688682 -341.8197) (xy 49.700853 -341.846256)
			(xy 49.710086 -341.857584) (xy 49.727709 -341.878531) (xy 49.757433 -341.924497) (xy 49.780279 -341.974241)
			(xy 49.795776 -342.026741) (xy 49.803606 -342.080917) (xy 49.803608 -342.135656) (xy 49.795782 -342.189833)
			(xy 49.780288 -342.242334) (xy 49.757446 -342.292079) (xy 49.727725 -342.338047) (xy 49.710086 -342.35898)
			(xy 49.700868 -342.370321) (xy 49.68869 -342.396874) (xy 49.684514 -342.425786) (xy 49.688682 -342.4547)
			(xy 49.700853 -342.481256) (xy 49.710086 -342.492584) (xy 49.727729 -342.513513) (xy 49.757441 -342.559486)
			(xy 49.780276 -342.609235) (xy 49.795766 -342.661736) (xy 49.803593 -342.715913) (xy 49.804066 -342.743282)
			(xy 49.803628 -342.770536) (xy 49.795872 -342.82449) (xy 49.780516 -342.876791) (xy 49.757873 -342.926374)
			(xy 49.728403 -342.972229) (xy 49.692706 -343.013423) (xy 49.65151 -343.049117) (xy 49.605653 -343.078584)
			(xy 49.556069 -343.101225) (xy 49.503767 -343.116577) (xy 49.449812 -343.12433) (xy 49.422558 -343.12479)
			(xy 49.393818 -343.124294) (xy 49.336989 -343.115665) (xy 49.282098 -343.098609) (xy 49.230387 -343.073511)
			(xy 49.183026 -343.04094) (xy 49.1617 -343.021666) (xy 49.150166 -343.011594) (xy 49.12262 -342.998252)
			(xy 49.092358 -342.993667) (xy 49.062096 -342.998252) (xy 49.03455 -343.011594) (xy 49.023016 -343.021666)
			(xy 49.001689 -343.040936) (xy 48.954326 -343.073501) (xy 48.902615 -343.098592) (xy 48.847724 -343.115642)
			(xy 48.790897 -343.124264) (xy 48.733419 -343.124264) (xy 48.676592 -343.115642) (xy 48.621701 -343.098592)
			(xy 48.56999 -343.073501) (xy 48.522627 -343.040936) (xy 48.5013 -343.021666) (xy 48.489766 -343.011594)
			(xy 48.46222 -342.998252) (xy 48.431958 -342.993667) (xy 48.401696 -342.998252) (xy 48.37415 -343.011594)
			(xy 48.362616 -343.021666) (xy 48.341307 -343.040957) (xy 48.29394 -343.073521) (xy 48.242224 -343.098609)
			(xy 48.187329 -343.115655) (xy 48.130498 -343.124272) (xy 48.101758 -343.12479) (xy 48.074505 -343.124361)
			(xy 48.020554 -343.116599) (xy 47.968257 -343.101237) (xy 47.918679 -343.07859) (xy 47.872828 -343.049117)
			(xy 47.831637 -343.01342) (xy 47.795947 -342.972224) (xy 47.766481 -342.926369) (xy 47.743842 -342.876786)
			(xy 47.728489 -342.824487) (xy 47.720735 -342.770535) (xy 47.72025 -342.743282) (xy 47.720693 -342.715911)
			(xy 47.728515 -342.66173) (xy 47.744008 -342.609226) (xy 47.766856 -342.55948) (xy 47.796586 -342.513514)
			(xy 47.81423 -342.492584) (xy 47.823482 -342.481269) (xy 47.835653 -342.454706) (xy 47.839821 -342.425786)
			(xy 47.835646 -342.396868) (xy 47.823467 -342.370308) (xy 47.81423 -342.35898) (xy 47.796572 -342.338062)
			(xy 47.766847 -342.292091) (xy 47.744003 -342.242343) (xy 47.728508 -342.189839) (xy 47.720681 -342.135658)
			(xy 47.720683 -342.080915) (xy 47.728514 -342.026735) (xy 47.744012 -341.974232) (xy 47.76686 -341.924485)
			(xy 47.796588 -341.878517) (xy 47.81423 -341.857584) (xy 47.823482 -341.846269) (xy 47.835653 -341.819706)
			(xy 47.839821 -341.790786) (xy 47.835646 -341.761868) (xy 47.823467 -341.735308) (xy 47.81423 -341.72398)
			(xy 47.796572 -341.703062) (xy 47.766847 -341.657091) (xy 47.744003 -341.607343) (xy 47.728508 -341.554839)
			(xy 47.720681 -341.500658) (xy 47.720683 -341.445915) (xy 47.728514 -341.391735) (xy 47.744012 -341.339232)
			(xy 47.76686 -341.289485) (xy 47.796588 -341.243517) (xy 47.81423 -341.222584) (xy 47.823482 -341.211269)
			(xy 47.835653 -341.184706) (xy 47.839821 -341.155786) (xy 47.835646 -341.126868) (xy 47.823467 -341.100308)
			(xy 47.81423 -341.08898) (xy 47.79662 -341.068025) (xy 47.766902 -341.022059) (xy 47.74406 -340.972317)
			(xy 47.728563 -340.919822) (xy 47.720728 -340.86565) (xy 47.72025 -340.838282) (xy 47.720805 -340.809724)
			(xy 47.729316 -340.753245) (xy 47.746145 -340.698664) (xy 47.770916 -340.647199) (xy 47.803078 -340.599998)
			(xy 47.822104 -340.578694) (xy 47.832243 -340.566983) (xy 47.845597 -340.539051) (xy 47.849963 -340.508401)
			(xy 47.844938 -340.477852) (xy 47.830985 -340.450214) (xy 47.82058 -340.43874) (xy 47.800448 -340.417251)
			(xy 47.766382 -340.369222) (xy 47.740099 -340.316531) (xy 47.722222 -340.260427) (xy 47.713176 -340.202243)
			(xy 47.71263 -340.172802) (xy 45.112546 -340.172802) (xy 45.11212 -340.19527) (xy 45.102814 -340.254209)
			(xy 45.08445 -340.310983) (xy 45.057476 -340.364207) (xy 45.022548 -340.412585) (xy 45.001942 -340.434168)
			(xy 44.991253 -340.445671) (xy 44.976891 -340.47358) (xy 44.971683 -340.504532) (xy 44.976121 -340.535604)
			(xy 44.989785 -340.56386) (xy 45.000164 -340.575646) (xy 45.019724 -340.597046) (xy 45.052847 -340.644627)
			(xy 45.078382 -340.696675) (xy 45.095741 -340.751989) (xy 45.104523 -340.809295) (xy 45.105066 -340.838282)
			(xy 45.104598 -340.865652) (xy 45.096782 -340.919832) (xy 45.081294 -340.972335) (xy 45.058452 -341.022082)
			(xy 45.028727 -341.068049) (xy 45.011086 -341.08898) (xy 45.001868 -341.100321) (xy 44.98969 -341.126874)
			(xy 44.985514 -341.155786) (xy 44.989682 -341.1847) (xy 45.001853 -341.211256) (xy 45.011086 -341.222584)
			(xy 45.028709 -341.243531) (xy 45.058433 -341.289497) (xy 45.081279 -341.339241) (xy 45.096776 -341.391741)
			(xy 45.104606 -341.445917) (xy 45.104608 -341.500656) (xy 45.096782 -341.554833) (xy 45.081288 -341.607334)
			(xy 45.058446 -341.657079) (xy 45.028725 -341.703047) (xy 45.011086 -341.72398) (xy 45.001868 -341.735321)
			(xy 44.98969 -341.761874) (xy 44.985514 -341.790786) (xy 44.989682 -341.8197) (xy 45.001853 -341.846256)
			(xy 45.011086 -341.857584) (xy 45.028709 -341.878531) (xy 45.058433 -341.924497) (xy 45.081279 -341.974241)
			(xy 45.096776 -342.026741) (xy 45.104606 -342.080917) (xy 45.104608 -342.135656) (xy 45.096782 -342.189833)
			(xy 45.081288 -342.242334) (xy 45.058446 -342.292079) (xy 45.028725 -342.338047) (xy 45.011086 -342.35898)
			(xy 45.001868 -342.370321) (xy 44.98969 -342.396874) (xy 44.985514 -342.425786) (xy 44.989682 -342.4547)
			(xy 45.001853 -342.481256) (xy 45.011086 -342.492584) (xy 45.028729 -342.513513) (xy 45.058441 -342.559486)
			(xy 45.081276 -342.609235) (xy 45.096766 -342.661736) (xy 45.104593 -342.715913) (xy 45.105066 -342.743282)
			(xy 45.104628 -342.770536) (xy 45.096872 -342.82449) (xy 45.081516 -342.876791) (xy 45.058873 -342.926374)
			(xy 45.029403 -342.972229) (xy 44.993706 -343.013423) (xy 44.95251 -343.049117) (xy 44.906653 -343.078584)
			(xy 44.857069 -343.101225) (xy 44.804767 -343.116577) (xy 44.750812 -343.12433) (xy 44.723558 -343.12479)
			(xy 44.694818 -343.124294) (xy 44.637989 -343.115665) (xy 44.583098 -343.098609) (xy 44.531387 -343.073511)
			(xy 44.484026 -343.04094) (xy 44.4627 -343.021666) (xy 44.451166 -343.011594) (xy 44.42362 -342.998252)
			(xy 44.393358 -342.993667) (xy 44.363096 -342.998252) (xy 44.33555 -343.011594) (xy 44.324016 -343.021666)
			(xy 44.302689 -343.040936) (xy 44.255326 -343.073501) (xy 44.203615 -343.098592) (xy 44.148724 -343.115642)
			(xy 44.091897 -343.124264) (xy 44.034419 -343.124264) (xy 43.977592 -343.115642) (xy 43.922701 -343.098592)
			(xy 43.87099 -343.073501) (xy 43.823627 -343.040936) (xy 43.8023 -343.021666) (xy 43.790766 -343.011594)
			(xy 43.76322 -342.998252) (xy 43.732958 -342.993667) (xy 43.702696 -342.998252) (xy 43.67515 -343.011594)
			(xy 43.663616 -343.021666) (xy 43.642307 -343.040957) (xy 43.59494 -343.073521) (xy 43.543224 -343.098609)
			(xy 43.488329 -343.115655) (xy 43.431498 -343.124272) (xy 43.402758 -343.12479) (xy 43.375505 -343.124361)
			(xy 43.321554 -343.116599) (xy 43.269257 -343.101237) (xy 43.219679 -343.07859) (xy 43.173828 -343.049117)
			(xy 43.132637 -343.01342) (xy 43.096947 -342.972224) (xy 43.067481 -342.926369) (xy 43.044842 -342.876786)
			(xy 43.029489 -342.824487) (xy 43.021735 -342.770535) (xy 43.02125 -342.743282) (xy 40.126666 -342.743282)
			(xy 40.126228 -342.770536) (xy 40.118472 -342.82449) (xy 40.103116 -342.876791) (xy 40.080473 -342.926374)
			(xy 40.051003 -342.972229) (xy 40.015306 -343.013423) (xy 39.97411 -343.049117) (xy 39.928253 -343.078584)
			(xy 39.878669 -343.101225) (xy 39.826367 -343.116577) (xy 39.772412 -343.12433) (xy 39.745158 -343.12479)
			(xy 39.716418 -343.124294) (xy 39.659589 -343.115665) (xy 39.604698 -343.098609) (xy 39.552987 -343.073511)
			(xy 39.505626 -343.04094) (xy 39.4843 -343.021666) (xy 39.472766 -343.011594) (xy 39.44522 -342.998252)
			(xy 39.414958 -342.993667) (xy 39.384696 -342.998252) (xy 39.35715 -343.011594) (xy 39.345616 -343.021666)
			(xy 39.324289 -343.040936) (xy 39.276926 -343.073501) (xy 39.225215 -343.098592) (xy 39.170324 -343.115642)
			(xy 39.113497 -343.124264) (xy 39.056019 -343.124264) (xy 38.999192 -343.115642) (xy 38.944301 -343.098592)
			(xy 38.89259 -343.073501) (xy 38.845227 -343.040936) (xy 38.8239 -343.021666) (xy 38.812366 -343.011594)
			(xy 38.78482 -342.998252) (xy 38.754558 -342.993667) (xy 38.724296 -342.998252) (xy 38.69675 -343.011594)
			(xy 38.685216 -343.021666) (xy 38.663907 -343.040957) (xy 38.61654 -343.073521) (xy 38.564824 -343.098609)
			(xy 38.509929 -343.115655) (xy 38.453098 -343.124272) (xy 38.424358 -343.12479) (xy 38.397105 -343.124361)
			(xy 38.343154 -343.116599) (xy 38.290857 -343.101237) (xy 38.241279 -343.07859) (xy 38.195428 -343.049117)
			(xy 38.154237 -343.01342) (xy 38.118547 -342.972224) (xy 38.089081 -342.926369) (xy 38.066442 -342.876786)
			(xy 38.051089 -342.824487) (xy 38.043335 -342.770535) (xy 38.04285 -342.743282) (xy 38.043293 -342.715911)
			(xy 38.051115 -342.66173) (xy 38.066608 -342.609226) (xy 38.089456 -342.55948) (xy 38.119186 -342.513514)
			(xy 38.13683 -342.492584) (xy 38.146082 -342.481269) (xy 38.158253 -342.454706) (xy 38.162421 -342.425786)
			(xy 38.158246 -342.396868) (xy 38.146067 -342.370308) (xy 38.13683 -342.35898) (xy 38.119172 -342.338062)
			(xy 38.089447 -342.292091) (xy 38.066603 -342.242343) (xy 38.051108 -342.189839) (xy 38.043281 -342.135658)
			(xy 38.043283 -342.080915) (xy 38.051114 -342.026735) (xy 38.066612 -341.974232) (xy 38.08946 -341.924485)
			(xy 38.119188 -341.878517) (xy 38.13683 -341.857584) (xy 38.146082 -341.846269) (xy 38.158253 -341.819706)
			(xy 38.162421 -341.790786) (xy 38.158246 -341.761868) (xy 38.146067 -341.735308) (xy 38.13683 -341.72398)
			(xy 38.119172 -341.703062) (xy 38.089447 -341.657091) (xy 38.066603 -341.607343) (xy 38.051108 -341.554839)
			(xy 38.043281 -341.500658) (xy 38.043283 -341.445915) (xy 38.051114 -341.391735) (xy 38.066612 -341.339232)
			(xy 38.08946 -341.289485) (xy 38.119188 -341.243517) (xy 38.13683 -341.222584) (xy 38.146082 -341.211269)
			(xy 38.158253 -341.184706) (xy 38.162421 -341.155786) (xy 38.158246 -341.126868) (xy 38.146067 -341.100308)
			(xy 38.13683 -341.08898) (xy 38.11922 -341.068025) (xy 38.089502 -341.022059) (xy 38.06666 -340.972317)
			(xy 38.051163 -340.919822) (xy 38.043328 -340.86565) (xy 38.04285 -340.838282) (xy 38.043409 -340.808158)
			(xy 38.052893 -340.748661) (xy 38.071607 -340.691393) (xy 38.099085 -340.637776) (xy 38.134646 -340.589142)
			(xy 38.155626 -340.567518) (xy 38.164862 -340.557812) (xy 38.178306 -340.534645) (xy 38.185266 -340.50878)
			(xy 38.185263 -340.481995) (xy 38.178297 -340.456131) (xy 38.164846 -340.432968) (xy 38.155626 -340.423246)
			(xy 38.134647 -340.40162) (xy 38.099078 -340.352992) (xy 38.071597 -340.299376) (xy 38.052888 -340.242106)
			(xy 38.043418 -340.182606) (xy 38.04285 -340.152482) (xy 38.043236 -340.126961) (xy 38.050033 -340.076373)
			(xy 38.063518 -340.027143) (xy 38.083448 -339.980152) (xy 38.109469 -339.93624) (xy 38.141114 -339.896191)
			(xy 38.159182 -339.878162) (xy 38.168936 -339.868167) (xy 38.182971 -339.844031) (xy 38.189938 -339.816994)
			(xy 38.189313 -339.789081) (xy 38.181143 -339.762383) (xy 38.166041 -339.7389) (xy 38.15588 -339.729318)
			(xy 38.136067 -339.711138) (xy 38.101279 -339.670134) (xy 38.072584 -339.624658) (xy 38.05055 -339.575606)
			(xy 38.035614 -339.523949) (xy 38.02807 -339.470708) (xy 38.02761 -339.443822) (xy 34.902394 -339.443822)
			(xy 34.902394 -353.70643) (xy 35.21405 -353.70643) (xy 35.218121 -353.650808) (xy 35.230247 -353.596371)
			(xy 35.25017 -353.54428) (xy 35.277466 -353.495645) (xy 35.311552 -353.451502) (xy 35.351701 -353.412793)
			(xy 35.397059 -353.380342) (xy 35.446659 -353.354841) (xy 35.499443 -353.336834) (xy 35.554286 -353.326704)
			(xy 35.61002 -353.324667) (xy 35.665457 -353.330767) (xy 35.719414 -353.344873) (xy 35.770743 -353.366685)
			(xy 35.818349 -353.395739) (xy 35.861217 -353.431414) (xy 35.898434 -353.472951) (xy 35.929207 -353.519464)
			(xy 35.952879 -353.569961) (xy 35.968947 -353.623368) (xy 35.977067 -353.678544) (xy 35.977576 -353.70643)
			(xy 35.977067 -353.734316) (xy 35.968947 -353.789492) (xy 35.952879 -353.842899) (xy 35.929207 -353.893396)
			(xy 35.898434 -353.939909) (xy 35.861217 -353.981446) (xy 35.818349 -354.017121) (xy 35.770743 -354.046175)
			(xy 35.719414 -354.067987) (xy 35.665457 -354.082093) (xy 35.61002 -354.088193) (xy 35.554286 -354.086156)
			(xy 35.499443 -354.076026) (xy 35.446659 -354.058019) (xy 35.397059 -354.032518) (xy 35.351701 -354.000067)
			(xy 35.311552 -353.961358) (xy 35.277466 -353.917215) (xy 35.25017 -353.86858) (xy 35.230247 -353.816489)
			(xy 35.218121 -353.762052) (xy 35.21405 -353.70643) (xy 34.902394 -353.70643) (xy 34.902394 -354.65385)
			(xy 35.21405 -354.65385) (xy 35.218121 -354.598228) (xy 35.230247 -354.543791) (xy 35.25017 -354.4917)
			(xy 35.277466 -354.443065) (xy 35.311552 -354.398922) (xy 35.351701 -354.360213) (xy 35.397059 -354.327762)
			(xy 35.446659 -354.302261) (xy 35.499443 -354.284254) (xy 35.554286 -354.274124) (xy 35.61002 -354.272087)
			(xy 35.665457 -354.278187) (xy 35.719414 -354.292293) (xy 35.770743 -354.314105) (xy 35.818349 -354.343159)
			(xy 35.861217 -354.378834) (xy 35.898434 -354.420371) (xy 35.929207 -354.466884) (xy 35.952879 -354.517381)
			(xy 35.968947 -354.570788) (xy 35.977067 -354.625964) (xy 35.977576 -354.65385) (xy 35.977067 -354.681736)
			(xy 35.968947 -354.736912) (xy 35.952879 -354.790319) (xy 35.929207 -354.840816) (xy 35.898434 -354.887329)
			(xy 35.861217 -354.928866) (xy 35.818349 -354.964541) (xy 35.770743 -354.993595) (xy 35.721478 -355.01453)
			(xy 37.608764 -355.01453) (xy 37.608764 -355.014276) (xy 37.609295 -354.986262) (xy 37.617514 -354.93084)
			(xy 37.633742 -354.877213) (xy 37.657631 -354.826533) (xy 37.688668 -354.779887) (xy 37.707062 -354.758752)
			(xy 37.716729 -354.747326) (xy 37.729509 -354.720278) (xy 37.733892 -354.690685) (xy 37.7295 -354.661093)
			(xy 37.716712 -354.634049) (xy 37.707062 -354.622608) (xy 37.688634 -354.601497) (xy 37.657566 -354.55486)
			(xy 37.633664 -354.504176) (xy 37.617442 -354.450538) (xy 37.609252 -354.395103) (xy 37.608764 -354.367084)
			(xy 37.608764 -354.36683) (xy 37.60925 -354.339579) (xy 37.617006 -354.285631) (xy 37.632361 -354.233336)
			(xy 37.655003 -354.183759) (xy 37.684469 -354.137909) (xy 37.72016 -354.096718) (xy 37.761351 -354.061027)
			(xy 37.807201 -354.031561) (xy 37.856778 -354.008919) (xy 37.909073 -353.993564) (xy 37.963021 -353.985808)
			(xy 38.017523 -353.985808) (xy 38.071471 -353.993564) (xy 38.123766 -354.008919) (xy 38.173343 -354.031561)
			(xy 38.219193 -354.061027) (xy 38.260384 -354.096718) (xy 38.296075 -354.137909) (xy 38.325541 -354.183759)
			(xy 38.348183 -354.233336) (xy 38.363538 -354.285631) (xy 38.371294 -354.339579) (xy 38.37178 -354.36683)
			(xy 38.37178 -354.367084) (xy 38.371299 -354.3951) (xy 38.36307 -354.450525) (xy 38.346831 -354.504153)
			(xy 38.322931 -354.554832) (xy 38.291882 -354.601475) (xy 38.273482 -354.622608) (xy 38.269002 -354.627942)
			(xy 45.58614 -354.627942) (xy 45.590211 -354.57232) (xy 45.602337 -354.517883) (xy 45.62226 -354.465792)
			(xy 45.649556 -354.417157) (xy 45.683642 -354.373014) (xy 45.723791 -354.334305) (xy 45.769149 -354.301854)
			(xy 45.818749 -354.276353) (xy 45.871533 -354.258346) (xy 45.926376 -354.248216) (xy 45.98211 -354.246179)
			(xy 46.037547 -354.252279) (xy 46.091504 -354.266385) (xy 46.142833 -354.288197) (xy 46.190439 -354.317251)
			(xy 46.233307 -354.352926) (xy 46.270524 -354.394463) (xy 46.301297 -354.440976) (xy 46.324969 -354.491473)
			(xy 46.341037 -354.54488) (xy 46.349157 -354.600056) (xy 46.349666 -354.627942) (xy 46.349157 -354.655828)
			(xy 46.341037 -354.711004) (xy 46.324969 -354.764411) (xy 46.301297 -354.814908) (xy 46.270524 -354.861421)
			(xy 46.233307 -354.902958) (xy 46.190439 -354.938633) (xy 46.142833 -354.967687) (xy 46.091504 -354.989499)
			(xy 46.037547 -355.003605) (xy 45.995969 -355.00818) (xy 47.297086 -355.00818) (xy 47.297544 -354.98081)
			(xy 47.305364 -354.92663) (xy 47.320855 -354.874127) (xy 47.343699 -354.82438) (xy 47.373424 -354.778414)
			(xy 47.391066 -354.757482) (xy 47.400325 -354.74617) (xy 47.412504 -354.719608) (xy 47.416674 -354.690685)
			(xy 47.412495 -354.661763) (xy 47.400308 -354.635204) (xy 47.391066 -354.623878) (xy 47.373445 -354.602932)
			(xy 47.343731 -354.556962) (xy 47.320893 -354.507218) (xy 47.305397 -354.454721) (xy 47.297563 -354.400548)
			(xy 47.297086 -354.37318) (xy 47.297572 -354.345929) (xy 47.305328 -354.291981) (xy 47.320683 -354.239686)
			(xy 47.343325 -354.190109) (xy 47.372791 -354.144259) (xy 47.408482 -354.103068) (xy 47.449673 -354.067377)
			(xy 47.495523 -354.037911) (xy 47.5451 -354.015269) (xy 47.597395 -353.999914) (xy 47.651343 -353.992158)
			(xy 47.705845 -353.992158) (xy 47.759793 -353.999914) (xy 47.812088 -354.015269) (xy 47.861665 -354.037911)
			(xy 47.907515 -354.067377) (xy 47.948706 -354.103068) (xy 47.984397 -354.144259) (xy 48.013863 -354.190109)
			(xy 48.036505 -354.239686) (xy 48.05186 -354.291981) (xy 48.059616 -354.345929) (xy 48.060102 -354.37318)
			(xy 48.059624 -354.40055) (xy 48.051809 -354.454728) (xy 48.036323 -354.507231) (xy 48.013484 -354.556978)
			(xy 47.983762 -354.602946) (xy 47.966122 -354.623878) (xy 47.956903 -354.635219) (xy 47.94472 -354.661771)
			(xy 47.940543 -354.690685) (xy 47.944712 -354.7196) (xy 47.956886 -354.746156) (xy 47.966122 -354.757482)
			(xy 47.98377 -354.778407) (xy 48.013479 -354.824382) (xy 48.036313 -354.874132) (xy 48.051802 -354.926634)
			(xy 48.059629 -354.98081) (xy 48.060102 -355.00818) (xy 48.059616 -355.035431) (xy 48.05186 -355.089379)
			(xy 48.036505 -355.141674) (xy 48.013863 -355.191251) (xy 47.984397 -355.237101) (xy 47.948706 -355.278292)
			(xy 47.907515 -355.313983) (xy 47.861665 -355.343449) (xy 47.812088 -355.366091) (xy 47.759793 -355.381446)
			(xy 47.705845 -355.389202) (xy 47.651343 -355.389202) (xy 47.597395 -355.381446) (xy 47.5451 -355.366091)
			(xy 47.495523 -355.343449) (xy 47.449673 -355.313983) (xy 47.408482 -355.278292) (xy 47.372791 -355.237101)
			(xy 47.343325 -355.191251) (xy 47.320683 -355.141674) (xy 47.305328 -355.089379) (xy 47.297572 -355.035431)
			(xy 47.297086 -355.00818) (xy 45.995969 -355.00818) (xy 45.98211 -355.009705) (xy 45.926376 -355.007668)
			(xy 45.871533 -354.997538) (xy 45.818749 -354.979531) (xy 45.769149 -354.95403) (xy 45.723791 -354.921579)
			(xy 45.683642 -354.88287) (xy 45.649556 -354.838727) (xy 45.62226 -354.790092) (xy 45.602337 -354.738001)
			(xy 45.590211 -354.683564) (xy 45.58614 -354.627942) (xy 38.269002 -354.627942) (xy 38.263859 -354.634066)
			(xy 38.251081 -354.661104) (xy 38.246693 -354.690685) (xy 38.251072 -354.720268) (xy 38.263843 -354.747309)
			(xy 38.273482 -354.758752) (xy 38.291898 -354.779873) (xy 38.322967 -354.826507) (xy 38.346871 -354.877189)
			(xy 38.363095 -354.930825) (xy 38.37129 -354.986258) (xy 38.37178 -355.014276) (xy 38.37178 -355.01453)
			(xy 38.371294 -355.041781) (xy 38.363538 -355.095729) (xy 38.348183 -355.148024) (xy 38.325541 -355.197601)
			(xy 38.296075 -355.243451) (xy 38.260384 -355.284642) (xy 38.219193 -355.320333) (xy 38.173343 -355.349799)
			(xy 38.123766 -355.372441) (xy 38.071471 -355.387796) (xy 38.017523 -355.395552) (xy 37.963021 -355.395552)
			(xy 37.909073 -355.387796) (xy 37.856778 -355.372441) (xy 37.807201 -355.349799) (xy 37.761351 -355.320333)
			(xy 37.72016 -355.284642) (xy 37.684469 -355.243451) (xy 37.655003 -355.197601) (xy 37.632361 -355.148024)
			(xy 37.617006 -355.095729) (xy 37.60925 -355.041781) (xy 37.608764 -355.01453) (xy 35.721478 -355.01453)
			(xy 35.719414 -355.015407) (xy 35.665457 -355.029513) (xy 35.61002 -355.035613) (xy 35.554286 -355.033576)
			(xy 35.499443 -355.023446) (xy 35.446659 -355.005439) (xy 35.397059 -354.979938) (xy 35.351701 -354.947487)
			(xy 35.311552 -354.908778) (xy 35.277466 -354.864635) (xy 35.25017 -354.816) (xy 35.230247 -354.763909)
			(xy 35.218121 -354.709472) (xy 35.21405 -354.65385) (xy 34.902394 -354.65385) (xy 34.902394 -355.4108)
			(xy 41.857303 -355.4108) (xy 41.861472 -355.355173) (xy 41.873886 -355.30079) (xy 41.894268 -355.248864)
			(xy 41.922161 -355.200556) (xy 41.956943 -355.156945) (xy 41.997837 -355.119006) (xy 42.04393 -355.087586)
			(xy 42.09419 -355.063388) (xy 42.147496 -355.046951) (xy 42.202657 -355.038644) (xy 42.230548 -355.038152)
			(xy 42.25788 -355.038623) (xy 42.31196 -355.046592) (xy 42.364295 -355.062379) (xy 42.41376 -355.085647)
			(xy 42.459292 -355.115895) (xy 42.499914 -355.152474) (xy 42.534753 -355.194597) (xy 42.549318 -355.21773)
			(xy 42.557239 -355.229955) (xy 42.578713 -355.249623) (xy 42.604866 -355.262425) (xy 42.633571 -355.267321)
			(xy 42.66249 -355.26391) (xy 42.676064 -355.258624) (xy 42.69928 -355.249149) (xy 42.74761 -355.235794)
			(xy 42.797297 -355.229059) (xy 42.822368 -355.228652) (xy 42.847438 -355.229064) (xy 42.897121 -355.235818)
			(xy 42.945455 -355.249155) (xy 42.968672 -355.258624) (xy 42.982249 -355.263871) (xy 43.011149 -355.267234)
			(xy 43.039827 -355.262322) (xy 43.065961 -355.249534) (xy 43.087437 -355.229904) (xy 43.095418 -355.21773)
			(xy 43.109987 -355.194599) (xy 43.14483 -355.152478) (xy 43.185453 -355.115899) (xy 43.230984 -355.085648)
			(xy 43.280446 -355.062372) (xy 43.332777 -355.046572) (xy 43.386856 -355.038586) (xy 43.44152 -355.038586)
			(xy 43.495599 -355.046572) (xy 43.54793 -355.062372) (xy 43.597392 -355.085648) (xy 43.642923 -355.115899)
			(xy 43.683546 -355.152478) (xy 43.718389 -355.194599) (xy 43.732958 -355.21773) (xy 43.740841 -355.229983)
			(xy 43.762325 -355.24965) (xy 43.788489 -355.262449) (xy 43.817203 -355.267337) (xy 43.846128 -355.263916)
			(xy 43.859704 -355.258624) (xy 43.882915 -355.249137) (xy 43.931247 -355.235786) (xy 43.980937 -355.229057)
			(xy 44.006008 -355.228652) (xy 44.033193 -355.229125) (xy 44.086987 -355.237015) (xy 44.139062 -355.252639)
			(xy 44.188314 -355.275667) (xy 44.233695 -355.305609) (xy 44.274243 -355.34183) (xy 44.309095 -355.383559)
			(xy 44.337512 -355.429911) (xy 44.348654 -355.454712) (xy 44.354556 -355.467303) (xy 44.371962 -355.48897)
			(xy 44.394568 -355.50514) (xy 44.420697 -355.514612) (xy 44.448413 -355.516686) (xy 44.475661 -355.511206)
			(xy 44.500421 -355.498581) (xy 44.51096 -355.48951) (xy 44.532202 -355.470607) (xy 44.579249 -355.438674)
			(xy 44.630518 -355.414084) (xy 44.684871 -355.397383) (xy 44.741102 -355.388941) (xy 44.769532 -355.388418)
			(xy 44.787551 -355.38864) (xy 44.823426 -355.392074) (xy 44.84116 -355.395276) (xy 44.856375 -355.397561)
			(xy 44.88692 -355.394044) (xy 44.915035 -355.381595) (xy 44.93817 -355.361343) (xy 44.954229 -355.335122)
			(xy 44.958508 -355.320346) (xy 44.965907 -355.293302) (xy 44.987537 -355.241577) (xy 45.016502 -355.193572)
			(xy 45.052177 -355.15032) (xy 45.093796 -355.112754) (xy 45.140463 -355.081679) (xy 45.191174 -355.057766)
			(xy 45.244838 -355.041529) (xy 45.300299 -355.033317) (xy 45.328332 -355.032818) (xy 45.355585 -355.033248)
			(xy 45.409536 -355.04101) (xy 45.461834 -355.05637) (xy 45.511413 -355.079017) (xy 45.557264 -355.108489)
			(xy 45.598455 -355.144186) (xy 45.634146 -355.185382) (xy 45.663611 -355.231238) (xy 45.68625 -355.280821)
			(xy 45.701603 -355.33312) (xy 45.709356 -355.387073) (xy 45.709777 -355.4108) (xy 51.545729 -355.4108)
			(xy 51.549897 -355.355185) (xy 51.562307 -355.300812) (xy 51.582681 -355.248895) (xy 51.610566 -355.200595)
			(xy 51.645337 -355.15699) (xy 51.686219 -355.119054) (xy 51.732297 -355.087635) (xy 51.782544 -355.063434)
			(xy 51.835837 -355.046991) (xy 51.890984 -355.038675) (xy 51.91887 -355.038152) (xy 51.946203 -355.038606)
			(xy 52.000284 -355.046577) (xy 52.052619 -355.062368) (xy 52.102083 -355.085639) (xy 52.147616 -355.115889)
			(xy 52.188237 -355.15247) (xy 52.223075 -355.194596) (xy 52.23764 -355.21773) (xy 52.24554 -355.22997)
			(xy 52.267019 -355.249638) (xy 52.293179 -355.262438) (xy 52.321888 -355.26733) (xy 52.350811 -355.263914)
			(xy 52.364386 -355.258624) (xy 52.387599 -355.249143) (xy 52.43593 -355.235789) (xy 52.485619 -355.229058)
			(xy 52.51069 -355.228652) (xy 52.535759 -355.229089) (xy 52.585442 -355.235833) (xy 52.633776 -355.24916)
			(xy 52.656994 -355.258624) (xy 52.670599 -355.263789) (xy 52.699485 -355.267169) (xy 52.728153 -355.262276)
			(xy 52.754282 -355.249507) (xy 52.775757 -355.229895) (xy 52.78374 -355.21773) (xy 52.798309 -355.194599)
			(xy 52.833152 -355.152478) (xy 52.873775 -355.115899) (xy 52.919306 -355.085648) (xy 52.968768 -355.062372)
			(xy 53.021099 -355.046572) (xy 53.075178 -355.038586) (xy 53.129842 -355.038586) (xy 53.183921 -355.046572)
			(xy 53.236252 -355.062372) (xy 53.285714 -355.085648) (xy 53.331245 -355.115899) (xy 53.371868 -355.152478)
			(xy 53.406711 -355.194599) (xy 53.42128 -355.21773) (xy 53.429237 -355.229929) (xy 53.450701 -355.249597)
			(xy 53.476845 -355.262403) (xy 53.505541 -355.267305) (xy 53.534453 -355.263904) (xy 53.548026 -355.258624)
			(xy 53.571234 -355.24913) (xy 53.619568 -355.235782) (xy 53.669258 -355.229055) (xy 53.69433 -355.228652)
			(xy 53.721172 -355.22911) (xy 53.774301 -355.236818) (xy 53.825774 -355.25207) (xy 53.874526 -355.27455)
			(xy 53.919548 -355.303792) (xy 53.959907 -355.339193) (xy 53.994769 -355.380018) (xy 54.023412 -355.425424)
			(xy 54.045244 -355.47447) (xy 54.052978 -355.500178) (xy 54.057673 -355.514662) (xy 54.074188 -355.540221)
			(xy 54.097497 -355.559782) (xy 54.125532 -355.571613) (xy 54.155809 -355.574663) (xy 54.185641 -355.568663)
			(xy 54.199282 -355.5619) (xy 54.227424 -355.547258) (xy 54.287377 -355.526534) (xy 54.349937 -355.516039)
			(xy 54.381654 -355.515418) (xy 54.409825 -355.515918) (xy 54.465554 -355.524209) (xy 54.492652 -355.531928)
			(xy 54.506084 -355.535519) (xy 54.533869 -355.53613) (xy 54.56079 -355.529225) (xy 54.584851 -355.515317)
			(xy 54.60427 -355.495435) (xy 54.617608 -355.471053) (xy 54.623877 -355.443977) (xy 54.623716 -355.430074)
			(xy 54.623208 -355.413056) (xy 54.623208 -355.412802) (xy 54.623654 -355.385561) (xy 54.631447 -355.331638)
			(xy 54.64683 -355.279371) (xy 54.669492 -355.229825) (xy 54.698971 -355.184006) (xy 54.734668 -355.142846)
			(xy 54.775858 -355.107183) (xy 54.821701 -355.077741) (xy 54.871266 -355.05512) (xy 54.923545 -355.03978)
			(xy 54.977474 -355.032032) (xy 55.004716 -355.031548) (xy 55.031966 -355.032063) (xy 55.08591 -355.03982)
			(xy 55.138202 -355.055175) (xy 55.187776 -355.077815) (xy 55.233624 -355.107279) (xy 55.274813 -355.142967)
			(xy 55.310504 -355.184153) (xy 55.339972 -355.229999) (xy 55.362615 -355.279572) (xy 55.377974 -355.331863)
			(xy 55.385735 -355.385806) (xy 55.386224 -355.413056) (xy 55.38572 -355.440629) (xy 55.377774 -355.4952)
			(xy 55.362056 -355.548059) (xy 55.338893 -355.598105) (xy 55.308768 -355.644295) (xy 55.272308 -355.685669)
			(xy 55.251604 -355.703886) (xy 55.240751 -355.713829) (xy 55.224677 -355.738467) (xy 55.216288 -355.766663)
			(xy 55.216279 -355.79608) (xy 55.224653 -355.824281) (xy 55.240713 -355.848928) (xy 55.251604 -355.858826)
			(xy 55.272265 -355.87709) (xy 55.308728 -355.918455) (xy 55.338855 -355.964639) (xy 55.362019 -356.01468)
			(xy 55.377736 -356.067534) (xy 55.38568 -356.122101) (xy 55.385684 -356.177242) (xy 55.377749 -356.23181)
			(xy 55.362039 -356.284667) (xy 55.338883 -356.334711) (xy 55.308763 -356.3809) (xy 55.272306 -356.42227)
			(xy 55.251604 -356.440486) (xy 55.240751 -356.450429) (xy 55.224677 -356.475067) (xy 55.216288 -356.503263)
			(xy 55.216279 -356.53268) (xy 55.224653 -356.560881) (xy 55.240713 -356.585528) (xy 55.251604 -356.595426)
			(xy 55.272332 -356.613619) (xy 55.308801 -356.654992) (xy 55.338931 -356.701185) (xy 55.362093 -356.751237)
			(xy 55.377806 -356.804103) (xy 55.385741 -356.85868) (xy 55.386224 -356.886256) (xy 55.385704 -356.913507)
			(xy 55.377953 -356.967455) (xy 55.362604 -357.019751) (xy 55.339967 -357.06933) (xy 55.310505 -357.115182)
			(xy 55.274818 -357.156375) (xy 55.23363 -357.192069) (xy 55.187783 -357.221539) (xy 55.138207 -357.244183)
			(xy 55.085914 -357.25954) (xy 55.031967 -357.2673) (xy 55.004716 -357.267764) (xy 54.978798 -357.267319)
			(xy 54.927439 -357.26031) (xy 54.877503 -357.246404) (xy 54.829912 -357.22586) (xy 54.785546 -357.199055)
			(xy 54.745221 -357.166484) (xy 54.709682 -357.128749) (xy 54.679585 -357.086546) (xy 54.66715 -357.063802)
			(xy 54.659833 -357.051012) (xy 54.639245 -357.029952) (xy 54.613507 -357.015635) (xy 54.584755 -357.009251)
			(xy 54.555377 -357.011328) (xy 54.54142 -357.01605) (xy 54.509071 -357.027446) (xy 54.441598 -357.039713)
			(xy 54.407308 -357.040434) (xy 54.407054 -357.040434) (xy 54.392905 -357.040345) (xy 54.364682 -357.038308)
			(xy 54.350666 -357.03637) (xy 54.337314 -357.034836) (xy 54.31063 -357.037929) (xy 54.285681 -357.04789)
			(xy 54.264204 -357.064025) (xy 54.24769 -357.085213) (xy 54.237288 -357.10998) (xy 54.235096 -357.123238)
			(xy 54.231023 -357.150394) (xy 54.21605 -357.203226) (xy 54.193657 -357.253366) (xy 54.164308 -357.299777)
			(xy 54.12861 -357.341502) (xy 54.087298 -357.377679) (xy 54.041227 -357.407559) (xy 53.991348 -357.430527)
			(xy 53.938692 -357.446107) (xy 53.884346 -357.453977) (xy 53.85689 -357.454454) (xy 53.829641 -357.453932)
			(xy 53.775697 -357.446175) (xy 53.723405 -357.430821) (xy 53.673831 -357.408182) (xy 53.627983 -357.378719)
			(xy 53.586794 -357.343031) (xy 53.551103 -357.301846) (xy 53.521635 -357.256001) (xy 53.498992 -357.206428)
			(xy 53.483633 -357.154139) (xy 53.475871 -357.100195) (xy 53.475382 -357.072946) (xy 53.475886 -357.045373)
			(xy 53.483831 -356.990802) (xy 53.499549 -356.937943) (xy 53.522712 -356.887897) (xy 53.552838 -356.841707)
			(xy 53.589298 -356.800333) (xy 53.610002 -356.782116) (xy 53.620852 -356.77217) (xy 53.636926 -356.747533)
			(xy 53.645315 -356.719338) (xy 53.645323 -356.689921) (xy 53.636951 -356.661721) (xy 53.620892 -356.637075)
			(xy 53.610002 -356.627176) (xy 53.589276 -356.608981) (xy 53.552807 -356.567609) (xy 53.522677 -356.521415)
			(xy 53.499513 -356.471364) (xy 53.4838 -356.418499) (xy 53.475865 -356.363922) (xy 53.475382 -356.336346)
			(xy 53.475827 -356.309845) (xy 53.483175 -356.257353) (xy 53.497722 -356.206386) (xy 53.519187 -356.157924)
			(xy 53.547156 -356.112901) (xy 53.563774 -356.092252) (xy 53.573204 -356.080099) (xy 53.584989 -356.051701)
			(xy 53.587811 -356.021084) (xy 53.581417 -355.991011) (xy 53.566382 -355.964191) (xy 53.544063 -355.943044)
			(xy 53.5305 -355.935788) (xy 53.506801 -355.923703) (xy 53.462822 -355.893775) (xy 53.423543 -355.857899)
			(xy 53.389762 -355.816804) (xy 53.37556 -355.79431) (xy 53.36765 -355.782076) (xy 53.346176 -355.762403)
			(xy 53.320019 -355.749599) (xy 53.29131 -355.744707) (xy 53.262388 -355.748125) (xy 53.248814 -355.753416)
			(xy 53.2256 -355.762894) (xy 53.177269 -355.776249) (xy 53.127581 -355.782982) (xy 53.10251 -355.783388)
			(xy 53.077441 -355.782948) (xy 53.027759 -355.776205) (xy 52.979424 -355.762879) (xy 52.956206 -355.753416)
			(xy 52.942619 -355.748185) (xy 52.913715 -355.744801) (xy 52.885029 -355.749698) (xy 52.858885 -355.762479)
			(xy 52.837401 -355.782108) (xy 52.82946 -355.79431) (xy 52.814891 -355.817441) (xy 52.780048 -355.859562)
			(xy 52.739425 -355.896141) (xy 52.693894 -355.926392) (xy 52.644432 -355.949668) (xy 52.592101 -355.965468)
			(xy 52.538022 -355.973454) (xy 52.483358 -355.973454) (xy 52.429279 -355.965468) (xy 52.376948 -355.949668)
			(xy 52.327486 -355.926392) (xy 52.281955 -355.896141) (xy 52.241332 -355.859562) (xy 52.206489 -355.817441)
			(xy 52.19192 -355.79431) (xy 52.183953 -355.782117) (xy 52.162494 -355.762445) (xy 52.136353 -355.749635)
			(xy 52.107657 -355.744732) (xy 52.078746 -355.748134) (xy 52.065174 -355.753416) (xy 52.041965 -355.762907)
			(xy 51.993631 -355.776257) (xy 51.943942 -355.782985) (xy 51.91887 -355.783388) (xy 51.890984 -355.782925)
			(xy 51.835837 -355.774609) (xy 51.782544 -355.758166) (xy 51.732297 -355.733965) (xy 51.686219 -355.702546)
			(xy 51.645337 -355.66461) (xy 51.610566 -355.621005) (xy 51.582681 -355.572705) (xy 51.562307 -355.520788)
			(xy 51.549897 -355.466415) (xy 51.545729 -355.4108) (xy 45.709777 -355.4108) (xy 45.70984 -355.414326)
			(xy 45.709344 -355.4419) (xy 45.701401 -355.496472) (xy 45.685683 -355.549332) (xy 45.662519 -355.599379)
			(xy 45.632391 -355.645569) (xy 45.595926 -355.68694) (xy 45.57522 -355.705156) (xy 45.564295 -355.715027)
			(xy 45.548221 -355.739685) (xy 45.539839 -355.7679) (xy 45.539844 -355.797334) (xy 45.548235 -355.825546)
			(xy 45.564318 -355.850198) (xy 45.57522 -355.860096) (xy 45.595951 -355.878284) (xy 45.632412 -355.91966)
			(xy 45.662537 -355.965854) (xy 45.685697 -356.015904) (xy 45.70141 -356.068768) (xy 45.709347 -356.123342)
			(xy 45.709345 -356.178491) (xy 45.701402 -356.233065) (xy 45.685685 -356.285927) (xy 45.662521 -356.335976)
			(xy 45.632392 -356.382167) (xy 45.595927 -356.42354) (xy 45.57522 -356.441756) (xy 45.564295 -356.451627)
			(xy 45.548221 -356.476285) (xy 45.548141 -356.476554) (xy 48.08804 -356.476554) (xy 48.092111 -356.420932)
			(xy 48.104237 -356.366495) (xy 48.12416 -356.314404) (xy 48.151456 -356.265769) (xy 48.185542 -356.221626)
			(xy 48.225691 -356.182917) (xy 48.271049 -356.150466) (xy 48.320649 -356.124965) (xy 48.373433 -356.106958)
			(xy 48.428276 -356.096828) (xy 48.48401 -356.094791) (xy 48.539447 -356.100891) (xy 48.593404 -356.114997)
			(xy 48.644733 -356.136809) (xy 48.692339 -356.165863) (xy 48.735207 -356.201538) (xy 48.772424 -356.243075)
			(xy 48.803197 -356.289588) (xy 48.826869 -356.340085) (xy 48.842937 -356.393492) (xy 48.851057 -356.448668)
			(xy 48.851566 -356.476554) (xy 48.851057 -356.50444) (xy 48.842937 -356.559616) (xy 48.826869 -356.613023)
			(xy 48.803197 -356.66352) (xy 48.772424 -356.710033) (xy 48.735207 -356.75157) (xy 48.692339 -356.787245)
			(xy 48.644733 -356.816299) (xy 48.593404 -356.838111) (xy 48.539447 -356.852217) (xy 48.48401 -356.858317)
			(xy 48.428276 -356.85628) (xy 48.373433 -356.84615) (xy 48.320649 -356.828143) (xy 48.271049 -356.802642)
			(xy 48.225691 -356.770191) (xy 48.185542 -356.731482) (xy 48.151456 -356.687339) (xy 48.12416 -356.638704)
			(xy 48.104237 -356.586613) (xy 48.092111 -356.532176) (xy 48.08804 -356.476554) (xy 45.548141 -356.476554)
			(xy 45.539839 -356.5045) (xy 45.539844 -356.533934) (xy 45.548235 -356.562146) (xy 45.564318 -356.586798)
			(xy 45.57522 -356.596696) (xy 45.595936 -356.614901) (xy 45.632405 -356.656272) (xy 45.662536 -356.702463)
			(xy 45.685701 -356.752512) (xy 45.701417 -356.805375) (xy 45.709355 -356.859951) (xy 45.70984 -356.887526)
			(xy 45.709346 -356.914776) (xy 45.701587 -356.968722) (xy 45.68623 -357.021015) (xy 45.663589 -357.07059)
			(xy 45.634123 -357.116439) (xy 45.598432 -357.157628) (xy 45.557244 -357.193319) (xy 45.511395 -357.222786)
			(xy 45.46182 -357.245428) (xy 45.409528 -357.260786) (xy 45.355582 -357.268546) (xy 45.328332 -357.269034)
			(xy 45.300479 -357.268457) (xy 45.245367 -357.260339) (xy 45.192019 -357.244299) (xy 45.141568 -357.220679)
			(xy 45.095084 -357.189979) (xy 45.053555 -357.15285) (xy 45.01786 -357.110082) (xy 44.988758 -357.062581)
			(xy 44.966867 -357.011356) (xy 44.95927 -356.984554) (xy 44.955023 -356.97043) (xy 44.939621 -356.945288)
			(xy 44.917696 -356.925576) (xy 44.891063 -356.912927) (xy 44.861931 -356.90839) (xy 44.847256 -356.909878)
			(xy 44.834303 -356.911544) (xy 44.808245 -356.913321) (xy 44.795186 -356.913434) (xy 44.794932 -356.913434)
			(xy 44.794678 -356.913434) (xy 44.765642 -356.912893) (xy 44.708242 -356.90409) (xy 44.680378 -356.895908)
			(xy 44.66662 -356.892054) (xy 44.638072 -356.891306) (xy 44.610434 -356.898498) (xy 44.58587 -356.913066)
			(xy 44.566305 -356.933869) (xy 44.553269 -356.959279) (xy 44.547784 -356.987305) (xy 44.548552 -357.001572)
			(xy 44.550076 -357.034846) (xy 44.549665 -357.0621) (xy 44.541901 -357.116052) (xy 44.526539 -357.16835)
			(xy 44.50389 -357.21793) (xy 44.474416 -357.263781) (xy 44.443447 -357.299514) (xy 47.423576 -357.299514)
			(xy 47.427647 -357.243892) (xy 47.439773 -357.189455) (xy 47.459696 -357.137364) (xy 47.486992 -357.088729)
			(xy 47.521078 -357.044586) (xy 47.561227 -357.005877) (xy 47.606585 -356.973426) (xy 47.656185 -356.947925)
			(xy 47.708969 -356.929918) (xy 47.763812 -356.919788) (xy 47.819546 -356.917751) (xy 47.874983 -356.923851)
			(xy 47.92894 -356.937957) (xy 47.980269 -356.959769) (xy 48.027875 -356.988823) (xy 48.070743 -357.024498)
			(xy 48.10796 -357.066035) (xy 48.138733 -357.112548) (xy 48.162405 -357.163045) (xy 48.178473 -357.216452)
			(xy 48.186593 -357.271628) (xy 48.187102 -357.299514) (xy 48.186593 -357.3274) (xy 48.178473 -357.382576)
			(xy 48.162405 -357.435983) (xy 48.138733 -357.48648) (xy 48.10796 -357.532993) (xy 48.070743 -357.57453)
			(xy 48.027875 -357.610205) (xy 47.980269 -357.639259) (xy 47.92894 -357.661071) (xy 47.874983 -357.675177)
			(xy 47.819546 -357.681277) (xy 47.763812 -357.67924) (xy 47.708969 -357.66911) (xy 47.656185 -357.651103)
			(xy 47.606585 -357.625602) (xy 47.561227 -357.593151) (xy 47.521078 -357.554442) (xy 47.486992 -357.510299)
			(xy 47.459696 -357.461664) (xy 47.439773 -357.409573) (xy 47.427647 -357.355136) (xy 47.423576 -357.299514)
			(xy 44.443447 -357.299514) (xy 44.438717 -357.304972) (xy 44.397519 -357.340663) (xy 44.351661 -357.370127)
			(xy 44.302077 -357.392766) (xy 44.249776 -357.408118) (xy 44.195822 -357.41587) (xy 44.168568 -357.416354)
			(xy 44.141318 -357.415852) (xy 44.087373 -357.408092) (xy 44.035082 -357.392736) (xy 43.985507 -357.370094)
			(xy 43.939659 -357.340629) (xy 43.898471 -357.304939) (xy 43.86278 -357.263752) (xy 43.833313 -357.217905)
			(xy 43.810669 -357.168331) (xy 43.795311 -357.11604) (xy 43.787549 -357.062096) (xy 43.78706 -357.034846)
			(xy 43.787536 -357.007272) (xy 43.795484 -356.952698) (xy 43.811205 -356.899838) (xy 43.834373 -356.849791)
			(xy 43.864505 -356.803602) (xy 43.900973 -356.762231) (xy 43.92168 -356.744016) (xy 43.932533 -356.734071)
			(xy 43.948609 -356.709435) (xy 43.957 -356.681239) (xy 43.957009 -356.651821) (xy 43.948635 -356.623619)
			(xy 43.932572 -356.598973) (xy 43.92168 -356.589076) (xy 43.90095 -356.570885) (xy 43.864482 -356.529512)
			(xy 43.834353 -356.483317) (xy 43.81119 -356.433265) (xy 43.795478 -356.3804) (xy 43.787543 -356.325822)
			(xy 43.78706 -356.298246) (xy 43.787663 -356.268495) (xy 43.796938 -356.209719) (xy 43.81521 -356.15309)
			(xy 43.842036 -356.099976) (xy 43.858942 -356.075488) (xy 43.866861 -356.063559) (xy 43.87646 -356.036601)
			(xy 43.878193 -356.008037) (xy 43.871925 -355.980115) (xy 43.85815 -355.955033) (xy 43.83795 -355.934763)
			(xy 43.825668 -355.927406) (xy 43.804606 -355.915307) (xy 43.765515 -355.886475) (xy 43.7305 -355.852809)
			(xy 43.700154 -355.814881) (xy 43.687238 -355.79431) (xy 43.679349 -355.782061) (xy 43.657869 -355.762388)
			(xy 43.631706 -355.749586) (xy 43.602992 -355.744698) (xy 43.574067 -355.748121) (xy 43.560492 -355.753416)
			(xy 43.53728 -355.762901) (xy 43.488948 -355.776254) (xy 43.439259 -355.782984) (xy 43.414188 -355.783388)
			(xy 43.389119 -355.782955) (xy 43.339436 -355.776209) (xy 43.291102 -355.76288) (xy 43.267884 -355.753416)
			(xy 43.254305 -355.748162) (xy 43.225397 -355.744783) (xy 43.196708 -355.749685) (xy 43.170562 -355.762471)
			(xy 43.149078 -355.782106) (xy 43.141138 -355.79431) (xy 43.126569 -355.817441) (xy 43.091726 -355.859562)
			(xy 43.051103 -355.896141) (xy 43.005572 -355.926392) (xy 42.95611 -355.949668) (xy 42.903779 -355.965468)
			(xy 42.8497 -355.973454) (xy 42.795036 -355.973454) (xy 42.740957 -355.965468) (xy 42.688626 -355.949668)
			(xy 42.639164 -355.926392) (xy 42.593633 -355.896141) (xy 42.55301 -355.859562) (xy 42.518167 -355.817441)
			(xy 42.503598 -355.79431) (xy 42.495652 -355.782102) (xy 42.474188 -355.76243) (xy 42.44804 -355.749622)
			(xy 42.41934 -355.744723) (xy 42.390425 -355.748131) (xy 42.376852 -355.753416) (xy 42.353645 -355.762913)
			(xy 42.305311 -355.776261) (xy 42.25562 -355.782986) (xy 42.230548 -355.783388) (xy 42.202657 -355.782956)
			(xy 42.147496 -355.774649) (xy 42.09419 -355.758212) (xy 42.04393 -355.734014) (xy 41.997837 -355.702594)
			(xy 41.956943 -355.664655) (xy 41.922161 -355.621044) (xy 41.894268 -355.572736) (xy 41.873886 -355.52081)
			(xy 41.861472 -355.466427) (xy 41.857303 -355.4108) (xy 34.902394 -355.4108) (xy 34.902394 -356.80523)
			(xy 37.03396 -356.80523) (xy 37.038031 -356.749608) (xy 37.050157 -356.695171) (xy 37.07008 -356.64308)
			(xy 37.097376 -356.594445) (xy 37.131462 -356.550302) (xy 37.171611 -356.511593) (xy 37.216969 -356.479142)
			(xy 37.266569 -356.453641) (xy 37.319353 -356.435634) (xy 37.374196 -356.425504) (xy 37.42993 -356.423467)
			(xy 37.485367 -356.429567) (xy 37.539324 -356.443673) (xy 37.590653 -356.465485) (xy 37.60879 -356.476554)
			(xy 38.399718 -356.476554) (xy 38.403789 -356.420932) (xy 38.415915 -356.366495) (xy 38.435838 -356.314404)
			(xy 38.463134 -356.265769) (xy 38.49722 -356.221626) (xy 38.537369 -356.182917) (xy 38.582727 -356.150466)
			(xy 38.632327 -356.124965) (xy 38.685111 -356.106958) (xy 38.739954 -356.096828) (xy 38.795688 -356.094791)
			(xy 38.851125 -356.100891) (xy 38.905082 -356.114997) (xy 38.956411 -356.136809) (xy 39.004017 -356.165863)
			(xy 39.046885 -356.201538) (xy 39.084102 -356.243075) (xy 39.114875 -356.289588) (xy 39.138547 -356.340085)
			(xy 39.154615 -356.393492) (xy 39.162735 -356.448668) (xy 39.163244 -356.476554) (xy 39.162735 -356.50444)
			(xy 39.154615 -356.559616) (xy 39.138547 -356.613023) (xy 39.114875 -356.66352) (xy 39.084102 -356.710033)
			(xy 39.046885 -356.75157) (xy 39.004017 -356.787245) (xy 38.956411 -356.816299) (xy 38.905082 -356.838111)
			(xy 38.851125 -356.852217) (xy 38.795688 -356.858317) (xy 38.739954 -356.85628) (xy 38.685111 -356.84615)
			(xy 38.632327 -356.828143) (xy 38.582727 -356.802642) (xy 38.537369 -356.770191) (xy 38.49722 -356.731482)
			(xy 38.463134 -356.687339) (xy 38.435838 -356.638704) (xy 38.415915 -356.586613) (xy 38.403789 -356.532176)
			(xy 38.399718 -356.476554) (xy 37.60879 -356.476554) (xy 37.638259 -356.494539) (xy 37.681127 -356.530214)
			(xy 37.718344 -356.571751) (xy 37.749117 -356.618264) (xy 37.772789 -356.668761) (xy 37.788857 -356.722168)
			(xy 37.796977 -356.777344) (xy 37.797486 -356.80523) (xy 37.796977 -356.833116) (xy 37.788857 -356.888292)
			(xy 37.772789 -356.941699) (xy 37.749117 -356.992196) (xy 37.718344 -357.038709) (xy 37.681127 -357.080246)
			(xy 37.638259 -357.115921) (xy 37.590653 -357.144975) (xy 37.539324 -357.166787) (xy 37.485367 -357.180893)
			(xy 37.42993 -357.186993) (xy 37.374196 -357.184956) (xy 37.319353 -357.174826) (xy 37.266569 -357.156819)
			(xy 37.216969 -357.131318) (xy 37.171611 -357.098867) (xy 37.131462 -357.060158) (xy 37.097376 -357.016015)
			(xy 37.07008 -356.96738) (xy 37.050157 -356.915289) (xy 37.038031 -356.860852) (xy 37.03396 -356.80523)
			(xy 34.902394 -356.80523) (xy 34.902394 -357.879142) (xy 35.008312 -357.98506) (xy 39.206424 -357.98506)
			(xy 39.206805 -357.95972) (xy 39.21352 -357.909488) (xy 39.226827 -357.860586) (xy 39.246491 -357.813877)
			(xy 39.272166 -357.770183) (xy 39.3034 -357.730272) (xy 39.321232 -357.712264) (xy 39.330672 -357.702529)
			(xy 39.344468 -357.679196) (xy 39.351619 -357.653049) (xy 39.351618 -357.625942) (xy 39.344464 -357.599795)
			(xy 39.330666 -357.576463) (xy 39.321232 -357.566722) (xy 39.30342 -357.548696) (xy 39.27219 -357.508788)
			(xy 39.246518 -357.465096) (xy 39.226857 -357.41839) (xy 39.213553 -357.369493) (xy 39.20684 -357.319264)
			(xy 39.206424 -357.293926) (xy 39.20691 -357.266675) (xy 39.214666 -357.212727) (xy 39.230021 -357.160432)
			(xy 39.252663 -357.110855) (xy 39.282129 -357.065005) (xy 39.31782 -357.023814) (xy 39.359011 -356.988123)
			(xy 39.404861 -356.958657) (xy 39.454438 -356.936015) (xy 39.506733 -356.92066) (xy 39.560681 -356.912904)
			(xy 39.615183 -356.912904) (xy 39.669131 -356.92066) (xy 39.721426 -356.936015) (xy 39.771003 -356.958657)
			(xy 39.816853 -356.988123) (xy 39.858044 -357.023814) (xy 39.893735 -357.065005) (xy 39.923201 -357.110855)
			(xy 39.945843 -357.160432) (xy 39.961198 -357.212727) (xy 39.968954 -357.266675) (xy 39.9691 -357.274876)
			(xy 40.83177 -357.274876) (xy 40.832255 -357.247625) (xy 40.840015 -357.193679) (xy 40.855372 -357.141385)
			(xy 40.878014 -357.091809) (xy 40.907481 -357.04596) (xy 40.943172 -357.004771) (xy 40.984362 -356.96908)
			(xy 41.030211 -356.939613) (xy 41.079787 -356.916971) (xy 41.132081 -356.901614) (xy 41.186027 -356.893855)
			(xy 41.213278 -356.893368) (xy 41.240528 -356.893899) (xy 41.294472 -356.901652) (xy 41.346765 -356.917003)
			(xy 41.39634 -356.939639) (xy 41.44219 -356.969101) (xy 41.483379 -357.004788) (xy 41.519071 -357.045974)
			(xy 41.548538 -357.091819) (xy 41.571181 -357.141392) (xy 41.586539 -357.193683) (xy 41.594298 -357.247626)
			(xy 41.594786 -357.274876) (xy 41.594544 -357.293543) (xy 41.590858 -357.330695) (xy 41.58742 -357.349044)
			(xy 41.585129 -357.363318) (xy 41.587649 -357.3921) (xy 41.598137 -357.419022) (xy 41.615752 -357.441924)
			(xy 41.63908 -357.458969) (xy 41.666252 -357.468792) (xy 41.680638 -357.470202) (xy 41.70929 -357.472578)
			(xy 41.765453 -357.484869) (xy 41.819137 -357.505447) (xy 41.869127 -357.533844) (xy 41.914291 -357.569419)
			(xy 41.953607 -357.611366) (xy 41.986186 -357.658737) (xy 42.01129 -357.710459) (xy 42.028351 -357.765361)
			(xy 42.036983 -357.822202) (xy 42.037508 -357.850948) (xy 42.037067 -357.8782) (xy 42.029304 -357.93215)
			(xy 42.013943 -357.984445) (xy 41.991296 -358.034023) (xy 41.963993 -358.0765) (xy 48.879506 -358.0765)
			(xy 48.879919 -358.051161) (xy 48.886628 -358.00093) (xy 48.899929 -357.95203) (xy 48.919587 -357.905321)
			(xy 48.945256 -357.861625) (xy 48.976485 -357.821713) (xy 48.994314 -357.803704) (xy 49.003707 -357.79393)
			(xy 49.017495 -357.770605) (xy 49.024645 -357.74447) (xy 49.024651 -357.717375) (xy 49.017513 -357.691237)
			(xy 49.003736 -357.667906) (xy 48.994314 -357.658162) (xy 48.97647 -357.640167) (xy 48.945243 -357.600252)
			(xy 48.919576 -357.556553) (xy 48.899921 -357.509842) (xy 48.886624 -357.460938) (xy 48.879918 -357.410705)
			(xy 48.879506 -357.385366) (xy 48.879992 -357.358115) (xy 48.887748 -357.304167) (xy 48.903103 -357.251872)
			(xy 48.925745 -357.202295) (xy 48.955211 -357.156445) (xy 48.990902 -357.115254) (xy 49.032093 -357.079563)
			(xy 49.077943 -357.050097) (xy 49.12752 -357.027455) (xy 49.179815 -357.0121) (xy 49.233763 -357.004344)
			(xy 49.288265 -357.004344) (xy 49.342213 -357.0121) (xy 49.394508 -357.027455) (xy 49.444085 -357.050097)
			(xy 49.489935 -357.079563) (xy 49.531126 -357.115254) (xy 49.566817 -357.156445) (xy 49.596283 -357.202295)
			(xy 49.618925 -357.251872) (xy 49.63428 -357.304167) (xy 49.642036 -357.358115) (xy 49.642522 -357.385366)
			(xy 49.642079 -357.410704) (xy 49.635374 -357.460933) (xy 49.622079 -357.509833) (xy 49.602426 -357.556542)
			(xy 49.576763 -357.600238) (xy 49.54554 -357.640151) (xy 49.527714 -357.658162) (xy 49.518299 -357.667899)
			(xy 49.504594 -357.691253) (xy 49.497496 -357.717384) (xy 49.497502 -357.744462) (xy 49.504612 -357.77059)
			(xy 49.518328 -357.793937) (xy 49.527714 -357.803704) (xy 49.545547 -357.82171) (xy 49.576774 -357.861623)
			(xy 49.602441 -357.905319) (xy 49.622098 -357.952029) (xy 49.635398 -358.00093) (xy 49.635935 -358.00495)
			(xy 49.911272 -358.00495) (xy 49.911272 -357.95045) (xy 49.919027 -357.896506) (xy 49.93438 -357.844214)
			(xy 49.957018 -357.794639) (xy 49.986481 -357.74879) (xy 50.022168 -357.7076) (xy 50.063353 -357.671908)
			(xy 50.109199 -357.64244) (xy 50.158771 -357.619796) (xy 50.211061 -357.604437) (xy 50.265004 -357.596675)
			(xy 50.292254 -357.596186) (xy 50.32106 -357.596711) (xy 50.378016 -357.605388) (xy 50.433023 -357.62252)
			(xy 50.484832 -357.647721) (xy 50.532268 -357.680417) (xy 50.574256 -357.719867) (xy 50.609841 -357.765176)
			(xy 50.624486 -357.789988) (xy 50.707798 -357.7971) (xy 50.730404 -357.772208) (xy 50.740446 -357.761125)
			(xy 50.754329 -357.734658) (xy 50.759967 -357.705307) (xy 50.756878 -357.67558) (xy 50.745326 -357.648016)
			(xy 50.726298 -357.624968) (xy 50.714148 -357.616252) (xy 50.69202 -357.601012) (xy 50.651853 -357.565328)
			(xy 50.617087 -357.524363) (xy 50.588411 -357.478927) (xy 50.566391 -357.429918) (xy 50.551463 -357.378305)
			(xy 50.543921 -357.325108) (xy 50.54346 -357.298244) (xy 50.543946 -357.270993) (xy 50.551702 -357.217045)
			(xy 50.567057 -357.16475) (xy 50.589699 -357.115173) (xy 50.619165 -357.069323) (xy 50.654856 -357.028132)
			(xy 50.696047 -356.992441) (xy 50.741897 -356.962975) (xy 50.791474 -356.940333) (xy 50.843769 -356.924978)
			(xy 50.897717 -356.917222) (xy 50.952219 -356.917222) (xy 51.006167 -356.924978) (xy 51.058462 -356.940333)
			(xy 51.108039 -356.962975) (xy 51.153889 -356.992441) (xy 51.19508 -357.028132) (xy 51.230771 -357.069323)
			(xy 51.260237 -357.115173) (xy 51.282879 -357.16475) (xy 51.298234 -357.217045) (xy 51.30599 -357.270993)
			(xy 51.306476 -357.298244) (xy 51.305909 -357.327899) (xy 51.296725 -357.386495) (xy 51.278585 -357.442963)
			(xy 51.251926 -357.495945) (xy 51.217391 -357.544164) (xy 51.197002 -357.565706) (xy 51.186943 -357.576775)
			(xy 51.17306 -357.603246) (xy 51.167424 -357.632601) (xy 51.170516 -357.662332) (xy 51.182073 -357.689898)
			(xy 51.201106 -357.712946) (xy 51.213258 -357.721662) (xy 51.235394 -357.736891) (xy 51.275561 -357.772577)
			(xy 51.310325 -357.813544) (xy 51.339 -357.858982) (xy 51.361019 -357.907993) (xy 51.375946 -357.959607)
			(xy 51.383486 -358.012805) (xy 51.383946 -358.03967) (xy 51.383394 -358.066919) (xy 51.375643 -358.120862)
			(xy 51.360293 -358.173153) (xy 51.337658 -358.222728) (xy 51.308199 -358.268576) (xy 51.272514 -358.309766)
			(xy 51.231331 -358.345458) (xy 51.185487 -358.374926) (xy 51.135917 -358.397569) (xy 51.083629 -358.412928)
			(xy 51.029687 -358.420689) (xy 51.002438 -358.421178) (xy 50.97328 -358.420631) (xy 50.915643 -358.411762)
			(xy 50.860027 -358.394223) (xy 50.807728 -358.368424) (xy 50.759965 -358.334966) (xy 50.717851 -358.294628)
			(xy 50.69967 -358.271826) (xy 50.690711 -358.260963) (xy 50.668153 -358.244136) (xy 50.64186 -358.234099)
			(xy 50.613827 -358.231613) (xy 50.586179 -358.236866) (xy 50.561011 -358.24946) (xy 50.550318 -358.258618)
			(xy 50.529074 -358.27741) (xy 50.482094 -358.309185) (xy 50.430927 -358.333651) (xy 50.376701 -358.350272)
			(xy 50.320612 -358.358678) (xy 50.292254 -358.359202) (xy 50.265004 -358.358725) (xy 50.211061 -358.350963)
			(xy 50.158771 -358.335604) (xy 50.109199 -358.31296) (xy 50.063353 -358.283492) (xy 50.022168 -358.2478)
			(xy 49.986481 -358.20661) (xy 49.957018 -358.160761) (xy 49.93438 -358.111186) (xy 49.919027 -358.058894)
			(xy 49.911272 -358.00495) (xy 49.635935 -358.00495) (xy 49.642108 -358.051161) (xy 49.642522 -358.0765)
			(xy 49.642036 -358.103751) (xy 49.63428 -358.157699) (xy 49.618925 -358.209994) (xy 49.596283 -358.259571)
			(xy 49.566817 -358.305421) (xy 49.531126 -358.346612) (xy 49.489935 -358.382303) (xy 49.444085 -358.411769)
			(xy 49.394508 -358.434411) (xy 49.342213 -358.449766) (xy 49.288265 -358.457522) (xy 49.233763 -358.457522)
			(xy 49.179815 -358.449766) (xy 49.12752 -358.434411) (xy 49.077943 -358.411769) (xy 49.032093 -358.382303)
			(xy 48.990902 -358.346612) (xy 48.955211 -358.305421) (xy 48.925745 -358.259571) (xy 48.903103 -358.209994)
			(xy 48.887748 -358.157699) (xy 48.879992 -358.103751) (xy 48.879506 -358.0765) (xy 41.963993 -358.0765)
			(xy 41.961825 -358.079873) (xy 41.926129 -358.121063) (xy 41.884934 -358.156753) (xy 41.839081 -358.186219)
			(xy 41.7895 -358.208859) (xy 41.737203 -358.224214) (xy 41.683252 -358.23197) (xy 41.656 -358.232456)
			(xy 41.628751 -358.231922) (xy 41.574807 -358.224167) (xy 41.522516 -358.208814) (xy 41.472942 -358.186177)
			(xy 41.427094 -358.156715) (xy 41.385905 -358.121029) (xy 41.350214 -358.079844) (xy 41.320746 -358.034)
			(xy 41.298102 -357.984429) (xy 41.282743 -357.93214) (xy 41.274981 -357.878197) (xy 41.274492 -357.850948)
			(xy 41.27473 -357.832281) (xy 41.278424 -357.79513) (xy 41.281858 -357.77678) (xy 41.284144 -357.762505)
			(xy 41.28163 -357.733721) (xy 41.271145 -357.706797) (xy 41.25353 -357.683894) (xy 41.2302 -357.666849)
			(xy 41.203027 -357.65703) (xy 41.18864 -357.655622) (xy 41.159985 -357.653254) (xy 41.103817 -357.64097)
			(xy 41.050129 -357.620398) (xy 41.000134 -357.592003) (xy 40.954967 -357.556428) (xy 40.915648 -357.514478)
			(xy 40.88307 -357.467103) (xy 40.857969 -357.415376) (xy 40.840913 -357.360469) (xy 40.83229 -357.303624)
			(xy 40.83177 -357.274876) (xy 39.9691 -357.274876) (xy 39.96944 -357.293926) (xy 39.969031 -357.319265)
			(xy 39.962318 -357.369495) (xy 39.949016 -357.418395) (xy 39.929357 -357.465104) (xy 39.903688 -357.508799)
			(xy 39.87246 -357.548712) (xy 39.854632 -357.566722) (xy 39.845256 -357.576494) (xy 39.831545 -357.599837)
			(xy 39.82444 -357.625959) (xy 39.824439 -357.653031) (xy 39.831541 -357.679154) (xy 39.84525 -357.702498)
			(xy 39.854632 -357.712264) (xy 39.872449 -357.730285) (xy 39.903676 -357.770195) (xy 39.929346 -357.813888)
			(xy 39.949006 -357.860595) (xy 39.962309 -357.909493) (xy 39.969023 -357.959722) (xy 39.969319 -357.977694)
			(xy 40.221914 -357.977694) (xy 40.225985 -357.922072) (xy 40.238111 -357.867635) (xy 40.258034 -357.815544)
			(xy 40.28533 -357.766909) (xy 40.319416 -357.722766) (xy 40.359565 -357.684057) (xy 40.404923 -357.651606)
			(xy 40.454523 -357.626105) (xy 40.507307 -357.608098) (xy 40.56215 -357.597968) (xy 40.617884 -357.595931)
			(xy 40.673321 -357.602031) (xy 40.727278 -357.616137) (xy 40.778607 -357.637949) (xy 40.826213 -357.667003)
			(xy 40.869081 -357.702678) (xy 40.906298 -357.744215) (xy 40.937071 -357.790728) (xy 40.960743 -357.841225)
			(xy 40.976811 -357.894632) (xy 40.984931 -357.949808) (xy 40.98544 -357.977694) (xy 40.984931 -358.00558)
			(xy 40.976811 -358.060756) (xy 40.960743 -358.114163) (xy 40.937071 -358.16466) (xy 40.906298 -358.211173)
			(xy 40.869081 -358.25271) (xy 40.826213 -358.288385) (xy 40.778607 -358.317439) (xy 40.727278 -358.339251)
			(xy 40.673321 -358.353357) (xy 40.617884 -358.359457) (xy 40.56215 -358.35742) (xy 40.507307 -358.34729)
			(xy 40.454523 -358.329283) (xy 40.404923 -358.303782) (xy 40.359565 -358.271331) (xy 40.319416 -358.232622)
			(xy 40.28533 -358.188479) (xy 40.258034 -358.139844) (xy 40.238111 -358.087753) (xy 40.225985 -358.033316)
			(xy 40.221914 -357.977694) (xy 39.969319 -357.977694) (xy 39.96944 -357.98506) (xy 39.968954 -358.012311)
			(xy 39.961198 -358.066259) (xy 39.945843 -358.118554) (xy 39.923201 -358.168131) (xy 39.893735 -358.213981)
			(xy 39.858044 -358.255172) (xy 39.816853 -358.290863) (xy 39.771003 -358.320329) (xy 39.721426 -358.342971)
			(xy 39.669131 -358.358326) (xy 39.615183 -358.366082) (xy 39.560681 -358.366082) (xy 39.506733 -358.358326)
			(xy 39.454438 -358.342971) (xy 39.404861 -358.320329) (xy 39.359011 -358.290863) (xy 39.31782 -358.255172)
			(xy 39.282129 -358.213981) (xy 39.252663 -358.168131) (xy 39.230021 -358.118554) (xy 39.214666 -358.066259)
			(xy 39.20691 -358.012311) (xy 39.206424 -357.98506) (xy 35.008312 -357.98506) (xy 37.1348 -360.111548)
			(xy 41.6814 -360.111548) (xy 42.8498 -361.279948) (xy 42.8498 -361.512612) (xy 44.706032 -361.512612)
			(xy 44.706601 -361.483444) (xy 44.715499 -361.425789) (xy 44.733074 -361.370162) (xy 44.758916 -361.317861)
			(xy 44.792423 -361.270106) (xy 44.832811 -361.228011) (xy 44.855638 -361.209844) (xy 44.866037 -361.201446)
			(xy 44.882331 -361.180263) (xy 44.892574 -361.155579) (xy 44.896065 -361.129083) (xy 44.892565 -361.102588)
			(xy 44.882314 -361.077908) (xy 44.866013 -361.05673) (xy 44.855638 -361.0483) (xy 44.832794 -361.03015)
			(xy 44.792392 -360.988061) (xy 44.758878 -360.940306) (xy 44.733034 -360.888) (xy 44.715466 -360.832365)
			(xy 44.706583 -360.774703) (xy 44.706032 -360.745532) (xy 44.706485 -360.718278) (xy 44.714239 -360.664325)
			(xy 44.729593 -360.612024) (xy 44.752235 -360.562442) (xy 44.781703 -360.516586) (xy 44.817398 -360.475392)
			(xy 44.858593 -360.439698) (xy 44.904449 -360.410231) (xy 44.954032 -360.38759) (xy 45.006333 -360.372237)
			(xy 45.060286 -360.364485) (xy 45.08754 -360.364024) (xy 45.116456 -360.364576) (xy 45.173626 -360.373297)
			(xy 45.228824 -360.390547) (xy 45.280786 -360.415933) (xy 45.328321 -360.448871) (xy 45.370339 -360.488607)
			(xy 45.38853 -360.51109) (xy 45.398427 -360.522895) (xy 45.423751 -360.540414) (xy 45.453144 -360.54959)
			(xy 45.483936 -360.54959) (xy 45.513329 -360.540414) (xy 45.538653 -360.522895) (xy 45.54855 -360.51109)
			(xy 45.566767 -360.488628) (xy 45.608781 -360.448892) (xy 45.656311 -360.415951) (xy 45.708267 -360.390559)
			(xy 45.76346 -360.373298) (xy 45.820626 -360.364563) (xy 45.84954 -360.364024) (xy 45.878086 -360.364584)
			(xy 45.934539 -360.373094) (xy 45.989094 -360.389919) (xy 46.040535 -360.414683) (xy 46.064424 -360.430318)
			(xy 46.075556 -360.4374) (xy 46.100412 -360.446212) (xy 46.126699 -360.448341) (xy 46.152649 -360.443643)
			(xy 46.176521 -360.432435) (xy 46.196711 -360.415469) (xy 46.204632 -360.404918) (xy 46.22004 -360.383903)
			(xy 46.255641 -360.345851) (xy 46.296087 -360.312995) (xy 46.340626 -360.285946) (xy 46.38843 -360.265206)
			(xy 46.438611 -360.251161) (xy 46.490235 -360.244072) (xy 46.51629 -360.243628) (xy 46.545207 -360.244143)
			(xy 46.602379 -360.252871) (xy 46.657578 -360.270129) (xy 46.70954 -360.295521) (xy 46.757074 -360.328466)
			(xy 46.79909 -360.368208) (xy 46.81728 -360.390694) (xy 46.827177 -360.402499) (xy 46.852501 -360.420018)
			(xy 46.881894 -360.429194) (xy 46.912686 -360.429194) (xy 46.942079 -360.420018) (xy 46.967403 -360.402499)
			(xy 46.9773 -360.390694) (xy 46.995489 -360.368209) (xy 47.03751 -360.328474) (xy 47.085045 -360.295536)
			(xy 47.137007 -360.270148) (xy 47.192204 -360.252892) (xy 47.249374 -360.244163) (xy 47.27829 -360.243628)
			(xy 47.305544 -360.244065) (xy 47.359498 -360.251821) (xy 47.411799 -360.267178) (xy 47.461381 -360.289822)
			(xy 47.507236 -360.319292) (xy 47.54843 -360.354989) (xy 47.584123 -360.396185) (xy 47.613591 -360.442042)
			(xy 47.636231 -360.491626) (xy 47.651584 -360.543927) (xy 47.659337 -360.597882) (xy 47.659798 -360.625136)
			(xy 47.659322 -360.651178) (xy 47.652244 -360.702778) (xy 47.638212 -360.752936) (xy 47.617485 -360.800718)
			(xy 47.59045 -360.845235) (xy 47.557609 -360.88566) (xy 47.538894 -360.903774) (xy 47.528968 -360.91375)
			(xy 47.514501 -360.937875) (xy 47.507156 -360.965029) (xy 47.507487 -360.993157) (xy 47.515471 -361.020131)
			(xy 47.530501 -361.043909) (xy 47.540672 -361.053634) (xy 47.56026 -361.07179) (xy 47.59465 -361.112652)
			(xy 47.623006 -361.157912) (xy 47.644772 -361.206684) (xy 47.659523 -361.258015) (xy 47.666971 -361.310902)
			(xy 47.667418 -361.337606) (xy 47.66692 -361.365376) (xy 47.658866 -361.420328) (xy 47.64293 -361.473533)
			(xy 47.619447 -361.523864) (xy 47.588915 -361.570258) (xy 47.551979 -361.611735) (xy 47.53102 -361.62996)
			(xy 47.520368 -361.639481) (xy 47.504384 -361.663145) (xy 47.495592 -361.690314) (xy 47.494682 -361.718856)
			(xy 47.501726 -361.74653) (xy 47.516171 -361.771164) (xy 47.526194 -361.781344) (xy 47.544559 -361.799414)
			(xy 47.576728 -361.839658) (xy 47.603195 -361.883862) (xy 47.623477 -361.931223) (xy 47.637207 -361.980882)
			(xy 47.644135 -362.031935) (xy 47.644558 -362.057696) (xy 47.6441 -362.085067) (xy 47.636282 -362.139246)
			(xy 47.620791 -362.19175) (xy 47.597948 -362.241497) (xy 47.568221 -362.287463) (xy 47.550578 -362.308394)
			(xy 47.541347 -362.319725) (xy 47.529172 -362.346282) (xy 47.524999 -362.375197) (xy 47.52917 -362.404112)
			(xy 47.541343 -362.43067) (xy 47.550578 -362.441998) (xy 47.568215 -362.462934) (xy 47.597939 -362.508901)
			(xy 47.620784 -362.558647) (xy 47.636281 -362.611149) (xy 47.64411 -362.665327) (xy 47.64411 -362.720067)
			(xy 47.636282 -362.774245) (xy 47.620787 -362.826747) (xy 47.597942 -362.876493) (xy 47.568218 -362.922461)
			(xy 47.550578 -362.943394) (xy 47.541347 -362.954725) (xy 47.529172 -362.981282) (xy 47.524999 -363.010197)
			(xy 47.52917 -363.039112) (xy 47.541343 -363.06567) (xy 47.550578 -363.076998) (xy 47.568215 -363.097934)
			(xy 47.597939 -363.143901) (xy 47.620784 -363.193647) (xy 47.636281 -363.246149) (xy 47.63987 -363.270984)
			(xy 48.72126 -363.270984) (xy 48.72126 -363.186288) (xy 48.729311 -363.101974) (xy 48.74534 -363.018808)
			(xy 48.769201 -362.937541) (xy 48.80068 -362.858911) (xy 48.839491 -362.78363) (xy 48.885281 -362.712378)
			(xy 48.937637 -362.645802) (xy 48.996085 -362.584504) (xy 49.060095 -362.529039) (xy 49.129087 -362.47991)
			(xy 49.202437 -362.437561) (xy 49.27948 -362.402377) (xy 49.359519 -362.374675) (xy 49.441828 -362.354707)
			(xy 49.525663 -362.342654) (xy 49.610264 -362.338624) (xy 49.694865 -362.342654) (xy 49.7787 -362.354707)
			(xy 49.861009 -362.374675) (xy 49.941048 -362.402377) (xy 50.018091 -362.437561) (xy 50.091441 -362.47991)
			(xy 50.160433 -362.529039) (xy 50.224443 -362.584504) (xy 50.282891 -362.645802) (xy 50.335247 -362.712378)
			(xy 50.381037 -362.78363) (xy 50.419848 -362.858911) (xy 50.451327 -362.937541) (xy 50.475188 -363.018808)
			(xy 50.491217 -363.101974) (xy 50.499268 -363.186288) (xy 50.499772 -363.228636) (xy 51.245773 -363.228636)
			(xy 51.249809 -363.145189) (xy 51.261881 -363.062521) (xy 51.281874 -362.981404) (xy 51.309603 -362.902595)
			(xy 51.344809 -362.82683) (xy 51.387163 -362.754817) (xy 51.436269 -362.687228) (xy 51.49167 -362.624694)
			(xy 51.552847 -362.567799) (xy 51.61923 -362.517073) (xy 51.690198 -362.472992) (xy 51.76509 -362.435966)
			(xy 51.843206 -362.40634) (xy 51.923816 -362.384392) (xy 52.006168 -362.370327) (xy 52.089494 -362.364275)
			(xy 52.173014 -362.366294) (xy 52.25595 -362.376364) (xy 52.337526 -362.394392) (xy 52.416982 -362.420209)
			(xy 52.493575 -362.453574) (xy 52.566591 -362.494175) (xy 52.635347 -362.541634) (xy 52.699201 -362.595507)
			(xy 52.757558 -362.655292) (xy 52.809873 -362.720429) (xy 52.855656 -362.790312) (xy 52.894481 -362.864287)
			(xy 52.925986 -362.941664) (xy 52.949875 -363.021721) (xy 52.965926 -363.103709) (xy 52.973989 -363.186864)
			(xy 52.974494 -363.228636) (xy 52.973989 -363.270408) (xy 52.965926 -363.353563) (xy 52.949875 -363.435551)
			(xy 52.925986 -363.515608) (xy 52.894481 -363.592985) (xy 52.855656 -363.66696) (xy 52.809873 -363.736843)
			(xy 52.757558 -363.80198) (xy 52.699201 -363.861765) (xy 52.635347 -363.915638) (xy 52.566591 -363.963097)
			(xy 52.493575 -364.003698) (xy 52.416982 -364.037063) (xy 52.337526 -364.06288) (xy 52.25595 -364.080908)
			(xy 52.173014 -364.090978) (xy 52.089494 -364.092997) (xy 52.006168 -364.086945) (xy 51.923816 -364.07288)
			(xy 51.843206 -364.050932) (xy 51.76509 -364.021306) (xy 51.690198 -363.98428) (xy 51.61923 -363.940199)
			(xy 51.552847 -363.889473) (xy 51.49167 -363.832578) (xy 51.436269 -363.770044) (xy 51.387163 -363.702455)
			(xy 51.344809 -363.630442) (xy 51.309603 -363.554677) (xy 51.281874 -363.475868) (xy 51.261881 -363.394751)
			(xy 51.249809 -363.312083) (xy 51.245773 -363.228636) (xy 50.499772 -363.228636) (xy 50.499268 -363.270984)
			(xy 50.491217 -363.355298) (xy 50.475188 -363.438464) (xy 50.451327 -363.519731) (xy 50.419848 -363.598361)
			(xy 50.381037 -363.673642) (xy 50.335247 -363.744894) (xy 50.282891 -363.81147) (xy 50.224443 -363.872768)
			(xy 50.160433 -363.928233) (xy 50.091441 -363.977362) (xy 50.018091 -364.019711) (xy 49.941048 -364.054895)
			(xy 49.861009 -364.082597) (xy 49.7787 -364.102565) (xy 49.694865 -364.114618) (xy 49.610264 -364.118649)
			(xy 49.525663 -364.114618) (xy 49.441828 -364.102565) (xy 49.359519 -364.082597) (xy 49.27948 -364.054895)
			(xy 49.202437 -364.019711) (xy 49.129087 -363.977362) (xy 49.060095 -363.928233) (xy 48.996085 -363.872768)
			(xy 48.937637 -363.81147) (xy 48.885281 -363.744894) (xy 48.839491 -363.673642) (xy 48.80068 -363.598361)
			(xy 48.769201 -363.519731) (xy 48.74534 -363.438464) (xy 48.729311 -363.355298) (xy 48.72126 -363.270984)
			(xy 47.63987 -363.270984) (xy 47.64411 -363.300327) (xy 47.64411 -363.355067) (xy 47.636282 -363.409245)
			(xy 47.620787 -363.461747) (xy 47.597942 -363.511493) (xy 47.568218 -363.557461) (xy 47.550578 -363.578394)
			(xy 47.541347 -363.589725) (xy 47.529172 -363.616282) (xy 47.524999 -363.645197) (xy 47.52917 -363.674112)
			(xy 47.541343 -363.70067) (xy 47.550578 -363.711998) (xy 47.568226 -363.732923) (xy 47.597937 -363.778897)
			(xy 47.620772 -363.828647) (xy 47.636261 -363.881149) (xy 47.644086 -363.935326) (xy 47.644558 -363.962696)
			(xy 47.644141 -363.989951) (xy 47.636383 -364.043906) (xy 47.621025 -364.096208) (xy 47.598379 -364.145791)
			(xy 47.568907 -364.191647) (xy 47.533208 -364.232841) (xy 47.49201 -364.268535) (xy 47.446151 -364.298001)
			(xy 47.396565 -364.320641) (xy 47.344261 -364.335993) (xy 47.290305 -364.343744) (xy 47.26305 -364.344204)
			(xy 47.234133 -364.343686) (xy 47.17696 -364.334962) (xy 47.121759 -364.317706) (xy 47.069797 -364.292315)
			(xy 47.022263 -364.259369) (xy 46.980249 -364.219625) (xy 46.96206 -364.197138) (xy 46.952163 -364.185333)
			(xy 46.926839 -364.167814) (xy 46.897446 -364.158638) (xy 46.866654 -364.158638) (xy 46.837261 -364.167814)
			(xy 46.811937 -364.185333) (xy 46.80204 -364.197138) (xy 46.783836 -364.21961) (xy 46.741818 -364.259344)
			(xy 46.694285 -364.292284) (xy 46.642327 -364.317674) (xy 46.587132 -364.334933) (xy 46.529965 -364.343666)
			(xy 46.50105 -364.344204) (xy 46.473798 -364.343698) (xy 46.419849 -364.335948) (xy 46.367551 -364.320598)
			(xy 46.317971 -364.297961) (xy 46.272117 -364.268498) (xy 46.230924 -364.232808) (xy 46.19523 -364.191619)
			(xy 46.165761 -364.145769) (xy 46.143118 -364.096192) (xy 46.127762 -364.043896) (xy 46.120005 -363.989948)
			(xy 46.119542 -363.962696) (xy 46.119995 -363.935325) (xy 46.127815 -363.881145) (xy 46.143306 -363.828642)
			(xy 46.166151 -363.778895) (xy 46.195879 -363.732929) (xy 46.213522 -363.711998) (xy 46.222761 -363.700673)
			(xy 46.234935 -363.674114) (xy 46.239106 -363.645197) (xy 46.234933 -363.61628) (xy 46.222758 -363.589722)
			(xy 46.213522 -363.578394) (xy 46.195878 -363.557464) (xy 46.166153 -363.511496) (xy 46.143309 -363.461749)
			(xy 46.127813 -363.409247) (xy 46.119985 -363.355068) (xy 46.119985 -363.300326) (xy 46.127814 -363.246148)
			(xy 46.143311 -363.193645) (xy 46.166156 -363.143899) (xy 46.195881 -363.097931) (xy 46.213522 -363.076998)
			(xy 46.222761 -363.065673) (xy 46.234935 -363.039114) (xy 46.239106 -363.010197) (xy 46.234933 -362.98128)
			(xy 46.222758 -362.954722) (xy 46.213522 -362.943394) (xy 46.195878 -362.922464) (xy 46.166153 -362.876496)
			(xy 46.143309 -362.826749) (xy 46.127813 -362.774247) (xy 46.119985 -362.720068) (xy 46.119985 -362.665326)
			(xy 46.127814 -362.611148) (xy 46.143311 -362.558645) (xy 46.166156 -362.508899) (xy 46.195881 -362.462931)
			(xy 46.213522 -362.441998) (xy 46.222761 -362.430673) (xy 46.234935 -362.404114) (xy 46.239106 -362.375197)
			(xy 46.234933 -362.34628) (xy 46.222758 -362.319722) (xy 46.213522 -362.308394) (xy 46.19587 -362.287472)
			(xy 46.166159 -362.241497) (xy 46.143326 -362.191747) (xy 46.127838 -362.139244) (xy 46.120014 -362.085066)
			(xy 46.119542 -362.057696) (xy 46.119779 -362.038641) (xy 46.123595 -362.000723) (xy 46.127162 -361.982004)
			(xy 46.129464 -361.968526) (xy 46.127624 -361.941254) (xy 46.118615 -361.915448) (xy 46.103081 -361.892958)
			(xy 46.082137 -361.875395) (xy 46.057284 -361.864018) (xy 46.030303 -361.859643) (xy 46.003128 -361.862584)
			(xy 45.990256 -361.867196) (xy 45.967794 -361.875742) (xy 45.921251 -361.887724) (xy 45.87357 -361.893759)
			(xy 45.84954 -361.89412) (xy 45.820623 -361.893603) (xy 45.76345 -361.884878) (xy 45.70825 -361.867622)
			(xy 45.656288 -361.84223) (xy 45.608754 -361.809285) (xy 45.566739 -361.769541) (xy 45.54855 -361.747054)
			(xy 45.538653 -361.735249) (xy 45.513329 -361.71773) (xy 45.483936 -361.708554) (xy 45.453144 -361.708554)
			(xy 45.423751 -361.71773) (xy 45.398427 -361.735249) (xy 45.38853 -361.747054) (xy 45.370336 -361.769534)
			(xy 45.328315 -361.809267) (xy 45.28078 -361.842205) (xy 45.22882 -361.867593) (xy 45.173624 -361.884851)
			(xy 45.116456 -361.893583) (xy 45.08754 -361.89412) (xy 45.060289 -361.893608) (xy 45.00634 -361.885856)
			(xy 44.954044 -361.870506) (xy 44.904465 -361.847869) (xy 44.858612 -361.818406) (xy 44.817419 -361.782718)
			(xy 44.781725 -361.74153) (xy 44.752256 -361.695681) (xy 44.729612 -361.646105) (xy 44.714255 -361.593811)
			(xy 44.706496 -361.539863) (xy 44.706032 -361.512612) (xy 42.8498 -361.512612) (xy 42.8498 -364.592108)
			(xy 55.39308 -364.592108) (xy 55.397151 -364.536486) (xy 55.409277 -364.482049) (xy 55.4292 -364.429958)
			(xy 55.456496 -364.381323) (xy 55.490582 -364.33718) (xy 55.530731 -364.298471) (xy 55.576089 -364.26602)
			(xy 55.625689 -364.240519) (xy 55.678473 -364.222512) (xy 55.733316 -364.212382) (xy 55.78905 -364.210345)
			(xy 55.844487 -364.216445) (xy 55.898444 -364.230551) (xy 55.949773 -364.252363) (xy 55.997379 -364.281417)
			(xy 56.040247 -364.317092) (xy 56.077464 -364.358629) (xy 56.108237 -364.405142) (xy 56.131909 -364.455639)
			(xy 56.147977 -364.509046) (xy 56.156097 -364.564222) (xy 56.156606 -364.592108) (xy 56.156097 -364.619994)
			(xy 56.147977 -364.67517) (xy 56.131909 -364.728577) (xy 56.108237 -364.779074) (xy 56.077464 -364.825587)
			(xy 56.040247 -364.867124) (xy 55.997379 -364.902799) (xy 55.949773 -364.931853) (xy 55.898444 -364.953665)
			(xy 55.844487 -364.967771) (xy 55.78905 -364.973871) (xy 55.733316 -364.971834) (xy 55.678473 -364.961704)
			(xy 55.625689 -364.943697) (xy 55.576089 -364.918196) (xy 55.530731 -364.885745) (xy 55.490582 -364.847036)
			(xy 55.456496 -364.802893) (xy 55.4292 -364.754258) (xy 55.409277 -364.702167) (xy 55.397151 -364.64773)
			(xy 55.39308 -364.592108) (xy 42.8498 -364.592108) (xy 42.8498 -365.608108) (xy 55.39308 -365.608108)
			(xy 55.397151 -365.552486) (xy 55.409277 -365.498049) (xy 55.4292 -365.445958) (xy 55.456496 -365.397323)
			(xy 55.490582 -365.35318) (xy 55.530731 -365.314471) (xy 55.576089 -365.28202) (xy 55.625689 -365.256519)
			(xy 55.678473 -365.238512) (xy 55.733316 -365.228382) (xy 55.78905 -365.226345) (xy 55.844487 -365.232445)
			(xy 55.898444 -365.246551) (xy 55.949773 -365.268363) (xy 55.997379 -365.297417) (xy 56.040247 -365.333092)
			(xy 56.077464 -365.374629) (xy 56.108237 -365.421142) (xy 56.131909 -365.471639) (xy 56.147977 -365.525046)
			(xy 56.156097 -365.580222) (xy 56.156606 -365.608108) (xy 56.156097 -365.635994) (xy 56.147977 -365.69117)
			(xy 56.131909 -365.744577) (xy 56.108237 -365.795074) (xy 56.077464 -365.841587) (xy 56.040247 -365.883124)
			(xy 55.997379 -365.918799) (xy 55.949773 -365.947853) (xy 55.898444 -365.969665) (xy 55.844487 -365.983771)
			(xy 55.78905 -365.989871) (xy 55.733316 -365.987834) (xy 55.678473 -365.977704) (xy 55.625689 -365.959697)
			(xy 55.576089 -365.934196) (xy 55.530731 -365.901745) (xy 55.490582 -365.863036) (xy 55.456496 -365.818893)
			(xy 55.4292 -365.770258) (xy 55.409277 -365.718167) (xy 55.397151 -365.66373) (xy 55.39308 -365.608108)
			(xy 42.8498 -365.608108) (xy 42.8498 -366.829848) (xy 43.0276 -367.007648) (xy 55.41391 -367.007648)
		)
		(stroke
			(width 0)
			(type solid)
		)
		(fill yes)
		(layer "In15.Cu")
		(net "GND")
	)
	(gr_poly
		(pts
			(xy 304.78095 -373.953786) (xy 304.78095 -358.717088) (xy 302.772318 -356.708456) (xy 302.772318 -346.801186)
			(xy 302.337978 -344.846148) (xy 300.76394 -343.27211) (xy 284.765242 -343.27211) (xy 283.294652 -344.7427)
			(xy 286.410396 -344.7427) (xy 286.410396 -344.658004) (xy 286.418447 -344.57369) (xy 286.434476 -344.490524)
			(xy 286.458337 -344.409257) (xy 286.489816 -344.330627) (xy 286.528627 -344.255346) (xy 286.574417 -344.184094)
			(xy 286.626773 -344.117518) (xy 286.685221 -344.05622) (xy 286.749231 -344.000755) (xy 286.818223 -343.951626)
			(xy 286.891573 -343.909277) (xy 286.968616 -343.874093) (xy 287.048655 -343.846391) (xy 287.130964 -343.826423)
			(xy 287.214799 -343.81437) (xy 287.2994 -343.81034) (xy 287.384001 -343.81437) (xy 287.467836 -343.826423)
			(xy 287.550145 -343.846391) (xy 287.630184 -343.874093) (xy 287.707227 -343.909277) (xy 287.780577 -343.951626)
			(xy 287.849569 -344.000755) (xy 287.913579 -344.05622) (xy 287.972027 -344.117518) (xy 288.024383 -344.184094)
			(xy 288.070173 -344.255346) (xy 288.108984 -344.330627) (xy 288.140463 -344.409257) (xy 288.164324 -344.490524)
			(xy 288.180353 -344.57369) (xy 288.188404 -344.658004) (xy 288.188908 -344.700352) (xy 288.188404 -344.7427)
			(xy 292.607996 -344.7427) (xy 292.607996 -344.658004) (xy 292.616047 -344.57369) (xy 292.632076 -344.490524)
			(xy 292.655937 -344.409257) (xy 292.687416 -344.330627) (xy 292.726227 -344.255346) (xy 292.772017 -344.184094)
			(xy 292.824373 -344.117518) (xy 292.882821 -344.05622) (xy 292.946831 -344.000755) (xy 293.015823 -343.951626)
			(xy 293.089173 -343.909277) (xy 293.166216 -343.874093) (xy 293.246255 -343.846391) (xy 293.328564 -343.826423)
			(xy 293.412399 -343.81437) (xy 293.497 -343.81034) (xy 293.581601 -343.81437) (xy 293.665436 -343.826423)
			(xy 293.747745 -343.846391) (xy 293.827784 -343.874093) (xy 293.904827 -343.909277) (xy 293.978177 -343.951626)
			(xy 294.047169 -344.000755) (xy 294.111179 -344.05622) (xy 294.169627 -344.117518) (xy 294.221983 -344.184094)
			(xy 294.267773 -344.255346) (xy 294.306584 -344.330627) (xy 294.338063 -344.409257) (xy 294.361924 -344.490524)
			(xy 294.377953 -344.57369) (xy 294.386004 -344.658004) (xy 294.386508 -344.700352) (xy 294.386004 -344.7427)
			(xy 298.805596 -344.7427) (xy 298.805596 -344.658004) (xy 298.813647 -344.57369) (xy 298.829676 -344.490524)
			(xy 298.853537 -344.409257) (xy 298.885016 -344.330627) (xy 298.923827 -344.255346) (xy 298.969617 -344.184094)
			(xy 299.021973 -344.117518) (xy 299.080421 -344.05622) (xy 299.144431 -344.000755) (xy 299.213423 -343.951626)
			(xy 299.286773 -343.909277) (xy 299.363816 -343.874093) (xy 299.443855 -343.846391) (xy 299.526164 -343.826423)
			(xy 299.609999 -343.81437) (xy 299.6946 -343.81034) (xy 299.779201 -343.81437) (xy 299.863036 -343.826423)
			(xy 299.945345 -343.846391) (xy 300.025384 -343.874093) (xy 300.102427 -343.909277) (xy 300.175777 -343.951626)
			(xy 300.244769 -344.000755) (xy 300.308779 -344.05622) (xy 300.367227 -344.117518) (xy 300.419583 -344.184094)
			(xy 300.465373 -344.255346) (xy 300.504184 -344.330627) (xy 300.535663 -344.409257) (xy 300.559524 -344.490524)
			(xy 300.575553 -344.57369) (xy 300.583604 -344.658004) (xy 300.584108 -344.700352) (xy 300.583604 -344.7427)
			(xy 300.575553 -344.827014) (xy 300.559524 -344.91018) (xy 300.535663 -344.991447) (xy 300.504184 -345.070077)
			(xy 300.465373 -345.145358) (xy 300.419583 -345.21661) (xy 300.367227 -345.283186) (xy 300.308779 -345.344484)
			(xy 300.244769 -345.399949) (xy 300.175777 -345.449078) (xy 300.102427 -345.491427) (xy 300.025384 -345.526611)
			(xy 299.945345 -345.554313) (xy 299.863036 -345.574281) (xy 299.779201 -345.586334) (xy 299.6946 -345.590365)
			(xy 299.609999 -345.586334) (xy 299.526164 -345.574281) (xy 299.443855 -345.554313) (xy 299.363816 -345.526611)
			(xy 299.286773 -345.491427) (xy 299.213423 -345.449078) (xy 299.144431 -345.399949) (xy 299.080421 -345.344484)
			(xy 299.021973 -345.283186) (xy 298.969617 -345.21661) (xy 298.923827 -345.145358) (xy 298.885016 -345.070077)
			(xy 298.853537 -344.991447) (xy 298.829676 -344.91018) (xy 298.813647 -344.827014) (xy 298.805596 -344.7427)
			(xy 294.386004 -344.7427) (xy 294.377953 -344.827014) (xy 294.361924 -344.91018) (xy 294.338063 -344.991447)
			(xy 294.306584 -345.070077) (xy 294.267773 -345.145358) (xy 294.221983 -345.21661) (xy 294.169627 -345.283186)
			(xy 294.111179 -345.344484) (xy 294.047169 -345.399949) (xy 293.978177 -345.449078) (xy 293.904827 -345.491427)
			(xy 293.827784 -345.526611) (xy 293.747745 -345.554313) (xy 293.665436 -345.574281) (xy 293.581601 -345.586334)
			(xy 293.497 -345.590365) (xy 293.412399 -345.586334) (xy 293.328564 -345.574281) (xy 293.246255 -345.554313)
			(xy 293.166216 -345.526611) (xy 293.089173 -345.491427) (xy 293.015823 -345.449078) (xy 292.946831 -345.399949)
			(xy 292.882821 -345.344484) (xy 292.824373 -345.283186) (xy 292.772017 -345.21661) (xy 292.726227 -345.145358)
			(xy 292.687416 -345.070077) (xy 292.655937 -344.991447) (xy 292.632076 -344.91018) (xy 292.616047 -344.827014)
			(xy 292.607996 -344.7427) (xy 288.188404 -344.7427) (xy 288.180353 -344.827014) (xy 288.164324 -344.91018)
			(xy 288.140463 -344.991447) (xy 288.108984 -345.070077) (xy 288.070173 -345.145358) (xy 288.024383 -345.21661)
			(xy 287.972027 -345.283186) (xy 287.913579 -345.344484) (xy 287.849569 -345.399949) (xy 287.780577 -345.449078)
			(xy 287.707227 -345.491427) (xy 287.630184 -345.526611) (xy 287.550145 -345.554313) (xy 287.467836 -345.574281)
			(xy 287.384001 -345.586334) (xy 287.2994 -345.590365) (xy 287.214799 -345.586334) (xy 287.130964 -345.574281)
			(xy 287.048655 -345.554313) (xy 286.968616 -345.526611) (xy 286.891573 -345.491427) (xy 286.818223 -345.449078)
			(xy 286.749231 -345.399949) (xy 286.685221 -345.344484) (xy 286.626773 -345.283186) (xy 286.574417 -345.21661)
			(xy 286.528627 -345.145358) (xy 286.489816 -345.070077) (xy 286.458337 -344.991447) (xy 286.434476 -344.91018)
			(xy 286.418447 -344.827014) (xy 286.410396 -344.7427) (xy 283.294652 -344.7427) (xy 282.69946 -345.337892)
			(xy 282.69946 -351.8408) (xy 285.286958 -351.8408) (xy 285.28741 -351.813429) (xy 285.295229 -351.759249)
			(xy 285.310721 -351.706745) (xy 285.333566 -351.656998) (xy 285.363295 -351.611033) (xy 285.380938 -351.590102)
			(xy 285.390172 -351.578773) (xy 285.402345 -351.552215) (xy 285.406515 -351.5233) (xy 285.402345 -351.494385)
			(xy 285.390172 -351.467827) (xy 285.380938 -351.456498) (xy 285.363297 -351.435565) (xy 285.333571 -351.389598)
			(xy 285.310725 -351.339852) (xy 285.295228 -351.28735) (xy 285.2874 -351.233171) (xy 285.2874 -351.178429)
			(xy 285.295228 -351.12425) (xy 285.310725 -351.071748) (xy 285.333571 -351.022002) (xy 285.363297 -350.976035)
			(xy 285.380938 -350.955102) (xy 285.390172 -350.943773) (xy 285.402345 -350.917215) (xy 285.406515 -350.8883)
			(xy 285.402345 -350.859385) (xy 285.390172 -350.832827) (xy 285.380938 -350.821498) (xy 285.363297 -350.800565)
			(xy 285.333571 -350.754598) (xy 285.310725 -350.704852) (xy 285.295228 -350.65235) (xy 285.2874 -350.598171)
			(xy 285.2874 -350.543429) (xy 285.295228 -350.48925) (xy 285.310725 -350.436748) (xy 285.333571 -350.387002)
			(xy 285.363297 -350.341035) (xy 285.380938 -350.320102) (xy 285.390172 -350.308773) (xy 285.402345 -350.282215)
			(xy 285.406515 -350.2533) (xy 285.402345 -350.224385) (xy 285.390172 -350.197827) (xy 285.380938 -350.186498)
			(xy 285.363297 -350.165565) (xy 285.333571 -350.119598) (xy 285.310725 -350.069852) (xy 285.295228 -350.01735)
			(xy 285.2874 -349.963171) (xy 285.2874 -349.908429) (xy 285.295228 -349.85425) (xy 285.310725 -349.801748)
			(xy 285.333571 -349.752002) (xy 285.363297 -349.706035) (xy 285.380938 -349.685102) (xy 285.390172 -349.673773)
			(xy 285.402345 -349.647215) (xy 285.406515 -349.6183) (xy 285.402345 -349.589385) (xy 285.390172 -349.562827)
			(xy 285.380938 -349.551498) (xy 285.363297 -349.530565) (xy 285.333571 -349.484598) (xy 285.310725 -349.434852)
			(xy 285.295228 -349.38235) (xy 285.2874 -349.328171) (xy 285.2874 -349.273429) (xy 285.295228 -349.21925)
			(xy 285.310725 -349.166748) (xy 285.333571 -349.117002) (xy 285.363297 -349.071035) (xy 285.380938 -349.050102)
			(xy 285.390172 -349.038773) (xy 285.402345 -349.012215) (xy 285.406515 -348.9833) (xy 285.402345 -348.954385)
			(xy 285.390172 -348.927827) (xy 285.380938 -348.916498) (xy 285.363297 -348.895565) (xy 285.333571 -348.849598)
			(xy 285.310725 -348.799852) (xy 285.295228 -348.74735) (xy 285.2874 -348.693171) (xy 285.2874 -348.638429)
			(xy 285.295228 -348.58425) (xy 285.310725 -348.531748) (xy 285.333571 -348.482002) (xy 285.363297 -348.436035)
			(xy 285.380938 -348.415102) (xy 285.390172 -348.403773) (xy 285.402345 -348.377215) (xy 285.406515 -348.3483)
			(xy 285.402345 -348.319385) (xy 285.390172 -348.292827) (xy 285.380938 -348.281498) (xy 285.36329 -348.260573)
			(xy 285.333579 -348.214599) (xy 285.310744 -348.164849) (xy 285.295255 -348.112347) (xy 285.28743 -348.05817)
			(xy 285.286958 -348.0308) (xy 285.287478 -348.00355) (xy 285.295233 -347.949606) (xy 285.310587 -347.897314)
			(xy 285.333225 -347.847739) (xy 285.362689 -347.80189) (xy 285.398376 -347.7607) (xy 285.439563 -347.725009)
			(xy 285.485409 -347.695542) (xy 285.534982 -347.672899) (xy 285.587272 -347.657541) (xy 285.641216 -347.64978)
			(xy 285.668466 -347.649292) (xy 285.695835 -347.64978) (xy 285.750013 -347.657593) (xy 285.802516 -347.673077)
			(xy 285.852263 -347.695914) (xy 285.898231 -347.725633) (xy 285.919164 -347.743272) (xy 285.930492 -347.752508)
			(xy 285.957049 -347.764684) (xy 285.985966 -347.768857) (xy 286.014883 -347.764684) (xy 286.04144 -347.752508)
			(xy 286.052768 -347.743272) (xy 286.073698 -347.72563) (xy 286.119672 -347.69592) (xy 286.16942 -347.673085)
			(xy 286.221921 -347.657594) (xy 286.276097 -347.649766) (xy 286.303466 -347.649292) (xy 286.331506 -347.649802)
			(xy 286.386983 -347.657998) (xy 286.440665 -347.67422) (xy 286.491398 -347.698118) (xy 286.53809 -347.729179)
			(xy 286.559244 -347.74759) (xy 286.570686 -347.757235) (xy 286.597729 -347.770015) (xy 286.627316 -347.774401)
			(xy 286.656903 -347.770015) (xy 286.683946 -347.757235) (xy 286.695388 -347.74759) (xy 286.71379 -347.731553)
			(xy 286.753943 -347.703798) (xy 286.797303 -347.68138) (xy 286.820102 -347.67266) (xy 286.833437 -347.667262)
			(xy 286.856596 -347.650215) (xy 286.874094 -347.627394) (xy 286.884546 -347.600604) (xy 286.887126 -347.571964)
			(xy 286.88163 -347.543737) (xy 286.868493 -347.518156) (xy 286.848753 -347.497245) (xy 286.836612 -347.489526)
			(xy 286.799538 -347.467197) (xy 286.729339 -347.416569) (xy 286.664236 -347.359536) (xy 286.604811 -347.296608)
			(xy 286.551597 -347.228348) (xy 286.505069 -347.155367) (xy 286.465642 -347.078317) (xy 286.433671 -346.997887)
			(xy 286.40944 -346.914797) (xy 286.393166 -346.829789) (xy 286.384995 -346.743624) (xy 286.384492 -346.700348)
			(xy 286.38498 -346.658072) (xy 286.392782 -346.57388) (xy 286.408318 -346.490767) (xy 286.431457 -346.409443)
			(xy 286.462001 -346.3306) (xy 286.499689 -346.254912) (xy 286.5442 -346.183024) (xy 286.595154 -346.11555)
			(xy 286.652117 -346.053065) (xy 286.714602 -345.996102) (xy 286.782076 -345.945148) (xy 286.853964 -345.900637)
			(xy 286.929652 -345.862949) (xy 287.008495 -345.832405) (xy 287.089819 -345.809266) (xy 287.172932 -345.79373)
			(xy 287.257124 -345.785928) (xy 287.341676 -345.785928) (xy 287.425868 -345.79373) (xy 287.508981 -345.809266)
			(xy 287.590305 -345.832405) (xy 287.669148 -345.862949) (xy 287.744836 -345.900637) (xy 287.816724 -345.945148)
			(xy 287.884198 -345.996102) (xy 287.946683 -346.053065) (xy 288.003646 -346.11555) (xy 288.0546 -346.183024)
			(xy 288.099111 -346.254912) (xy 288.136799 -346.3306) (xy 288.167343 -346.409443) (xy 288.190482 -346.490767)
			(xy 288.206018 -346.57388) (xy 288.21382 -346.658072) (xy 288.214308 -346.700348) (xy 292.581589 -346.700348)
			(xy 292.585611 -346.614628) (xy 292.597642 -346.52966) (xy 292.617578 -346.446193) (xy 292.645241 -346.364959)
			(xy 292.68039 -346.286673) (xy 292.722716 -346.212022) (xy 292.771845 -346.141663) (xy 292.827348 -346.076213)
			(xy 292.888735 -346.016249) (xy 292.955468 -345.962296) (xy 293.02696 -345.914829) (xy 293.102582 -345.874265)
			(xy 293.181671 -345.840961) (xy 293.263531 -345.815209) (xy 293.347442 -345.797236) (xy 293.432668 -345.7872)
			(xy 293.51846 -345.785188) (xy 293.604062 -345.791219) (xy 293.688724 -345.805239) (xy 293.771701 -345.827125)
			(xy 293.852264 -345.856686) (xy 293.929704 -345.89366) (xy 294.003343 -345.937724) (xy 294.072531 -345.98849)
			(xy 294.136662 -346.045511) (xy 294.195171 -346.108287) (xy 294.247544 -346.176267) (xy 294.293322 -346.248852)
			(xy 294.332102 -346.325404) (xy 294.363543 -346.405252) (xy 294.387369 -346.487693) (xy 294.40337 -346.572003)
			(xy 294.411405 -346.657441) (xy 294.411908 -346.700348) (xy 298.779189 -346.700348) (xy 298.783211 -346.614628)
			(xy 298.795242 -346.52966) (xy 298.815178 -346.446193) (xy 298.842841 -346.364959) (xy 298.87799 -346.286673)
			(xy 298.920316 -346.212022) (xy 298.969445 -346.141663) (xy 299.024948 -346.076213) (xy 299.086335 -346.016249)
			(xy 299.153068 -345.962296) (xy 299.22456 -345.914829) (xy 299.300182 -345.874265) (xy 299.379271 -345.840961)
			(xy 299.461131 -345.815209) (xy 299.545042 -345.797236) (xy 299.630268 -345.7872) (xy 299.71606 -345.785188)
			(xy 299.801662 -345.791219) (xy 299.886324 -345.805239) (xy 299.969301 -345.827125) (xy 300.049864 -345.856686)
			(xy 300.127304 -345.89366) (xy 300.200943 -345.937724) (xy 300.270131 -345.98849) (xy 300.334262 -346.045511)
			(xy 300.392771 -346.108287) (xy 300.445144 -346.176267) (xy 300.490922 -346.248852) (xy 300.529702 -346.325404)
			(xy 300.561143 -346.405252) (xy 300.584969 -346.487693) (xy 300.60097 -346.572003) (xy 300.609005 -346.657441)
			(xy 300.609508 -346.700348) (xy 300.609005 -346.743255) (xy 300.60097 -346.828693) (xy 300.584969 -346.913003)
			(xy 300.561143 -346.995444) (xy 300.529702 -347.075292) (xy 300.490922 -347.151844) (xy 300.445144 -347.224429)
			(xy 300.392771 -347.292409) (xy 300.334262 -347.355185) (xy 300.270131 -347.412206) (xy 300.200943 -347.462972)
			(xy 300.127304 -347.507036) (xy 300.049864 -347.54401) (xy 299.969301 -347.573571) (xy 299.886324 -347.595457)
			(xy 299.801662 -347.609477) (xy 299.71606 -347.615508) (xy 299.630268 -347.613496) (xy 299.545042 -347.60346)
			(xy 299.461131 -347.585487) (xy 299.379271 -347.559735) (xy 299.300182 -347.526431) (xy 299.22456 -347.485867)
			(xy 299.153068 -347.4384) (xy 299.086335 -347.384447) (xy 299.024948 -347.324483) (xy 298.969445 -347.259033)
			(xy 298.920316 -347.188674) (xy 298.87799 -347.114023) (xy 298.842841 -347.035737) (xy 298.815178 -346.954503)
			(xy 298.795242 -346.871036) (xy 298.783211 -346.786068) (xy 298.779189 -346.700348) (xy 294.411908 -346.700348)
			(xy 294.411405 -346.743255) (xy 294.40337 -346.828693) (xy 294.387369 -346.913003) (xy 294.363543 -346.995444)
			(xy 294.332102 -347.075292) (xy 294.293322 -347.151844) (xy 294.247544 -347.224429) (xy 294.195171 -347.292409)
			(xy 294.136662 -347.355185) (xy 294.072531 -347.412206) (xy 294.003343 -347.462972) (xy 293.929704 -347.507036)
			(xy 293.852264 -347.54401) (xy 293.771701 -347.573571) (xy 293.688724 -347.595457) (xy 293.604062 -347.609477)
			(xy 293.51846 -347.615508) (xy 293.432668 -347.613496) (xy 293.347442 -347.60346) (xy 293.263531 -347.585487)
			(xy 293.181671 -347.559735) (xy 293.102582 -347.526431) (xy 293.02696 -347.485867) (xy 292.955468 -347.4384)
			(xy 292.888735 -347.384447) (xy 292.827348 -347.324483) (xy 292.771845 -347.259033) (xy 292.722716 -347.188674)
			(xy 292.68039 -347.114023) (xy 292.645241 -347.035737) (xy 292.617578 -346.954503) (xy 292.597642 -346.871036)
			(xy 292.585611 -346.786068) (xy 292.581589 -346.700348) (xy 288.214308 -346.700348) (xy 288.21379 -346.742119)
			(xy 288.206161 -346.825312) (xy 288.190979 -346.907463) (xy 288.168372 -346.987888) (xy 288.138526 -347.065917)
			(xy 288.101692 -347.140901) (xy 288.058175 -347.212214) (xy 288.008338 -347.279263) (xy 287.952597 -347.34149)
			(xy 287.891415 -347.398376) (xy 287.825301 -347.449448) (xy 287.754807 -347.49428) (xy 287.68052 -347.532499)
			(xy 287.603058 -347.563786) (xy 287.523066 -347.587882) (xy 287.44121 -347.604585) (xy 287.358173 -347.613756)
			(xy 287.316418 -347.615002) (xy 287.302046 -347.615754) (xy 287.274565 -347.624259) (xy 287.250547 -347.640089)
			(xy 287.231895 -347.661989) (xy 287.22009 -347.688222) (xy 287.216068 -347.716706) (xy 287.220149 -347.745181)
			(xy 287.232008 -347.771389) (xy 287.24098 -347.782642) (xy 287.258186 -347.803491) (xy 287.287192 -347.849105)
			(xy 287.309471 -347.898356) (xy 287.324576 -347.950258) (xy 287.332204 -348.003772) (xy 287.332674 -348.0308)
			(xy 287.332214 -348.058171) (xy 287.324396 -348.11235) (xy 287.308906 -348.164854) (xy 287.286062 -348.2146)
			(xy 287.256336 -348.260567) (xy 287.238694 -348.281498) (xy 287.229458 -348.292825) (xy 287.217281 -348.319383)
			(xy 287.213109 -348.3483) (xy 287.217281 -348.377217) (xy 287.229458 -348.403775) (xy 287.238694 -348.415102)
			(xy 287.256334 -348.436035) (xy 287.286057 -348.482003) (xy 287.308901 -348.53175) (xy 287.324396 -348.584252)
			(xy 287.332225 -348.63843) (xy 287.332225 -348.69317) (xy 287.324396 -348.747348) (xy 287.308901 -348.79985)
			(xy 287.286057 -348.849597) (xy 287.256334 -348.895565) (xy 287.238694 -348.916498) (xy 287.229458 -348.927825)
			(xy 287.217281 -348.954383) (xy 287.213109 -348.9833) (xy 287.217281 -349.012217) (xy 287.229458 -349.038775)
			(xy 287.238694 -349.050102) (xy 287.256334 -349.071035) (xy 287.286057 -349.117003) (xy 287.308901 -349.16675)
			(xy 287.324396 -349.219252) (xy 287.332225 -349.27343) (xy 287.332225 -349.32817) (xy 287.324396 -349.382348)
			(xy 287.308901 -349.43485) (xy 287.286057 -349.484597) (xy 287.256334 -349.530565) (xy 287.238694 -349.551498)
			(xy 287.229458 -349.562825) (xy 287.217281 -349.589383) (xy 287.213109 -349.6183) (xy 287.217281 -349.647217)
			(xy 287.229458 -349.673775) (xy 287.238694 -349.685102) (xy 287.256334 -349.706035) (xy 287.286057 -349.752003)
			(xy 287.308901 -349.80175) (xy 287.324396 -349.854252) (xy 287.332225 -349.90843) (xy 287.332225 -349.96317)
			(xy 287.324396 -350.017348) (xy 287.308901 -350.06985) (xy 287.286057 -350.119597) (xy 287.256334 -350.165565)
			(xy 287.238694 -350.186498) (xy 287.229458 -350.197825) (xy 287.217281 -350.224383) (xy 287.213109 -350.2533)
			(xy 287.217281 -350.282217) (xy 287.229458 -350.308775) (xy 287.238694 -350.320102) (xy 287.256334 -350.341035)
			(xy 287.286057 -350.387003) (xy 287.308901 -350.43675) (xy 287.324396 -350.489252) (xy 287.332225 -350.54343)
			(xy 287.332225 -350.59817) (xy 287.324396 -350.652348) (xy 287.308901 -350.70485) (xy 287.286057 -350.754597)
			(xy 287.256334 -350.800565) (xy 287.238694 -350.821498) (xy 287.229458 -350.832825) (xy 287.217281 -350.859383)
			(xy 287.213109 -350.8883) (xy 287.217281 -350.917217) (xy 287.229458 -350.943775) (xy 287.238694 -350.955102)
			(xy 287.256334 -350.976035) (xy 287.286057 -351.022003) (xy 287.308901 -351.07175) (xy 287.324396 -351.124252)
			(xy 287.332225 -351.17843) (xy 287.332225 -351.23317) (xy 287.324396 -351.287348) (xy 287.308901 -351.33985)
			(xy 287.286057 -351.389597) (xy 287.256334 -351.435565) (xy 287.238694 -351.456498) (xy 287.229458 -351.467825)
			(xy 287.217281 -351.494383) (xy 287.213109 -351.5233) (xy 287.217281 -351.552217) (xy 287.229458 -351.578775)
			(xy 287.238694 -351.590102) (xy 287.256347 -351.611023) (xy 287.286057 -351.656999) (xy 287.30889 -351.706749)
			(xy 287.324378 -351.759252) (xy 287.332202 -351.81343) (xy 287.332674 -351.8408) (xy 290.25723 -351.8408)
			(xy 290.257689 -351.813429) (xy 290.265507 -351.75925) (xy 290.280998 -351.706746) (xy 290.303841 -351.656999)
			(xy 290.333568 -351.611033) (xy 290.35121 -351.590102) (xy 290.360446 -351.578774) (xy 290.372622 -351.552217)
			(xy 290.376794 -351.5233) (xy 290.372622 -351.494383) (xy 290.360446 -351.467826) (xy 290.35121 -351.456498)
			(xy 290.33357 -351.435565) (xy 290.303847 -351.389597) (xy 290.281002 -351.33985) (xy 290.265507 -351.287349)
			(xy 290.257678 -351.23317) (xy 290.257678 -351.17843) (xy 290.265507 -351.124251) (xy 290.281002 -351.07175)
			(xy 290.303847 -351.022003) (xy 290.33357 -350.976035) (xy 290.35121 -350.955102) (xy 290.360446 -350.943774)
			(xy 290.372622 -350.917217) (xy 290.376794 -350.8883) (xy 290.372622 -350.859383) (xy 290.360446 -350.832826)
			(xy 290.35121 -350.821498) (xy 290.33357 -350.800565) (xy 290.303847 -350.754597) (xy 290.281002 -350.70485)
			(xy 290.265507 -350.652349) (xy 290.257678 -350.59817) (xy 290.257678 -350.54343) (xy 290.265507 -350.489251)
			(xy 290.281002 -350.43675) (xy 290.303847 -350.387003) (xy 290.33357 -350.341035) (xy 290.35121 -350.320102)
			(xy 290.360446 -350.308774) (xy 290.372622 -350.282217) (xy 290.376794 -350.2533) (xy 290.372622 -350.224383)
			(xy 290.360446 -350.197826) (xy 290.35121 -350.186498) (xy 290.33357 -350.165565) (xy 290.303847 -350.119597)
			(xy 290.281002 -350.06985) (xy 290.265507 -350.017349) (xy 290.257678 -349.96317) (xy 290.257678 -349.90843)
			(xy 290.265507 -349.854251) (xy 290.281002 -349.80175) (xy 290.303847 -349.752003) (xy 290.33357 -349.706035)
			(xy 290.35121 -349.685102) (xy 290.360446 -349.673774) (xy 290.372622 -349.647217) (xy 290.376794 -349.6183)
			(xy 290.372622 -349.589383) (xy 290.360446 -349.562826) (xy 290.35121 -349.551498) (xy 290.33357 -349.530565)
			(xy 290.303847 -349.484597) (xy 290.281002 -349.43485) (xy 290.265507 -349.382349) (xy 290.257678 -349.32817)
			(xy 290.257678 -349.27343) (xy 290.265507 -349.219251) (xy 290.281002 -349.16675) (xy 290.303847 -349.117003)
			(xy 290.33357 -349.071035) (xy 290.35121 -349.050102) (xy 290.360446 -349.038774) (xy 290.372622 -349.012217)
			(xy 290.376794 -348.9833) (xy 290.372622 -348.954383) (xy 290.360446 -348.927826) (xy 290.35121 -348.916498)
			(xy 290.33357 -348.895565) (xy 290.303847 -348.849597) (xy 290.281002 -348.79985) (xy 290.265507 -348.747349)
			(xy 290.257678 -348.69317) (xy 290.257678 -348.63843) (xy 290.265507 -348.584251) (xy 290.281002 -348.53175)
			(xy 290.303847 -348.482003) (xy 290.33357 -348.436035) (xy 290.35121 -348.415102) (xy 290.360446 -348.403774)
			(xy 290.372622 -348.377217) (xy 290.376794 -348.3483) (xy 290.372622 -348.319383) (xy 290.360446 -348.292826)
			(xy 290.35121 -348.281498) (xy 290.333558 -348.260576) (xy 290.303848 -348.214601) (xy 290.281014 -348.164851)
			(xy 290.265526 -348.112348) (xy 290.257702 -348.05817) (xy 290.25723 -348.0308) (xy 290.257655 -348.003545)
			(xy 290.265413 -347.949591) (xy 290.280771 -347.89729) (xy 290.303417 -347.847708) (xy 290.332888 -347.801853)
			(xy 290.368586 -347.760659) (xy 290.409783 -347.724965) (xy 290.455641 -347.695498) (xy 290.505226 -347.672858)
			(xy 290.557528 -347.657505) (xy 290.611483 -347.649753) (xy 290.638738 -347.649292) (xy 290.666779 -347.649759)
			(xy 290.722259 -347.657966) (xy 290.775941 -347.674198) (xy 290.826673 -347.698105) (xy 290.873363 -347.729175)
			(xy 290.894516 -347.74759) (xy 290.905958 -347.757235) (xy 290.933001 -347.770015) (xy 290.962588 -347.774401)
			(xy 290.992175 -347.770015) (xy 291.019218 -347.757235) (xy 291.03066 -347.74759) (xy 291.051808 -347.729166)
			(xy 291.098486 -347.698072) (xy 291.149217 -347.674157) (xy 291.202907 -347.657938) (xy 291.258395 -347.649765)
			(xy 291.286438 -347.649292) (xy 291.313807 -347.649796) (xy 291.367984 -347.657605) (xy 291.420487 -347.673085)
			(xy 291.470234 -347.695919) (xy 291.516203 -347.725635) (xy 291.537136 -347.743272) (xy 291.548464 -347.752508)
			(xy 291.575021 -347.764684) (xy 291.603938 -347.768857) (xy 291.632855 -347.764684) (xy 291.659412 -347.752508)
			(xy 291.67074 -347.743272) (xy 291.69168 -347.725643) (xy 291.737651 -347.695931) (xy 291.787397 -347.673093)
			(xy 291.839895 -347.6576) (xy 291.894069 -347.649768) (xy 291.921438 -347.649292) (xy 291.94869 -347.649742)
			(xy 292.002639 -347.657504) (xy 292.054935 -347.672864) (xy 292.104512 -347.69551) (xy 292.150362 -347.72498)
			(xy 292.191552 -347.760675) (xy 292.227243 -347.801868) (xy 292.256709 -347.847721) (xy 292.279349 -347.897301)
			(xy 292.294704 -347.949598) (xy 292.30246 -348.003548) (xy 292.302946 -348.0308) (xy 292.302493 -348.058171)
			(xy 292.294674 -348.112351) (xy 292.279183 -348.164855) (xy 292.256338 -348.214602) (xy 292.226609 -348.260567)
			(xy 292.208966 -348.281498) (xy 292.199732 -348.292826) (xy 292.187559 -348.319384) (xy 292.183388 -348.3483)
			(xy 292.187559 -348.377216) (xy 292.199732 -348.403774) (xy 292.208966 -348.415102) (xy 292.226607 -348.436035)
			(xy 292.256332 -348.482002) (xy 292.279178 -348.531748) (xy 292.294675 -348.584251) (xy 292.302503 -348.638429)
			(xy 292.302503 -348.693171) (xy 292.294675 -348.747349) (xy 292.279178 -348.799852) (xy 292.256332 -348.849598)
			(xy 292.226607 -348.895565) (xy 292.208966 -348.916498) (xy 292.199732 -348.927826) (xy 292.187559 -348.954384)
			(xy 292.183388 -348.9833) (xy 292.187559 -349.012216) (xy 292.199732 -349.038774) (xy 292.208966 -349.050102)
			(xy 292.226607 -349.071035) (xy 292.256332 -349.117002) (xy 292.279178 -349.166748) (xy 292.294675 -349.219251)
			(xy 292.302503 -349.273429) (xy 292.302503 -349.328171) (xy 292.294675 -349.382349) (xy 292.279178 -349.434852)
			(xy 292.256332 -349.484598) (xy 292.226607 -349.530565) (xy 292.208966 -349.551498) (xy 292.199732 -349.562826)
			(xy 292.187559 -349.589384) (xy 292.183388 -349.6183) (xy 292.187559 -349.647216) (xy 292.199732 -349.673774)
			(xy 292.208966 -349.685102) (xy 292.226607 -349.706035) (xy 292.256332 -349.752002) (xy 292.279178 -349.801748)
			(xy 292.294675 -349.854251) (xy 292.302503 -349.908429) (xy 292.302503 -349.963171) (xy 292.294675 -350.017349)
			(xy 292.279178 -350.069852) (xy 292.256332 -350.119598) (xy 292.226607 -350.165565) (xy 292.208966 -350.186498)
			(xy 292.199732 -350.197826) (xy 292.187559 -350.224384) (xy 292.183388 -350.2533) (xy 292.187559 -350.282216)
			(xy 292.199732 -350.308774) (xy 292.208966 -350.320102) (xy 292.226607 -350.341035) (xy 292.256332 -350.387002)
			(xy 292.279178 -350.436748) (xy 292.294675 -350.489251) (xy 292.302503 -350.543429) (xy 292.302503 -350.598171)
			(xy 292.294675 -350.652349) (xy 292.279178 -350.704852) (xy 292.256332 -350.754598) (xy 292.226607 -350.800565)
			(xy 292.208966 -350.821498) (xy 292.199732 -350.832826) (xy 292.187559 -350.859384) (xy 292.183388 -350.8883)
			(xy 292.187559 -350.917216) (xy 292.199732 -350.943774) (xy 292.208966 -350.955102) (xy 292.226607 -350.976035)
			(xy 292.256332 -351.022002) (xy 292.279178 -351.071748) (xy 292.294675 -351.124251) (xy 292.302503 -351.178429)
			(xy 292.302503 -351.233171) (xy 292.294675 -351.287349) (xy 292.279178 -351.339852) (xy 292.256332 -351.389598)
			(xy 292.226607 -351.435565) (xy 292.208966 -351.456498) (xy 292.199732 -351.467826) (xy 292.187559 -351.494384)
			(xy 292.183388 -351.5233) (xy 292.187559 -351.552216) (xy 292.199732 -351.578774) (xy 292.208966 -351.590102)
			(xy 292.226614 -351.611027) (xy 292.256326 -351.657001) (xy 292.279161 -351.70675) (xy 292.294649 -351.759253)
			(xy 292.302474 -351.81343) (xy 292.302946 -351.8408) (xy 294.964358 -351.8408) (xy 294.96481 -351.813429)
			(xy 294.972629 -351.759249) (xy 294.988121 -351.706745) (xy 295.010966 -351.656998) (xy 295.040695 -351.611033)
			(xy 295.058338 -351.590102) (xy 295.067572 -351.578773) (xy 295.079745 -351.552215) (xy 295.083915 -351.5233)
			(xy 295.079745 -351.494385) (xy 295.067572 -351.467827) (xy 295.058338 -351.456498) (xy 295.040697 -351.435565)
			(xy 295.010971 -351.389598) (xy 294.988125 -351.339852) (xy 294.972628 -351.28735) (xy 294.9648 -351.233171)
			(xy 294.9648 -351.178429) (xy 294.972628 -351.12425) (xy 294.988125 -351.071748) (xy 295.010971 -351.022002)
			(xy 295.040697 -350.976035) (xy 295.058338 -350.955102) (xy 295.067572 -350.943773) (xy 295.079745 -350.917215)
			(xy 295.083915 -350.8883) (xy 295.079745 -350.859385) (xy 295.067572 -350.832827) (xy 295.058338 -350.821498)
			(xy 295.040697 -350.800565) (xy 295.010971 -350.754598) (xy 294.988125 -350.704852) (xy 294.972628 -350.65235)
			(xy 294.9648 -350.598171) (xy 294.9648 -350.543429) (xy 294.972628 -350.48925) (xy 294.988125 -350.436748)
			(xy 295.010971 -350.387002) (xy 295.040697 -350.341035) (xy 295.058338 -350.320102) (xy 295.067572 -350.308773)
			(xy 295.079745 -350.282215) (xy 295.083915 -350.2533) (xy 295.079745 -350.224385) (xy 295.067572 -350.197827)
			(xy 295.058338 -350.186498) (xy 295.040697 -350.165565) (xy 295.010971 -350.119598) (xy 294.988125 -350.069852)
			(xy 294.972628 -350.01735) (xy 294.9648 -349.963171) (xy 294.9648 -349.908429) (xy 294.972628 -349.85425)
			(xy 294.988125 -349.801748) (xy 295.010971 -349.752002) (xy 295.040697 -349.706035) (xy 295.058338 -349.685102)
			(xy 295.067572 -349.673773) (xy 295.079745 -349.647215) (xy 295.083915 -349.6183) (xy 295.079745 -349.589385)
			(xy 295.067572 -349.562827) (xy 295.058338 -349.551498) (xy 295.040697 -349.530565) (xy 295.010971 -349.484598)
			(xy 294.988125 -349.434852) (xy 294.972628 -349.38235) (xy 294.9648 -349.328171) (xy 294.9648 -349.273429)
			(xy 294.972628 -349.21925) (xy 294.988125 -349.166748) (xy 295.010971 -349.117002) (xy 295.040697 -349.071035)
			(xy 295.058338 -349.050102) (xy 295.067572 -349.038773) (xy 295.079745 -349.012215) (xy 295.083915 -348.9833)
			(xy 295.079745 -348.954385) (xy 295.067572 -348.927827) (xy 295.058338 -348.916498) (xy 295.040697 -348.895565)
			(xy 295.010971 -348.849598) (xy 294.988125 -348.799852) (xy 294.972628 -348.74735) (xy 294.9648 -348.693171)
			(xy 294.9648 -348.638429) (xy 294.972628 -348.58425) (xy 294.988125 -348.531748) (xy 295.010971 -348.482002)
			(xy 295.040697 -348.436035) (xy 295.058338 -348.415102) (xy 295.067572 -348.403773) (xy 295.079745 -348.377215)
			(xy 295.083915 -348.3483) (xy 295.079745 -348.319385) (xy 295.067572 -348.292827) (xy 295.058338 -348.281498)
			(xy 295.04069 -348.260573) (xy 295.010979 -348.214599) (xy 294.988144 -348.164849) (xy 294.972655 -348.112347)
			(xy 294.96483 -348.05817) (xy 294.964358 -348.0308) (xy 294.964878 -348.00355) (xy 294.972633 -347.949606)
			(xy 294.987987 -347.897314) (xy 295.010625 -347.847739) (xy 295.040089 -347.80189) (xy 295.075776 -347.7607)
			(xy 295.116963 -347.725009) (xy 295.162809 -347.695542) (xy 295.212382 -347.672899) (xy 295.264672 -347.657541)
			(xy 295.318616 -347.64978) (xy 295.345866 -347.649292) (xy 295.373235 -347.64978) (xy 295.427413 -347.657593)
			(xy 295.479916 -347.673077) (xy 295.529663 -347.695914) (xy 295.575631 -347.725633) (xy 295.596564 -347.743272)
			(xy 295.607892 -347.752508) (xy 295.634449 -347.764684) (xy 295.663366 -347.768857) (xy 295.692283 -347.764684)
			(xy 295.71884 -347.752508) (xy 295.730168 -347.743272) (xy 295.751098 -347.72563) (xy 295.797072 -347.69592)
			(xy 295.84682 -347.673085) (xy 295.899321 -347.657594) (xy 295.953497 -347.649766) (xy 295.980866 -347.649292)
			(xy 296.008906 -347.649802) (xy 296.064383 -347.657998) (xy 296.118065 -347.67422) (xy 296.168798 -347.698118)
			(xy 296.21549 -347.729179) (xy 296.236644 -347.74759) (xy 296.248086 -347.757235) (xy 296.275129 -347.770015)
			(xy 296.304716 -347.774401) (xy 296.334303 -347.770015) (xy 296.361346 -347.757235) (xy 296.372788 -347.74759)
			(xy 296.393925 -347.729153) (xy 296.440606 -347.698061) (xy 296.49134 -347.674149) (xy 296.545032 -347.657932)
			(xy 296.600522 -347.649763) (xy 296.628566 -347.649292) (xy 296.655818 -347.649787) (xy 296.709768 -347.657539)
			(xy 296.762065 -347.672891) (xy 296.811645 -347.69553) (xy 296.857498 -347.724994) (xy 296.898691 -347.760684)
			(xy 296.934386 -347.801874) (xy 296.963854 -347.847725) (xy 296.986497 -347.897303) (xy 297.001853 -347.949599)
			(xy 297.009611 -348.003548) (xy 297.010074 -348.0308) (xy 297.009614 -348.058171) (xy 297.001796 -348.11235)
			(xy 296.986306 -348.164854) (xy 296.963462 -348.2146) (xy 296.933736 -348.260567) (xy 296.916094 -348.281498)
			(xy 296.906858 -348.292825) (xy 296.894681 -348.319383) (xy 296.890509 -348.3483) (xy 296.894681 -348.377217)
			(xy 296.906858 -348.403775) (xy 296.916094 -348.415102) (xy 296.933734 -348.436035) (xy 296.963457 -348.482003)
			(xy 296.986301 -348.53175) (xy 297.001796 -348.584252) (xy 297.009625 -348.63843) (xy 297.009625 -348.69317)
			(xy 297.001796 -348.747348) (xy 296.986301 -348.79985) (xy 296.963457 -348.849597) (xy 296.933734 -348.895565)
			(xy 296.916094 -348.916498) (xy 296.906858 -348.927825) (xy 296.894681 -348.954383) (xy 296.890509 -348.9833)
			(xy 296.894681 -349.012217) (xy 296.906858 -349.038775) (xy 296.916094 -349.050102) (xy 296.933734 -349.071035)
			(xy 296.963457 -349.117003) (xy 296.986301 -349.16675) (xy 297.001796 -349.219252) (xy 297.009625 -349.27343)
			(xy 297.009625 -349.32817) (xy 297.001796 -349.382348) (xy 296.986301 -349.43485) (xy 296.963457 -349.484597)
			(xy 296.933734 -349.530565) (xy 296.916094 -349.551498) (xy 296.906858 -349.562825) (xy 296.894681 -349.589383)
			(xy 296.890509 -349.6183) (xy 296.894681 -349.647217) (xy 296.906858 -349.673775) (xy 296.916094 -349.685102)
			(xy 296.933734 -349.706035) (xy 296.963457 -349.752003) (xy 296.986301 -349.80175) (xy 297.001796 -349.854252)
			(xy 297.009625 -349.90843) (xy 297.009625 -349.96317) (xy 297.001796 -350.017348) (xy 296.986301 -350.06985)
			(xy 296.963457 -350.119597) (xy 296.933734 -350.165565) (xy 296.916094 -350.186498) (xy 296.906858 -350.197825)
			(xy 296.894681 -350.224383) (xy 296.890509 -350.2533) (xy 296.894681 -350.282217) (xy 296.906858 -350.308775)
			(xy 296.916094 -350.320102) (xy 296.933734 -350.341035) (xy 296.963457 -350.387003) (xy 296.986301 -350.43675)
			(xy 297.001796 -350.489252) (xy 297.009625 -350.54343) (xy 297.009625 -350.59817) (xy 297.001796 -350.652348)
			(xy 296.986301 -350.70485) (xy 296.963457 -350.754597) (xy 296.933734 -350.800565) (xy 296.916094 -350.821498)
			(xy 296.906858 -350.832825) (xy 296.894681 -350.859383) (xy 296.890509 -350.8883) (xy 296.894681 -350.917217)
			(xy 296.906858 -350.943775) (xy 296.916094 -350.955102) (xy 296.933734 -350.976035) (xy 296.963457 -351.022003)
			(xy 296.986301 -351.07175) (xy 297.001796 -351.124252) (xy 297.009625 -351.17843) (xy 297.009625 -351.23317)
			(xy 297.001796 -351.287348) (xy 296.986301 -351.33985) (xy 296.963457 -351.389597) (xy 296.933734 -351.435565)
			(xy 296.916094 -351.456498) (xy 296.906858 -351.467825) (xy 296.894681 -351.494383) (xy 296.890509 -351.5233)
			(xy 296.894681 -351.552217) (xy 296.906858 -351.578775) (xy 296.916094 -351.590102) (xy 296.933747 -351.611023)
			(xy 296.963457 -351.656999) (xy 296.98629 -351.706749) (xy 297.001778 -351.759252) (xy 297.009602 -351.81343)
			(xy 297.010074 -351.8408) (xy 300.03623 -351.8408) (xy 300.036689 -351.813429) (xy 300.044507 -351.75925)
			(xy 300.059998 -351.706746) (xy 300.082841 -351.656999) (xy 300.112568 -351.611033) (xy 300.13021 -351.590102)
			(xy 300.139446 -351.578774) (xy 300.151622 -351.552217) (xy 300.155794 -351.5233) (xy 300.151622 -351.494383)
			(xy 300.139446 -351.467826) (xy 300.13021 -351.456498) (xy 300.11257 -351.435565) (xy 300.082847 -351.389597)
			(xy 300.060002 -351.33985) (xy 300.044507 -351.287349) (xy 300.036678 -351.23317) (xy 300.036678 -351.17843)
			(xy 300.044507 -351.124251) (xy 300.060002 -351.07175) (xy 300.082847 -351.022003) (xy 300.11257 -350.976035)
			(xy 300.13021 -350.955102) (xy 300.139446 -350.943774) (xy 300.151622 -350.917217) (xy 300.155794 -350.8883)
			(xy 300.151622 -350.859383) (xy 300.139446 -350.832826) (xy 300.13021 -350.821498) (xy 300.11257 -350.800565)
			(xy 300.082847 -350.754597) (xy 300.060002 -350.70485) (xy 300.044507 -350.652349) (xy 300.036678 -350.59817)
			(xy 300.036678 -350.54343) (xy 300.044507 -350.489251) (xy 300.060002 -350.43675) (xy 300.082847 -350.387003)
			(xy 300.11257 -350.341035) (xy 300.13021 -350.320102) (xy 300.139446 -350.308774) (xy 300.151622 -350.282217)
			(xy 300.155794 -350.2533) (xy 300.151622 -350.224383) (xy 300.139446 -350.197826) (xy 300.13021 -350.186498)
			(xy 300.11257 -350.165565) (xy 300.082847 -350.119597) (xy 300.060002 -350.06985) (xy 300.044507 -350.017349)
			(xy 300.036678 -349.96317) (xy 300.036678 -349.90843) (xy 300.044507 -349.854251) (xy 300.060002 -349.80175)
			(xy 300.082847 -349.752003) (xy 300.11257 -349.706035) (xy 300.13021 -349.685102) (xy 300.139446 -349.673774)
			(xy 300.151622 -349.647217) (xy 300.155794 -349.6183) (xy 300.151622 -349.589383) (xy 300.139446 -349.562826)
			(xy 300.13021 -349.551498) (xy 300.11257 -349.530565) (xy 300.082847 -349.484597) (xy 300.060002 -349.43485)
			(xy 300.044507 -349.382349) (xy 300.036678 -349.32817) (xy 300.036678 -349.27343) (xy 300.044507 -349.219251)
			(xy 300.060002 -349.16675) (xy 300.082847 -349.117003) (xy 300.11257 -349.071035) (xy 300.13021 -349.050102)
			(xy 300.139446 -349.038774) (xy 300.151622 -349.012217) (xy 300.155794 -348.9833) (xy 300.151622 -348.954383)
			(xy 300.139446 -348.927826) (xy 300.13021 -348.916498) (xy 300.11257 -348.895565) (xy 300.082847 -348.849597)
			(xy 300.060002 -348.79985) (xy 300.044507 -348.747349) (xy 300.036678 -348.69317) (xy 300.036678 -348.63843)
			(xy 300.044507 -348.584251) (xy 300.060002 -348.53175) (xy 300.082847 -348.482003) (xy 300.11257 -348.436035)
			(xy 300.13021 -348.415102) (xy 300.139446 -348.403774) (xy 300.151622 -348.377217) (xy 300.155794 -348.3483)
			(xy 300.151622 -348.319383) (xy 300.139446 -348.292826) (xy 300.13021 -348.281498) (xy 300.112558 -348.260576)
			(xy 300.082848 -348.214601) (xy 300.060014 -348.164851) (xy 300.044526 -348.112348) (xy 300.036702 -348.05817)
			(xy 300.03623 -348.0308) (xy 300.036655 -348.003545) (xy 300.044413 -347.949591) (xy 300.059771 -347.89729)
			(xy 300.082417 -347.847708) (xy 300.111888 -347.801853) (xy 300.147586 -347.760659) (xy 300.188783 -347.724965)
			(xy 300.234641 -347.695498) (xy 300.284226 -347.672858) (xy 300.336528 -347.657505) (xy 300.390483 -347.649753)
			(xy 300.417738 -347.649292) (xy 300.445779 -347.649759) (xy 300.501259 -347.657966) (xy 300.554941 -347.674198)
			(xy 300.605673 -347.698105) (xy 300.652363 -347.729175) (xy 300.673516 -347.74759) (xy 300.684958 -347.757235)
			(xy 300.712001 -347.770015) (xy 300.741588 -347.774401) (xy 300.771175 -347.770015) (xy 300.798218 -347.757235)
			(xy 300.80966 -347.74759) (xy 300.830808 -347.729166) (xy 300.877486 -347.698072) (xy 300.928217 -347.674157)
			(xy 300.981907 -347.657938) (xy 301.037395 -347.649765) (xy 301.065438 -347.649292) (xy 301.092807 -347.649796)
			(xy 301.146984 -347.657605) (xy 301.199487 -347.673085) (xy 301.249234 -347.695919) (xy 301.295203 -347.725635)
			(xy 301.316136 -347.743272) (xy 301.327464 -347.752508) (xy 301.354021 -347.764684) (xy 301.382938 -347.768857)
			(xy 301.411855 -347.764684) (xy 301.438412 -347.752508) (xy 301.44974 -347.743272) (xy 301.47068 -347.725643)
			(xy 301.516651 -347.695931) (xy 301.566397 -347.673093) (xy 301.618895 -347.6576) (xy 301.673069 -347.649768)
			(xy 301.700438 -347.649292) (xy 301.72769 -347.649742) (xy 301.781639 -347.657504) (xy 301.833935 -347.672864)
			(xy 301.883512 -347.69551) (xy 301.929362 -347.72498) (xy 301.970552 -347.760675) (xy 302.006243 -347.801868)
			(xy 302.035709 -347.847721) (xy 302.058349 -347.897301) (xy 302.073704 -347.949598) (xy 302.08146 -348.003548)
			(xy 302.081946 -348.0308) (xy 302.081493 -348.058171) (xy 302.073674 -348.112351) (xy 302.058183 -348.164855)
			(xy 302.035338 -348.214602) (xy 302.005609 -348.260567) (xy 301.987966 -348.281498) (xy 301.978732 -348.292826)
			(xy 301.966559 -348.319384) (xy 301.962388 -348.3483) (xy 301.966559 -348.377216) (xy 301.978732 -348.403774)
			(xy 301.987966 -348.415102) (xy 302.005607 -348.436035) (xy 302.035332 -348.482002) (xy 302.058178 -348.531748)
			(xy 302.073675 -348.584251) (xy 302.081503 -348.638429) (xy 302.081503 -348.693171) (xy 302.073675 -348.747349)
			(xy 302.058178 -348.799852) (xy 302.035332 -348.849598) (xy 302.005607 -348.895565) (xy 301.987966 -348.916498)
			(xy 301.978732 -348.927826) (xy 301.966559 -348.954384) (xy 301.962388 -348.9833) (xy 301.966559 -349.012216)
			(xy 301.978732 -349.038774) (xy 301.987966 -349.050102) (xy 302.005607 -349.071035) (xy 302.035332 -349.117002)
			(xy 302.058178 -349.166748) (xy 302.073675 -349.219251) (xy 302.081503 -349.273429) (xy 302.081503 -349.328171)
			(xy 302.073675 -349.382349) (xy 302.058178 -349.434852) (xy 302.035332 -349.484598) (xy 302.005607 -349.530565)
			(xy 301.987966 -349.551498) (xy 301.978732 -349.562826) (xy 301.966559 -349.589384) (xy 301.962388 -349.6183)
			(xy 301.966559 -349.647216) (xy 301.978732 -349.673774) (xy 301.987966 -349.685102) (xy 302.005607 -349.706035)
			(xy 302.035332 -349.752002) (xy 302.058178 -349.801748) (xy 302.073675 -349.854251) (xy 302.081503 -349.908429)
			(xy 302.081503 -349.963171) (xy 302.073675 -350.017349) (xy 302.058178 -350.069852) (xy 302.035332 -350.119598)
			(xy 302.005607 -350.165565) (xy 301.987966 -350.186498) (xy 301.978732 -350.197826) (xy 301.966559 -350.224384)
			(xy 301.962388 -350.2533) (xy 301.966559 -350.282216) (xy 301.978732 -350.308774) (xy 301.987966 -350.320102)
			(xy 302.005607 -350.341035) (xy 302.035332 -350.387002) (xy 302.058178 -350.436748) (xy 302.073675 -350.489251)
			(xy 302.081503 -350.543429) (xy 302.081503 -350.598171) (xy 302.073675 -350.652349) (xy 302.058178 -350.704852)
			(xy 302.035332 -350.754598) (xy 302.005607 -350.800565) (xy 301.987966 -350.821498) (xy 301.978732 -350.832826)
			(xy 301.966559 -350.859384) (xy 301.962388 -350.8883) (xy 301.966559 -350.917216) (xy 301.978732 -350.943774)
			(xy 301.987966 -350.955102) (xy 302.005607 -350.976035) (xy 302.035332 -351.022002) (xy 302.058178 -351.071748)
			(xy 302.073675 -351.124251) (xy 302.081503 -351.178429) (xy 302.081503 -351.233171) (xy 302.073675 -351.287349)
			(xy 302.058178 -351.339852) (xy 302.035332 -351.389598) (xy 302.005607 -351.435565) (xy 301.987966 -351.456498)
			(xy 301.978732 -351.467826) (xy 301.966559 -351.494384) (xy 301.962388 -351.5233) (xy 301.966559 -351.552216)
			(xy 301.978732 -351.578774) (xy 301.987966 -351.590102) (xy 302.005614 -351.611027) (xy 302.035326 -351.657001)
			(xy 302.058161 -351.70675) (xy 302.073649 -351.759253) (xy 302.081474 -351.81343) (xy 302.081946 -351.8408)
			(xy 302.081422 -351.86805) (xy 302.073667 -351.921994) (xy 302.058314 -351.974286) (xy 302.035675 -352.02386)
			(xy 302.006212 -352.069709) (xy 301.970525 -352.110898) (xy 301.929339 -352.14659) (xy 301.883494 -352.176057)
			(xy 301.833921 -352.1987) (xy 301.781631 -352.214059) (xy 301.727687 -352.22182) (xy 301.700438 -352.222308)
			(xy 301.673069 -352.221818) (xy 301.618891 -352.214005) (xy 301.566388 -352.198522) (xy 301.516641 -352.175686)
			(xy 301.470673 -352.145967) (xy 301.44974 -352.128328) (xy 301.438412 -352.119092) (xy 301.411855 -352.106916)
			(xy 301.382938 -352.102743) (xy 301.354021 -352.106916) (xy 301.327464 -352.119092) (xy 301.316136 -352.128328)
			(xy 301.295205 -352.145968) (xy 301.249231 -352.175679) (xy 301.199484 -352.198514) (xy 301.146983 -352.214005)
			(xy 301.092807 -352.221834) (xy 301.065438 -352.222308) (xy 301.037398 -352.221796) (xy 300.981921 -352.2136)
			(xy 300.928239 -352.197379) (xy 300.877507 -352.173481) (xy 300.830814 -352.142421) (xy 300.80966 -352.12401)
			(xy 300.798218 -352.114365) (xy 300.771175 -352.101585) (xy 300.741588 -352.097199) (xy 300.712001 -352.101585)
			(xy 300.684958 -352.114365) (xy 300.673516 -352.12401) (xy 300.652378 -352.142445) (xy 300.605697 -352.173537)
			(xy 300.554963 -352.19745) (xy 300.501271 -352.213667) (xy 300.445782 -352.221837) (xy 300.417738 -352.222308)
			(xy 300.390486 -352.221809) (xy 300.336536 -352.214058) (xy 300.284239 -352.198706) (xy 300.234659 -352.176068)
			(xy 300.188806 -352.146604) (xy 300.147613 -352.110914) (xy 300.111919 -352.069725) (xy 300.08245 -352.023874)
			(xy 300.059807 -351.974296) (xy 300.044451 -351.922001) (xy 300.036693 -351.868052) (xy 300.03623 -351.8408)
			(xy 297.010074 -351.8408) (xy 297.009645 -351.868054) (xy 297.001887 -351.922008) (xy 296.986529 -351.974309)
			(xy 296.963884 -352.023891) (xy 296.934413 -352.069746) (xy 296.898715 -352.11094) (xy 296.857519 -352.146633)
			(xy 296.811661 -352.1761) (xy 296.762077 -352.198741) (xy 296.709775 -352.214094) (xy 296.65582 -352.221847)
			(xy 296.628566 -352.222308) (xy 296.600525 -352.221839) (xy 296.545046 -352.213632) (xy 296.491363 -352.197401)
			(xy 296.440631 -352.173494) (xy 296.393941 -352.142425) (xy 296.372788 -352.12401) (xy 296.361346 -352.114365)
			(xy 296.334303 -352.101585) (xy 296.304716 -352.097199) (xy 296.275129 -352.101585) (xy 296.248086 -352.114365)
			(xy 296.236644 -352.12401) (xy 296.215495 -352.142432) (xy 296.168817 -352.173526) (xy 296.118086 -352.197441)
			(xy 296.064396 -352.213661) (xy 296.008909 -352.221835) (xy 295.980866 -352.222308) (xy 295.953495 -352.22186)
			(xy 295.899315 -352.214037) (xy 295.846812 -352.198544) (xy 295.797066 -352.175698) (xy 295.751099 -352.145971)
			(xy 295.730168 -352.128328) (xy 295.71884 -352.119092) (xy 295.692283 -352.106916) (xy 295.663366 -352.102743)
			(xy 295.634449 -352.106916) (xy 295.607892 -352.119092) (xy 295.596564 -352.128328) (xy 295.575622 -352.145955)
			(xy 295.529652 -352.175668) (xy 295.479907 -352.198505) (xy 295.427408 -352.213999) (xy 295.373234 -352.221832)
			(xy 295.345866 -352.222308) (xy 295.318614 -352.221854) (xy 295.264665 -352.214093) (xy 295.21237 -352.198733)
			(xy 295.162792 -352.176088) (xy 295.116942 -352.146618) (xy 295.075752 -352.110924) (xy 295.040061 -352.069731)
			(xy 295.010596 -352.023878) (xy 294.987955 -351.974298) (xy 294.9726 -351.922002) (xy 294.964844 -351.868052)
			(xy 294.964358 -351.8408) (xy 292.302946 -351.8408) (xy 292.302422 -351.86805) (xy 292.294667 -351.921994)
			(xy 292.279314 -351.974286) (xy 292.256675 -352.02386) (xy 292.227212 -352.069709) (xy 292.191525 -352.110898)
			(xy 292.150339 -352.14659) (xy 292.104494 -352.176057) (xy 292.054921 -352.1987) (xy 292.002631 -352.214059)
			(xy 291.948687 -352.22182) (xy 291.921438 -352.222308) (xy 291.894069 -352.221818) (xy 291.839891 -352.214005)
			(xy 291.787388 -352.198522) (xy 291.737641 -352.175686) (xy 291.691673 -352.145967) (xy 291.67074 -352.128328)
			(xy 291.659412 -352.119092) (xy 291.632855 -352.106916) (xy 291.603938 -352.102743) (xy 291.575021 -352.106916)
			(xy 291.548464 -352.119092) (xy 291.537136 -352.128328) (xy 291.516205 -352.145968) (xy 291.470231 -352.175679)
			(xy 291.420484 -352.198514) (xy 291.367983 -352.214005) (xy 291.313807 -352.221834) (xy 291.286438 -352.222308)
			(xy 291.258398 -352.221796) (xy 291.202921 -352.2136) (xy 291.149239 -352.197379) (xy 291.098507 -352.173481)
			(xy 291.051814 -352.142421) (xy 291.03066 -352.12401) (xy 291.019218 -352.114365) (xy 290.992175 -352.101585)
			(xy 290.962588 -352.097199) (xy 290.933001 -352.101585) (xy 290.905958 -352.114365) (xy 290.894516 -352.12401)
			(xy 290.873378 -352.142445) (xy 290.826697 -352.173537) (xy 290.775963 -352.19745) (xy 290.722271 -352.213667)
			(xy 290.666782 -352.221837) (xy 290.638738 -352.222308) (xy 290.611486 -352.221809) (xy 290.557536 -352.214058)
			(xy 290.505239 -352.198706) (xy 290.455659 -352.176068) (xy 290.409806 -352.146604) (xy 290.368613 -352.110914)
			(xy 290.332919 -352.069725) (xy 290.30345 -352.023874) (xy 290.280807 -351.974296) (xy 290.265451 -351.922001)
			(xy 290.257693 -351.868052) (xy 290.25723 -351.8408) (xy 287.332674 -351.8408) (xy 287.332245 -351.868054)
			(xy 287.324487 -351.922008) (xy 287.309129 -351.974309) (xy 287.286484 -352.023891) (xy 287.257013 -352.069746)
			(xy 287.221315 -352.11094) (xy 287.180119 -352.146633) (xy 287.134261 -352.1761) (xy 287.084677 -352.198741)
			(xy 287.032375 -352.214094) (xy 286.97842 -352.221847) (xy 286.951166 -352.222308) (xy 286.923125 -352.221839)
			(xy 286.867646 -352.213632) (xy 286.813963 -352.197401) (xy 286.763231 -352.173494) (xy 286.716541 -352.142425)
			(xy 286.695388 -352.12401) (xy 286.683946 -352.114365) (xy 286.656903 -352.101585) (xy 286.627316 -352.097199)
			(xy 286.597729 -352.101585) (xy 286.570686 -352.114365) (xy 286.559244 -352.12401) (xy 286.538095 -352.142432)
			(xy 286.491417 -352.173526) (xy 286.440686 -352.197441) (xy 286.386996 -352.213661) (xy 286.331509 -352.221835)
			(xy 286.303466 -352.222308) (xy 286.276095 -352.22186) (xy 286.221915 -352.214037) (xy 286.169412 -352.198544)
			(xy 286.119666 -352.175698) (xy 286.073699 -352.145971) (xy 286.052768 -352.128328) (xy 286.04144 -352.119092)
			(xy 286.014883 -352.106916) (xy 285.985966 -352.102743) (xy 285.957049 -352.106916) (xy 285.930492 -352.119092)
			(xy 285.919164 -352.128328) (xy 285.898222 -352.145955) (xy 285.852252 -352.175668) (xy 285.802507 -352.198505)
			(xy 285.750008 -352.213999) (xy 285.695834 -352.221832) (xy 285.668466 -352.222308) (xy 285.641214 -352.221854)
			(xy 285.587265 -352.214093) (xy 285.53497 -352.198733) (xy 285.485392 -352.176088) (xy 285.439542 -352.146618)
			(xy 285.398352 -352.110924) (xy 285.362661 -352.069731) (xy 285.333196 -352.023878) (xy 285.310555 -351.974298)
			(xy 285.2952 -351.922002) (xy 285.287444 -351.868052) (xy 285.286958 -351.8408) (xy 282.69946 -351.8408)
			(xy 282.69946 -362.290868) (xy 283.044644 -362.290868) (xy 283.048715 -362.235246) (xy 283.060841 -362.180809)
			(xy 283.080764 -362.128718) (xy 283.10806 -362.080083) (xy 283.142146 -362.03594) (xy 283.182295 -361.997231)
			(xy 283.227653 -361.96478) (xy 283.277253 -361.939279) (xy 283.330037 -361.921272) (xy 283.38488 -361.911142)
			(xy 283.440614 -361.909105) (xy 283.496051 -361.915205) (xy 283.550008 -361.929311) (xy 283.601337 -361.951123)
			(xy 283.648943 -361.980177) (xy 283.691811 -362.015852) (xy 283.729028 -362.057389) (xy 283.759801 -362.103902)
			(xy 283.783473 -362.154399) (xy 283.799541 -362.207806) (xy 283.807661 -362.262982) (xy 283.80817 -362.290868)
			(xy 283.807661 -362.318754) (xy 283.799541 -362.37393) (xy 283.783473 -362.427337) (xy 283.759801 -362.477834)
			(xy 283.729028 -362.524347) (xy 283.691811 -362.565884) (xy 283.648943 -362.601559) (xy 283.601337 -362.630613)
			(xy 283.550008 -362.652425) (xy 283.496051 -362.666531) (xy 283.440614 -362.672631) (xy 283.38488 -362.670594)
			(xy 283.330037 -362.660464) (xy 283.277253 -362.642457) (xy 283.227653 -362.616956) (xy 283.182295 -362.584505)
			(xy 283.142146 -362.545796) (xy 283.10806 -362.501653) (xy 283.080764 -362.453018) (xy 283.060841 -362.400927)
			(xy 283.048715 -362.34649) (xy 283.044644 -362.290868) (xy 282.69946 -362.290868) (xy 282.69946 -364.242096)
			(xy 284.829758 -364.242096) (xy 284.830254 -364.214056) (xy 284.838455 -364.158578) (xy 284.854681 -364.104896)
			(xy 284.878582 -364.054164) (xy 284.909644 -364.007472) (xy 284.928056 -363.986318) (xy 284.937658 -363.974842)
			(xy 284.950447 -363.947812) (xy 284.954843 -363.918234) (xy 284.950467 -363.888653) (xy 284.937697 -363.861615)
			(xy 284.928056 -363.850174) (xy 284.909643 -363.829017) (xy 284.878549 -363.782341) (xy 284.854632 -363.731612)
			(xy 284.83841 -363.677924) (xy 284.830233 -363.622439) (xy 284.829758 -363.594396) (xy 284.830244 -363.567145)
			(xy 284.838 -363.513197) (xy 284.853355 -363.460902) (xy 284.875997 -363.411325) (xy 284.905463 -363.365475)
			(xy 284.941154 -363.324284) (xy 284.982345 -363.288593) (xy 285.028195 -363.259127) (xy 285.077772 -363.236485)
			(xy 285.130067 -363.22113) (xy 285.184015 -363.213374) (xy 285.238517 -363.213374) (xy 285.292465 -363.22113)
			(xy 285.34476 -363.236485) (xy 285.394337 -363.259127) (xy 285.440187 -363.288593) (xy 285.481378 -363.324284)
			(xy 285.517069 -363.365475) (xy 285.546535 -363.411325) (xy 285.569177 -363.460902) (xy 285.584532 -363.513197)
			(xy 285.592288 -363.567145) (xy 285.592774 -363.594396) (xy 285.592291 -363.622437) (xy 285.584089 -363.677916)
			(xy 285.567862 -363.731598) (xy 285.543957 -363.78233) (xy 285.51289 -363.829021) (xy 285.494476 -363.850174)
			(xy 285.489947 -363.855508) (xy 292.807134 -363.855508) (xy 292.811205 -363.799886) (xy 292.823331 -363.745449)
			(xy 292.843254 -363.693358) (xy 292.87055 -363.644723) (xy 292.904636 -363.60058) (xy 292.944785 -363.561871)
			(xy 292.990143 -363.52942) (xy 293.039743 -363.503919) (xy 293.092527 -363.485912) (xy 293.14737 -363.475782)
			(xy 293.203104 -363.473745) (xy 293.258541 -363.479845) (xy 293.312498 -363.493951) (xy 293.363827 -363.515763)
			(xy 293.411433 -363.544817) (xy 293.454301 -363.580492) (xy 293.491518 -363.622029) (xy 293.522291 -363.668542)
			(xy 293.545963 -363.719039) (xy 293.562031 -363.772446) (xy 293.570151 -363.827622) (xy 293.57066 -363.855508)
			(xy 293.570151 -363.883394) (xy 293.562031 -363.93857) (xy 293.545963 -363.991977) (xy 293.522291 -364.042474)
			(xy 293.491518 -364.088987) (xy 293.454301 -364.130524) (xy 293.411433 -364.166199) (xy 293.363827 -364.195253)
			(xy 293.312498 -364.217065) (xy 293.258541 -364.231171) (xy 293.216963 -364.235746) (xy 294.51808 -364.235746)
			(xy 294.518554 -364.208376) (xy 294.526367 -364.154196) (xy 294.541853 -364.101692) (xy 294.564693 -364.051945)
			(xy 294.594418 -364.005979) (xy 294.61206 -363.985048) (xy 294.621255 -363.973689) (xy 294.633443 -363.947143)
			(xy 294.637626 -363.918235) (xy 294.633463 -363.889324) (xy 294.621293 -363.86277) (xy 294.61206 -363.851444)
			(xy 294.594421 -363.830512) (xy 294.564711 -363.784538) (xy 294.541875 -363.734791) (xy 294.526384 -363.68229)
			(xy 294.518554 -363.628115) (xy 294.51808 -363.600746) (xy 294.518566 -363.573495) (xy 294.526322 -363.519547)
			(xy 294.541677 -363.467252) (xy 294.564319 -363.417675) (xy 294.593785 -363.371825) (xy 294.629476 -363.330634)
			(xy 294.670667 -363.294943) (xy 294.716517 -363.265477) (xy 294.766094 -363.242835) (xy 294.818389 -363.22748)
			(xy 294.872337 -363.219724) (xy 294.926839 -363.219724) (xy 294.980787 -363.22748) (xy 295.033082 -363.242835)
			(xy 295.082659 -363.265477) (xy 295.128509 -363.294943) (xy 295.1697 -363.330634) (xy 295.205391 -363.371825)
			(xy 295.234857 -363.417675) (xy 295.257499 -363.467252) (xy 295.272854 -363.519547) (xy 295.28061 -363.573495)
			(xy 295.281096 -363.600746) (xy 295.280599 -363.628115) (xy 295.272789 -363.682293) (xy 295.257307 -363.734796)
			(xy 295.234472 -363.784543) (xy 295.204754 -363.830511) (xy 295.187116 -363.851444) (xy 295.180853 -363.859064)
			(xy 302.365154 -363.859064) (xy 302.369225 -363.803442) (xy 302.381351 -363.749005) (xy 302.401274 -363.696914)
			(xy 302.42857 -363.648279) (xy 302.462656 -363.604136) (xy 302.502805 -363.565427) (xy 302.548163 -363.532976)
			(xy 302.597763 -363.507475) (xy 302.650547 -363.489468) (xy 302.70539 -363.479338) (xy 302.761124 -363.477301)
			(xy 302.816561 -363.483401) (xy 302.870518 -363.497507) (xy 302.921847 -363.519319) (xy 302.969453 -363.548373)
			(xy 303.012321 -363.584048) (xy 303.049538 -363.625585) (xy 303.080311 -363.672098) (xy 303.103983 -363.722595)
			(xy 303.120051 -363.776002) (xy 303.128171 -363.831178) (xy 303.12868 -363.859064) (xy 303.128171 -363.88695)
			(xy 303.120051 -363.942126) (xy 303.103983 -363.995533) (xy 303.080311 -364.04603) (xy 303.049538 -364.092543)
			(xy 303.012321 -364.13408) (xy 302.969453 -364.169755) (xy 302.921847 -364.198809) (xy 302.870518 -364.220621)
			(xy 302.816561 -364.234727) (xy 302.761124 -364.240827) (xy 302.70539 -364.23879) (xy 302.650547 -364.22866)
			(xy 302.597763 -364.210653) (xy 302.548163 -364.185152) (xy 302.502805 -364.152701) (xy 302.462656 -364.113992)
			(xy 302.42857 -364.069849) (xy 302.401274 -364.021214) (xy 302.381351 -363.969123) (xy 302.369225 -363.914686)
			(xy 302.365154 -363.859064) (xy 295.180853 -363.859064) (xy 295.177834 -363.862738) (xy 295.16566 -363.889307)
			(xy 295.161495 -363.918235) (xy 295.165679 -363.94716) (xy 295.177871 -363.973721) (xy 295.187116 -363.985048)
			(xy 295.204747 -364.005987) (xy 295.234459 -364.051958) (xy 295.257297 -364.101704) (xy 295.27279 -364.154203)
			(xy 295.28062 -364.208377) (xy 295.281096 -364.235746) (xy 295.28061 -364.262997) (xy 295.272854 -364.316945)
			(xy 295.257499 -364.36924) (xy 295.234857 -364.418817) (xy 295.205391 -364.464667) (xy 295.1697 -364.505858)
			(xy 295.128509 -364.541549) (xy 295.082659 -364.571015) (xy 295.033082 -364.593657) (xy 294.980787 -364.609012)
			(xy 294.926839 -364.616768) (xy 294.872337 -364.616768) (xy 294.818389 -364.609012) (xy 294.766094 -364.593657)
			(xy 294.716517 -364.571015) (xy 294.670667 -364.541549) (xy 294.629476 -364.505858) (xy 294.593785 -364.464667)
			(xy 294.564319 -364.418817) (xy 294.541677 -364.36924) (xy 294.526322 -364.316945) (xy 294.518566 -364.262997)
			(xy 294.51808 -364.235746) (xy 293.216963 -364.235746) (xy 293.203104 -364.237271) (xy 293.14737 -364.235234)
			(xy 293.092527 -364.225104) (xy 293.039743 -364.207097) (xy 292.990143 -364.181596) (xy 292.944785 -364.149145)
			(xy 292.904636 -364.110436) (xy 292.87055 -364.066293) (xy 292.843254 -364.017658) (xy 292.823331 -363.965567)
			(xy 292.811205 -363.91113) (xy 292.807134 -363.855508) (xy 285.489947 -363.855508) (xy 285.484789 -363.861583)
			(xy 285.47202 -363.888638) (xy 285.467644 -363.918234) (xy 285.47204 -363.947827) (xy 285.484827 -363.974874)
			(xy 285.494476 -363.986318) (xy 285.512891 -364.007473) (xy 285.543984 -364.05415) (xy 285.567899 -364.10488)
			(xy 285.584121 -364.158568) (xy 285.592299 -364.214053) (xy 285.592774 -364.242096) (xy 285.592288 -364.269347)
			(xy 285.584532 -364.323295) (xy 285.569177 -364.37559) (xy 285.546535 -364.425167) (xy 285.517069 -364.471017)
			(xy 285.481378 -364.512208) (xy 285.440187 -364.547899) (xy 285.394337 -364.577365) (xy 285.34476 -364.600007)
			(xy 285.292465 -364.615362) (xy 285.238517 -364.623118) (xy 285.184015 -364.623118) (xy 285.130067 -364.615362)
			(xy 285.077772 -364.600007) (xy 285.028195 -364.577365) (xy 284.982345 -364.547899) (xy 284.941154 -364.512208)
			(xy 284.905463 -364.471017) (xy 284.875997 -364.425167) (xy 284.853355 -364.37559) (xy 284.838 -364.323295)
			(xy 284.830244 -364.269347) (xy 284.829758 -364.242096) (xy 282.69946 -364.242096) (xy 282.69946 -364.625128)
			(xy 283.044644 -364.625128) (xy 283.048715 -364.569506) (xy 283.060841 -364.515069) (xy 283.080764 -364.462978)
			(xy 283.10806 -364.414343) (xy 283.142146 -364.3702) (xy 283.182295 -364.331491) (xy 283.227653 -364.29904)
			(xy 283.277253 -364.273539) (xy 283.330037 -364.255532) (xy 283.38488 -364.245402) (xy 283.440614 -364.243365)
			(xy 283.496051 -364.249465) (xy 283.550008 -364.263571) (xy 283.601337 -364.285383) (xy 283.648943 -364.314437)
			(xy 283.691811 -364.350112) (xy 283.729028 -364.391649) (xy 283.759801 -364.438162) (xy 283.783473 -364.488659)
			(xy 283.799541 -364.542066) (xy 283.807661 -364.597242) (xy 283.80817 -364.625128) (xy 283.80793 -364.6383)
			(xy 289.07837 -364.6383) (xy 289.082538 -364.582684) (xy 289.094949 -364.52831) (xy 289.115327 -364.476394)
			(xy 289.143215 -364.428095) (xy 289.17799 -364.384492) (xy 289.218876 -364.34656) (xy 289.264959 -364.315146)
			(xy 289.31521 -364.290951) (xy 289.368506 -364.274517) (xy 289.423656 -364.26621) (xy 289.451542 -364.265718)
			(xy 289.478873 -364.26621) (xy 289.532952 -364.274177) (xy 289.585285 -364.289962) (xy 289.634749 -364.313227)
			(xy 289.680282 -364.343471) (xy 289.720905 -364.380046) (xy 289.755745 -364.422165) (xy 289.770312 -364.445296)
			(xy 289.778247 -364.457512) (xy 289.799715 -364.477184) (xy 289.825865 -364.48999) (xy 289.854568 -364.494887)
			(xy 289.883485 -364.491477) (xy 289.897058 -364.48619) (xy 289.920264 -364.47669) (xy 289.968599 -364.463343)
			(xy 290.01829 -364.456619) (xy 290.043362 -364.456218) (xy 290.068432 -364.456634) (xy 290.118115 -364.463387)
			(xy 290.166449 -364.476723) (xy 290.189666 -364.48619) (xy 290.203241 -364.491445) (xy 290.232143 -364.494811)
			(xy 290.260823 -364.4899) (xy 290.286959 -364.477108) (xy 290.308433 -364.457473) (xy 290.316412 -364.445296)
			(xy 290.330981 -364.422165) (xy 290.365824 -364.380044) (xy 290.406447 -364.343465) (xy 290.451978 -364.313214)
			(xy 290.50144 -364.289938) (xy 290.553771 -364.274138) (xy 290.60785 -364.266152) (xy 290.662514 -364.266152)
			(xy 290.716593 -364.274138) (xy 290.768924 -364.289938) (xy 290.818386 -364.313214) (xy 290.863917 -364.343465)
			(xy 290.90454 -364.380044) (xy 290.939383 -364.422165) (xy 290.953952 -364.445296) (xy 290.961849 -364.457539)
			(xy 290.983327 -364.477211) (xy 291.009488 -364.490013) (xy 291.038199 -364.494904) (xy 291.067123 -364.491483)
			(xy 291.080698 -364.48619) (xy 291.103911 -364.476708) (xy 291.152242 -364.463354) (xy 291.201931 -364.456623)
			(xy 291.227002 -364.456218) (xy 291.254319 -364.456686) (xy 291.308365 -364.464677) (xy 291.360665 -364.480472)
			(xy 291.410099 -364.503733) (xy 291.455607 -364.533963) (xy 291.496215 -364.570512) (xy 291.531052 -364.612598)
			(xy 291.559371 -364.659318) (xy 291.57041 -364.68431) (xy 291.575959 -364.69653) (xy 291.592461 -364.717688)
			(xy 291.613901 -364.733822) (xy 291.638801 -364.74382) (xy 291.665445 -364.746992) (xy 291.691997 -364.743119)
			(xy 291.716625 -364.73247) (xy 291.727382 -364.724442) (xy 291.747719 -364.708764) (xy 291.791824 -364.682466)
			(xy 291.839056 -364.662316) (xy 291.888563 -364.648679) (xy 291.939451 -364.641799) (xy 291.965126 -364.641384)
			(xy 291.983145 -364.641606) (xy 292.01902 -364.645039) (xy 292.036754 -364.648242) (xy 292.051967 -364.650546)
			(xy 292.082518 -364.64703) (xy 292.110636 -364.634578) (xy 292.133772 -364.614319) (xy 292.149827 -364.588091)
			(xy 292.154102 -364.573312) (xy 292.161484 -364.546264) (xy 292.183118 -364.494539) (xy 292.212086 -364.446535)
			(xy 292.247764 -364.403285) (xy 292.289385 -364.365719) (xy 292.336054 -364.334645) (xy 292.386766 -364.310733)
			(xy 292.44043 -364.294496) (xy 292.495893 -364.286284) (xy 292.523926 -364.285784) (xy 292.551178 -364.286254)
			(xy 292.605125 -364.294013) (xy 292.65742 -364.309371) (xy 292.706997 -364.332015) (xy 292.752847 -364.361483)
			(xy 292.794036 -364.397176) (xy 292.829728 -364.438368) (xy 292.859194 -364.484219) (xy 292.881835 -364.533797)
			(xy 292.89719 -364.586092) (xy 292.904698 -364.6383) (xy 298.766795 -364.6383) (xy 298.770962 -364.582695)
			(xy 298.783369 -364.528332) (xy 298.80374 -364.476425) (xy 298.831619 -364.428134) (xy 298.866383 -364.384537)
			(xy 298.907257 -364.346608) (xy 298.953327 -364.315194) (xy 299.003564 -364.290997) (xy 299.056846 -364.274557)
			(xy 299.111984 -364.266241) (xy 299.139864 -364.265718) (xy 299.167196 -364.266193) (xy 299.221275 -364.274163)
			(xy 299.273609 -364.289951) (xy 299.323073 -364.313218) (xy 299.368605 -364.343465) (xy 299.409228 -364.380043)
			(xy 299.444068 -364.422164) (xy 299.458634 -364.445296) (xy 299.466548 -364.457527) (xy 299.488021 -364.477199)
			(xy 299.514177 -364.490003) (xy 299.542885 -364.494896) (xy 299.571806 -364.49148) (xy 299.58538 -364.48619)
			(xy 299.608595 -364.476714) (xy 299.656925 -364.463358) (xy 299.706613 -364.456624) (xy 299.731684 -364.456218)
			(xy 299.756753 -364.45666) (xy 299.806435 -364.463402) (xy 299.85477 -364.476727) (xy 299.877988 -364.48619)
			(xy 299.891578 -364.491412) (xy 299.92048 -364.494797) (xy 299.949165 -364.489902) (xy 299.975309 -364.477123)
			(xy 299.996793 -364.457496) (xy 300.004734 -364.445296) (xy 300.019303 -364.422165) (xy 300.054146 -364.380044)
			(xy 300.094769 -364.343465) (xy 300.1403 -364.313214) (xy 300.189762 -364.289938) (xy 300.242093 -364.274138)
			(xy 300.296172 -364.266152) (xy 300.350836 -364.266152) (xy 300.404915 -364.274138) (xy 300.457246 -364.289938)
			(xy 300.506708 -364.313214) (xy 300.552239 -364.343465) (xy 300.592862 -364.380044) (xy 300.627705 -364.422165)
			(xy 300.642274 -364.445296) (xy 300.650245 -364.457486) (xy 300.671703 -364.477157) (xy 300.697843 -364.489967)
			(xy 300.726538 -364.494871) (xy 300.755449 -364.491471) (xy 300.76902 -364.48619) (xy 300.79223 -364.476701)
			(xy 300.840563 -364.46335) (xy 300.890252 -364.456622) (xy 300.915324 -364.456218) (xy 300.942169 -364.456634)
			(xy 300.995301 -364.464342) (xy 301.046778 -364.479596) (xy 301.095533 -364.50208) (xy 301.140556 -364.531328)
			(xy 301.180915 -364.566735) (xy 301.215776 -364.607567) (xy 301.244415 -364.65298) (xy 301.266241 -364.702032)
			(xy 301.273972 -364.727744) (xy 301.27869 -364.742221) (xy 301.295197 -364.767781) (xy 301.318501 -364.787346)
			(xy 301.346533 -364.799179) (xy 301.376807 -364.80223) (xy 301.406637 -364.796229) (xy 301.420276 -364.789466)
			(xy 301.448418 -364.774824) (xy 301.508371 -364.7541) (xy 301.570931 -364.743605) (xy 301.602648 -364.742984)
			(xy 301.620667 -364.743202) (xy 301.656542 -364.746638) (xy 301.674276 -364.749842) (xy 301.689487 -364.752168)
			(xy 301.720039 -364.748646) (xy 301.748159 -364.736189) (xy 301.771295 -364.715925) (xy 301.787349 -364.689693)
			(xy 301.791624 -364.674912) (xy 301.798986 -364.647858) (xy 301.820622 -364.596131) (xy 301.849592 -364.548127)
			(xy 301.885273 -364.504876) (xy 301.926896 -364.46731) (xy 301.973568 -364.436238) (xy 302.024282 -364.412327)
			(xy 302.077949 -364.396092) (xy 302.133414 -364.387882) (xy 302.161448 -364.387384) (xy 302.1887 -364.387833)
			(xy 302.242649 -364.395596) (xy 302.294944 -364.410957) (xy 302.34452 -364.433603) (xy 302.39037 -364.463073)
			(xy 302.43156 -364.498769) (xy 302.467251 -364.539962) (xy 302.496716 -364.585815) (xy 302.519357 -364.635394)
			(xy 302.534713 -364.68769) (xy 302.54247 -364.74164) (xy 302.542956 -364.768892) (xy 302.5425 -364.796467)
			(xy 302.534548 -364.851041) (xy 302.518822 -364.903902) (xy 302.49565 -364.953948) (xy 302.465515 -365.000137)
			(xy 302.429045 -365.041507) (xy 302.408336 -365.059722) (xy 302.397444 -365.069627) (xy 302.381366 -365.094274)
			(xy 302.372978 -365.122481) (xy 302.372977 -365.151909) (xy 302.381361 -365.180116) (xy 302.397437 -365.204765)
			(xy 302.408336 -365.214662) (xy 302.429032 -365.232888) (xy 302.465492 -365.274259) (xy 302.495616 -365.320449)
			(xy 302.518776 -365.370494) (xy 302.53449 -365.423352) (xy 302.54243 -365.477922) (xy 302.542431 -365.533067)
			(xy 302.534492 -365.587637) (xy 302.51878 -365.640496) (xy 302.495621 -365.690542) (xy 302.465498 -365.736733)
			(xy 302.429039 -365.778105) (xy 302.408336 -365.796322) (xy 302.397444 -365.806227) (xy 302.381366 -365.830874)
			(xy 302.372978 -365.859081) (xy 302.372977 -365.888509) (xy 302.381361 -365.916716) (xy 302.397437 -365.941365)
			(xy 302.408336 -365.951262) (xy 302.429039 -365.969482) (xy 302.465509 -366.010849) (xy 302.495641 -366.057038)
			(xy 302.518808 -366.107084) (xy 302.534526 -366.159945) (xy 302.542469 -366.214518) (xy 302.542956 -366.242092)
			(xy 302.542415 -366.269341) (xy 302.534661 -366.323284) (xy 302.519309 -366.375575) (xy 302.496672 -366.425149)
			(xy 302.467211 -366.470997) (xy 302.431526 -366.512186) (xy 302.390342 -366.547878) (xy 302.344498 -366.577345)
			(xy 302.294927 -366.599989) (xy 302.242639 -366.615349) (xy 302.188697 -366.623111) (xy 302.161448 -366.6236)
			(xy 302.133594 -366.623034) (xy 302.07848 -366.614917) (xy 302.025131 -366.598878) (xy 301.974679 -366.575257)
			(xy 301.928194 -366.544555) (xy 301.886664 -366.507425) (xy 301.85097 -366.464655) (xy 301.82187 -366.417151)
			(xy 301.799981 -366.365923) (xy 301.792386 -366.33912) (xy 301.788085 -366.325013) (xy 301.772701 -366.29987)
			(xy 301.75079 -366.280153) (xy 301.724168 -366.2675) (xy 301.695043 -366.262958) (xy 301.680372 -366.264444)
			(xy 301.667356 -366.266114) (xy 301.641171 -366.267893) (xy 301.628048 -366.268) (xy 301.613899 -366.267901)
			(xy 301.585676 -366.26587) (xy 301.57166 -366.263936) (xy 301.558312 -366.262339) (xy 301.531617 -366.265436)
			(xy 301.506661 -366.275405) (xy 301.485179 -366.291553) (xy 301.468668 -366.312756) (xy 301.458275 -366.337539)
			(xy 301.45609 -366.350804) (xy 301.451996 -366.377957) (xy 301.437027 -366.430789) (xy 301.414638 -366.480929)
			(xy 301.385293 -366.527342) (xy 301.349596 -366.569067) (xy 301.308286 -366.605245) (xy 301.262217 -366.635126)
			(xy 301.21234 -366.658094) (xy 301.159685 -366.673674) (xy 301.10534 -366.681544) (xy 301.077884 -366.68202)
			(xy 301.050633 -366.681537) (xy 300.996686 -366.673779) (xy 300.944392 -366.658422) (xy 300.894815 -366.63578)
			(xy 300.848965 -366.606313) (xy 300.807776 -366.570622) (xy 300.772084 -366.529431) (xy 300.742618 -366.483581)
			(xy 300.719976 -366.434005) (xy 300.70462 -366.38171) (xy 300.696863 -366.327763) (xy 300.696376 -366.300512)
			(xy 300.696858 -366.272938) (xy 300.704809 -366.218366) (xy 300.720531 -366.165507) (xy 300.743698 -366.115461)
			(xy 300.773827 -366.069271) (xy 300.810291 -366.027899) (xy 300.830996 -366.009682) (xy 300.841881 -365.999771)
			(xy 300.857954 -365.975124) (xy 300.866339 -365.94692) (xy 300.866342 -365.917495) (xy 300.857961 -365.88929)
			(xy 300.841891 -365.864641) (xy 300.830996 -365.854742) (xy 300.810301 -365.836513) (xy 300.77383 -365.795148)
			(xy 300.743696 -365.748962) (xy 300.720527 -365.698917) (xy 300.704807 -365.646058) (xy 300.696864 -365.591486)
			(xy 300.696376 -365.563912) (xy 300.69686 -365.537412) (xy 300.704199 -365.484922) (xy 300.718737 -365.433955)
			(xy 300.740193 -365.385492) (xy 300.768154 -365.340468) (xy 300.784768 -365.319818) (xy 300.79424 -365.307695)
			(xy 300.806022 -365.279286) (xy 300.808838 -365.248661) (xy 300.802436 -365.218581) (xy 300.787392 -365.191757)
			(xy 300.765062 -365.170609) (xy 300.751494 -365.163354) (xy 300.727822 -365.15122) (xy 300.683837 -365.121307)
			(xy 300.644551 -365.085446) (xy 300.610762 -365.044364) (xy 300.596554 -365.021876) (xy 300.588658 -365.009633)
			(xy 300.567178 -364.989964) (xy 300.541017 -364.977164) (xy 300.512307 -364.972273) (xy 300.483383 -364.975691)
			(xy 300.469808 -364.980982) (xy 300.446594 -364.99046) (xy 300.398263 -365.003816) (xy 300.348575 -365.010548)
			(xy 300.323504 -365.010954) (xy 300.298435 -365.010518) (xy 300.248752 -365.003774) (xy 300.200418 -364.990446)
			(xy 300.1772 -364.980982) (xy 300.163598 -364.975809) (xy 300.13471 -364.972429) (xy 300.106041 -364.977324)
			(xy 300.079911 -364.990095) (xy 300.058436 -365.009709) (xy 300.050454 -365.021876) (xy 300.035885 -365.045007)
			(xy 300.001042 -365.087128) (xy 299.960419 -365.123707) (xy 299.914888 -365.153958) (xy 299.865426 -365.177234)
			(xy 299.813095 -365.193034) (xy 299.759016 -365.20102) (xy 299.704352 -365.20102) (xy 299.650273 -365.193034)
			(xy 299.597942 -365.177234) (xy 299.54848 -365.153958) (xy 299.502949 -365.123707) (xy 299.462326 -365.087128)
			(xy 299.427483 -365.045007) (xy 299.412914 -365.021876) (xy 299.404961 -365.009674) (xy 299.383497 -364.990005)
			(xy 299.357351 -364.977199) (xy 299.328654 -364.972298) (xy 299.299741 -364.9757) (xy 299.286168 -364.980982)
			(xy 299.262959 -364.990473) (xy 299.214626 -365.003824) (xy 299.164936 -365.010551) (xy 299.139864 -365.010954)
			(xy 299.111984 -365.010359) (xy 299.056846 -365.002043) (xy 299.003564 -364.985603) (xy 298.953327 -364.961406)
			(xy 298.907257 -364.929992) (xy 298.866383 -364.892063) (xy 298.831619 -364.848466) (xy 298.80374 -364.800175)
			(xy 298.783369 -364.748268) (xy 298.770962 -364.693905) (xy 298.766795 -364.6383) (xy 292.904698 -364.6383)
			(xy 292.904948 -364.64004) (xy 292.905434 -364.667292) (xy 292.904986 -364.694867) (xy 292.897033 -364.749442)
			(xy 292.881306 -364.802303) (xy 292.858133 -364.85235) (xy 292.827996 -364.898539) (xy 292.791524 -364.939908)
			(xy 292.770814 -364.958122) (xy 292.759924 -364.968028) (xy 292.743849 -364.992676) (xy 292.735464 -365.020882)
			(xy 292.735462 -365.050308) (xy 292.743845 -365.078515) (xy 292.759917 -365.103164) (xy 292.770814 -365.113062)
			(xy 292.791511 -365.131287) (xy 292.827973 -365.172658) (xy 292.858099 -365.218847) (xy 292.88126 -365.268892)
			(xy 292.896975 -365.321751) (xy 292.904916 -365.376322) (xy 292.904916 -365.431468) (xy 292.896977 -365.486038)
			(xy 292.881264 -365.538898) (xy 292.858104 -365.588944) (xy 292.827979 -365.635134) (xy 292.791518 -365.676506)
			(xy 292.770814 -365.694722) (xy 292.760482 -365.70412) (xy 295.309034 -365.70412) (xy 295.313105 -365.648498)
			(xy 295.325231 -365.594061) (xy 295.345154 -365.54197) (xy 295.37245 -365.493335) (xy 295.406536 -365.449192)
			(xy 295.446685 -365.410483) (xy 295.492043 -365.378032) (xy 295.541643 -365.352531) (xy 295.594427 -365.334524)
			(xy 295.64927 -365.324394) (xy 295.705004 -365.322357) (xy 295.760441 -365.328457) (xy 295.814398 -365.342563)
			(xy 295.865727 -365.364375) (xy 295.913333 -365.393429) (xy 295.956201 -365.429104) (xy 295.993418 -365.470641)
			(xy 296.024191 -365.517154) (xy 296.047863 -365.567651) (xy 296.063931 -365.621058) (xy 296.072051 -365.676234)
			(xy 296.07256 -365.70412) (xy 296.072051 -365.732006) (xy 296.063931 -365.787182) (xy 296.047863 -365.840589)
			(xy 296.024191 -365.891086) (xy 295.993418 -365.937599) (xy 295.956201 -365.979136) (xy 295.913333 -366.014811)
			(xy 295.865727 -366.043865) (xy 295.814398 -366.065677) (xy 295.760441 -366.079783) (xy 295.705004 -366.085883)
			(xy 295.64927 -366.083846) (xy 295.594427 -366.073716) (xy 295.541643 -366.055709) (xy 295.492043 -366.030208)
			(xy 295.446685 -365.997757) (xy 295.406536 -365.959048) (xy 295.37245 -365.914905) (xy 295.345154 -365.86627)
			(xy 295.325231 -365.814179) (xy 295.313105 -365.759742) (xy 295.309034 -365.70412) (xy 292.760482 -365.70412)
			(xy 292.759924 -365.704628) (xy 292.743849 -365.729276) (xy 292.735464 -365.757482) (xy 292.735462 -365.786908)
			(xy 292.743845 -365.815115) (xy 292.759917 -365.839764) (xy 292.770814 -365.849662) (xy 292.791513 -365.867886)
			(xy 292.827983 -365.909253) (xy 292.858117 -365.95544) (xy 292.881285 -366.005485) (xy 292.897004 -366.058345)
			(xy 292.904947 -366.112918) (xy 292.905434 -366.140492) (xy 292.904915 -366.167742) (xy 292.89716 -366.221687)
			(xy 292.881807 -366.27398) (xy 292.859169 -366.323555) (xy 292.829706 -366.369404) (xy 292.794018 -366.410594)
			(xy 292.752832 -366.446286) (xy 292.706985 -366.475753) (xy 292.657412 -366.498395) (xy 292.60512 -366.513753)
			(xy 292.551176 -366.521512) (xy 292.523926 -366.522) (xy 292.496072 -366.521453) (xy 292.440957 -366.513334)
			(xy 292.387607 -366.497291) (xy 292.337155 -366.473668) (xy 292.29067 -366.442964) (xy 292.24914 -366.405831)
			(xy 292.213447 -366.363059) (xy 292.184347 -366.315553) (xy 292.162459 -366.264324) (xy 292.154864 -366.23752)
			(xy 292.150585 -366.223406) (xy 292.135197 -366.19826) (xy 292.11328 -366.178543) (xy 292.086652 -366.165892)
			(xy 292.057523 -366.161355) (xy 292.04285 -366.162844) (xy 292.029834 -366.164516) (xy 292.003649 -366.166294)
			(xy 291.990526 -366.1664) (xy 291.966978 -366.166093) (xy 291.920234 -366.160356) (xy 291.897308 -366.15497)
			(xy 291.884306 -366.152198) (xy 291.857736 -366.152613) (xy 291.832177 -366.159878) (xy 291.809361 -366.1735)
			(xy 291.79084 -366.192554) (xy 291.77787 -366.215746) (xy 291.771332 -366.241501) (xy 291.77107 -366.254792)
			(xy 291.77107 -366.259872) (xy 291.770584 -366.287123) (xy 291.762828 -366.341071) (xy 291.747473 -366.393366)
			(xy 291.724831 -366.442943) (xy 291.695365 -366.488793) (xy 291.659674 -366.529984) (xy 291.618483 -366.565675)
			(xy 291.572633 -366.595141) (xy 291.523056 -366.617783) (xy 291.470761 -366.633138) (xy 291.416813 -366.640894)
			(xy 291.362311 -366.640894) (xy 291.308363 -366.633138) (xy 291.256068 -366.617783) (xy 291.206491 -366.595141)
			(xy 291.160641 -366.565675) (xy 291.11945 -366.529984) (xy 291.083759 -366.488793) (xy 291.054293 -366.442943)
			(xy 291.031651 -366.393366) (xy 291.016296 -366.341071) (xy 291.00854 -366.287123) (xy 291.008054 -366.259872)
			(xy 291.00855 -366.232298) (xy 291.016494 -366.177726) (xy 291.032212 -366.124866) (xy 291.055376 -366.074819)
			(xy 291.085504 -366.028629) (xy 291.121968 -365.987258) (xy 291.142674 -365.969042) (xy 291.153601 -365.959173)
			(xy 291.169676 -365.934515) (xy 291.178059 -365.906299) (xy 291.178054 -365.876865) (xy 291.169661 -365.848652)
			(xy 291.153577 -365.824) (xy 291.142674 -365.814102) (xy 291.121955 -365.795899) (xy 291.085487 -365.754528)
			(xy 291.055356 -365.708336) (xy 291.032192 -365.658287) (xy 291.016477 -365.605423) (xy 291.008539 -365.550847)
			(xy 291.008054 -365.523272) (xy 291.008619 -365.493749) (xy 291.017752 -365.435413) (xy 291.035766 -365.379181)
			(xy 291.062229 -365.326397) (xy 291.07892 -365.302038) (xy 291.08686 -365.290159) (xy 291.096379 -365.263229)
			(xy 291.098067 -365.234716) (xy 291.09179 -365.206852) (xy 291.078041 -365.181816) (xy 291.057895 -365.161568)
			(xy 291.045646 -365.15421) (xy 291.024749 -365.14215) (xy 290.985971 -365.113443) (xy 290.951219 -365.079973)
			(xy 290.921074 -365.042301) (xy 290.908232 -365.021876) (xy 290.900357 -365.009618) (xy 290.878871 -364.989949)
			(xy 290.852705 -364.977151) (xy 290.823989 -364.972264) (xy 290.795062 -364.975688) (xy 290.781486 -364.980982)
			(xy 290.758274 -364.990467) (xy 290.709942 -365.00382) (xy 290.660253 -365.01055) (xy 290.635182 -365.010954)
			(xy 290.610113 -365.010525) (xy 290.56043 -365.003778) (xy 290.512095 -364.990447) (xy 290.488878 -364.980982)
			(xy 290.475284 -364.975785) (xy 290.446392 -364.972411) (xy 290.41772 -364.977311) (xy 290.391589 -364.990088)
			(xy 290.370114 -365.009707) (xy 290.362132 -365.021876) (xy 290.347563 -365.045007) (xy 290.31272 -365.087128)
			(xy 290.272097 -365.123707) (xy 290.226566 -365.153958) (xy 290.177104 -365.177234) (xy 290.124773 -365.193034)
			(xy 290.070694 -365.20102) (xy 290.01603 -365.20102) (xy 289.961951 -365.193034) (xy 289.90962 -365.177234)
			(xy 289.860158 -365.153958) (xy 289.814627 -365.123707) (xy 289.774004 -365.087128) (xy 289.739161 -365.045007)
			(xy 289.724592 -365.021876) (xy 289.71666 -365.009659) (xy 289.69519 -364.98999) (xy 289.669039 -364.977186)
			(xy 289.640337 -364.972289) (xy 289.61142 -364.975697) (xy 289.597846 -364.980982) (xy 289.574639 -364.99048)
			(xy 289.526305 -365.003828) (xy 289.476614 -365.010553) (xy 289.451542 -365.010954) (xy 289.423656 -365.01039)
			(xy 289.368506 -365.002083) (xy 289.31521 -364.985649) (xy 289.264959 -364.961454) (xy 289.218876 -364.93004)
			(xy 289.17799 -364.892108) (xy 289.143215 -364.848505) (xy 289.115327 -364.800206) (xy 289.094949 -364.74829)
			(xy 289.082538 -364.693916) (xy 289.07837 -364.6383) (xy 283.80793 -364.6383) (xy 283.807661 -364.653014)
			(xy 283.799541 -364.70819) (xy 283.783473 -364.761597) (xy 283.759801 -364.812094) (xy 283.729028 -364.858607)
			(xy 283.691811 -364.900144) (xy 283.648943 -364.935819) (xy 283.601337 -364.964873) (xy 283.550008 -364.986685)
			(xy 283.496051 -365.000791) (xy 283.440614 -365.006891) (xy 283.38488 -365.004854) (xy 283.330037 -364.994724)
			(xy 283.277253 -364.976717) (xy 283.227653 -364.951216) (xy 283.182295 -364.918765) (xy 283.142146 -364.880056)
			(xy 283.10806 -364.835913) (xy 283.080764 -364.787278) (xy 283.060841 -364.735187) (xy 283.048715 -364.68075)
			(xy 283.044644 -364.625128) (xy 282.69946 -364.625128) (xy 282.69946 -365.70412) (xy 285.620712 -365.70412)
			(xy 285.624783 -365.648498) (xy 285.636909 -365.594061) (xy 285.656832 -365.54197) (xy 285.684128 -365.493335)
			(xy 285.718214 -365.449192) (xy 285.758363 -365.410483) (xy 285.803721 -365.378032) (xy 285.853321 -365.352531)
			(xy 285.906105 -365.334524) (xy 285.960948 -365.324394) (xy 286.016682 -365.322357) (xy 286.072119 -365.328457)
			(xy 286.126076 -365.342563) (xy 286.177405 -365.364375) (xy 286.225011 -365.393429) (xy 286.267879 -365.429104)
			(xy 286.305096 -365.470641) (xy 286.335869 -365.517154) (xy 286.359541 -365.567651) (xy 286.375609 -365.621058)
			(xy 286.383729 -365.676234) (xy 286.384238 -365.70412) (xy 286.383729 -365.732006) (xy 286.375609 -365.787182)
			(xy 286.359541 -365.840589) (xy 286.335869 -365.891086) (xy 286.305096 -365.937599) (xy 286.267879 -365.979136)
			(xy 286.225011 -366.014811) (xy 286.177405 -366.043865) (xy 286.126076 -366.065677) (xy 286.072119 -366.079783)
			(xy 286.016682 -366.085883) (xy 285.960948 -366.083846) (xy 285.906105 -366.073716) (xy 285.853321 -366.055709)
			(xy 285.803721 -366.030208) (xy 285.758363 -365.997757) (xy 285.718214 -365.959048) (xy 285.684128 -365.914905)
			(xy 285.656832 -365.86627) (xy 285.636909 -365.814179) (xy 285.624783 -365.759742) (xy 285.620712 -365.70412)
			(xy 282.69946 -365.70412) (xy 282.69946 -366.670082) (xy 284.956248 -366.670082) (xy 284.960319 -366.61446)
			(xy 284.972445 -366.560023) (xy 284.992368 -366.507932) (xy 285.019664 -366.459297) (xy 285.05375 -366.415154)
			(xy 285.093899 -366.376445) (xy 285.139257 -366.343994) (xy 285.188857 -366.318493) (xy 285.241641 -366.300486)
			(xy 285.296484 -366.290356) (xy 285.352218 -366.288319) (xy 285.407655 -366.294419) (xy 285.461612 -366.308525)
			(xy 285.512941 -366.330337) (xy 285.560547 -366.359391) (xy 285.603415 -366.395066) (xy 285.640632 -366.436603)
			(xy 285.671405 -366.483116) (xy 285.695077 -366.533613) (xy 285.711145 -366.58702) (xy 285.719265 -366.642196)
			(xy 285.719774 -366.670082) (xy 285.719265 -366.697968) (xy 285.711145 -366.753144) (xy 285.695077 -366.806551)
			(xy 285.671405 -366.857048) (xy 285.640632 -366.903561) (xy 285.603415 -366.945098) (xy 285.560547 -366.980773)
			(xy 285.512941 -367.009827) (xy 285.461612 -367.031639) (xy 285.407655 -367.045745) (xy 285.352218 -367.051845)
			(xy 285.296484 -367.049808) (xy 285.241641 -367.039678) (xy 285.188857 -367.021671) (xy 285.139257 -366.99617)
			(xy 285.093899 -366.963719) (xy 285.05375 -366.92501) (xy 285.019664 -366.880867) (xy 284.992368 -366.832232)
			(xy 284.972445 -366.780141) (xy 284.960319 -366.725704) (xy 284.956248 -366.670082) (xy 282.69946 -366.670082)
			(xy 282.69946 -367.212626) (xy 286.427418 -367.212626) (xy 286.427844 -367.187288) (xy 286.43455 -367.137057)
			(xy 286.447848 -367.088157) (xy 286.467504 -367.041447) (xy 286.493171 -366.997752) (xy 286.524398 -366.95784)
			(xy 286.542226 -366.93983) (xy 286.5517 -366.930126) (xy 286.565495 -366.906784) (xy 286.572642 -366.880629)
			(xy 286.572634 -366.853515) (xy 286.565473 -366.827364) (xy 286.551665 -366.804029) (xy 286.542226 -366.794288)
			(xy 286.524397 -366.776279) (xy 286.493168 -366.736367) (xy 286.467499 -366.692672) (xy 286.447841 -366.645963)
			(xy 286.434541 -366.597062) (xy 286.427832 -366.546831) (xy 286.427418 -366.521492) (xy 286.427904 -366.494241)
			(xy 286.43566 -366.440293) (xy 286.451015 -366.387998) (xy 286.473657 -366.338421) (xy 286.503123 -366.292571)
			(xy 286.538814 -366.25138) (xy 286.580005 -366.215689) (xy 286.625855 -366.186223) (xy 286.675432 -366.163581)
			(xy 286.727727 -366.148226) (xy 286.781675 -366.14047) (xy 286.836177 -366.14047) (xy 286.890125 -366.148226)
			(xy 286.94242 -366.163581) (xy 286.991997 -366.186223) (xy 287.037847 -366.215689) (xy 287.079038 -366.25138)
			(xy 287.114729 -366.292571) (xy 287.144195 -366.338421) (xy 287.166837 -366.387998) (xy 287.182192 -366.440293)
			(xy 287.189948 -366.494241) (xy 287.190094 -366.502442) (xy 288.052764 -366.502442) (xy 288.05325 -366.475191)
			(xy 288.061006 -366.421243) (xy 288.076361 -366.368948) (xy 288.099003 -366.319371) (xy 288.128469 -366.273521)
			(xy 288.16416 -366.23233) (xy 288.205351 -366.196639) (xy 288.251201 -366.167173) (xy 288.300778 -366.144531)
			(xy 288.353073 -366.129176) (xy 288.407021 -366.12142) (xy 288.461523 -366.12142) (xy 288.515471 -366.129176)
			(xy 288.567766 -366.144531) (xy 288.617343 -366.167173) (xy 288.663193 -366.196639) (xy 288.704384 -366.23233)
			(xy 288.740075 -366.273521) (xy 288.769541 -366.319371) (xy 288.792183 -366.368948) (xy 288.807538 -366.421243)
			(xy 288.815294 -366.475191) (xy 288.81578 -366.502442) (xy 288.815548 -366.521109) (xy 288.811855 -366.558261)
			(xy 288.808414 -366.57661) (xy 288.806165 -366.590889) (xy 288.808676 -366.619667) (xy 288.819156 -366.646586)
			(xy 288.836762 -366.669487) (xy 288.853909 -366.68202) (xy 294.64457 -366.68202) (xy 294.648641 -366.626398)
			(xy 294.660767 -366.571961) (xy 294.68069 -366.51987) (xy 294.707986 -366.471235) (xy 294.742072 -366.427092)
			(xy 294.782221 -366.388383) (xy 294.827579 -366.355932) (xy 294.877179 -366.330431) (xy 294.929963 -366.312424)
			(xy 294.984806 -366.302294) (xy 295.04054 -366.300257) (xy 295.095977 -366.306357) (xy 295.149934 -366.320463)
			(xy 295.201263 -366.342275) (xy 295.248869 -366.371329) (xy 295.291737 -366.407004) (xy 295.328954 -366.448541)
			(xy 295.359727 -366.495054) (xy 295.383399 -366.545551) (xy 295.399467 -366.598958) (xy 295.407587 -366.654134)
			(xy 295.408096 -366.68202) (xy 295.407587 -366.709906) (xy 295.399467 -366.765082) (xy 295.383399 -366.818489)
			(xy 295.359727 -366.868986) (xy 295.328954 -366.915499) (xy 295.291737 -366.957036) (xy 295.248869 -366.992711)
			(xy 295.201263 -367.021765) (xy 295.149934 -367.043577) (xy 295.095977 -367.057683) (xy 295.04054 -367.063783)
			(xy 294.984806 -367.061746) (xy 294.929963 -367.051616) (xy 294.877179 -367.033609) (xy 294.827579 -367.008108)
			(xy 294.782221 -366.975657) (xy 294.742072 -366.936948) (xy 294.707986 -366.892805) (xy 294.68069 -366.84417)
			(xy 294.660767 -366.792079) (xy 294.648641 -366.737642) (xy 294.64457 -366.68202) (xy 288.853909 -366.68202)
			(xy 288.860084 -366.686533) (xy 288.887249 -366.696356) (xy 288.901632 -366.697768) (xy 288.930291 -366.700084)
			(xy 288.98646 -366.712378) (xy 289.040148 -366.732959) (xy 289.090142 -366.761361) (xy 289.135308 -366.796943)
			(xy 289.174624 -366.838898) (xy 289.207202 -366.886277) (xy 289.232302 -366.938007) (xy 289.249357 -366.992917)
			(xy 289.257982 -367.049765) (xy 289.258502 -367.078514) (xy 289.258016 -367.105765) (xy 289.25026 -367.159713)
			(xy 289.234905 -367.212008) (xy 289.212263 -367.261585) (xy 289.203734 -367.274856) (xy 296.11574 -367.274856)
			(xy 296.116241 -367.246409) (xy 296.124701 -367.190149) (xy 296.141428 -367.13577) (xy 296.166048 -367.084479)
			(xy 296.198017 -367.037417) (xy 296.236624 -366.995627) (xy 296.258488 -366.977422) (xy 296.269983 -366.967503)
			(xy 296.287 -366.942374) (xy 296.295897 -366.913358) (xy 296.295892 -366.883009) (xy 296.286985 -366.853997)
			(xy 296.269961 -366.828873) (xy 296.258488 -366.818926) (xy 296.236618 -366.800728) (xy 296.198016 -366.758936)
			(xy 296.166053 -366.711871) (xy 296.141438 -366.660579) (xy 296.124719 -366.606199) (xy 296.116266 -366.549938)
			(xy 296.11574 -366.521492) (xy 296.116226 -366.494241) (xy 296.123982 -366.440293) (xy 296.139337 -366.387998)
			(xy 296.161979 -366.338421) (xy 296.191445 -366.292571) (xy 296.227136 -366.25138) (xy 296.268327 -366.215689)
			(xy 296.314177 -366.186223) (xy 296.363754 -366.163581) (xy 296.416049 -366.148226) (xy 296.469997 -366.14047)
			(xy 296.524499 -366.14047) (xy 296.578447 -366.148226) (xy 296.630742 -366.163581) (xy 296.680319 -366.186223)
			(xy 296.726169 -366.215689) (xy 296.76736 -366.25138) (xy 296.803051 -366.292571) (xy 296.832517 -366.338421)
			(xy 296.855159 -366.387998) (xy 296.870514 -366.440293) (xy 296.87827 -366.494241) (xy 296.878416 -366.502442)
			(xy 297.741086 -366.502442) (xy 297.741572 -366.475191) (xy 297.749328 -366.421243) (xy 297.764683 -366.368948)
			(xy 297.787325 -366.319371) (xy 297.816791 -366.273521) (xy 297.852482 -366.23233) (xy 297.893673 -366.196639)
			(xy 297.939523 -366.167173) (xy 297.9891 -366.144531) (xy 298.041395 -366.129176) (xy 298.095343 -366.12142)
			(xy 298.149845 -366.12142) (xy 298.203793 -366.129176) (xy 298.256088 -366.144531) (xy 298.305665 -366.167173)
			(xy 298.351515 -366.196639) (xy 298.392706 -366.23233) (xy 298.428397 -366.273521) (xy 298.457863 -366.319371)
			(xy 298.480505 -366.368948) (xy 298.49586 -366.421243) (xy 298.503616 -366.475191) (xy 298.504102 -366.502442)
			(xy 298.503863 -366.521109) (xy 298.50017 -366.55826) (xy 298.496736 -366.57661) (xy 298.494466 -366.590887)
			(xy 298.496978 -366.619669) (xy 298.50746 -366.646591) (xy 298.525071 -366.669494) (xy 298.548398 -366.686539)
			(xy 298.575569 -366.696359) (xy 298.589954 -366.697768) (xy 298.618607 -366.700151) (xy 298.674774 -366.712433)
			(xy 298.728462 -366.733004) (xy 298.778456 -366.761398) (xy 298.823623 -366.796971) (xy 298.862942 -366.83892)
			(xy 298.895521 -366.886292) (xy 298.920622 -366.938017) (xy 298.937679 -366.992923) (xy 298.946304 -367.049767)
			(xy 298.946824 -367.078514) (xy 298.946338 -367.105765) (xy 298.938582 -367.159713) (xy 298.923227 -367.212008)
			(xy 298.900585 -367.261585) (xy 298.871119 -367.307435) (xy 298.835428 -367.348626) (xy 298.794237 -367.384317)
			(xy 298.748387 -367.413783) (xy 298.69881 -367.436425) (xy 298.646515 -367.45178) (xy 298.592567 -367.459536)
			(xy 298.538065 -367.459536) (xy 298.484117 -367.45178) (xy 298.431822 -367.436425) (xy 298.382245 -367.413783)
			(xy 298.336395 -367.384317) (xy 298.295204 -367.348626) (xy 298.259513 -367.307435) (xy 298.230047 -367.261585)
			(xy 298.207405 -367.212008) (xy 298.19205 -367.159713) (xy 298.184294 -367.105765) (xy 298.183808 -367.078514)
			(xy 298.184048 -367.059847) (xy 298.187736 -367.022695) (xy 298.191174 -367.004346) (xy 298.193481 -366.990074)
			(xy 298.190958 -366.96129) (xy 298.180467 -366.934367) (xy 298.16285 -366.911464) (xy 298.139518 -366.894419)
			(xy 298.112343 -366.884598) (xy 298.097956 -366.883188) (xy 298.069302 -366.880827) (xy 298.013138 -366.868534)
			(xy 297.959454 -366.847956) (xy 297.909464 -366.819557) (xy 297.864299 -366.78398) (xy 297.824983 -366.742031)
			(xy 297.792405 -366.694658) (xy 297.767301 -366.642935) (xy 297.750241 -366.588031) (xy 297.74161 -366.531189)
			(xy 297.741086 -366.502442) (xy 296.878416 -366.502442) (xy 296.878756 -366.521492) (xy 296.87822 -366.549937)
			(xy 296.869767 -366.606197) (xy 296.853048 -366.660575) (xy 296.828434 -366.711865) (xy 296.796471 -366.758929)
			(xy 296.75787 -366.80072) (xy 296.736008 -366.818926) (xy 296.724565 -366.8289) (xy 296.707548 -366.854015)
			(xy 296.698646 -366.883016) (xy 296.698641 -366.913352) (xy 296.707534 -366.942356) (xy 296.724543 -366.967475)
			(xy 296.736008 -366.977422) (xy 296.757852 -366.995649) (xy 296.796456 -367.037436) (xy 296.828422 -367.084494)
			(xy 296.853041 -367.13578) (xy 296.869766 -367.190155) (xy 296.87051 -367.1951) (xy 297.13885 -367.1951)
			(xy 297.142921 -367.139478) (xy 297.155047 -367.085041) (xy 297.17497 -367.03295) (xy 297.202266 -366.984315)
			(xy 297.236352 -366.940172) (xy 297.276501 -366.901463) (xy 297.321859 -366.869012) (xy 297.371459 -366.843511)
			(xy 297.424243 -366.825504) (xy 297.479086 -366.815374) (xy 297.53482 -366.813337) (xy 297.590257 -366.819437)
			(xy 297.644214 -366.833543) (xy 297.695543 -366.855355) (xy 297.743149 -366.884409) (xy 297.786017 -366.920084)
			(xy 297.823234 -366.961621) (xy 297.854007 -367.008134) (xy 297.877679 -367.058631) (xy 297.893747 -367.112038)
			(xy 297.901867 -367.167214) (xy 297.902376 -367.1951) (xy 297.901867 -367.222986) (xy 297.893747 -367.278162)
			(xy 297.877679 -367.331569) (xy 297.854007 -367.382066) (xy 297.823234 -367.428579) (xy 297.786017 -367.470116)
			(xy 297.743149 -367.505791) (xy 297.695543 -367.534845) (xy 297.644214 -367.556657) (xy 297.590257 -367.570763)
			(xy 297.53482 -367.576863) (xy 297.479086 -367.574826) (xy 297.424243 -367.564696) (xy 297.371459 -367.546689)
			(xy 297.321859 -367.521188) (xy 297.276501 -367.488737) (xy 297.236352 -367.450028) (xy 297.202266 -367.405885)
			(xy 297.17497 -367.35725) (xy 297.155047 -367.305159) (xy 297.142921 -367.250722) (xy 297.13885 -367.1951)
			(xy 296.87051 -367.1951) (xy 296.878226 -367.246412) (xy 296.878756 -367.274856) (xy 296.87827 -367.302107)
			(xy 296.870514 -367.356055) (xy 296.855159 -367.40835) (xy 296.832517 -367.457927) (xy 296.803051 -367.503777)
			(xy 296.76736 -367.544968) (xy 296.726169 -367.580659) (xy 296.680319 -367.610125) (xy 296.630742 -367.632767)
			(xy 296.578447 -367.648122) (xy 296.524499 -367.655878) (xy 296.469997 -367.655878) (xy 296.416049 -367.648122)
			(xy 296.363754 -367.632767) (xy 296.314177 -367.610125) (xy 296.268327 -367.580659) (xy 296.227136 -367.544968)
			(xy 296.191445 -367.503777) (xy 296.161979 -367.457927) (xy 296.139337 -367.40835) (xy 296.123982 -367.356055)
			(xy 296.116226 -367.302107) (xy 296.11574 -367.274856) (xy 289.203734 -367.274856) (xy 289.182797 -367.307435)
			(xy 289.147106 -367.348626) (xy 289.105915 -367.384317) (xy 289.060065 -367.413783) (xy 289.010488 -367.436425)
			(xy 288.958193 -367.45178) (xy 288.904245 -367.459536) (xy 288.849743 -367.459536) (xy 288.795795 -367.45178)
			(xy 288.7435 -367.436425) (xy 288.693923 -367.413783) (xy 288.648073 -367.384317) (xy 288.606882 -367.348626)
			(xy 288.571191 -367.307435) (xy 288.541725 -367.261585) (xy 288.519083 -367.212008) (xy 288.503728 -367.159713)
			(xy 288.495972 -367.105765) (xy 288.495486 -367.078514) (xy 288.495734 -367.059847) (xy 288.499421 -367.022696)
			(xy 288.502852 -367.004346) (xy 288.505179 -366.990076) (xy 288.502656 -366.961288) (xy 288.492163 -366.934361)
			(xy 288.474541 -366.911457) (xy 288.451204 -366.894413) (xy 288.424024 -366.884595) (xy 288.409634 -366.883188)
			(xy 288.380986 -366.88076) (xy 288.324824 -366.868479) (xy 288.27114 -366.84791) (xy 288.221149 -366.81952)
			(xy 288.175984 -366.783951) (xy 288.136666 -366.742009) (xy 288.104086 -366.694643) (xy 288.078981 -366.642924)
			(xy 288.06192 -366.588025) (xy 288.053288 -366.531187) (xy 288.052764 -366.502442) (xy 287.190094 -366.502442)
			(xy 287.190434 -366.521492) (xy 287.190004 -366.54683) (xy 287.183297 -366.59706) (xy 287.169998 -366.64596)
			(xy 287.150343 -366.692669) (xy 287.124677 -366.736364) (xy 287.093453 -366.776278) (xy 287.075626 -366.794288)
			(xy 287.066284 -366.80409) (xy 287.052572 -366.827425) (xy 287.045463 -366.853539) (xy 287.045456 -366.880604)
			(xy 287.05255 -366.906722) (xy 287.066249 -366.930064) (xy 287.075626 -366.93983) (xy 287.093474 -366.957822)
			(xy 287.124698 -366.997738) (xy 287.150364 -367.041438) (xy 287.170018 -367.08815) (xy 287.183315 -367.137053)
			(xy 287.190021 -367.187287) (xy 287.190314 -367.20526) (xy 287.442908 -367.20526) (xy 287.446979 -367.149638)
			(xy 287.459105 -367.095201) (xy 287.479028 -367.04311) (xy 287.506324 -366.994475) (xy 287.54041 -366.950332)
			(xy 287.580559 -366.911623) (xy 287.625917 -366.879172) (xy 287.675517 -366.853671) (xy 287.728301 -366.835664)
			(xy 287.783144 -366.825534) (xy 287.838878 -366.823497) (xy 287.894315 -366.829597) (xy 287.948272 -366.843703)
			(xy 287.999601 -366.865515) (xy 288.047207 -366.894569) (xy 288.090075 -366.930244) (xy 288.127292 -366.971781)
			(xy 288.158065 -367.018294) (xy 288.181737 -367.068791) (xy 288.197805 -367.122198) (xy 288.205925 -367.177374)
			(xy 288.206434 -367.20526) (xy 288.205925 -367.233146) (xy 288.197805 -367.288322) (xy 288.181737 -367.341729)
			(xy 288.158065 -367.392226) (xy 288.127292 -367.438739) (xy 288.090075 -367.480276) (xy 288.047207 -367.515951)
			(xy 287.999601 -367.545005) (xy 287.948272 -367.566817) (xy 287.894315 -367.580923) (xy 287.838878 -367.587023)
			(xy 287.783144 -367.584986) (xy 287.728301 -367.574856) (xy 287.675517 -367.556849) (xy 287.625917 -367.531348)
			(xy 287.580559 -367.498897) (xy 287.54041 -367.460188) (xy 287.506324 -367.416045) (xy 287.479028 -367.36741)
			(xy 287.459105 -367.315319) (xy 287.446979 -367.260882) (xy 287.442908 -367.20526) (xy 287.190314 -367.20526)
			(xy 287.190434 -367.212626) (xy 287.189948 -367.239877) (xy 287.182192 -367.293825) (xy 287.166837 -367.34612)
			(xy 287.144195 -367.395697) (xy 287.114729 -367.441547) (xy 287.079038 -367.482738) (xy 287.037847 -367.518429)
			(xy 286.991997 -367.547895) (xy 286.94242 -367.570537) (xy 286.890125 -367.585892) (xy 286.836177 -367.593648)
			(xy 286.781675 -367.593648) (xy 286.727727 -367.585892) (xy 286.675432 -367.570537) (xy 286.625855 -367.547895)
			(xy 286.580005 -367.518429) (xy 286.538814 -367.482738) (xy 286.503123 -367.441547) (xy 286.473657 -367.395697)
			(xy 286.451015 -367.34612) (xy 286.43566 -367.293825) (xy 286.427904 -367.239877) (xy 286.427418 -367.212626)
			(xy 282.69946 -367.212626) (xy 282.69946 -371.888258) (xy 283.798279 -372.987077) (xy 286.21657 -372.987077)
			(xy 286.220304 -372.933821) (xy 286.231425 -372.881605) (xy 286.249717 -372.83145) (xy 286.274821 -372.784334)
			(xy 286.306249 -372.741178) (xy 286.343386 -372.702825) (xy 286.364172 -372.686072) (xy 286.376017 -372.676217)
			(xy 286.393536 -372.650882) (xy 286.402709 -372.621478) (xy 286.402702 -372.590676) (xy 286.393516 -372.561275)
			(xy 286.375984 -372.535949) (xy 286.364172 -372.526052) (xy 286.341708 -372.507839) (xy 286.301972 -372.465823)
			(xy 286.269032 -372.418292) (xy 286.243641 -372.366335) (xy 286.22638 -372.311142) (xy 286.217645 -372.253977)
			(xy 286.217106 -372.225062) (xy 286.217607 -372.197693) (xy 286.225416 -372.143515) (xy 286.240897 -372.091013)
			(xy 286.263731 -372.041265) (xy 286.293448 -371.995297) (xy 286.311086 -371.974364) (xy 286.320361 -371.963065)
			(xy 286.332535 -371.936497) (xy 286.336701 -371.907571) (xy 286.332519 -371.878648) (xy 286.320329 -371.852087)
			(xy 286.311086 -371.84076) (xy 286.29341 -371.819857) (xy 286.26369 -371.773883) (xy 286.240849 -371.724131)
			(xy 286.225357 -371.671625) (xy 286.217533 -371.617443) (xy 286.217537 -371.562699) (xy 286.22537 -371.508519)
			(xy 286.240869 -371.456015) (xy 286.263717 -371.406267) (xy 286.293444 -371.360298) (xy 286.311086 -371.339364)
			(xy 286.320361 -371.328065) (xy 286.332535 -371.301497) (xy 286.336701 -371.272571) (xy 286.332519 -371.243648)
			(xy 286.320329 -371.217087) (xy 286.311086 -371.20576) (xy 286.293459 -371.184818) (xy 286.263746 -371.138848)
			(xy 286.240908 -371.089103) (xy 286.225414 -371.036604) (xy 286.217582 -370.98243) (xy 286.217106 -370.955062)
			(xy 286.217543 -370.927809) (xy 286.225305 -370.873859) (xy 286.240665 -370.821562) (xy 286.263312 -370.771984)
			(xy 286.292783 -370.726133) (xy 286.32848 -370.684943) (xy 286.369675 -370.649252) (xy 286.41553 -370.619787)
			(xy 286.465111 -370.597147) (xy 286.51741 -370.581793) (xy 286.571361 -370.574039) (xy 286.598614 -370.573554)
			(xy 286.625985 -370.573999) (xy 286.680166 -370.58182) (xy 286.73267 -370.597313) (xy 286.782416 -370.62016)
			(xy 286.828382 -370.64989) (xy 286.849312 -370.667534) (xy 286.86064 -370.67677) (xy 286.887197 -370.688946)
			(xy 286.916114 -370.693119) (xy 286.945031 -370.688946) (xy 286.971588 -370.67677) (xy 286.982916 -370.667534)
			(xy 287.003873 -370.649926) (xy 287.049839 -370.620208) (xy 287.09958 -370.597366) (xy 287.152075 -370.581868)
			(xy 287.206246 -370.574032) (xy 287.233614 -370.573554) (xy 287.26253 -370.574114) (xy 287.3197 -370.582831)
			(xy 287.374899 -370.60008) (xy 287.426861 -370.625464) (xy 287.474396 -370.658401) (xy 287.516413 -370.698137)
			(xy 287.534604 -370.72062) (xy 287.544501 -370.732425) (xy 287.569825 -370.749944) (xy 287.599218 -370.75912)
			(xy 287.63001 -370.75912) (xy 287.659403 -370.749944) (xy 287.684727 -370.732425) (xy 287.694624 -370.72062)
			(xy 287.712807 -370.698129) (xy 287.754827 -370.658394) (xy 287.802364 -370.625455) (xy 287.854327 -370.600068)
			(xy 287.909526 -370.582813) (xy 287.966697 -370.574087) (xy 287.995614 -370.573554) (xy 288.022864 -370.574065)
			(xy 288.076809 -370.581822) (xy 288.129101 -370.597177) (xy 288.178675 -370.619817) (xy 288.224524 -370.649281)
			(xy 288.265713 -370.68497) (xy 288.301404 -370.726157) (xy 288.330871 -370.772003) (xy 288.353515 -370.821577)
			(xy 288.368873 -370.873868) (xy 288.376634 -370.927812) (xy 288.377122 -370.955062) (xy 288.376653 -370.982432)
			(xy 288.368839 -371.036612) (xy 288.353351 -371.089116) (xy 288.33051 -371.138863) (xy 288.300784 -371.184829)
			(xy 288.283142 -371.20576) (xy 288.273946 -371.217117) (xy 288.261772 -371.243665) (xy 288.257594 -371.272571)
			(xy 288.261755 -371.30148) (xy 288.273915 -371.328035) (xy 288.283142 -371.339364) (xy 288.300747 -371.360326)
			(xy 288.330475 -371.406288) (xy 288.353325 -371.456029) (xy 288.368825 -371.508527) (xy 288.376658 -371.562702)
			(xy 288.376662 -371.617441) (xy 288.368838 -371.671617) (xy 288.353345 -371.724117) (xy 288.330503 -371.773862)
			(xy 288.300781 -371.819828) (xy 288.283142 -371.84076) (xy 288.273946 -371.852117) (xy 288.261772 -371.878665)
			(xy 288.257594 -371.907571) (xy 288.261755 -371.93648) (xy 288.273915 -371.963035) (xy 288.283142 -371.974364)
			(xy 288.300785 -371.995293) (xy 288.330495 -372.041267) (xy 288.353329 -372.091016) (xy 288.36882 -372.143517)
			(xy 288.376648 -372.197693) (xy 288.377122 -372.225062) (xy 288.376606 -372.253979) (xy 288.367881 -372.311152)
			(xy 288.350624 -372.366352) (xy 288.325232 -372.418315) (xy 288.292287 -372.465848) (xy 288.252543 -372.507863)
			(xy 288.230056 -372.526052) (xy 288.218285 -372.535989) (xy 288.200759 -372.561299) (xy 288.191575 -372.590684)
			(xy 288.191568 -372.62147) (xy 288.200738 -372.650858) (xy 288.218252 -372.676177) (xy 288.230056 -372.686072)
			(xy 288.250801 -372.702871) (xy 288.287929 -372.741219) (xy 288.319349 -372.784369) (xy 288.344448 -372.831477)
			(xy 288.362735 -372.881624) (xy 288.373854 -372.93383) (xy 288.375806 -372.961677) (xy 289.58207 -372.961677)
			(xy 289.585804 -372.908421) (xy 289.596925 -372.856205) (xy 289.615217 -372.80605) (xy 289.640321 -372.758934)
			(xy 289.671749 -372.715778) (xy 289.708886 -372.677425) (xy 289.729672 -372.660672) (xy 289.741517 -372.650817)
			(xy 289.759036 -372.625482) (xy 289.768209 -372.596078) (xy 289.768202 -372.565276) (xy 289.759016 -372.535875)
			(xy 289.741484 -372.510549) (xy 289.729672 -372.500652) (xy 289.707208 -372.482439) (xy 289.667472 -372.440423)
			(xy 289.634532 -372.392892) (xy 289.609141 -372.340935) (xy 289.59188 -372.285742) (xy 289.583145 -372.228577)
			(xy 289.582606 -372.199662) (xy 289.583107 -372.172293) (xy 289.590916 -372.118115) (xy 289.606397 -372.065613)
			(xy 289.629231 -372.015865) (xy 289.658948 -371.969897) (xy 289.676586 -371.948964) (xy 289.685861 -371.937665)
			(xy 289.698035 -371.911097) (xy 289.702201 -371.882171) (xy 289.698019 -371.853248) (xy 289.685829 -371.826687)
			(xy 289.676586 -371.81536) (xy 289.65891 -371.794457) (xy 289.62919 -371.748483) (xy 289.606349 -371.698731)
			(xy 289.590857 -371.646225) (xy 289.583033 -371.592043) (xy 289.583037 -371.537299) (xy 289.59087 -371.483119)
			(xy 289.606369 -371.430615) (xy 289.629217 -371.380867) (xy 289.658944 -371.334898) (xy 289.676586 -371.313964)
			(xy 289.685861 -371.302665) (xy 289.698035 -371.276097) (xy 289.702201 -371.247171) (xy 289.698019 -371.218248)
			(xy 289.685829 -371.191687) (xy 289.676586 -371.18036) (xy 289.658959 -371.159418) (xy 289.629246 -371.113448)
			(xy 289.606408 -371.063703) (xy 289.590914 -371.011204) (xy 289.583082 -370.95703) (xy 289.582606 -370.929662)
			(xy 289.583092 -370.902411) (xy 289.590848 -370.848463) (xy 289.606203 -370.796168) (xy 289.628845 -370.746591)
			(xy 289.658311 -370.700741) (xy 289.694002 -370.65955) (xy 289.735193 -370.623859) (xy 289.781043 -370.594393)
			(xy 289.83062 -370.571751) (xy 289.882915 -370.556396) (xy 289.936863 -370.54864) (xy 289.991365 -370.54864)
			(xy 290.045313 -370.556396) (xy 290.097608 -370.571751) (xy 290.147185 -370.594393) (xy 290.193035 -370.623859)
			(xy 290.234226 -370.65955) (xy 290.269917 -370.700741) (xy 290.295262 -370.740178) (xy 291.927026 -370.740178)
			(xy 291.927573 -370.711009) (xy 291.936476 -370.653353) (xy 291.954056 -370.597726) (xy 291.979902 -370.545425)
			(xy 292.013412 -370.497671) (xy 292.053803 -370.455576) (xy 292.076632 -370.43741) (xy 292.086966 -370.428937)
			(xy 292.103261 -370.407771) (xy 292.113508 -370.383104) (xy 292.117008 -370.356623) (xy 292.113521 -370.330141)
			(xy 292.103284 -370.305469) (xy 292.086999 -370.284296) (xy 292.076632 -370.275866) (xy 292.053819 -370.25768)
			(xy 292.013415 -370.215598) (xy 291.979897 -370.16785) (xy 291.954048 -370.115551) (xy 291.936473 -370.059924)
			(xy 291.927582 -370.002267) (xy 291.927026 -369.973098) (xy 291.927454 -369.945844) (xy 291.935212 -369.89189)
			(xy 291.95057 -369.839589) (xy 291.973215 -369.790007) (xy 292.002686 -369.744152) (xy 292.038384 -369.702958)
			(xy 292.079581 -369.667265) (xy 292.125438 -369.637798) (xy 292.175023 -369.615157) (xy 292.227325 -369.599804)
			(xy 292.28128 -369.592051) (xy 292.308534 -369.59159) (xy 292.337451 -369.592122) (xy 292.394623 -369.600843)
			(xy 292.449823 -369.618096) (xy 292.501786 -369.643485) (xy 292.549319 -369.676428) (xy 292.591335 -369.71617)
			(xy 292.609524 -369.738656) (xy 292.619421 -369.750461) (xy 292.644745 -369.76798) (xy 292.674138 -369.777156)
			(xy 292.70493 -369.777156) (xy 292.734323 -369.76798) (xy 292.759647 -369.750461) (xy 292.769544 -369.738656)
			(xy 292.787699 -369.716142) (xy 292.829728 -369.676411) (xy 292.87727 -369.643477) (xy 292.929239 -369.618094)
			(xy 292.984442 -369.600844) (xy 293.041616 -369.592122) (xy 293.070534 -369.59159) (xy 293.099081 -369.59211)
			(xy 293.155536 -369.600633) (xy 293.210091 -369.61747) (xy 293.26153 -369.642244) (xy 293.285418 -369.657884)
			(xy 293.296563 -369.664941) (xy 293.321415 -369.673747) (xy 293.347695 -369.675874) (xy 293.37364 -369.671181)
			(xy 293.39751 -369.659982) (xy 293.417702 -369.643028) (xy 293.425626 -369.632484) (xy 293.441057 -369.611486)
			(xy 293.476652 -369.573431) (xy 293.517093 -369.540572) (xy 293.561628 -369.513519) (xy 293.609429 -369.492776)
			(xy 293.659607 -369.478729) (xy 293.71123 -369.471638) (xy 293.737284 -369.471194) (xy 293.766202 -369.471688)
			(xy 293.823376 -369.480417) (xy 293.878577 -369.497677) (xy 293.93054 -369.523073) (xy 293.978072 -369.556023)
			(xy 294.020086 -369.595771) (xy 294.038274 -369.61826) (xy 294.048171 -369.630065) (xy 294.073495 -369.647584)
			(xy 294.102888 -369.65676) (xy 294.13368 -369.65676) (xy 294.163073 -369.647584) (xy 294.188397 -369.630065)
			(xy 294.198294 -369.61826) (xy 294.216478 -369.595771) (xy 294.258501 -369.556038) (xy 294.306037 -369.523101)
			(xy 294.358 -369.497714) (xy 294.413198 -369.480458) (xy 294.470368 -369.471729) (xy 294.499284 -369.471194)
			(xy 294.526537 -369.47167) (xy 294.580487 -369.479425) (xy 294.632785 -369.494779) (xy 294.682365 -369.51742)
			(xy 294.728218 -369.546886) (xy 294.769411 -369.582579) (xy 294.805105 -369.62377) (xy 294.834573 -369.669623)
			(xy 294.857216 -369.719202) (xy 294.872572 -369.771499) (xy 294.880329 -369.825449) (xy 294.880792 -369.852702)
			(xy 294.880362 -369.878745) (xy 294.873275 -369.930348) (xy 294.859233 -369.980506) (xy 294.838498 -370.028288)
			(xy 294.811455 -370.072804) (xy 294.778606 -370.113227) (xy 294.759888 -370.13134) (xy 294.749997 -370.141348)
			(xy 294.735529 -370.165464) (xy 294.72818 -370.19261) (xy 294.728505 -370.220731) (xy 294.73648 -370.247699)
			(xy 294.7515 -370.271474) (xy 294.761666 -370.2812) (xy 294.781236 -370.299374) (xy 294.815628 -370.340233)
			(xy 294.843987 -370.385488) (xy 294.865756 -370.434257) (xy 294.880511 -370.485585) (xy 294.887963 -370.538469)
			(xy 294.888412 -370.565172) (xy 294.887892 -370.592941) (xy 294.879843 -370.647893) (xy 294.863911 -370.701096)
			(xy 294.840433 -370.751428) (xy 294.809904 -370.797823) (xy 294.772971 -370.8393) (xy 294.752014 -370.857526)
			(xy 294.741396 -370.867082) (xy 294.725411 -370.890736) (xy 294.716616 -370.917896) (xy 294.7157 -370.94643)
			(xy 294.722736 -370.974099) (xy 294.737171 -370.998729) (xy 294.747188 -371.00891) (xy 294.765535 -371.026997)
			(xy 294.797707 -371.067237) (xy 294.824176 -371.111437) (xy 294.844461 -371.158796) (xy 294.858194 -371.208451)
			(xy 294.865127 -371.259502) (xy 294.865552 -371.285262) (xy 294.865075 -371.312632) (xy 294.857262 -371.366811)
			(xy 294.841776 -371.419315) (xy 294.818936 -371.469062) (xy 294.789213 -371.515028) (xy 294.771572 -371.53596)
			(xy 294.762374 -371.547316) (xy 294.750196 -371.573864) (xy 294.746017 -371.602771) (xy 294.750179 -371.631681)
			(xy 294.762343 -371.658236) (xy 294.771572 -371.669564) (xy 294.789176 -371.690527) (xy 294.818902 -371.736489)
			(xy 294.84175 -371.786231) (xy 294.857249 -371.838728) (xy 294.865081 -371.892903) (xy 294.865085 -371.94764)
			(xy 294.857261 -372.001816) (xy 294.84177 -372.054316) (xy 294.81893 -372.10406) (xy 294.78921 -372.150027)
			(xy 294.771572 -372.17096) (xy 294.762374 -372.182316) (xy 294.750196 -372.208864) (xy 294.746017 -372.237771)
			(xy 294.750179 -372.266681) (xy 294.762343 -372.293236) (xy 294.771572 -372.304564) (xy 294.789176 -372.325527)
			(xy 294.818902 -372.371489) (xy 294.84175 -372.421231) (xy 294.857249 -372.473728) (xy 294.860837 -372.49855)
			(xy 295.942254 -372.49855) (xy 295.942254 -372.413854) (xy 295.950305 -372.32954) (xy 295.966334 -372.246374)
			(xy 295.990195 -372.165107) (xy 296.021674 -372.086477) (xy 296.060485 -372.011196) (xy 296.106275 -371.939944)
			(xy 296.158631 -371.873368) (xy 296.217079 -371.81207) (xy 296.281089 -371.756605) (xy 296.350081 -371.707476)
			(xy 296.423431 -371.665127) (xy 296.500474 -371.629943) (xy 296.580513 -371.602241) (xy 296.662822 -371.582273)
			(xy 296.746657 -371.57022) (xy 296.831258 -371.56619) (xy 296.915859 -371.57022) (xy 296.999694 -371.582273)
			(xy 297.082003 -371.602241) (xy 297.162042 -371.629943) (xy 297.239085 -371.665127) (xy 297.312435 -371.707476)
			(xy 297.381427 -371.756605) (xy 297.445437 -371.81207) (xy 297.503885 -371.873368) (xy 297.556241 -371.939944)
			(xy 297.602031 -372.011196) (xy 297.640842 -372.086477) (xy 297.672321 -372.165107) (xy 297.696182 -372.246374)
			(xy 297.712211 -372.32954) (xy 297.720262 -372.413854) (xy 297.720766 -372.456202) (xy 298.466767 -372.456202)
			(xy 298.470803 -372.372755) (xy 298.482875 -372.290087) (xy 298.502868 -372.20897) (xy 298.530597 -372.130161)
			(xy 298.565803 -372.054396) (xy 298.608157 -371.982383) (xy 298.657263 -371.914794) (xy 298.712664 -371.85226)
			(xy 298.773841 -371.795365) (xy 298.840224 -371.744639) (xy 298.911192 -371.700558) (xy 298.986084 -371.663532)
			(xy 299.0642 -371.633906) (xy 299.14481 -371.611958) (xy 299.227162 -371.597893) (xy 299.310488 -371.591841)
			(xy 299.394008 -371.59386) (xy 299.476944 -371.60393) (xy 299.55852 -371.621958) (xy 299.637976 -371.647775)
			(xy 299.714569 -371.68114) (xy 299.787585 -371.721741) (xy 299.856341 -371.7692) (xy 299.920195 -371.823073)
			(xy 299.978552 -371.882858) (xy 300.030867 -371.947995) (xy 300.07665 -372.017878) (xy 300.115475 -372.091853)
			(xy 300.14698 -372.16923) (xy 300.170869 -372.249287) (xy 300.18692 -372.331275) (xy 300.194983 -372.41443)
			(xy 300.195488 -372.456202) (xy 300.194983 -372.497974) (xy 300.18692 -372.581129) (xy 300.170869 -372.663117)
			(xy 300.14698 -372.743174) (xy 300.115475 -372.820551) (xy 300.07665 -372.894526) (xy 300.030867 -372.964409)
			(xy 299.978552 -373.029546) (xy 299.920195 -373.089331) (xy 299.856341 -373.143204) (xy 299.787585 -373.190663)
			(xy 299.714569 -373.231264) (xy 299.637976 -373.264629) (xy 299.55852 -373.290446) (xy 299.476944 -373.308474)
			(xy 299.394008 -373.318544) (xy 299.310488 -373.320563) (xy 299.227162 -373.314511) (xy 299.14481 -373.300446)
			(xy 299.0642 -373.278498) (xy 298.986084 -373.248872) (xy 298.911192 -373.211846) (xy 298.840224 -373.167765)
			(xy 298.773841 -373.117039) (xy 298.712664 -373.060144) (xy 298.657263 -372.99761) (xy 298.608157 -372.930021)
			(xy 298.565803 -372.858008) (xy 298.530597 -372.782243) (xy 298.502868 -372.703434) (xy 298.482875 -372.622317)
			(xy 298.470803 -372.539649) (xy 298.466767 -372.456202) (xy 297.720766 -372.456202) (xy 297.720262 -372.49855)
			(xy 297.712211 -372.582864) (xy 297.696182 -372.66603) (xy 297.672321 -372.747297) (xy 297.640842 -372.825927)
			(xy 297.602031 -372.901208) (xy 297.556241 -372.97246) (xy 297.503885 -373.039036) (xy 297.445437 -373.100334)
			(xy 297.381427 -373.155799) (xy 297.312435 -373.204928) (xy 297.239085 -373.247277) (xy 297.162042 -373.282461)
			(xy 297.082003 -373.310163) (xy 296.999694 -373.330131) (xy 296.915859 -373.342184) (xy 296.831258 -373.346215)
			(xy 296.746657 -373.342184) (xy 296.662822 -373.330131) (xy 296.580513 -373.310163) (xy 296.500474 -373.282461)
			(xy 296.423431 -373.247277) (xy 296.350081 -373.204928) (xy 296.281089 -373.155799) (xy 296.217079 -373.100334)
			(xy 296.158631 -373.039036) (xy 296.106275 -372.97246) (xy 296.060485 -372.901208) (xy 296.021674 -372.825927)
			(xy 295.990195 -372.747297) (xy 295.966334 -372.66603) (xy 295.950305 -372.582864) (xy 295.942254 -372.49855)
			(xy 294.860837 -372.49855) (xy 294.865081 -372.527903) (xy 294.865085 -372.58264) (xy 294.857261 -372.636816)
			(xy 294.84177 -372.689316) (xy 294.81893 -372.73906) (xy 294.78921 -372.785027) (xy 294.771572 -372.80596)
			(xy 294.762374 -372.817316) (xy 294.750196 -372.843864) (xy 294.746017 -372.872771) (xy 294.750179 -372.901681)
			(xy 294.762343 -372.928236) (xy 294.771572 -372.939564) (xy 294.789203 -372.960502) (xy 294.818917 -373.006473)
			(xy 294.841755 -373.056219) (xy 294.857248 -373.108718) (xy 294.865077 -373.162893) (xy 294.865552 -373.190262)
			(xy 294.864987 -373.21751) (xy 294.857236 -373.271453) (xy 294.841888 -373.323743) (xy 294.819255 -373.373317)
			(xy 294.789797 -373.419166) (xy 294.754113 -373.460355) (xy 294.712932 -373.496047) (xy 294.667089 -373.525515)
			(xy 294.61752 -373.54816) (xy 294.565233 -373.563519) (xy 294.511292 -373.571281) (xy 294.484044 -373.57177)
			(xy 294.455128 -373.571232) (xy 294.397957 -373.562508) (xy 294.342758 -373.545255) (xy 294.290796 -373.519867)
			(xy 294.243262 -373.486927) (xy 294.201244 -373.447188) (xy 294.183054 -373.424704) (xy 294.173157 -373.412899)
			(xy 294.147833 -373.39538) (xy 294.11844 -373.386204) (xy 294.087648 -373.386204) (xy 294.058255 -373.39538)
			(xy 294.032931 -373.412899) (xy 294.023034 -373.424704) (xy 294.004825 -373.447172) (xy 293.962809 -373.486908)
			(xy 293.915278 -373.519849) (xy 293.86332 -373.54524) (xy 293.808126 -373.562499) (xy 293.750959 -373.571233)
			(xy 293.722044 -373.57177) (xy 293.694791 -373.571304) (xy 293.640838 -373.563552) (xy 293.588538 -373.548199)
			(xy 293.538955 -373.525559) (xy 293.4931 -373.496092) (xy 293.451906 -373.460399) (xy 293.416211 -373.419205)
			(xy 293.386744 -373.37335) (xy 293.364103 -373.323768) (xy 293.34875 -373.271468) (xy 293.340997 -373.217515)
			(xy 293.340536 -373.190262) (xy 293.34103 -373.162893) (xy 293.348839 -373.108714) (xy 293.364322 -373.056211)
			(xy 293.387157 -373.006464) (xy 293.416877 -372.960496) (xy 293.434516 -372.939564) (xy 293.443788 -372.928264)
			(xy 293.455959 -372.901696) (xy 293.460124 -372.872771) (xy 293.455943 -372.843849) (xy 293.443757 -372.817288)
			(xy 293.434516 -372.80596) (xy 293.416839 -372.785057) (xy 293.387116 -372.739084) (xy 293.364274 -372.689333)
			(xy 293.348781 -372.636826) (xy 293.340956 -372.582644) (xy 293.34096 -372.527899) (xy 293.348793 -372.473718)
			(xy 293.364294 -372.421214) (xy 293.387144 -372.371466) (xy 293.416873 -372.325497) (xy 293.434516 -372.304564)
			(xy 293.443788 -372.293264) (xy 293.455959 -372.266696) (xy 293.460124 -372.237771) (xy 293.455943 -372.208849)
			(xy 293.443757 -372.182288) (xy 293.434516 -372.17096) (xy 293.416839 -372.150057) (xy 293.387116 -372.104084)
			(xy 293.364274 -372.054333) (xy 293.348781 -372.001826) (xy 293.340956 -371.947644) (xy 293.34096 -371.892899)
			(xy 293.348793 -371.838718) (xy 293.364294 -371.786214) (xy 293.387144 -371.736466) (xy 293.416873 -371.690497)
			(xy 293.434516 -371.669564) (xy 293.443788 -371.658264) (xy 293.455959 -371.631696) (xy 293.460124 -371.602771)
			(xy 293.455943 -371.573849) (xy 293.443757 -371.547288) (xy 293.434516 -371.53596) (xy 293.416894 -371.515014)
			(xy 293.387179 -371.469045) (xy 293.36434 -371.419301) (xy 293.348845 -371.366804) (xy 293.341012 -371.31263)
			(xy 293.340536 -371.285262) (xy 293.340768 -371.266207) (xy 293.344587 -371.228289) (xy 293.348156 -371.20957)
			(xy 293.3505 -371.196098) (xy 293.348653 -371.168823) (xy 293.339636 -371.143015) (xy 293.324096 -371.120524)
			(xy 293.303147 -371.102961) (xy 293.278289 -371.091584) (xy 293.251304 -371.087209) (xy 293.224125 -371.09015)
			(xy 293.21125 -371.094762) (xy 293.188788 -371.103308) (xy 293.142245 -371.11529) (xy 293.094564 -371.121325)
			(xy 293.070534 -371.121686) (xy 293.041618 -371.121149) (xy 292.984447 -371.112424) (xy 292.929249 -371.09517)
			(xy 292.877287 -371.069782) (xy 292.829752 -371.036842) (xy 292.787735 -370.997104) (xy 292.769544 -370.97462)
			(xy 292.759647 -370.962815) (xy 292.734323 -370.945296) (xy 292.70493 -370.93612) (xy 292.674138 -370.93612)
			(xy 292.644745 -370.945296) (xy 292.619421 -370.962815) (xy 292.609524 -370.97462) (xy 292.591324 -370.997096)
			(xy 292.549306 -371.036831) (xy 292.501773 -371.06977) (xy 292.449813 -371.09516) (xy 292.394617 -371.112418)
			(xy 292.337449 -371.121149) (xy 292.308534 -371.121686) (xy 292.281281 -371.121213) (xy 292.227329 -371.11346)
			(xy 292.17503 -371.098107) (xy 292.125449 -371.075467) (xy 292.079594 -371.046001) (xy 292.038401 -371.010308)
			(xy 292.002707 -370.969115) (xy 291.973239 -370.923262) (xy 291.950597 -370.873681) (xy 291.935242 -370.821382)
			(xy 291.927488 -370.767431) (xy 291.927026 -370.740178) (xy 290.295262 -370.740178) (xy 290.299383 -370.746591)
			(xy 290.322025 -370.796168) (xy 290.33738 -370.848463) (xy 290.345136 -370.902411) (xy 290.345622 -370.929662)
			(xy 290.345153 -370.957032) (xy 290.337339 -371.011212) (xy 290.321851 -371.063716) (xy 290.29901 -371.113463)
			(xy 290.269284 -371.159429) (xy 290.251642 -371.18036) (xy 290.242446 -371.191717) (xy 290.230272 -371.218265)
			(xy 290.226094 -371.247171) (xy 290.230255 -371.27608) (xy 290.242415 -371.302635) (xy 290.251642 -371.313964)
			(xy 290.269247 -371.334926) (xy 290.298975 -371.380888) (xy 290.321825 -371.430629) (xy 290.337325 -371.483127)
			(xy 290.345158 -371.537302) (xy 290.345162 -371.592041) (xy 290.337338 -371.646217) (xy 290.321845 -371.698717)
			(xy 290.299003 -371.748462) (xy 290.269281 -371.794428) (xy 290.251642 -371.81536) (xy 290.242446 -371.826717)
			(xy 290.230272 -371.853265) (xy 290.226094 -371.882171) (xy 290.230255 -371.91108) (xy 290.242415 -371.937635)
			(xy 290.251642 -371.948964) (xy 290.269285 -371.969893) (xy 290.298995 -372.015867) (xy 290.321829 -372.065616)
			(xy 290.33732 -372.118117) (xy 290.345148 -372.172293) (xy 290.345622 -372.199662) (xy 290.345106 -372.228579)
			(xy 290.336381 -372.285752) (xy 290.319124 -372.340952) (xy 290.293732 -372.392915) (xy 290.260787 -372.440448)
			(xy 290.221043 -372.482463) (xy 290.198556 -372.500652) (xy 290.186785 -372.510589) (xy 290.169259 -372.535899)
			(xy 290.160075 -372.565284) (xy 290.160068 -372.59607) (xy 290.169238 -372.625458) (xy 290.186752 -372.650777)
			(xy 290.198556 -372.660672) (xy 290.219301 -372.677471) (xy 290.256429 -372.715819) (xy 290.287849 -372.758969)
			(xy 290.312948 -372.806077) (xy 290.331235 -372.856224) (xy 290.342354 -372.90843) (xy 290.346086 -372.961677)
			(xy 290.34236 -373.014924) (xy 290.331248 -373.067131) (xy 290.312967 -373.11728) (xy 290.287874 -373.164392)
			(xy 290.256459 -373.207545) (xy 290.219335 -373.245898) (xy 290.198556 -373.262652) (xy 290.186785 -373.272589)
			(xy 290.169259 -373.297899) (xy 290.160075 -373.327284) (xy 290.160068 -373.35807) (xy 290.169238 -373.387458)
			(xy 290.186752 -373.412777) (xy 290.198556 -373.422672) (xy 290.221017 -373.44089) (xy 290.260756 -373.482903)
			(xy 290.293698 -373.530432) (xy 290.319091 -373.582388) (xy 290.336352 -373.637581) (xy 290.345085 -373.694747)
			(xy 290.345622 -373.723662) (xy 290.345136 -373.750913) (xy 290.33738 -373.804861) (xy 290.322025 -373.857156)
			(xy 290.299383 -373.906733) (xy 290.269917 -373.952583) (xy 290.234226 -373.993774) (xy 290.193035 -374.029465)
			(xy 290.147185 -374.058931) (xy 290.097608 -374.081573) (xy 290.045313 -374.096928) (xy 289.991365 -374.104684)
			(xy 289.936863 -374.104684) (xy 289.882915 -374.096928) (xy 289.83062 -374.081573) (xy 289.781043 -374.058931)
			(xy 289.735193 -374.029465) (xy 289.694002 -373.993774) (xy 289.658311 -373.952583) (xy 289.628845 -373.906733)
			(xy 289.606203 -373.857156) (xy 289.590848 -373.804861) (xy 289.583092 -373.750913) (xy 289.582606 -373.723662)
			(xy 289.583167 -373.694747) (xy 289.591886 -373.637577) (xy 289.609136 -373.582379) (xy 289.63452 -373.530417)
			(xy 289.667456 -373.482882) (xy 289.70719 -373.440863) (xy 289.729672 -373.422672) (xy 289.741517 -373.412817)
			(xy 289.759036 -373.387482) (xy 289.768209 -373.358078) (xy 289.768202 -373.327276) (xy 289.759016 -373.297875)
			(xy 289.741484 -373.272549) (xy 289.729672 -373.262652) (xy 289.708851 -373.245944) (xy 289.671719 -373.207586)
			(xy 289.640296 -373.164426) (xy 289.615197 -373.117307) (xy 289.596912 -373.06715) (xy 289.585797 -373.014933)
			(xy 289.58207 -372.961677) (xy 288.375806 -372.961677) (xy 288.377586 -372.987077) (xy 288.37386 -373.040324)
			(xy 288.362748 -373.092531) (xy 288.344467 -373.14268) (xy 288.319374 -373.189792) (xy 288.287959 -373.232945)
			(xy 288.250835 -373.271298) (xy 288.230056 -373.288052) (xy 288.218285 -373.297989) (xy 288.200759 -373.323299)
			(xy 288.191575 -373.352684) (xy 288.191568 -373.38347) (xy 288.200738 -373.412858) (xy 288.218252 -373.438177)
			(xy 288.230056 -373.448072) (xy 288.252517 -373.46629) (xy 288.292256 -373.508303) (xy 288.325198 -373.555832)
			(xy 288.350591 -373.607788) (xy 288.367852 -373.662981) (xy 288.376585 -373.720147) (xy 288.377122 -373.749062)
			(xy 288.376609 -373.776313) (xy 288.368858 -373.830262) (xy 288.353507 -373.882558) (xy 288.33087 -373.932137)
			(xy 288.301408 -373.977989) (xy 288.265719 -374.019182) (xy 288.224531 -374.054876) (xy 288.178683 -374.084345)
			(xy 288.129107 -374.106989) (xy 288.076813 -374.122347) (xy 288.022865 -374.130106) (xy 287.995614 -374.13057)
			(xy 287.966697 -374.130053) (xy 287.909525 -374.121325) (xy 287.854326 -374.104068) (xy 287.802364 -374.078676)
			(xy 287.75483 -374.045732) (xy 287.712814 -374.00599) (xy 287.694624 -373.983504) (xy 287.684727 -373.971699)
			(xy 287.659403 -373.95418) (xy 287.63001 -373.945004) (xy 287.599218 -373.945004) (xy 287.569825 -373.95418)
			(xy 287.544501 -373.971699) (xy 287.534604 -373.983504) (xy 287.516412 -374.005986) (xy 287.474392 -374.045721)
			(xy 287.426857 -374.07866) (xy 287.374896 -374.104049) (xy 287.319699 -374.121306) (xy 287.26253 -374.130035)
			(xy 287.233614 -374.13057) (xy 287.206244 -374.130103) (xy 287.152064 -374.122287) (xy 287.099561 -374.106798)
			(xy 287.049814 -374.083956) (xy 287.003847 -374.054232) (xy 286.982916 -374.03659) (xy 286.971588 -374.027354)
			(xy 286.945031 -374.015178) (xy 286.916114 -374.011005) (xy 286.887197 -374.015178) (xy 286.86064 -374.027354)
			(xy 286.849312 -374.03659) (xy 286.828385 -374.054235) (xy 286.782411 -374.083947) (xy 286.732662 -374.106782)
			(xy 286.68016 -374.122271) (xy 286.625984 -374.130097) (xy 286.598614 -374.13057) (xy 286.57136 -374.130132)
			(xy 286.517406 -374.122375) (xy 286.465105 -374.107019) (xy 286.415523 -374.084376) (xy 286.369668 -374.054906)
			(xy 286.328474 -374.019209) (xy 286.29278 -373.978013) (xy 286.263313 -373.932156) (xy 286.240672 -373.882572)
			(xy 286.225319 -373.830271) (xy 286.217567 -373.776316) (xy 286.217106 -373.749062) (xy 286.217667 -373.720147)
			(xy 286.226386 -373.662977) (xy 286.243636 -373.607779) (xy 286.26902 -373.555817) (xy 286.301956 -373.508282)
			(xy 286.34169 -373.466263) (xy 286.364172 -373.448072) (xy 286.376017 -373.438217) (xy 286.393536 -373.412882)
			(xy 286.402709 -373.383478) (xy 286.402702 -373.352676) (xy 286.393516 -373.323275) (xy 286.375984 -373.297949)
			(xy 286.364172 -373.288052) (xy 286.343351 -373.271344) (xy 286.306219 -373.232986) (xy 286.274796 -373.189826)
			(xy 286.249697 -373.142707) (xy 286.231412 -373.09255) (xy 286.220297 -373.040333) (xy 286.21657 -372.987077)
			(xy 283.798279 -372.987077) (xy 287.743138 -376.931936) (xy 301.8028 -376.931936)
		)
		(stroke
			(width 0)
			(type solid)
		)
		(fill yes)
		(layer "In15.Cu")
		(net "GND")
	)
	(gr_poly
		(pts
			(xy 432.010058 -371.46103) (xy 432.010058 -342.995504) (xy 430.347882 -341.333328) (xy 413.31007 -341.333328)
			(xy 410.590054 -344.053344) (xy 414.212782 -344.053344) (xy 414.212782 -343.968648) (xy 414.220833 -343.884334)
			(xy 414.236862 -343.801168) (xy 414.260723 -343.719901) (xy 414.292202 -343.641271) (xy 414.331013 -343.56599)
			(xy 414.376803 -343.494738) (xy 414.429159 -343.428162) (xy 414.487607 -343.366864) (xy 414.551617 -343.311399)
			(xy 414.620609 -343.26227) (xy 414.693959 -343.219921) (xy 414.771002 -343.184737) (xy 414.851041 -343.157035)
			(xy 414.93335 -343.137067) (xy 415.017185 -343.125014) (xy 415.101786 -343.120984) (xy 415.186387 -343.125014)
			(xy 415.270222 -343.137067) (xy 415.352531 -343.157035) (xy 415.43257 -343.184737) (xy 415.509613 -343.219921)
			(xy 415.582963 -343.26227) (xy 415.651955 -343.311399) (xy 415.715965 -343.366864) (xy 415.774413 -343.428162)
			(xy 415.826769 -343.494738) (xy 415.872559 -343.56599) (xy 415.91137 -343.641271) (xy 415.942849 -343.719901)
			(xy 415.96671 -343.801168) (xy 415.982739 -343.884334) (xy 415.99079 -343.968648) (xy 415.991294 -344.010996)
			(xy 415.99079 -344.053344) (xy 415.990184 -344.059694) (xy 420.403524 -344.059694) (xy 420.403524 -343.974998)
			(xy 420.411575 -343.890684) (xy 420.427604 -343.807518) (xy 420.451465 -343.726251) (xy 420.482944 -343.647621)
			(xy 420.521755 -343.57234) (xy 420.567545 -343.501088) (xy 420.619901 -343.434512) (xy 420.678349 -343.373214)
			(xy 420.742359 -343.317749) (xy 420.811351 -343.26862) (xy 420.884701 -343.226271) (xy 420.961744 -343.191087)
			(xy 421.041783 -343.163385) (xy 421.124092 -343.143417) (xy 421.207927 -343.131364) (xy 421.292528 -343.127334)
			(xy 421.377129 -343.131364) (xy 421.460964 -343.143417) (xy 421.543273 -343.163385) (xy 421.623312 -343.191087)
			(xy 421.700355 -343.226271) (xy 421.773705 -343.26862) (xy 421.842697 -343.317749) (xy 421.906707 -343.373214)
			(xy 421.965155 -343.434512) (xy 422.017511 -343.501088) (xy 422.063301 -343.57234) (xy 422.102112 -343.647621)
			(xy 422.133591 -343.726251) (xy 422.157452 -343.807518) (xy 422.173481 -343.890684) (xy 422.181532 -343.974998)
			(xy 422.182036 -344.017346) (xy 422.181532 -344.059694) (xy 426.601124 -344.059694) (xy 426.601124 -343.974998)
			(xy 426.609175 -343.890684) (xy 426.625204 -343.807518) (xy 426.649065 -343.726251) (xy 426.680544 -343.647621)
			(xy 426.719355 -343.57234) (xy 426.765145 -343.501088) (xy 426.817501 -343.434512) (xy 426.875949 -343.373214)
			(xy 426.939959 -343.317749) (xy 427.008951 -343.26862) (xy 427.082301 -343.226271) (xy 427.159344 -343.191087)
			(xy 427.239383 -343.163385) (xy 427.321692 -343.143417) (xy 427.405527 -343.131364) (xy 427.490128 -343.127334)
			(xy 427.574729 -343.131364) (xy 427.658564 -343.143417) (xy 427.740873 -343.163385) (xy 427.820912 -343.191087)
			(xy 427.897955 -343.226271) (xy 427.971305 -343.26862) (xy 428.040297 -343.317749) (xy 428.104307 -343.373214)
			(xy 428.162755 -343.434512) (xy 428.215111 -343.501088) (xy 428.260901 -343.57234) (xy 428.299712 -343.647621)
			(xy 428.331191 -343.726251) (xy 428.355052 -343.807518) (xy 428.371081 -343.890684) (xy 428.379132 -343.974998)
			(xy 428.379636 -344.017346) (xy 428.379132 -344.059694) (xy 428.371081 -344.144008) (xy 428.355052 -344.227174)
			(xy 428.331191 -344.308441) (xy 428.299712 -344.387071) (xy 428.260901 -344.462352) (xy 428.215111 -344.533604)
			(xy 428.162755 -344.60018) (xy 428.104307 -344.661478) (xy 428.040297 -344.716943) (xy 427.971305 -344.766072)
			(xy 427.897955 -344.808421) (xy 427.820912 -344.843605) (xy 427.740873 -344.871307) (xy 427.658564 -344.891275)
			(xy 427.574729 -344.903328) (xy 427.490128 -344.907359) (xy 427.405527 -344.903328) (xy 427.321692 -344.891275)
			(xy 427.239383 -344.871307) (xy 427.159344 -344.843605) (xy 427.082301 -344.808421) (xy 427.008951 -344.766072)
			(xy 426.939959 -344.716943) (xy 426.875949 -344.661478) (xy 426.817501 -344.60018) (xy 426.765145 -344.533604)
			(xy 426.719355 -344.462352) (xy 426.680544 -344.387071) (xy 426.649065 -344.308441) (xy 426.625204 -344.227174)
			(xy 426.609175 -344.144008) (xy 426.601124 -344.059694) (xy 422.181532 -344.059694) (xy 422.173481 -344.144008)
			(xy 422.157452 -344.227174) (xy 422.133591 -344.308441) (xy 422.102112 -344.387071) (xy 422.063301 -344.462352)
			(xy 422.017511 -344.533604) (xy 421.965155 -344.60018) (xy 421.906707 -344.661478) (xy 421.842697 -344.716943)
			(xy 421.773705 -344.766072) (xy 421.700355 -344.808421) (xy 421.623312 -344.843605) (xy 421.543273 -344.871307)
			(xy 421.460964 -344.891275) (xy 421.377129 -344.903328) (xy 421.292528 -344.907359) (xy 421.207927 -344.903328)
			(xy 421.124092 -344.891275) (xy 421.041783 -344.871307) (xy 420.961744 -344.843605) (xy 420.884701 -344.808421)
			(xy 420.811351 -344.766072) (xy 420.742359 -344.716943) (xy 420.678349 -344.661478) (xy 420.619901 -344.60018)
			(xy 420.567545 -344.533604) (xy 420.521755 -344.462352) (xy 420.482944 -344.387071) (xy 420.451465 -344.308441)
			(xy 420.427604 -344.227174) (xy 420.411575 -344.144008) (xy 420.403524 -344.059694) (xy 415.990184 -344.059694)
			(xy 415.982739 -344.137658) (xy 415.96671 -344.220824) (xy 415.942849 -344.302091) (xy 415.91137 -344.380721)
			(xy 415.872559 -344.456002) (xy 415.826769 -344.527254) (xy 415.774413 -344.59383) (xy 415.715965 -344.655128)
			(xy 415.651955 -344.710593) (xy 415.582963 -344.759722) (xy 415.509613 -344.802071) (xy 415.43257 -344.837255)
			(xy 415.352531 -344.864957) (xy 415.270222 -344.884925) (xy 415.186387 -344.896978) (xy 415.101786 -344.901009)
			(xy 415.017185 -344.896978) (xy 414.93335 -344.884925) (xy 414.851041 -344.864957) (xy 414.771002 -344.837255)
			(xy 414.693959 -344.802071) (xy 414.620609 -344.759722) (xy 414.551617 -344.710593) (xy 414.487607 -344.655128)
			(xy 414.429159 -344.59383) (xy 414.376803 -344.527254) (xy 414.331013 -344.456002) (xy 414.292202 -344.380721)
			(xy 414.260723 -344.302091) (xy 414.236862 -344.220824) (xy 414.220833 -344.137658) (xy 414.212782 -344.053344)
			(xy 410.590054 -344.053344) (xy 409.29306 -345.350338) (xy 409.29306 -346.010992) (xy 414.186375 -346.010992)
			(xy 414.190397 -345.925272) (xy 414.202428 -345.840304) (xy 414.222364 -345.756837) (xy 414.250027 -345.675603)
			(xy 414.285176 -345.597317) (xy 414.327502 -345.522666) (xy 414.376631 -345.452307) (xy 414.432134 -345.386857)
			(xy 414.493521 -345.326893) (xy 414.560254 -345.27294) (xy 414.631746 -345.225473) (xy 414.707368 -345.184909)
			(xy 414.786457 -345.151605) (xy 414.868317 -345.125853) (xy 414.952228 -345.10788) (xy 415.037454 -345.097844)
			(xy 415.123246 -345.095832) (xy 415.208848 -345.101863) (xy 415.29351 -345.115883) (xy 415.376487 -345.137769)
			(xy 415.45705 -345.16733) (xy 415.53449 -345.204304) (xy 415.608129 -345.248368) (xy 415.677317 -345.299134)
			(xy 415.741448 -345.356155) (xy 415.799957 -345.418931) (xy 415.85233 -345.486911) (xy 415.898108 -345.559496)
			(xy 415.936888 -345.636048) (xy 415.968329 -345.715896) (xy 415.992155 -345.798337) (xy 416.008156 -345.882647)
			(xy 416.016191 -345.968085) (xy 416.016694 -346.010992) (xy 416.01662 -346.017342) (xy 420.377117 -346.017342)
			(xy 420.381139 -345.931622) (xy 420.39317 -345.846654) (xy 420.413106 -345.763187) (xy 420.440769 -345.681953)
			(xy 420.475918 -345.603667) (xy 420.518244 -345.529016) (xy 420.567373 -345.458657) (xy 420.622876 -345.393207)
			(xy 420.684263 -345.333243) (xy 420.750996 -345.27929) (xy 420.822488 -345.231823) (xy 420.89811 -345.191259)
			(xy 420.977199 -345.157955) (xy 421.059059 -345.132203) (xy 421.14297 -345.11423) (xy 421.228196 -345.104194)
			(xy 421.313988 -345.102182) (xy 421.39959 -345.108213) (xy 421.484252 -345.122233) (xy 421.567229 -345.144119)
			(xy 421.647792 -345.17368) (xy 421.725232 -345.210654) (xy 421.798871 -345.254718) (xy 421.868059 -345.305484)
			(xy 421.93219 -345.362505) (xy 421.990699 -345.425281) (xy 422.043072 -345.493261) (xy 422.08885 -345.565846)
			(xy 422.12763 -345.642398) (xy 422.159071 -345.722246) (xy 422.182897 -345.804687) (xy 422.198898 -345.888997)
			(xy 422.206933 -345.974435) (xy 422.207436 -346.017342) (xy 426.574717 -346.017342) (xy 426.578739 -345.931622)
			(xy 426.59077 -345.846654) (xy 426.610706 -345.763187) (xy 426.638369 -345.681953) (xy 426.673518 -345.603667)
			(xy 426.715844 -345.529016) (xy 426.764973 -345.458657) (xy 426.820476 -345.393207) (xy 426.881863 -345.333243)
			(xy 426.948596 -345.27929) (xy 427.020088 -345.231823) (xy 427.09571 -345.191259) (xy 427.174799 -345.157955)
			(xy 427.256659 -345.132203) (xy 427.34057 -345.11423) (xy 427.425796 -345.104194) (xy 427.511588 -345.102182)
			(xy 427.59719 -345.108213) (xy 427.681852 -345.122233) (xy 427.764829 -345.144119) (xy 427.845392 -345.17368)
			(xy 427.922832 -345.210654) (xy 427.996471 -345.254718) (xy 428.065659 -345.305484) (xy 428.12979 -345.362505)
			(xy 428.188299 -345.425281) (xy 428.240672 -345.493261) (xy 428.28645 -345.565846) (xy 428.32523 -345.642398)
			(xy 428.356671 -345.722246) (xy 428.380497 -345.804687) (xy 428.396498 -345.888997) (xy 428.404533 -345.974435)
			(xy 428.405036 -346.017342) (xy 428.404533 -346.060249) (xy 428.396498 -346.145687) (xy 428.380497 -346.229997)
			(xy 428.356671 -346.312438) (xy 428.32523 -346.392286) (xy 428.28645 -346.468838) (xy 428.240672 -346.541423)
			(xy 428.188299 -346.609403) (xy 428.12979 -346.672179) (xy 428.065659 -346.7292) (xy 427.996471 -346.779966)
			(xy 427.922832 -346.82403) (xy 427.845392 -346.861004) (xy 427.764829 -346.890565) (xy 427.681852 -346.912451)
			(xy 427.59719 -346.926471) (xy 427.511588 -346.932502) (xy 427.425796 -346.93049) (xy 427.34057 -346.920454)
			(xy 427.256659 -346.902481) (xy 427.174799 -346.876729) (xy 427.09571 -346.843425) (xy 427.020088 -346.802861)
			(xy 426.948596 -346.755394) (xy 426.881863 -346.701441) (xy 426.820476 -346.641477) (xy 426.764973 -346.576027)
			(xy 426.715844 -346.505668) (xy 426.673518 -346.431017) (xy 426.638369 -346.352731) (xy 426.610706 -346.271497)
			(xy 426.59077 -346.18803) (xy 426.578739 -346.103062) (xy 426.574717 -346.017342) (xy 422.207436 -346.017342)
			(xy 422.206933 -346.060249) (xy 422.198898 -346.145687) (xy 422.182897 -346.229997) (xy 422.159071 -346.312438)
			(xy 422.12763 -346.392286) (xy 422.08885 -346.468838) (xy 422.043072 -346.541423) (xy 421.990699 -346.609403)
			(xy 421.93219 -346.672179) (xy 421.868059 -346.7292) (xy 421.798871 -346.779966) (xy 421.725232 -346.82403)
			(xy 421.647792 -346.861004) (xy 421.567229 -346.890565) (xy 421.484252 -346.912451) (xy 421.39959 -346.926471)
			(xy 421.313988 -346.932502) (xy 421.228196 -346.93049) (xy 421.14297 -346.920454) (xy 421.059059 -346.902481)
			(xy 420.977199 -346.876729) (xy 420.89811 -346.843425) (xy 420.822488 -346.802861) (xy 420.750996 -346.755394)
			(xy 420.684263 -346.701441) (xy 420.622876 -346.641477) (xy 420.567373 -346.576027) (xy 420.518244 -346.505668)
			(xy 420.475918 -346.431017) (xy 420.440769 -346.352731) (xy 420.413106 -346.271497) (xy 420.39317 -346.18803)
			(xy 420.381139 -346.103062) (xy 420.377117 -346.017342) (xy 416.01662 -346.017342) (xy 416.016191 -346.053899)
			(xy 416.008156 -346.139337) (xy 415.992155 -346.223647) (xy 415.968329 -346.306088) (xy 415.936888 -346.385936)
			(xy 415.898108 -346.462488) (xy 415.85233 -346.535073) (xy 415.799957 -346.603053) (xy 415.741448 -346.665829)
			(xy 415.677317 -346.72285) (xy 415.608129 -346.773616) (xy 415.53449 -346.81768) (xy 415.45705 -346.854654)
			(xy 415.376487 -346.884215) (xy 415.29351 -346.906101) (xy 415.208848 -346.920121) (xy 415.123246 -346.926152)
			(xy 415.037454 -346.92414) (xy 414.952228 -346.914104) (xy 414.868317 -346.896131) (xy 414.786457 -346.870379)
			(xy 414.707368 -346.837075) (xy 414.631746 -346.796511) (xy 414.560254 -346.749044) (xy 414.493521 -346.695091)
			(xy 414.432134 -346.635127) (xy 414.376631 -346.569677) (xy 414.327502 -346.499318) (xy 414.285176 -346.424667)
			(xy 414.250027 -346.346381) (xy 414.222364 -346.265147) (xy 414.202428 -346.18168) (xy 414.190397 -346.096712)
			(xy 414.186375 -346.010992) (xy 409.29306 -346.010992) (xy 409.29306 -359.217468) (xy 409.293529 -359.232055)
			(xy 409.30177 -359.26004) (xy 409.317587 -359.284554) (xy 409.339691 -359.303594) (xy 409.366276 -359.315607)
			(xy 409.395173 -359.319612) (xy 409.424024 -359.315282) (xy 409.450472 -359.302972) (xy 409.461716 -359.293668)
			(xy 409.482721 -359.275804) (xy 409.528906 -359.245682) (xy 409.578948 -359.222525) (xy 409.631802 -359.206815)
			(xy 409.686368 -359.198881) (xy 409.713938 -359.198418) (xy 409.741186 -359.198907) (xy 409.795125 -359.206667)
			(xy 409.847412 -359.222025) (xy 409.896981 -359.244666) (xy 409.942823 -359.274132) (xy 409.984006 -359.309821)
			(xy 410.019691 -359.351007) (xy 410.049152 -359.396852) (xy 410.071789 -359.446424) (xy 410.087141 -359.498712)
			(xy 410.094896 -359.552652) (xy 410.094896 -359.607148) (xy 410.087141 -359.661088) (xy 410.071789 -359.713376)
			(xy 410.049152 -359.762948) (xy 410.019691 -359.808793) (xy 409.984006 -359.849979) (xy 409.942823 -359.885668)
			(xy 409.896981 -359.915134) (xy 409.847412 -359.937775) (xy 409.795125 -359.953133) (xy 409.741186 -359.960893)
			(xy 409.713938 -359.961434) (xy 409.686371 -359.960944) (xy 409.631811 -359.953001) (xy 409.578962 -359.93729)
			(xy 409.528924 -359.914137) (xy 409.482738 -359.884024) (xy 409.461716 -359.866184) (xy 409.450453 -359.856907)
			(xy 409.424 -359.844616) (xy 409.395153 -359.840297) (xy 409.36626 -359.844304) (xy 409.339676 -359.856308)
			(xy 409.317566 -359.875333) (xy 409.30173 -359.899829) (xy 409.293459 -359.9278) (xy 409.29306 -359.942384)
			(xy 409.29306 -360.995214) (xy 409.84373 -360.995214) (xy 409.847801 -360.939592) (xy 409.859927 -360.885155)
			(xy 409.87985 -360.833064) (xy 409.907146 -360.784429) (xy 409.941232 -360.740286) (xy 409.981381 -360.701577)
			(xy 410.026739 -360.669126) (xy 410.076339 -360.643625) (xy 410.129123 -360.625618) (xy 410.183966 -360.615488)
			(xy 410.2397 -360.613451) (xy 410.295137 -360.619551) (xy 410.349094 -360.633657) (xy 410.400423 -360.655469)
			(xy 410.448029 -360.684523) (xy 410.490897 -360.720198) (xy 410.528114 -360.761735) (xy 410.558887 -360.808248)
			(xy 410.582559 -360.858745) (xy 410.598627 -360.912152) (xy 410.606747 -360.967328) (xy 410.607256 -360.995214)
			(xy 410.606747 -361.0231) (xy 410.598627 -361.078276) (xy 410.582559 -361.131683) (xy 410.558887 -361.18218)
			(xy 410.528114 -361.228693) (xy 410.490897 -361.27023) (xy 410.448029 -361.305905) (xy 410.400423 -361.334959)
			(xy 410.349094 -361.356771) (xy 410.295137 -361.370877) (xy 410.2397 -361.376977) (xy 410.183966 -361.37494)
			(xy 410.129123 -361.36481) (xy 410.076339 -361.346803) (xy 410.026739 -361.321302) (xy 409.981381 -361.288851)
			(xy 409.941232 -361.250142) (xy 409.907146 -361.205999) (xy 409.87985 -361.157364) (xy 409.859927 -361.105273)
			(xy 409.847801 -361.050836) (xy 409.84373 -360.995214) (xy 409.29306 -360.995214) (xy 409.29306 -362.223304)
			(xy 409.80944 -362.223304) (xy 409.813511 -362.167682) (xy 409.825637 -362.113245) (xy 409.84556 -362.061154)
			(xy 409.872856 -362.012519) (xy 409.906942 -361.968376) (xy 409.947091 -361.929667) (xy 409.992449 -361.897216)
			(xy 410.042049 -361.871715) (xy 410.094833 -361.853708) (xy 410.149676 -361.843578) (xy 410.20541 -361.841541)
			(xy 410.260847 -361.847641) (xy 410.314804 -361.861747) (xy 410.366133 -361.883559) (xy 410.413739 -361.912613)
			(xy 410.456607 -361.948288) (xy 410.493824 -361.989825) (xy 410.524597 -362.036338) (xy 410.548269 -362.086835)
			(xy 410.564337 -362.140242) (xy 410.572457 -362.195418) (xy 410.572966 -362.223304) (xy 410.572457 -362.25119)
			(xy 410.564337 -362.306366) (xy 410.548269 -362.359773) (xy 410.524597 -362.41027) (xy 410.493824 -362.456783)
			(xy 410.456607 -362.49832) (xy 410.413739 -362.533995) (xy 410.366133 -362.563049) (xy 410.314804 -362.584861)
			(xy 410.260847 -362.598967) (xy 410.20541 -362.605067) (xy 410.149676 -362.60303) (xy 410.094833 -362.5929)
			(xy 410.042049 -362.574893) (xy 409.992449 -362.549392) (xy 409.947091 -362.516941) (xy 409.906942 -362.478232)
			(xy 409.872856 -362.434089) (xy 409.84556 -362.385454) (xy 409.825637 -362.333363) (xy 409.813511 -362.278926)
			(xy 409.80944 -362.223304) (xy 409.29306 -362.223304) (xy 409.29306 -363.193584) (xy 409.80944 -363.193584)
			(xy 409.813511 -363.137962) (xy 409.825637 -363.083525) (xy 409.84556 -363.031434) (xy 409.872856 -362.982799)
			(xy 409.906942 -362.938656) (xy 409.947091 -362.899947) (xy 409.992449 -362.867496) (xy 410.042049 -362.841995)
			(xy 410.094833 -362.823988) (xy 410.149676 -362.813858) (xy 410.20541 -362.811821) (xy 410.260847 -362.817921)
			(xy 410.314804 -362.832027) (xy 410.366133 -362.853839) (xy 410.413739 -362.882893) (xy 410.456607 -362.918568)
			(xy 410.493824 -362.960105) (xy 410.524597 -363.006618) (xy 410.548269 -363.057115) (xy 410.564337 -363.110522)
			(xy 410.572457 -363.165698) (xy 410.572966 -363.193584) (xy 410.572457 -363.22147) (xy 410.564337 -363.276646)
			(xy 410.548269 -363.330053) (xy 410.524597 -363.38055) (xy 410.493824 -363.427063) (xy 410.456607 -363.4686)
			(xy 410.413739 -363.504275) (xy 410.366133 -363.533329) (xy 410.314804 -363.555141) (xy 410.260847 -363.569247)
			(xy 410.20541 -363.575347) (xy 410.149676 -363.57331) (xy 410.094833 -363.56318) (xy 410.042049 -363.545173)
			(xy 409.992449 -363.519672) (xy 409.947091 -363.487221) (xy 409.906942 -363.448512) (xy 409.872856 -363.404369)
			(xy 409.84556 -363.355734) (xy 409.825637 -363.303643) (xy 409.813511 -363.249206) (xy 409.80944 -363.193584)
			(xy 409.29306 -363.193584) (xy 409.29306 -365.006382) (xy 411.232604 -365.006382) (xy 411.232604 -352.645472)
			(xy 411.233096 -352.620498) (xy 411.240882 -352.57116) (xy 411.256288 -352.523647) (xy 411.278935 -352.479128)
			(xy 411.308267 -352.4387) (xy 411.325568 -352.420682) (xy 412.668466 -351.077784) (xy 412.672022 -351.063814)
			(xy 412.679745 -351.034192) (xy 412.703338 -350.977709) (xy 412.735674 -350.925735) (xy 412.755334 -350.90227)
			(xy 412.764599 -350.890965) (xy 412.776768 -350.864398) (xy 412.780933 -350.835476) (xy 412.776755 -350.806555)
			(xy 412.764573 -350.779995) (xy 412.755334 -350.768666) (xy 412.737662 -350.747759) (xy 412.707938 -350.701787)
			(xy 412.685094 -350.652036) (xy 412.6696 -350.59953) (xy 412.661774 -350.545348) (xy 412.661777 -350.490604)
			(xy 412.66961 -350.436423) (xy 412.685111 -350.383918) (xy 412.707961 -350.334171) (xy 412.737691 -350.288203)
			(xy 412.755334 -350.26727) (xy 412.764599 -350.255965) (xy 412.776768 -350.229398) (xy 412.780933 -350.200476)
			(xy 412.776755 -350.171555) (xy 412.764573 -350.144995) (xy 412.755334 -350.133666) (xy 412.737662 -350.112759)
			(xy 412.707938 -350.066787) (xy 412.685094 -350.017036) (xy 412.6696 -349.96453) (xy 412.661774 -349.910348)
			(xy 412.661777 -349.855604) (xy 412.66961 -349.801423) (xy 412.685111 -349.748918) (xy 412.707961 -349.699171)
			(xy 412.737691 -349.653203) (xy 412.755334 -349.63227) (xy 412.764599 -349.620965) (xy 412.776768 -349.594398)
			(xy 412.780933 -349.565476) (xy 412.776755 -349.536555) (xy 412.764573 -349.509995) (xy 412.755334 -349.498666)
			(xy 412.737662 -349.477759) (xy 412.707938 -349.431787) (xy 412.685094 -349.382036) (xy 412.6696 -349.32953)
			(xy 412.661774 -349.275348) (xy 412.661777 -349.220604) (xy 412.66961 -349.166423) (xy 412.685111 -349.113918)
			(xy 412.707961 -349.064171) (xy 412.737691 -349.018203) (xy 412.755334 -348.99727) (xy 412.764599 -348.985965)
			(xy 412.776768 -348.959398) (xy 412.780933 -348.930476) (xy 412.776755 -348.901555) (xy 412.764573 -348.874995)
			(xy 412.755334 -348.863666) (xy 412.737662 -348.842759) (xy 412.707938 -348.796787) (xy 412.685094 -348.747036)
			(xy 412.6696 -348.69453) (xy 412.661774 -348.640348) (xy 412.661777 -348.585604) (xy 412.66961 -348.531423)
			(xy 412.685111 -348.478918) (xy 412.707961 -348.429171) (xy 412.737691 -348.383203) (xy 412.755334 -348.36227)
			(xy 412.764599 -348.350965) (xy 412.776768 -348.324398) (xy 412.780933 -348.295476) (xy 412.776755 -348.266555)
			(xy 412.764573 -348.239995) (xy 412.755334 -348.228666) (xy 412.737662 -348.207759) (xy 412.707938 -348.161787)
			(xy 412.685094 -348.112036) (xy 412.6696 -348.05953) (xy 412.661774 -348.005348) (xy 412.661777 -347.950604)
			(xy 412.66961 -347.896423) (xy 412.685111 -347.843918) (xy 412.707961 -347.794171) (xy 412.737691 -347.748203)
			(xy 412.755334 -347.72727) (xy 412.764599 -347.715965) (xy 412.776768 -347.689398) (xy 412.780933 -347.660476)
			(xy 412.776755 -347.631555) (xy 412.764573 -347.604995) (xy 412.755334 -347.593666) (xy 412.737718 -347.572715)
			(xy 412.708001 -347.526748) (xy 412.68516 -347.477006) (xy 412.669664 -347.424509) (xy 412.661831 -347.370336)
			(xy 412.661354 -347.342968) (xy 412.661848 -347.315718) (xy 412.669608 -347.261772) (xy 412.684965 -347.20948)
			(xy 412.707607 -347.159905) (xy 412.737073 -347.114057) (xy 412.772764 -347.072868) (xy 412.813952 -347.037177)
			(xy 412.8598 -347.00771) (xy 412.909374 -346.985067) (xy 412.961666 -346.969709) (xy 413.015612 -346.961948)
			(xy 413.042862 -346.96146) (xy 413.070232 -346.961934) (xy 413.124411 -346.969747) (xy 413.176915 -346.985234)
			(xy 413.226662 -347.008074) (xy 413.272629 -347.037799) (xy 413.29356 -347.05544) (xy 413.304888 -347.064676)
			(xy 413.331445 -347.076852) (xy 413.360362 -347.081025) (xy 413.389279 -347.076852) (xy 413.415836 -347.064676)
			(xy 413.427164 -347.05544) (xy 413.448104 -347.037811) (xy 413.494074 -347.008096) (xy 413.543819 -346.985257)
			(xy 413.596319 -346.969764) (xy 413.650493 -346.961935) (xy 413.677862 -346.96146) (xy 413.705901 -346.96198)
			(xy 413.761378 -346.970176) (xy 413.815059 -346.986395) (xy 413.865792 -347.010291) (xy 413.912485 -347.041349)
			(xy 413.93364 -347.059758) (xy 413.945082 -347.069403) (xy 413.972125 -347.082183) (xy 414.001712 -347.086569)
			(xy 414.031299 -347.082183) (xy 414.058342 -347.069403) (xy 414.069784 -347.059758) (xy 414.090918 -347.041318)
			(xy 414.1376 -347.010227) (xy 414.188336 -346.986316) (xy 414.242028 -346.970101) (xy 414.297518 -346.961931)
			(xy 414.325562 -346.96146) (xy 414.352812 -346.961991) (xy 414.406759 -346.969742) (xy 414.459054 -346.985091)
			(xy 414.508632 -347.007727) (xy 414.554484 -347.037188) (xy 414.595676 -347.072875) (xy 414.63137 -347.11406)
			(xy 414.66084 -347.159907) (xy 414.683484 -347.20948) (xy 414.698844 -347.261772) (xy 414.706604 -347.315718)
			(xy 414.70707 -347.342968) (xy 414.706592 -347.370338) (xy 414.698779 -347.424517) (xy 414.683293 -347.47702)
			(xy 414.660453 -347.526767) (xy 414.63073 -347.572734) (xy 414.61309 -347.593666) (xy 414.603885 -347.605017)
			(xy 414.591705 -347.631566) (xy 414.587527 -347.660476) (xy 414.591691 -347.689387) (xy 414.603858 -347.715943)
			(xy 414.61309 -347.72727) (xy 414.630699 -347.748228) (xy 414.660423 -347.794192) (xy 414.68327 -347.843934)
			(xy 414.698768 -347.896432) (xy 414.706599 -347.950607) (xy 414.706602 -348.005345) (xy 414.698778 -348.059521)
			(xy 414.683287 -348.11202) (xy 414.660447 -348.161765) (xy 414.630728 -348.207733) (xy 414.61309 -348.228666)
			(xy 414.603885 -348.240017) (xy 414.591705 -348.266566) (xy 414.587527 -348.295476) (xy 414.591691 -348.324387)
			(xy 414.603858 -348.350943) (xy 414.61309 -348.36227) (xy 414.630699 -348.383228) (xy 414.660423 -348.429192)
			(xy 414.68327 -348.478934) (xy 414.698768 -348.531432) (xy 414.706599 -348.585607) (xy 414.706602 -348.640345)
			(xy 414.698778 -348.694521) (xy 414.683287 -348.74702) (xy 414.660447 -348.796765) (xy 414.630728 -348.842733)
			(xy 414.61309 -348.863666) (xy 414.603885 -348.875017) (xy 414.591705 -348.901566) (xy 414.587527 -348.930476)
			(xy 414.591691 -348.959387) (xy 414.603858 -348.985943) (xy 414.61309 -348.99727) (xy 414.630699 -349.018228)
			(xy 414.660423 -349.064192) (xy 414.68327 -349.113934) (xy 414.698768 -349.166432) (xy 414.706599 -349.220607)
			(xy 414.706602 -349.275345) (xy 414.698778 -349.329521) (xy 414.683287 -349.38202) (xy 414.660447 -349.431765)
			(xy 414.630728 -349.477733) (xy 414.61309 -349.498666) (xy 414.603885 -349.510017) (xy 414.591705 -349.536566)
			(xy 414.587527 -349.565476) (xy 414.591691 -349.594387) (xy 414.603858 -349.620943) (xy 414.61309 -349.63227)
			(xy 414.630699 -349.653228) (xy 414.660423 -349.699192) (xy 414.68327 -349.748934) (xy 414.698768 -349.801432)
			(xy 414.706599 -349.855607) (xy 414.706602 -349.910345) (xy 414.698778 -349.964521) (xy 414.683287 -350.01702)
			(xy 414.660447 -350.066765) (xy 414.630728 -350.112733) (xy 414.61309 -350.133666) (xy 414.603885 -350.145017)
			(xy 414.591705 -350.171566) (xy 414.587527 -350.200476) (xy 414.591691 -350.229387) (xy 414.603858 -350.255943)
			(xy 414.61309 -350.26727) (xy 414.630699 -350.288228) (xy 414.660423 -350.334192) (xy 414.68327 -350.383934)
			(xy 414.698768 -350.436432) (xy 414.706599 -350.490607) (xy 414.706602 -350.545345) (xy 414.698778 -350.599521)
			(xy 414.683287 -350.65202) (xy 414.660447 -350.701765) (xy 414.630728 -350.747733) (xy 414.61309 -350.768666)
			(xy 414.603885 -350.780017) (xy 414.591705 -350.806566) (xy 414.587527 -350.835476) (xy 414.591691 -350.864387)
			(xy 414.603858 -350.890943) (xy 414.61309 -350.90227) (xy 414.630727 -350.923204) (xy 414.660439 -350.969176)
			(xy 414.683276 -351.018923) (xy 414.698767 -351.071423) (xy 414.706596 -351.125599) (xy 414.70707 -351.152968)
			(xy 417.631626 -351.152968) (xy 417.632067 -351.125597) (xy 417.63989 -351.071416) (xy 417.655384 -351.018913)
			(xy 417.678232 -350.969166) (xy 417.707962 -350.923201) (xy 417.725606 -350.90227) (xy 417.734873 -350.890966)
			(xy 417.747046 -350.864399) (xy 417.751212 -350.835476) (xy 417.747032 -350.806554) (xy 417.734847 -350.779994)
			(xy 417.725606 -350.768666) (xy 417.707935 -350.747758) (xy 417.678213 -350.701786) (xy 417.655371 -350.652035)
			(xy 417.639878 -350.599529) (xy 417.632053 -350.545348) (xy 417.632056 -350.490604) (xy 417.639888 -350.436423)
			(xy 417.655388 -350.38392) (xy 417.678236 -350.334172) (xy 417.707964 -350.288203) (xy 417.725606 -350.26727)
			(xy 417.734873 -350.255966) (xy 417.747046 -350.229399) (xy 417.751212 -350.200476) (xy 417.747032 -350.171554)
			(xy 417.734847 -350.144994) (xy 417.725606 -350.133666) (xy 417.707935 -350.112758) (xy 417.678213 -350.066786)
			(xy 417.655371 -350.017035) (xy 417.639878 -349.964529) (xy 417.632053 -349.910348) (xy 417.632056 -349.855604)
			(xy 417.639888 -349.801423) (xy 417.655388 -349.74892) (xy 417.678236 -349.699172) (xy 417.707964 -349.653203)
			(xy 417.725606 -349.63227) (xy 417.734873 -349.620966) (xy 417.747046 -349.594399) (xy 417.751212 -349.565476)
			(xy 417.747032 -349.536554) (xy 417.734847 -349.509994) (xy 417.725606 -349.498666) (xy 417.707935 -349.477758)
			(xy 417.678213 -349.431786) (xy 417.655371 -349.382035) (xy 417.639878 -349.329529) (xy 417.632053 -349.275348)
			(xy 417.632056 -349.220604) (xy 417.639888 -349.166423) (xy 417.655388 -349.11392) (xy 417.678236 -349.064172)
			(xy 417.707964 -349.018203) (xy 417.725606 -348.99727) (xy 417.734873 -348.985966) (xy 417.747046 -348.959399)
			(xy 417.751212 -348.930476) (xy 417.747032 -348.901554) (xy 417.734847 -348.874994) (xy 417.725606 -348.863666)
			(xy 417.707935 -348.842758) (xy 417.678213 -348.796786) (xy 417.655371 -348.747035) (xy 417.639878 -348.694529)
			(xy 417.632053 -348.640348) (xy 417.632056 -348.585604) (xy 417.639888 -348.531423) (xy 417.655388 -348.47892)
			(xy 417.678236 -348.429172) (xy 417.707964 -348.383203) (xy 417.725606 -348.36227) (xy 417.734873 -348.350966)
			(xy 417.747046 -348.324399) (xy 417.751212 -348.295476) (xy 417.747032 -348.266554) (xy 417.734847 -348.239994)
			(xy 417.725606 -348.228666) (xy 417.707935 -348.207758) (xy 417.678213 -348.161786) (xy 417.655371 -348.112035)
			(xy 417.639878 -348.059529) (xy 417.632053 -348.005348) (xy 417.632056 -347.950604) (xy 417.639888 -347.896423)
			(xy 417.655388 -347.84392) (xy 417.678236 -347.794172) (xy 417.707964 -347.748203) (xy 417.725606 -347.72727)
			(xy 417.734873 -347.715966) (xy 417.747046 -347.689399) (xy 417.751212 -347.660476) (xy 417.747032 -347.631554)
			(xy 417.734847 -347.604994) (xy 417.725606 -347.593666) (xy 417.707985 -347.572719) (xy 417.678271 -347.52675)
			(xy 417.655431 -347.477007) (xy 417.639936 -347.424509) (xy 417.632103 -347.370336) (xy 417.631626 -347.342968)
			(xy 417.632025 -347.315713) (xy 417.639787 -347.261758) (xy 417.655149 -347.209457) (xy 417.677798 -347.159874)
			(xy 417.707273 -347.114019) (xy 417.742973 -347.072826) (xy 417.784172 -347.037133) (xy 417.830032 -347.007666)
			(xy 417.879619 -346.985026) (xy 417.931922 -346.969673) (xy 417.985879 -346.96192) (xy 418.013134 -346.96146)
			(xy 418.041175 -346.961937) (xy 418.096653 -346.970143) (xy 418.150335 -346.986373) (xy 418.201067 -347.010278)
			(xy 418.247758 -347.041345) (xy 418.268912 -347.059758) (xy 418.280354 -347.069403) (xy 418.307397 -347.082183)
			(xy 418.336984 -347.086569) (xy 418.366571 -347.082183) (xy 418.393614 -347.069403) (xy 418.405056 -347.059758)
			(xy 418.426201 -347.041331) (xy 418.47288 -347.010239) (xy 418.523613 -346.986325) (xy 418.577303 -346.970106)
			(xy 418.63279 -346.961933) (xy 418.660834 -346.96146) (xy 418.688206 -346.961892) (xy 418.742387 -346.969715)
			(xy 418.794891 -346.985212) (xy 418.844637 -347.008062) (xy 418.890602 -347.037795) (xy 418.911532 -347.05544)
			(xy 418.92286 -347.064676) (xy 418.949417 -347.076852) (xy 418.978334 -347.081025) (xy 419.007251 -347.076852)
			(xy 419.033808 -347.064676) (xy 419.045136 -347.05544) (xy 419.066087 -347.037824) (xy 419.112054 -347.008107)
			(xy 419.161796 -346.985266) (xy 419.214293 -346.96977) (xy 419.268466 -346.961937) (xy 419.295834 -346.96146)
			(xy 419.323085 -346.961946) (xy 419.377031 -346.969706) (xy 419.429323 -346.985064) (xy 419.478899 -347.007707)
			(xy 419.524747 -347.037174) (xy 419.565936 -347.072865) (xy 419.601627 -347.114054) (xy 419.631094 -347.159903)
			(xy 419.653736 -347.209478) (xy 419.669094 -347.261771) (xy 419.676854 -347.315717) (xy 419.677342 -347.342968)
			(xy 419.676871 -347.370338) (xy 419.669057 -347.424518) (xy 419.65357 -347.477021) (xy 419.630728 -347.526768)
			(xy 419.601004 -347.572735) (xy 419.583362 -347.593666) (xy 419.574159 -347.605018) (xy 419.561982 -347.631567)
			(xy 419.557806 -347.660476) (xy 419.561969 -347.689386) (xy 419.574133 -347.715942) (xy 419.583362 -347.72727)
			(xy 419.600972 -347.748228) (xy 419.630699 -347.794191) (xy 419.653547 -347.843933) (xy 419.669046 -347.896431)
			(xy 419.676878 -347.950607) (xy 419.676881 -348.005345) (xy 419.669056 -348.059521) (xy 419.653564 -348.112022)
			(xy 419.630722 -348.161767) (xy 419.601001 -348.207734) (xy 419.583362 -348.228666) (xy 419.574159 -348.240018)
			(xy 419.561982 -348.266567) (xy 419.557806 -348.295476) (xy 419.561969 -348.324386) (xy 419.574133 -348.350942)
			(xy 419.583362 -348.36227) (xy 419.600972 -348.383228) (xy 419.630699 -348.429191) (xy 419.653547 -348.478933)
			(xy 419.669046 -348.531431) (xy 419.676878 -348.585607) (xy 419.676881 -348.640345) (xy 419.669056 -348.694521)
			(xy 419.653564 -348.747022) (xy 419.630722 -348.796767) (xy 419.601001 -348.842734) (xy 419.583362 -348.863666)
			(xy 419.574159 -348.875018) (xy 419.561982 -348.901567) (xy 419.557806 -348.930476) (xy 419.561969 -348.959386)
			(xy 419.574133 -348.985942) (xy 419.583362 -348.99727) (xy 419.600972 -349.018228) (xy 419.630699 -349.064191)
			(xy 419.653547 -349.113933) (xy 419.669046 -349.166431) (xy 419.676878 -349.220607) (xy 419.676881 -349.275345)
			(xy 419.669056 -349.329521) (xy 419.653564 -349.382022) (xy 419.630722 -349.431767) (xy 419.601001 -349.477734)
			(xy 419.583362 -349.498666) (xy 419.574159 -349.510018) (xy 419.561982 -349.536567) (xy 419.557806 -349.565476)
			(xy 419.561969 -349.594386) (xy 419.574133 -349.620942) (xy 419.583362 -349.63227) (xy 419.600972 -349.653228)
			(xy 419.630699 -349.699191) (xy 419.653547 -349.748933) (xy 419.669046 -349.801431) (xy 419.676878 -349.855607)
			(xy 419.676881 -349.910345) (xy 419.669056 -349.964521) (xy 419.653564 -350.017022) (xy 419.630722 -350.066767)
			(xy 419.601001 -350.112734) (xy 419.583362 -350.133666) (xy 419.574159 -350.145018) (xy 419.561982 -350.171567)
			(xy 419.557806 -350.200476) (xy 419.561969 -350.229386) (xy 419.574133 -350.255942) (xy 419.583362 -350.26727)
			(xy 419.600972 -350.288228) (xy 419.630699 -350.334191) (xy 419.653547 -350.383933) (xy 419.669046 -350.436431)
			(xy 419.676878 -350.490607) (xy 419.676881 -350.545345) (xy 419.669056 -350.599521) (xy 419.653564 -350.652022)
			(xy 419.630722 -350.701767) (xy 419.601001 -350.747734) (xy 419.583362 -350.768666) (xy 419.574159 -350.780018)
			(xy 419.561982 -350.806567) (xy 419.557806 -350.835476) (xy 419.561969 -350.864386) (xy 419.574133 -350.890942)
			(xy 419.583362 -350.90227) (xy 419.600995 -350.923207) (xy 419.630709 -350.969178) (xy 419.653547 -351.018924)
			(xy 419.669039 -351.071424) (xy 419.676868 -351.125599) (xy 419.677342 -351.152968) (xy 419.676792 -351.180217)
			(xy 419.669041 -351.234161) (xy 419.653691 -351.286452) (xy 419.631057 -351.336027) (xy 419.601597 -351.381876)
			(xy 419.565912 -351.423065) (xy 419.524728 -351.458757) (xy 419.478885 -351.488225) (xy 419.429314 -351.510868)
			(xy 419.377025 -351.526227) (xy 419.323083 -351.533987) (xy 419.295834 -351.534476) (xy 419.268464 -351.533996)
			(xy 419.214285 -351.526182) (xy 419.161782 -351.510697) (xy 419.112035 -351.487858) (xy 419.066068 -351.458136)
			(xy 419.045136 -351.440496) (xy 419.033808 -351.43126) (xy 419.007251 -351.419084) (xy 418.978334 -351.414911)
			(xy 418.949417 -351.419084) (xy 418.92286 -351.43126) (xy 418.911532 -351.440496) (xy 418.890598 -351.458133)
			(xy 418.844626 -351.487845) (xy 418.794879 -351.510682) (xy 418.742379 -351.526173) (xy 418.688203 -351.534002)
			(xy 418.660834 -351.534476) (xy 418.632794 -351.533974) (xy 418.577316 -351.525777) (xy 418.523633 -351.509554)
			(xy 418.472901 -351.485654) (xy 418.42621 -351.45459) (xy 418.405056 -351.436178) (xy 418.393614 -351.426533)
			(xy 418.366571 -351.413753) (xy 418.336984 -351.409367) (xy 418.307397 -351.413753) (xy 418.280354 -351.426533)
			(xy 418.268912 -351.436178) (xy 418.247785 -351.454626) (xy 418.2011 -351.485714) (xy 418.150363 -351.509624)
			(xy 418.096669 -351.525837) (xy 418.041179 -351.534006) (xy 418.013134 -351.534476) (xy 417.985881 -351.534013)
			(xy 417.931928 -351.52626) (xy 417.879628 -351.510906) (xy 417.830046 -351.488266) (xy 417.784191 -351.458798)
			(xy 417.742997 -351.423104) (xy 417.707303 -351.38191) (xy 417.677835 -351.336056) (xy 417.655194 -351.286474)
			(xy 417.639841 -351.234174) (xy 417.632087 -351.180221) (xy 417.631626 -351.152968) (xy 414.70707 -351.152968)
			(xy 414.706615 -351.180222) (xy 414.698861 -351.234175) (xy 414.683507 -351.286475) (xy 414.660866 -351.336058)
			(xy 414.631398 -351.381913) (xy 414.595703 -351.423107) (xy 414.554508 -351.458801) (xy 414.508653 -351.488269)
			(xy 414.45907 -351.510909) (xy 414.406769 -351.526262) (xy 414.352816 -351.534015) (xy 414.325562 -351.534476)
			(xy 414.29752 -351.534017) (xy 414.24204 -351.52581) (xy 414.188357 -351.509576) (xy 414.137626 -351.485667)
			(xy 414.090936 -351.454594) (xy 414.069784 -351.436178) (xy 414.058342 -351.426533) (xy 414.031299 -351.413753)
			(xy 414.001712 -351.409367) (xy 413.972125 -351.413753) (xy 413.945082 -351.426533) (xy 413.93364 -351.436178)
			(xy 413.912502 -351.454613) (xy 413.86582 -351.485703) (xy 413.815086 -351.509615) (xy 413.761394 -351.525832)
			(xy 413.705906 -351.534004) (xy 413.677862 -351.534476) (xy 413.650493 -351.533979) (xy 413.596315 -351.52617)
			(xy 413.543812 -351.510688) (xy 413.494064 -351.487853) (xy 413.448096 -351.458135) (xy 413.427164 -351.440496)
			(xy 413.415836 -351.43126) (xy 413.389279 -351.419084) (xy 413.360362 -351.414911) (xy 413.331445 -351.419084)
			(xy 413.304888 -351.43126) (xy 413.29356 -351.440496) (xy 413.270084 -351.460138) (xy 413.218097 -351.492445)
			(xy 413.161629 -351.516061) (xy 413.132016 -351.523808) (xy 413.118046 -351.527364) (xy 411.868112 -352.777044)
			(xy 411.868112 -363.554264) (xy 412.204154 -363.554264) (xy 412.204632 -363.526223) (xy 412.212837 -363.470745)
			(xy 412.229067 -363.417063) (xy 412.252972 -363.366331) (xy 412.284039 -363.31964) (xy 412.302452 -363.298486)
			(xy 412.312086 -363.287035) (xy 412.324872 -363.259996) (xy 412.329261 -363.23041) (xy 412.324878 -363.200824)
			(xy 412.312097 -363.173783) (xy 412.302452 -363.162342) (xy 412.284023 -363.141199) (xy 412.252931 -363.094519)
			(xy 412.229018 -363.043786) (xy 412.2128 -362.990095) (xy 412.204627 -362.934608) (xy 412.204154 -362.906564)
			(xy 412.20464 -362.879313) (xy 412.212396 -362.825365) (xy 412.227751 -362.77307) (xy 412.250393 -362.723493)
			(xy 412.279859 -362.677643) (xy 412.31555 -362.636452) (xy 412.356741 -362.600761) (xy 412.402591 -362.571295)
			(xy 412.452168 -362.548653) (xy 412.504463 -362.533298) (xy 412.558411 -362.525542) (xy 412.612913 -362.525542)
			(xy 412.666861 -362.533298) (xy 412.719156 -362.548653) (xy 412.768733 -362.571295) (xy 412.814583 -362.600761)
			(xy 412.855774 -362.636452) (xy 412.891465 -362.677643) (xy 412.920931 -362.723493) (xy 412.943573 -362.77307)
			(xy 412.958928 -362.825365) (xy 412.966684 -362.879313) (xy 412.96717 -362.906564) (xy 412.966669 -362.934604)
			(xy 412.958472 -362.990082) (xy 412.942248 -363.043765) (xy 412.918348 -363.094497) (xy 412.887284 -363.141188)
			(xy 412.868872 -363.162342) (xy 412.864368 -363.167676) (xy 420.18153 -363.167676) (xy 420.185601 -363.112054)
			(xy 420.197727 -363.057617) (xy 420.21765 -363.005526) (xy 420.244946 -362.956891) (xy 420.279032 -362.912748)
			(xy 420.319181 -362.874039) (xy 420.364539 -362.841588) (xy 420.414139 -362.816087) (xy 420.466923 -362.79808)
			(xy 420.521766 -362.78795) (xy 420.5775 -362.785913) (xy 420.632937 -362.792013) (xy 420.686894 -362.806119)
			(xy 420.738223 -362.827931) (xy 420.785829 -362.856985) (xy 420.828697 -362.89266) (xy 420.865914 -362.934197)
			(xy 420.896687 -362.98071) (xy 420.920359 -363.031207) (xy 420.936427 -363.084614) (xy 420.944547 -363.13979)
			(xy 420.945056 -363.167676) (xy 420.944547 -363.195562) (xy 420.936427 -363.250738) (xy 420.920359 -363.304145)
			(xy 420.896687 -363.354642) (xy 420.865914 -363.401155) (xy 420.828697 -363.442692) (xy 420.785829 -363.478367)
			(xy 420.738223 -363.507421) (xy 420.686894 -363.529233) (xy 420.632937 -363.543339) (xy 420.591359 -363.547914)
			(xy 421.892476 -363.547914) (xy 421.892932 -363.520543) (xy 421.900749 -363.466363) (xy 421.91624 -363.413859)
			(xy 421.939084 -363.364112) (xy 421.968813 -363.318147) (xy 421.986456 -363.297216) (xy 421.995675 -363.285877)
			(xy 422.007847 -363.259322) (xy 422.01202 -363.230411) (xy 422.007853 -363.201498) (xy 421.995686 -363.174941)
			(xy 421.986456 -363.163612) (xy 421.968802 -363.142692) (xy 421.939094 -363.096715) (xy 421.916261 -363.046965)
			(xy 421.900773 -362.994462) (xy 421.892948 -362.940284) (xy 421.892476 -362.912914) (xy 421.892962 -362.885663)
			(xy 421.900718 -362.831715) (xy 421.916073 -362.77942) (xy 421.938715 -362.729843) (xy 421.968181 -362.683993)
			(xy 422.003872 -362.642802) (xy 422.045063 -362.607111) (xy 422.090913 -362.577645) (xy 422.14049 -362.555003)
			(xy 422.192785 -362.539648) (xy 422.246733 -362.531892) (xy 422.301235 -362.531892) (xy 422.355183 -362.539648)
			(xy 422.407478 -362.555003) (xy 422.457055 -362.577645) (xy 422.502905 -362.607111) (xy 422.544096 -362.642802)
			(xy 422.579787 -362.683993) (xy 422.609253 -362.729843) (xy 422.631895 -362.77942) (xy 422.64725 -362.831715)
			(xy 422.655006 -362.885663) (xy 422.655492 -362.912914) (xy 422.655036 -362.940285) (xy 422.647216 -362.994464)
			(xy 422.631725 -363.046968) (xy 422.608881 -363.096714) (xy 422.579154 -363.142681) (xy 422.561512 -363.163612)
			(xy 422.552261 -363.174929) (xy 422.540084 -363.20149) (xy 422.535913 -363.230411) (xy 422.54009 -363.25933)
			(xy 422.552272 -363.285889) (xy 422.561512 -363.297216) (xy 422.578977 -363.317995) (xy 422.608507 -363.363537)
			(xy 422.631279 -363.412807) (xy 422.646832 -363.46481) (xy 422.654851 -363.518492) (xy 422.655492 -363.545628)
			(xy 422.656109 -363.560576) (xy 422.664969 -363.589137) (xy 422.681717 -363.61391) (xy 422.704919 -363.632776)
			(xy 422.732588 -363.644118) (xy 422.762356 -363.646966) (xy 422.791674 -363.641075) (xy 422.818032 -363.626951)
			(xy 422.828974 -363.616748) (xy 422.863264 -363.582712) (xy 422.863264 -355.822504) (xy 422.49852 -355.458014)
			(xy 422.4812 -355.440011) (xy 422.451848 -355.399588) (xy 422.429189 -355.355067) (xy 422.413779 -355.307548)
			(xy 422.406 -355.258202) (xy 422.405556 -355.233224) (xy 422.405556 -351.36836) (xy 422.389802 -351.344447)
			(xy 422.364852 -351.292905) (xy 422.347886 -351.238213) (xy 422.339287 -351.181599) (xy 422.338754 -351.152968)
			(xy 422.339188 -351.125596) (xy 422.347012 -351.071415) (xy 422.362507 -351.018912) (xy 422.385357 -350.969165)
			(xy 422.415089 -350.9232) (xy 422.432734 -350.90227) (xy 422.441999 -350.890965) (xy 422.454168 -350.864398)
			(xy 422.458333 -350.835476) (xy 422.454155 -350.806555) (xy 422.441973 -350.779995) (xy 422.432734 -350.768666)
			(xy 422.415062 -350.747759) (xy 422.385338 -350.701787) (xy 422.362494 -350.652036) (xy 422.347 -350.59953)
			(xy 422.339174 -350.545348) (xy 422.339177 -350.490604) (xy 422.34701 -350.436423) (xy 422.362511 -350.383918)
			(xy 422.385361 -350.334171) (xy 422.415091 -350.288203) (xy 422.432734 -350.26727) (xy 422.441999 -350.255965)
			(xy 422.454168 -350.229398) (xy 422.458333 -350.200476) (xy 422.454155 -350.171555) (xy 422.441973 -350.144995)
			(xy 422.432734 -350.133666) (xy 422.415062 -350.112759) (xy 422.385338 -350.066787) (xy 422.362494 -350.017036)
			(xy 422.347 -349.96453) (xy 422.339174 -349.910348) (xy 422.339177 -349.855604) (xy 422.34701 -349.801423)
			(xy 422.362511 -349.748918) (xy 422.385361 -349.699171) (xy 422.415091 -349.653203) (xy 422.432734 -349.63227)
			(xy 422.441999 -349.620965) (xy 422.454168 -349.594398) (xy 422.458333 -349.565476) (xy 422.454155 -349.536555)
			(xy 422.441973 -349.509995) (xy 422.432734 -349.498666) (xy 422.415062 -349.477759) (xy 422.385338 -349.431787)
			(xy 422.362494 -349.382036) (xy 422.347 -349.32953) (xy 422.339174 -349.275348) (xy 422.339177 -349.220604)
			(xy 422.34701 -349.166423) (xy 422.362511 -349.113918) (xy 422.385361 -349.064171) (xy 422.415091 -349.018203)
			(xy 422.432734 -348.99727) (xy 422.441999 -348.985965) (xy 422.454168 -348.959398) (xy 422.458333 -348.930476)
			(xy 422.454155 -348.901555) (xy 422.441973 -348.874995) (xy 422.432734 -348.863666) (xy 422.415062 -348.842759)
			(xy 422.385338 -348.796787) (xy 422.362494 -348.747036) (xy 422.347 -348.69453) (xy 422.339174 -348.640348)
			(xy 422.339177 -348.585604) (xy 422.34701 -348.531423) (xy 422.362511 -348.478918) (xy 422.385361 -348.429171)
			(xy 422.415091 -348.383203) (xy 422.432734 -348.36227) (xy 422.441999 -348.350965) (xy 422.454168 -348.324398)
			(xy 422.458333 -348.295476) (xy 422.454155 -348.266555) (xy 422.441973 -348.239995) (xy 422.432734 -348.228666)
			(xy 422.415062 -348.207759) (xy 422.385338 -348.161787) (xy 422.362494 -348.112036) (xy 422.347 -348.05953)
			(xy 422.339174 -348.005348) (xy 422.339177 -347.950604) (xy 422.34701 -347.896423) (xy 422.362511 -347.843918)
			(xy 422.385361 -347.794171) (xy 422.415091 -347.748203) (xy 422.432734 -347.72727) (xy 422.441999 -347.715965)
			(xy 422.454168 -347.689398) (xy 422.458333 -347.660476) (xy 422.454155 -347.631555) (xy 422.441973 -347.604995)
			(xy 422.432734 -347.593666) (xy 422.415118 -347.572715) (xy 422.385401 -347.526748) (xy 422.36256 -347.477006)
			(xy 422.347064 -347.424509) (xy 422.339231 -347.370336) (xy 422.338754 -347.342968) (xy 422.339248 -347.315718)
			(xy 422.347008 -347.261772) (xy 422.362365 -347.20948) (xy 422.385007 -347.159905) (xy 422.414473 -347.114057)
			(xy 422.450164 -347.072868) (xy 422.491352 -347.037177) (xy 422.5372 -347.00771) (xy 422.586774 -346.985067)
			(xy 422.639066 -346.969709) (xy 422.693012 -346.961948) (xy 422.720262 -346.96146) (xy 422.747632 -346.961934)
			(xy 422.801811 -346.969747) (xy 422.854315 -346.985234) (xy 422.904062 -347.008074) (xy 422.950029 -347.037799)
			(xy 422.97096 -347.05544) (xy 422.982288 -347.064676) (xy 423.008845 -347.076852) (xy 423.037762 -347.081025)
			(xy 423.066679 -347.076852) (xy 423.093236 -347.064676) (xy 423.104564 -347.05544) (xy 423.125504 -347.037811)
			(xy 423.171474 -347.008096) (xy 423.221219 -346.985257) (xy 423.273719 -346.969764) (xy 423.327893 -346.961935)
			(xy 423.355262 -346.96146) (xy 423.383301 -346.96198) (xy 423.438778 -346.970176) (xy 423.492459 -346.986395)
			(xy 423.543192 -347.010291) (xy 423.589885 -347.041349) (xy 423.61104 -347.059758) (xy 423.622482 -347.069403)
			(xy 423.649525 -347.082183) (xy 423.679112 -347.086569) (xy 423.708699 -347.082183) (xy 423.735742 -347.069403)
			(xy 423.747184 -347.059758) (xy 423.768318 -347.041318) (xy 423.815 -347.010227) (xy 423.865736 -346.986316)
			(xy 423.919428 -346.970101) (xy 423.974918 -346.961931) (xy 424.002962 -346.96146) (xy 424.030212 -346.961991)
			(xy 424.084159 -346.969742) (xy 424.136454 -346.985091) (xy 424.186032 -347.007727) (xy 424.231884 -347.037188)
			(xy 424.273076 -347.072875) (xy 424.30877 -347.11406) (xy 424.33824 -347.159907) (xy 424.360884 -347.20948)
			(xy 424.376244 -347.261772) (xy 424.384004 -347.315718) (xy 424.38447 -347.342968) (xy 424.383992 -347.370338)
			(xy 424.376179 -347.424517) (xy 424.360693 -347.47702) (xy 424.337853 -347.526767) (xy 424.30813 -347.572734)
			(xy 424.29049 -347.593666) (xy 424.281285 -347.605017) (xy 424.269105 -347.631566) (xy 424.264927 -347.660476)
			(xy 424.269091 -347.689387) (xy 424.281258 -347.715943) (xy 424.29049 -347.72727) (xy 424.308099 -347.748228)
			(xy 424.337823 -347.794192) (xy 424.36067 -347.843934) (xy 424.376168 -347.896432) (xy 424.383999 -347.950607)
			(xy 424.384002 -348.005345) (xy 424.376178 -348.059521) (xy 424.360687 -348.11202) (xy 424.337847 -348.161765)
			(xy 424.308128 -348.207733) (xy 424.29049 -348.228666) (xy 424.281285 -348.240017) (xy 424.269105 -348.266566)
			(xy 424.264927 -348.295476) (xy 424.269091 -348.324387) (xy 424.281258 -348.350943) (xy 424.29049 -348.36227)
			(xy 424.308099 -348.383228) (xy 424.337823 -348.429192) (xy 424.36067 -348.478934) (xy 424.376168 -348.531432)
			(xy 424.383999 -348.585607) (xy 424.384002 -348.640345) (xy 424.376178 -348.694521) (xy 424.360687 -348.74702)
			(xy 424.337847 -348.796765) (xy 424.308128 -348.842733) (xy 424.29049 -348.863666) (xy 424.281285 -348.875017)
			(xy 424.269105 -348.901566) (xy 424.264927 -348.930476) (xy 424.269091 -348.959387) (xy 424.281258 -348.985943)
			(xy 424.29049 -348.99727) (xy 424.308099 -349.018228) (xy 424.337823 -349.064192) (xy 424.36067 -349.113934)
			(xy 424.376168 -349.166432) (xy 424.383999 -349.220607) (xy 424.384002 -349.275345) (xy 424.376178 -349.329521)
			(xy 424.360687 -349.38202) (xy 424.337847 -349.431765) (xy 424.308128 -349.477733) (xy 424.29049 -349.498666)
			(xy 424.281285 -349.510017) (xy 424.269105 -349.536566) (xy 424.264927 -349.565476) (xy 424.269091 -349.594387)
			(xy 424.281258 -349.620943) (xy 424.29049 -349.63227) (xy 424.308099 -349.653228) (xy 424.337823 -349.699192)
			(xy 424.36067 -349.748934) (xy 424.376168 -349.801432) (xy 424.383999 -349.855607) (xy 424.384002 -349.910345)
			(xy 424.376178 -349.964521) (xy 424.360687 -350.01702) (xy 424.337847 -350.066765) (xy 424.308128 -350.112733)
			(xy 424.29049 -350.133666) (xy 424.281285 -350.145017) (xy 424.269105 -350.171566) (xy 424.264927 -350.200476)
			(xy 424.269091 -350.229387) (xy 424.281258 -350.255943) (xy 424.29049 -350.26727) (xy 424.308099 -350.288228)
			(xy 424.337823 -350.334192) (xy 424.36067 -350.383934) (xy 424.376168 -350.436432) (xy 424.383999 -350.490607)
			(xy 424.384002 -350.545345) (xy 424.376178 -350.599521) (xy 424.360687 -350.65202) (xy 424.337847 -350.701765)
			(xy 424.308128 -350.747733) (xy 424.29049 -350.768666) (xy 424.281285 -350.780017) (xy 424.269105 -350.806566)
			(xy 424.264927 -350.835476) (xy 424.269091 -350.864387) (xy 424.281258 -350.890943) (xy 424.29049 -350.90227)
			(xy 424.308127 -350.923204) (xy 424.337839 -350.969176) (xy 424.360676 -351.018923) (xy 424.376167 -351.071423)
			(xy 424.383996 -351.125599) (xy 424.38447 -351.152968) (xy 427.95444 -351.152968) (xy 427.954878 -351.125597)
			(xy 427.962701 -351.071416) (xy 427.978196 -351.018912) (xy 428.001044 -350.969166) (xy 428.030775 -350.9232)
			(xy 428.04842 -350.90227) (xy 428.057686 -350.890965) (xy 428.069857 -350.864399) (xy 428.074023 -350.835476)
			(xy 428.069843 -350.806555) (xy 428.05766 -350.779994) (xy 428.04842 -350.768666) (xy 428.030748 -350.747758)
			(xy 428.001025 -350.701786) (xy 427.978182 -350.652036) (xy 427.962689 -350.59953) (xy 427.954863 -350.545348)
			(xy 427.954867 -350.490604) (xy 427.962699 -350.436423) (xy 427.978199 -350.383919) (xy 428.001049 -350.334172)
			(xy 428.030777 -350.288203) (xy 428.04842 -350.26727) (xy 428.057686 -350.255965) (xy 428.069857 -350.229399)
			(xy 428.074023 -350.200476) (xy 428.069843 -350.171555) (xy 428.05766 -350.144994) (xy 428.04842 -350.133666)
			(xy 428.030748 -350.112758) (xy 428.001025 -350.066786) (xy 427.978182 -350.017036) (xy 427.962689 -349.96453)
			(xy 427.954863 -349.910348) (xy 427.954867 -349.855604) (xy 427.962699 -349.801423) (xy 427.978199 -349.748919)
			(xy 428.001049 -349.699172) (xy 428.030777 -349.653203) (xy 428.04842 -349.63227) (xy 428.057686 -349.620965)
			(xy 428.069857 -349.594399) (xy 428.074023 -349.565476) (xy 428.069843 -349.536555) (xy 428.05766 -349.509994)
			(xy 428.04842 -349.498666) (xy 428.030748 -349.477758) (xy 428.001025 -349.431786) (xy 427.978182 -349.382036)
			(xy 427.962689 -349.32953) (xy 427.954863 -349.275348) (xy 427.954867 -349.220604) (xy 427.962699 -349.166423)
			(xy 427.978199 -349.113919) (xy 428.001049 -349.064172) (xy 428.030777 -349.018203) (xy 428.04842 -348.99727)
			(xy 428.057686 -348.985965) (xy 428.069857 -348.959399) (xy 428.074023 -348.930476) (xy 428.069843 -348.901555)
			(xy 428.05766 -348.874994) (xy 428.04842 -348.863666) (xy 428.030748 -348.842758) (xy 428.001025 -348.796786)
			(xy 427.978182 -348.747036) (xy 427.962689 -348.69453) (xy 427.954863 -348.640348) (xy 427.954867 -348.585604)
			(xy 427.962699 -348.531423) (xy 427.978199 -348.478919) (xy 428.001049 -348.429172) (xy 428.030777 -348.383203)
			(xy 428.04842 -348.36227) (xy 428.057686 -348.350965) (xy 428.069857 -348.324399) (xy 428.074023 -348.295476)
			(xy 428.069843 -348.266555) (xy 428.05766 -348.239994) (xy 428.04842 -348.228666) (xy 428.030748 -348.207758)
			(xy 428.001025 -348.161786) (xy 427.978182 -348.112036) (xy 427.962689 -348.05953) (xy 427.954863 -348.005348)
			(xy 427.954867 -347.950604) (xy 427.962699 -347.896423) (xy 427.978199 -347.843919) (xy 428.001049 -347.794172)
			(xy 428.030777 -347.748203) (xy 428.04842 -347.72727) (xy 428.057686 -347.715965) (xy 428.069857 -347.689399)
			(xy 428.074023 -347.660476) (xy 428.069843 -347.631555) (xy 428.05766 -347.604994) (xy 428.04842 -347.593666)
			(xy 428.030801 -347.572717) (xy 428.001086 -347.526749) (xy 427.978246 -347.477006) (xy 427.96275 -347.424509)
			(xy 427.954917 -347.370336) (xy 427.95444 -347.342968) (xy 427.954825 -347.315712) (xy 427.962588 -347.261756)
			(xy 427.97795 -347.209454) (xy 428.0006 -347.15987) (xy 428.030076 -347.114015) (xy 428.065778 -347.072821)
			(xy 428.106979 -347.037128) (xy 428.15284 -347.007662) (xy 428.202429 -346.985022) (xy 428.254734 -346.969671)
			(xy 428.308692 -346.96192) (xy 428.335948 -346.96146) (xy 428.363987 -346.961989) (xy 428.419463 -346.970182)
			(xy 428.473145 -346.9864) (xy 428.523877 -347.010293) (xy 428.570571 -347.041349) (xy 428.591726 -347.059758)
			(xy 428.603168 -347.069403) (xy 428.630211 -347.082183) (xy 428.659798 -347.086569) (xy 428.689385 -347.082183)
			(xy 428.716428 -347.069403) (xy 428.72787 -347.059758) (xy 428.74901 -347.041324) (xy 428.79569 -347.010233)
			(xy 428.846424 -346.98632) (xy 428.900115 -346.970103) (xy 428.955604 -346.961932) (xy 428.983648 -346.96146)
			(xy 429.011018 -346.961942) (xy 429.065197 -346.969754) (xy 429.1177 -346.985238) (xy 429.167448 -347.008077)
			(xy 429.213414 -347.037799) (xy 429.234346 -347.05544) (xy 429.245674 -347.064676) (xy 429.272231 -347.076852)
			(xy 429.301148 -347.081025) (xy 429.330065 -347.076852) (xy 429.356622 -347.064676) (xy 429.36795 -347.05544)
			(xy 429.388895 -347.037817) (xy 429.434864 -347.008101) (xy 429.484608 -346.985262) (xy 429.537106 -346.969767)
			(xy 429.59128 -346.961936) (xy 429.618648 -346.96146) (xy 429.645899 -346.961933) (xy 429.699845 -346.969695)
			(xy 429.752138 -346.985055) (xy 429.801714 -347.007699) (xy 429.847562 -347.037168) (xy 429.888751 -347.07286)
			(xy 429.924442 -347.11405) (xy 429.953908 -347.1599) (xy 429.976551 -347.209477) (xy 429.991908 -347.26177)
			(xy 429.999668 -347.315717) (xy 430.000156 -347.342968) (xy 429.999682 -347.370338) (xy 429.991868 -347.424517)
			(xy 429.976381 -347.477021) (xy 429.953541 -347.526768) (xy 429.923817 -347.572734) (xy 429.906176 -347.593666)
			(xy 429.896972 -347.605017) (xy 429.884794 -347.631567) (xy 429.880616 -347.660476) (xy 429.88478 -347.689387)
			(xy 429.896946 -347.715942) (xy 429.906176 -347.72727) (xy 429.923785 -347.748228) (xy 429.953511 -347.794192)
			(xy 429.976358 -347.843934) (xy 429.991857 -347.896432) (xy 429.999688 -347.950607) (xy 429.999692 -348.005345)
			(xy 429.991867 -348.059521) (xy 429.976375 -348.112021) (xy 429.953534 -348.161766) (xy 429.923814 -348.207733)
			(xy 429.906176 -348.228666) (xy 429.896972 -348.240017) (xy 429.884794 -348.266567) (xy 429.880616 -348.295476)
			(xy 429.88478 -348.324387) (xy 429.896946 -348.350942) (xy 429.906176 -348.36227) (xy 429.923785 -348.383228)
			(xy 429.953511 -348.429192) (xy 429.976358 -348.478934) (xy 429.991857 -348.531432) (xy 429.999688 -348.585607)
			(xy 429.999692 -348.640345) (xy 429.991867 -348.694521) (xy 429.976375 -348.747021) (xy 429.953534 -348.796766)
			(xy 429.923814 -348.842733) (xy 429.906176 -348.863666) (xy 429.896972 -348.875017) (xy 429.884794 -348.901567)
			(xy 429.880616 -348.930476) (xy 429.88478 -348.959387) (xy 429.896946 -348.985942) (xy 429.906176 -348.99727)
			(xy 429.923785 -349.018228) (xy 429.953511 -349.064192) (xy 429.976358 -349.113934) (xy 429.991857 -349.166432)
			(xy 429.999688 -349.220607) (xy 429.999692 -349.275345) (xy 429.991867 -349.329521) (xy 429.976375 -349.382021)
			(xy 429.953534 -349.431766) (xy 429.923814 -349.477733) (xy 429.906176 -349.498666) (xy 429.896972 -349.510017)
			(xy 429.884794 -349.536567) (xy 429.880616 -349.565476) (xy 429.88478 -349.594387) (xy 429.896946 -349.620942)
			(xy 429.906176 -349.63227) (xy 429.923785 -349.653228) (xy 429.953511 -349.699192) (xy 429.976358 -349.748934)
			(xy 429.991857 -349.801432) (xy 429.999688 -349.855607) (xy 429.999692 -349.910345) (xy 429.991867 -349.964521)
			(xy 429.976375 -350.017021) (xy 429.953534 -350.066766) (xy 429.923814 -350.112733) (xy 429.906176 -350.133666)
			(xy 429.896972 -350.145017) (xy 429.884794 -350.171567) (xy 429.880616 -350.200476) (xy 429.88478 -350.229387)
			(xy 429.896946 -350.255942) (xy 429.906176 -350.26727) (xy 429.923785 -350.288228) (xy 429.953511 -350.334192)
			(xy 429.976358 -350.383934) (xy 429.991857 -350.436432) (xy 429.999688 -350.490607) (xy 429.999692 -350.545345)
			(xy 429.991867 -350.599521) (xy 429.976375 -350.652021) (xy 429.953534 -350.701766) (xy 429.923814 -350.747733)
			(xy 429.906176 -350.768666) (xy 429.896972 -350.780017) (xy 429.884794 -350.806567) (xy 429.880616 -350.835476)
			(xy 429.88478 -350.864387) (xy 429.896946 -350.890942) (xy 429.906176 -350.90227) (xy 429.923811 -350.923206)
			(xy 429.953524 -350.969177) (xy 429.976361 -351.018924) (xy 429.991853 -351.071424) (xy 429.999682 -351.125599)
			(xy 430.000156 -351.152968) (xy 429.999592 -351.180216) (xy 429.991841 -351.234159) (xy 429.976493 -351.286449)
			(xy 429.953859 -351.336023) (xy 429.9244 -351.381871) (xy 429.888717 -351.42306) (xy 429.847535 -351.458752)
			(xy 429.801693 -351.48822) (xy 429.752124 -351.510865) (xy 429.699837 -351.526224) (xy 429.645896 -351.533986)
			(xy 429.618648 -351.534476) (xy 429.591279 -351.533988) (xy 429.5371 -351.526176) (xy 429.484597 -351.510693)
			(xy 429.43485 -351.487856) (xy 429.388882 -351.458135) (xy 429.36795 -351.440496) (xy 429.356622 -351.43126)
			(xy 429.330065 -351.419084) (xy 429.301148 -351.414911) (xy 429.272231 -351.419084) (xy 429.245674 -351.43126)
			(xy 429.234346 -351.440496) (xy 429.213407 -351.458126) (xy 429.167436 -351.48784) (xy 429.11769 -351.510677)
			(xy 429.065191 -351.52617) (xy 429.011017 -351.534001) (xy 428.983648 -351.534476) (xy 428.955608 -351.533966)
			(xy 428.900131 -351.525771) (xy 428.846448 -351.509549) (xy 428.795716 -351.485651) (xy 428.749024 -351.45459)
			(xy 428.72787 -351.436178) (xy 428.716428 -351.426533) (xy 428.689385 -351.413753) (xy 428.659798 -351.409367)
			(xy 428.630211 -351.413753) (xy 428.603168 -351.426533) (xy 428.591726 -351.436178) (xy 428.570593 -351.45462)
			(xy 428.52391 -351.485709) (xy 428.473174 -351.509619) (xy 428.419482 -351.525835) (xy 428.363992 -351.534005)
			(xy 428.335948 -351.534476) (xy 428.308695 -351.534) (xy 428.254743 -351.526249) (xy 428.202443 -351.510897)
			(xy 428.152861 -351.488258) (xy 428.107006 -351.458792) (xy 428.065812 -351.423099) (xy 428.030118 -351.381907)
			(xy 428.00065 -351.336053) (xy 427.978008 -351.286472) (xy 427.962655 -351.234173) (xy 427.954901 -351.180221)
			(xy 427.95444 -351.152968) (xy 424.38447 -351.152968) (xy 424.384015 -351.180222) (xy 424.376261 -351.234175)
			(xy 424.360907 -351.286475) (xy 424.338266 -351.336058) (xy 424.308798 -351.381913) (xy 424.273103 -351.423107)
			(xy 424.231908 -351.458801) (xy 424.186053 -351.488269) (xy 424.13647 -351.510909) (xy 424.084169 -351.526262)
			(xy 424.030216 -351.534015) (xy 424.002962 -351.534476) (xy 423.97492 -351.534017) (xy 423.91944 -351.52581)
			(xy 423.865757 -351.509576) (xy 423.815026 -351.485667) (xy 423.768336 -351.454594) (xy 423.747184 -351.436178)
			(xy 423.735742 -351.426533) (xy 423.708699 -351.413753) (xy 423.679112 -351.409367) (xy 423.649525 -351.413753)
			(xy 423.622482 -351.426533) (xy 423.61104 -351.436178) (xy 423.589902 -351.454613) (xy 423.54322 -351.485703)
			(xy 423.492486 -351.509615) (xy 423.438794 -351.525832) (xy 423.383306 -351.534004) (xy 423.355262 -351.534476)
			(xy 423.326277 -351.533916) (xy 423.268972 -351.525162) (xy 423.213645 -351.50786) (xy 423.187368 -351.495614)
			(xy 423.173903 -351.489607) (xy 423.144845 -351.484715) (xy 423.1156 -351.488325) (xy 423.088603 -351.500136)
			(xy 423.066103 -351.519165) (xy 423.049974 -351.543826) (xy 423.041559 -351.572066) (xy 423.041064 -351.5868)
			(xy 423.041064 -355.101652) (xy 423.405808 -355.466142) (xy 423.42316 -355.484116) (xy 423.452506 -355.524548)
			(xy 423.47516 -355.569075) (xy 423.490562 -355.616601) (xy 423.498332 -355.665952) (xy 423.498772 -355.690932)
			(xy 423.498772 -363.171232) (xy 429.73955 -363.171232) (xy 429.743621 -363.11561) (xy 429.755747 -363.061173)
			(xy 429.77567 -363.009082) (xy 429.802966 -362.960447) (xy 429.837052 -362.916304) (xy 429.877201 -362.877595)
			(xy 429.922559 -362.845144) (xy 429.972159 -362.819643) (xy 430.024943 -362.801636) (xy 430.079786 -362.791506)
			(xy 430.13552 -362.789469) (xy 430.190957 -362.795569) (xy 430.244914 -362.809675) (xy 430.296243 -362.831487)
			(xy 430.343849 -362.860541) (xy 430.386717 -362.896216) (xy 430.423934 -362.937753) (xy 430.454707 -362.984266)
			(xy 430.478379 -363.034763) (xy 430.494447 -363.08817) (xy 430.502567 -363.143346) (xy 430.503076 -363.171232)
			(xy 430.502567 -363.199118) (xy 430.494447 -363.254294) (xy 430.478379 -363.307701) (xy 430.454707 -363.358198)
			(xy 430.423934 -363.404711) (xy 430.386717 -363.446248) (xy 430.343849 -363.481923) (xy 430.296243 -363.510977)
			(xy 430.244914 -363.532789) (xy 430.190957 -363.546895) (xy 430.13552 -363.552995) (xy 430.079786 -363.550958)
			(xy 430.024943 -363.540828) (xy 429.972159 -363.522821) (xy 429.922559 -363.49732) (xy 429.877201 -363.464869)
			(xy 429.837052 -363.42616) (xy 429.802966 -363.382017) (xy 429.77567 -363.333382) (xy 429.755747 -363.281291)
			(xy 429.743621 -363.226854) (xy 429.73955 -363.171232) (xy 423.498772 -363.171232) (xy 423.498772 -363.714284)
			(xy 423.498293 -363.739259) (xy 423.490501 -363.788596) (xy 423.475091 -363.836108) (xy 423.452441 -363.880626)
			(xy 423.423108 -363.921056) (xy 423.405808 -363.939074) (xy 423.394382 -363.9505) (xy 426.141163 -363.9505)
			(xy 426.145331 -363.894891) (xy 426.157739 -363.840523) (xy 426.178111 -363.788612) (xy 426.205992 -363.740317)
			(xy 426.240759 -363.696717) (xy 426.281635 -363.658784) (xy 426.327709 -363.627368) (xy 426.37795 -363.603168)
			(xy 426.431236 -363.586726) (xy 426.486377 -363.57841) (xy 426.51426 -363.577886) (xy 426.541591 -363.57838)
			(xy 426.595669 -363.586348) (xy 426.648001 -363.602134) (xy 426.697465 -363.625399) (xy 426.742997 -363.655643)
			(xy 426.78362 -363.692216) (xy 426.818463 -363.734334) (xy 426.83303 -363.757464) (xy 426.840956 -363.769687)
			(xy 426.862424 -363.789363) (xy 426.888577 -363.80217) (xy 426.917283 -363.807065) (xy 426.946203 -363.803649)
			(xy 426.959776 -363.798358) (xy 426.982991 -363.788881) (xy 427.031321 -363.775526) (xy 427.081009 -363.768793)
			(xy 427.10608 -363.768386) (xy 427.131148 -363.768832) (xy 427.180831 -363.775573) (xy 427.229166 -363.788896)
			(xy 427.252384 -363.798358) (xy 427.265997 -363.803497) (xy 427.294878 -363.806878) (xy 427.323541 -363.801989)
			(xy 427.349668 -363.789227) (xy 427.371145 -363.769625) (xy 427.37913 -363.757464) (xy 427.393699 -363.734333)
			(xy 427.428542 -363.692212) (xy 427.469165 -363.655633) (xy 427.514696 -363.625382) (xy 427.564158 -363.602106)
			(xy 427.616489 -363.586306) (xy 427.670568 -363.57832) (xy 427.725232 -363.57832) (xy 427.779311 -363.586306)
			(xy 427.831642 -363.602106) (xy 427.881104 -363.625382) (xy 427.926635 -363.655633) (xy 427.967258 -363.692212)
			(xy 428.002101 -363.734333) (xy 428.01667 -363.757464) (xy 428.024558 -363.769715) (xy 428.046036 -363.78939)
			(xy 428.0722 -363.802194) (xy 428.100915 -363.807082) (xy 428.129841 -363.803655) (xy 428.143416 -363.798358)
			(xy 428.166626 -363.788869) (xy 428.214959 -363.775518) (xy 428.264648 -363.76879) (xy 428.28972 -363.768386)
			(xy 428.316563 -363.768828) (xy 428.369694 -363.776536) (xy 428.421169 -363.791788) (xy 428.469922 -363.814269)
			(xy 428.514944 -363.843513) (xy 428.555304 -363.878916) (xy 428.590165 -363.919745) (xy 428.618807 -363.965153)
			(xy 428.640635 -364.014202) (xy 428.648368 -364.039912) (xy 428.653106 -364.054383) (xy 428.669606 -364.079945)
			(xy 428.692905 -364.099513) (xy 428.720934 -364.111348) (xy 428.751206 -364.1144) (xy 428.781034 -364.108398)
			(xy 428.794672 -364.101634) (xy 428.822813 -364.086991) (xy 428.882767 -364.066268) (xy 428.945327 -364.055774)
			(xy 428.977044 -364.055152) (xy 428.995063 -364.055372) (xy 429.030938 -364.058807) (xy 429.048672 -364.06201)
			(xy 429.063881 -364.064356) (xy 429.094438 -364.060834) (xy 429.122561 -364.048373) (xy 429.145697 -364.028104)
			(xy 429.161749 -364.001864) (xy 429.16602 -363.98708) (xy 429.173431 -363.960039) (xy 429.195057 -363.908313)
			(xy 429.224019 -363.860306) (xy 429.259692 -363.817054) (xy 429.30131 -363.779486) (xy 429.347976 -363.748411)
			(xy 429.398687 -363.724498) (xy 429.45235 -363.708261) (xy 429.507811 -363.700051) (xy 429.535844 -363.699552)
			(xy 429.563095 -363.700037) (xy 429.61704 -363.707798) (xy 429.669332 -363.723157) (xy 429.718907 -363.7458)
			(xy 429.764755 -363.775267) (xy 429.805944 -363.810959) (xy 429.841635 -363.852148) (xy 429.871102 -363.897996)
			(xy 429.893744 -363.947571) (xy 429.909103 -363.999864) (xy 429.916864 -364.053809) (xy 429.917352 -364.08106)
			(xy 429.916876 -364.108634) (xy 429.908928 -364.163207) (xy 429.893206 -364.216068) (xy 429.870038 -364.266114)
			(xy 429.839906 -364.312304) (xy 429.803439 -364.353675) (xy 429.782732 -364.37189) (xy 429.771872 -364.381828)
			(xy 429.755794 -364.406466) (xy 429.747403 -364.434664) (xy 429.747395 -364.464084) (xy 429.755772 -364.492287)
			(xy 429.771838 -364.516933) (xy 429.782732 -364.52683) (xy 429.803396 -364.54509) (xy 429.839856 -364.586457)
			(xy 429.869981 -364.632642) (xy 429.893143 -364.682683) (xy 429.908859 -364.735537) (xy 429.916801 -364.790103)
			(xy 429.916805 -364.845245) (xy 429.90887 -364.899812) (xy 429.893161 -364.952669) (xy 429.870006 -365.002713)
			(xy 429.839888 -365.048902) (xy 429.803433 -365.090273) (xy 429.782732 -365.10849) (xy 429.771872 -365.118428)
			(xy 429.755794 -365.143066) (xy 429.747403 -365.171264) (xy 429.747395 -365.200684) (xy 429.755772 -365.228887)
			(xy 429.771838 -365.253533) (xy 429.782732 -365.26343) (xy 429.803467 -365.281615) (xy 429.839934 -365.32299)
			(xy 429.870063 -365.369186) (xy 429.893224 -365.419239) (xy 429.908935 -365.472105) (xy 429.91687 -365.526684)
			(xy 429.917352 -365.55426) (xy 429.916785 -365.581508) (xy 429.909035 -365.635451) (xy 429.893687 -365.687741)
			(xy 429.871054 -365.737315) (xy 429.841596 -365.783164) (xy 429.805913 -365.824353) (xy 429.764731 -365.860045)
			(xy 429.718889 -365.889513) (xy 429.66932 -365.912158) (xy 429.617033 -365.927517) (xy 429.563092 -365.935279)
			(xy 429.535844 -365.935768) (xy 429.507989 -365.935229) (xy 429.452873 -365.927111) (xy 429.399522 -365.91107)
			(xy 429.349068 -365.887446) (xy 429.302582 -365.856741) (xy 429.261052 -365.819607) (xy 429.225359 -365.776832)
			(xy 429.196261 -365.729325) (xy 429.174375 -365.678093) (xy 429.166782 -365.651288) (xy 429.162503 -365.637174)
			(xy 429.147112 -365.612032) (xy 429.125194 -365.592318) (xy 429.098568 -365.579666) (xy 429.069441 -365.575125)
			(xy 429.054768 -365.576612) (xy 429.041752 -365.578282) (xy 429.015567 -365.580061) (xy 429.002444 -365.580168)
			(xy 428.988295 -365.58007) (xy 428.960072 -365.578039) (xy 428.946056 -365.576104) (xy 428.932707 -365.574531)
			(xy 428.906016 -365.577627) (xy 428.881063 -365.587594) (xy 428.859584 -365.603737) (xy 428.843071 -365.624934)
			(xy 428.832675 -365.64971) (xy 428.830486 -365.662972) (xy 428.826449 -365.690134) (xy 428.811471 -365.742967)
			(xy 428.789074 -365.793107) (xy 428.75972 -365.839519) (xy 428.724017 -365.881243) (xy 428.682701 -365.917419)
			(xy 428.636627 -365.947298) (xy 428.586745 -365.970264) (xy 428.534086 -365.985843) (xy 428.479738 -365.993712)
			(xy 428.45228 -365.994188) (xy 428.425027 -365.993741) (xy 428.371077 -365.985981) (xy 428.318781 -365.970622)
			(xy 428.269202 -365.947977) (xy 428.223351 -365.918507) (xy 428.18216 -365.882812) (xy 428.146469 -365.841617)
			(xy 428.117003 -365.795763) (xy 428.094364 -365.746182) (xy 428.07901 -365.693884) (xy 428.071256 -365.639933)
			(xy 428.070772 -365.61268) (xy 428.071303 -365.585108) (xy 428.079243 -365.530538) (xy 428.094956 -365.47768)
			(xy 428.118114 -365.427634) (xy 428.148235 -365.381443) (xy 428.18469 -365.340068) (xy 428.205392 -365.32185)
			(xy 428.21631 -365.311972) (xy 428.232382 -365.287316) (xy 428.240764 -365.259103) (xy 428.24076 -365.229671)
			(xy 428.232371 -365.20146) (xy 428.216292 -365.176809) (xy 428.205392 -365.16691) (xy 428.184681 -365.148699)
			(xy 428.148211 -365.10733) (xy 428.118079 -365.06114) (xy 428.094913 -365.011092) (xy 428.079197 -364.95823)
			(xy 428.071257 -364.903655) (xy 428.070772 -364.87608) (xy 428.071239 -364.849579) (xy 428.078582 -364.797089)
			(xy 428.093124 -364.746122) (xy 428.114584 -364.697659) (xy 428.142548 -364.652636) (xy 428.159164 -364.631986)
			(xy 428.168558 -364.619807) (xy 428.180349 -364.591418) (xy 428.183178 -364.560808) (xy 428.17679 -364.530739)
			(xy 428.161762 -364.503922) (xy 428.13945 -364.482778) (xy 428.12589 -364.475522) (xy 428.102212 -364.463399)
			(xy 428.058228 -364.433483) (xy 428.018943 -364.397619) (xy 427.985156 -364.356534) (xy 427.97095 -364.334044)
			(xy 427.963041 -364.321808) (xy 427.941569 -364.302132) (xy 427.915411 -364.289326) (xy 427.8867 -364.284434)
			(xy 427.857778 -364.287856) (xy 427.844204 -364.29315) (xy 427.820992 -364.302633) (xy 427.77266 -364.315986)
			(xy 427.722971 -364.322717) (xy 427.6979 -364.323122) (xy 427.672831 -364.32269) (xy 427.623148 -364.315945)
			(xy 427.574814 -364.302615) (xy 427.551596 -364.29315) (xy 427.537991 -364.287986) (xy 427.509106 -364.28461)
			(xy 427.480439 -364.289503) (xy 427.45431 -364.302271) (xy 427.432834 -364.32188) (xy 427.42485 -364.334044)
			(xy 427.410281 -364.357175) (xy 427.375438 -364.399296) (xy 427.334815 -364.435875) (xy 427.289284 -364.466126)
			(xy 427.239822 -364.489402) (xy 427.187491 -364.505202) (xy 427.133412 -364.513188) (xy 427.078748 -364.513188)
			(xy 427.024669 -364.505202) (xy 426.972338 -364.489402) (xy 426.922876 -364.466126) (xy 426.877345 -364.435875)
			(xy 426.836722 -364.399296) (xy 426.801879 -364.357175) (xy 426.78731 -364.334044) (xy 426.779344 -364.321849)
			(xy 426.757887 -364.302173) (xy 426.731745 -364.289362) (xy 426.703048 -364.284459) (xy 426.674135 -364.287865)
			(xy 426.660564 -364.29315) (xy 426.637357 -364.302646) (xy 426.589022 -364.315994) (xy 426.539332 -364.32272)
			(xy 426.51426 -364.323122) (xy 426.486377 -364.32259) (xy 426.431236 -364.314274) (xy 426.37795 -364.297832)
			(xy 426.327709 -364.273632) (xy 426.281635 -364.242216) (xy 426.240759 -364.204283) (xy 426.205992 -364.160683)
			(xy 426.178111 -364.112388) (xy 426.157739 -364.060477) (xy 426.145331 -364.006109) (xy 426.141163 -363.9505)
			(xy 423.394382 -363.9505) (xy 422.718992 -364.62589) (xy 422.718992 -364.751874) (xy 422.789858 -364.751874)
			(xy 422.804336 -364.738158) (xy 422.825655 -364.718825) (xy 422.873053 -364.686181) (xy 422.924818 -364.66103)
			(xy 422.979773 -364.64394) (xy 423.036672 -364.635301) (xy 423.065448 -364.63478) (xy 423.092696 -364.635294)
			(xy 423.146637 -364.643055) (xy 423.198924 -364.658414) (xy 423.248494 -364.681057) (xy 423.294337 -364.710524)
			(xy 423.33552 -364.746214) (xy 423.371205 -364.787402) (xy 423.400666 -364.833248) (xy 423.423303 -364.882821)
			(xy 423.438655 -364.93511) (xy 423.44641 -364.989052) (xy 423.44641 -365.043548) (xy 423.438655 -365.09749)
			(xy 423.423303 -365.149779) (xy 423.400666 -365.199352) (xy 423.371205 -365.245198) (xy 423.33552 -365.286386)
			(xy 423.294337 -365.322076) (xy 423.248494 -365.351543) (xy 423.198924 -365.374186) (xy 423.146637 -365.389545)
			(xy 423.092696 -365.397306) (xy 423.065448 -365.397796) (xy 423.04007 -365.397381) (xy 422.989757 -365.390695)
			(xy 422.940776 -365.377394) (xy 422.893992 -365.357714) (xy 422.8719 -365.345218) (xy 422.858457 -365.337974)
			(xy 422.828747 -365.330993) (xy 422.7983 -365.333101) (xy 422.769835 -365.344111) (xy 422.745893 -365.363039)
			(xy 422.728613 -365.388196) (xy 422.719537 -365.417335) (xy 422.718992 -365.432594) (xy 422.718992 -365.783114)
			(xy 422.734021 -365.806701) (xy 422.757774 -365.857334) (xy 422.773888 -365.91089) (xy 422.782018 -365.966224)
			(xy 422.782492 -365.994188) (xy 422.782006 -366.021439) (xy 422.77425 -366.075387) (xy 422.758895 -366.127682)
			(xy 422.736253 -366.177259) (xy 422.706787 -366.223109) (xy 422.671096 -366.2643) (xy 422.629905 -366.299991)
			(xy 422.584055 -366.329457) (xy 422.534478 -366.352099) (xy 422.482183 -366.367454) (xy 422.428235 -366.37521)
			(xy 422.373733 -366.37521) (xy 422.319785 -366.367454) (xy 422.26749 -366.352099) (xy 422.217913 -366.329457)
			(xy 422.172063 -366.299991) (xy 422.130872 -366.2643) (xy 422.095181 -366.223109) (xy 422.065715 -366.177259)
			(xy 422.043073 -366.127682) (xy 422.027718 -366.075387) (xy 422.019962 -366.021439) (xy 422.019476 -365.994188)
			(xy 422.019915 -365.966221) (xy 422.028034 -365.91088) (xy 422.044153 -365.85732) (xy 422.067927 -365.806691)
			(xy 422.082976 -365.783114) (xy 422.082976 -364.494318) (xy 422.083472 -364.469332) (xy 422.091303 -364.419977)
			(xy 422.10676 -364.372455) (xy 422.129461 -364.327937) (xy 422.158848 -364.287518) (xy 422.176194 -364.269528)
			(xy 422.342818 -364.102904) (xy 422.353048 -364.091993) (xy 422.36715 -364.065629) (xy 422.373023 -364.036312)
			(xy 422.370165 -364.00655) (xy 422.358821 -363.978887) (xy 422.33996 -363.955688) (xy 422.315195 -363.938936)
			(xy 422.286643 -363.930063) (xy 422.271698 -363.929422) (xy 422.244554 -363.928775) (xy 422.190855 -363.920754)
			(xy 422.138836 -363.9052) (xy 422.089548 -363.88243) (xy 422.043985 -363.852901) (xy 422.003068 -363.817212)
			(xy 421.967625 -363.776082) (xy 421.93837 -363.730343) (xy 421.915895 -363.680919) (xy 421.900655 -363.628807)
			(xy 421.892955 -363.575061) (xy 421.892476 -363.547914) (xy 420.591359 -363.547914) (xy 420.5775 -363.549439)
			(xy 420.521766 -363.547402) (xy 420.466923 -363.537272) (xy 420.414139 -363.519265) (xy 420.364539 -363.493764)
			(xy 420.319181 -363.461313) (xy 420.279032 -363.422604) (xy 420.244946 -363.378461) (xy 420.21765 -363.329826)
			(xy 420.197727 -363.277735) (xy 420.185601 -363.223298) (xy 420.18153 -363.167676) (xy 412.864368 -363.167676)
			(xy 412.859217 -363.173775) (xy 412.846444 -363.200822) (xy 412.842063 -363.23041) (xy 412.84645 -363.259998)
			(xy 412.859228 -363.287043) (xy 412.868872 -363.298486) (xy 412.887318 -363.319615) (xy 412.918407 -363.366299)
			(xy 412.942317 -363.417036) (xy 412.958531 -363.470729) (xy 412.966699 -363.526219) (xy 412.96717 -363.554264)
			(xy 412.966684 -363.581515) (xy 412.958928 -363.635463) (xy 412.943573 -363.687758) (xy 412.920931 -363.737335)
			(xy 412.891465 -363.783185) (xy 412.855774 -363.824376) (xy 412.814583 -363.860067) (xy 412.768733 -363.889533)
			(xy 412.719156 -363.912175) (xy 412.666861 -363.92753) (xy 412.612913 -363.935286) (xy 412.558411 -363.935286)
			(xy 412.504463 -363.92753) (xy 412.452168 -363.912175) (xy 412.402591 -363.889533) (xy 412.356741 -363.860067)
			(xy 412.31555 -363.824376) (xy 412.279859 -363.783185) (xy 412.250393 -363.737335) (xy 412.227751 -363.687758)
			(xy 412.212396 -363.635463) (xy 412.20464 -363.581515) (xy 412.204154 -363.554264) (xy 411.868112 -363.554264)
			(xy 411.868112 -363.9505) (xy 416.452737 -363.9505) (xy 416.456906 -363.894879) (xy 416.469318 -363.840501)
			(xy 416.489697 -363.788581) (xy 416.517587 -363.740278) (xy 416.552365 -363.696672) (xy 416.593254 -363.658736)
			(xy 416.639341 -363.627319) (xy 416.689595 -363.603122) (xy 416.742895 -363.586686) (xy 416.79805 -363.578378)
			(xy 416.825938 -363.577886) (xy 416.853268 -363.578397) (xy 416.907345 -363.586362) (xy 416.959677 -363.602145)
			(xy 417.009141 -363.625407) (xy 417.054673 -363.655648) (xy 417.095297 -363.692219) (xy 417.13014 -363.734335)
			(xy 417.144708 -363.757464) (xy 417.152655 -363.769672) (xy 417.174117 -363.789348) (xy 417.200265 -363.802157)
			(xy 417.228966 -363.807056) (xy 417.257882 -363.803645) (xy 417.271454 -363.798358) (xy 417.29466 -363.788857)
			(xy 417.342995 -363.775511) (xy 417.392686 -363.768787) (xy 417.417758 -363.768386) (xy 417.442827 -363.768806)
			(xy 417.49251 -363.775558) (xy 417.540845 -363.788892) (xy 417.564062 -363.798358) (xy 417.577647 -363.803579)
			(xy 417.606542 -363.806943) (xy 417.635215 -363.802036) (xy 417.661347 -363.789254) (xy 417.682824 -363.769633)
			(xy 417.690808 -363.757464) (xy 417.705377 -363.734333) (xy 417.74022 -363.692212) (xy 417.780843 -363.655633)
			(xy 417.826374 -363.625382) (xy 417.875836 -363.602106) (xy 417.928167 -363.586306) (xy 417.982246 -363.57832)
			(xy 418.03691 -363.57832) (xy 418.090989 -363.586306) (xy 418.14332 -363.602106) (xy 418.192782 -363.625382)
			(xy 418.238313 -363.655633) (xy 418.278936 -363.692212) (xy 418.313779 -363.734333) (xy 418.328348 -363.757464)
			(xy 418.336257 -363.7697) (xy 418.35773 -363.789375) (xy 418.383887 -363.802181) (xy 418.412598 -363.807072)
			(xy 418.44152 -363.803652) (xy 418.455094 -363.798358) (xy 418.478307 -363.788876) (xy 418.526638 -363.775523)
			(xy 418.576327 -363.768791) (xy 418.601398 -363.768386) (xy 418.627622 -363.768832) (xy 418.679552 -363.776174)
			(xy 418.72994 -363.790728) (xy 418.777787 -363.812206) (xy 418.822149 -363.840183) (xy 418.862149 -363.874105)
			(xy 418.896994 -363.913303) (xy 418.925997 -363.957001) (xy 418.937694 -363.980476) (xy 418.9441 -363.992667)
			(xy 418.962164 -364.013433) (xy 418.985123 -364.028613) (xy 419.011303 -364.037104) (xy 419.038801 -364.038288)
			(xy 419.065615 -364.032078) (xy 419.089792 -364.018927) (xy 419.1 -364.009686) (xy 419.121475 -363.98975)
			(xy 419.169373 -363.956) (xy 419.221866 -363.929965) (xy 419.277721 -363.912257) (xy 419.335625 -363.903292)
			(xy 419.364922 -363.902752) (xy 419.382941 -363.902975) (xy 419.418816 -363.906408) (xy 419.43655 -363.90961)
			(xy 419.451762 -363.911934) (xy 419.482317 -363.908418) (xy 419.510438 -363.895963) (xy 419.533574 -363.875698)
			(xy 419.549626 -363.849463) (xy 419.553898 -363.83468) (xy 419.561329 -363.807646) (xy 419.582954 -363.75592)
			(xy 419.611913 -363.707915) (xy 419.647584 -363.664662) (xy 419.689199 -363.627094) (xy 419.735863 -363.596019)
			(xy 419.78657 -363.572104) (xy 419.840231 -363.555866) (xy 419.89569 -363.547652) (xy 419.923722 -363.547152)
			(xy 419.950972 -363.547657) (xy 420.004917 -363.555416) (xy 420.057209 -363.570772) (xy 420.106783 -363.593412)
			(xy 420.152632 -363.622877) (xy 420.193821 -363.658566) (xy 420.229512 -363.699754) (xy 420.258979 -363.745601)
			(xy 420.281622 -363.795174) (xy 420.29698 -363.847465) (xy 420.304742 -363.90141) (xy 420.30523 -363.92866)
			(xy 420.304726 -363.956233) (xy 420.29678 -364.010804) (xy 420.281062 -364.063662) (xy 420.257899 -364.113708)
			(xy 420.227774 -364.159899) (xy 420.191314 -364.201273) (xy 420.17061 -364.21949) (xy 420.159752 -364.229429)
			(xy 420.143677 -364.254067) (xy 420.135288 -364.282265) (xy 420.135281 -364.311684) (xy 420.143655 -364.339885)
			(xy 420.159718 -364.364532) (xy 420.17061 -364.37443) (xy 420.191275 -364.39269) (xy 420.227737 -364.434056)
			(xy 420.257864 -364.48024) (xy 420.281027 -364.530281) (xy 420.296744 -364.583136) (xy 420.304687 -364.637703)
			(xy 420.304691 -364.692845) (xy 420.296755 -364.747413) (xy 420.281046 -364.80027) (xy 420.257889 -364.850314)
			(xy 420.227769 -364.896503) (xy 420.191312 -364.937874) (xy 420.17061 -364.95609) (xy 420.159752 -364.966029)
			(xy 420.143677 -364.990667) (xy 420.135288 -365.018865) (xy 420.135281 -365.048284) (xy 420.143655 -365.076485)
			(xy 420.159718 -365.101132) (xy 420.17061 -365.11103) (xy 420.191341 -365.12922) (xy 420.227809 -365.170593)
			(xy 420.257939 -365.216788) (xy 420.281101 -365.26684) (xy 420.296813 -365.319706) (xy 420.304748 -365.374284)
			(xy 420.30523 -365.40186) (xy 420.304708 -365.429111) (xy 420.296957 -365.483059) (xy 420.281607 -365.535354)
			(xy 420.258971 -365.584932) (xy 420.229509 -365.630785) (xy 420.193821 -365.671977) (xy 420.152634 -365.707672)
			(xy 420.106787 -365.737141) (xy 420.057212 -365.759785) (xy 420.004919 -365.775143) (xy 419.950973 -365.782903)
			(xy 419.923722 -365.783368) (xy 419.895866 -365.782849) (xy 419.840749 -365.774727) (xy 419.787398 -365.758683)
			(xy 419.736944 -365.735057) (xy 419.690459 -365.704349) (xy 419.648929 -365.667213) (xy 419.613236 -365.624437)
			(xy 419.584138 -365.576927) (xy 419.562253 -365.525694) (xy 419.55466 -365.498888) (xy 419.550403 -365.484766)
			(xy 419.535007 -365.459622) (xy 419.513085 -365.439908) (xy 419.486453 -365.427258) (xy 419.45732 -365.422722)
			(xy 419.442646 -365.424212) (xy 419.42963 -365.425885) (xy 419.403445 -365.427662) (xy 419.390322 -365.427768)
			(xy 419.361422 -365.427257) (xy 419.304278 -365.418587) (xy 419.27653 -365.410496) (xy 419.262999 -365.40669)
			(xy 419.234907 -365.405954) (xy 419.207676 -365.412891) (xy 419.183359 -365.426976) (xy 419.163794 -365.447148)
			(xy 419.150457 -365.471882) (xy 419.144354 -365.499313) (xy 419.144704 -365.513366) (xy 419.145466 -365.53648)
			(xy 419.14498 -365.563731) (xy 419.137224 -365.617679) (xy 419.121869 -365.669974) (xy 419.099227 -365.719551)
			(xy 419.069761 -365.765401) (xy 419.03407 -365.806592) (xy 418.992879 -365.842283) (xy 418.947029 -365.871749)
			(xy 418.897452 -365.894391) (xy 418.845157 -365.909746) (xy 418.791209 -365.917502) (xy 418.736707 -365.917502)
			(xy 418.682759 -365.909746) (xy 418.630464 -365.894391) (xy 418.580887 -365.871749) (xy 418.535037 -365.842283)
			(xy 418.493846 -365.806592) (xy 418.458155 -365.765401) (xy 418.428689 -365.719551) (xy 418.406047 -365.669974)
			(xy 418.390692 -365.617679) (xy 418.382936 -365.563731) (xy 418.38245 -365.53648) (xy 418.382953 -365.508907)
			(xy 418.390896 -365.454335) (xy 418.406612 -365.401475) (xy 418.429775 -365.351428) (xy 418.459902 -365.305238)
			(xy 418.496365 -365.263866) (xy 418.51707 -365.24565) (xy 418.52799 -365.235773) (xy 418.544066 -365.211118)
			(xy 418.552449 -365.182904) (xy 418.552446 -365.15347) (xy 418.544055 -365.125259) (xy 418.527972 -365.100607)
			(xy 418.51707 -365.09071) (xy 418.496354 -365.072504) (xy 418.459886 -365.031133) (xy 418.429755 -364.984942)
			(xy 418.40659 -364.934893) (xy 418.390874 -364.88203) (xy 418.382935 -364.827455) (xy 418.38245 -364.79988)
			(xy 418.38292 -364.77338) (xy 418.390262 -364.720892) (xy 418.404802 -364.669925) (xy 418.42626 -364.621464)
			(xy 418.439854 -364.598712) (xy 418.446578 -364.587148) (xy 418.454271 -364.561535) (xy 418.455055 -364.534802)
			(xy 418.448875 -364.508782) (xy 418.436156 -364.485257) (xy 418.417769 -364.465837) (xy 418.40658 -364.458504)
			(xy 418.381664 -364.442569) (xy 418.336742 -364.404103) (xy 418.298456 -364.359028) (xy 418.282628 -364.334044)
			(xy 418.27474 -364.321793) (xy 418.253262 -364.302117) (xy 418.227099 -364.289313) (xy 418.198383 -364.284425)
			(xy 418.169457 -364.287852) (xy 418.155882 -364.29315) (xy 418.132672 -364.30264) (xy 418.084339 -364.31599)
			(xy 418.03465 -364.322718) (xy 418.009578 -364.323122) (xy 417.984509 -364.322697) (xy 417.934826 -364.315949)
			(xy 417.886491 -364.302616) (xy 417.863274 -364.29315) (xy 417.849677 -364.287963) (xy 417.820788 -364.284591)
			(xy 417.792118 -364.28949) (xy 417.765988 -364.302264) (xy 417.744512 -364.321878) (xy 417.736528 -364.334044)
			(xy 417.721959 -364.357175) (xy 417.687116 -364.399296) (xy 417.646493 -364.435875) (xy 417.600962 -364.466126)
			(xy 417.5515 -364.489402) (xy 417.499169 -364.505202) (xy 417.44509 -364.513188) (xy 417.390426 -364.513188)
			(xy 417.336347 -364.505202) (xy 417.284016 -364.489402) (xy 417.234554 -364.466126) (xy 417.189023 -364.435875)
			(xy 417.1484 -364.399296) (xy 417.113557 -364.357175) (xy 417.098988 -364.334044) (xy 417.091043 -364.321834)
			(xy 417.06958 -364.302158) (xy 417.043432 -364.289349) (xy 417.014731 -364.28445) (xy 416.985814 -364.287862)
			(xy 416.972242 -364.29315) (xy 416.949037 -364.302652) (xy 416.900702 -364.315998) (xy 416.85101 -364.322721)
			(xy 416.825938 -364.323122) (xy 416.79805 -364.322622) (xy 416.742895 -364.314314) (xy 416.689595 -364.297878)
			(xy 416.639341 -364.273681) (xy 416.593254 -364.242264) (xy 416.552365 -364.204328) (xy 416.517587 -364.160722)
			(xy 416.489697 -364.112419) (xy 416.469318 -364.060499) (xy 416.456906 -364.006121) (xy 416.452737 -363.9505)
			(xy 411.868112 -363.9505) (xy 411.868112 -364.87481) (xy 412.009639 -365.016288) (xy 412.995108 -365.016288)
			(xy 412.999179 -364.960666) (xy 413.011305 -364.906229) (xy 413.031228 -364.854138) (xy 413.058524 -364.805503)
			(xy 413.09261 -364.76136) (xy 413.132759 -364.722651) (xy 413.178117 -364.6902) (xy 413.227717 -364.664699)
			(xy 413.280501 -364.646692) (xy 413.335344 -364.636562) (xy 413.391078 -364.634525) (xy 413.446515 -364.640625)
			(xy 413.500472 -364.654731) (xy 413.551801 -364.676543) (xy 413.599407 -364.705597) (xy 413.642275 -364.741272)
			(xy 413.679492 -364.782809) (xy 413.710265 -364.829322) (xy 413.733937 -364.879819) (xy 413.750005 -364.933226)
			(xy 413.758125 -364.988402) (xy 413.758634 -365.016288) (xy 413.758125 -365.044174) (xy 413.750005 -365.09935)
			(xy 413.733937 -365.152757) (xy 413.710265 -365.203254) (xy 413.679492 -365.249767) (xy 413.642275 -365.291304)
			(xy 413.599407 -365.326979) (xy 413.551801 -365.356033) (xy 413.500472 -365.377845) (xy 413.446515 -365.391951)
			(xy 413.391078 -365.398051) (xy 413.335344 -365.396014) (xy 413.280501 -365.385884) (xy 413.227717 -365.367877)
			(xy 413.178117 -365.342376) (xy 413.132759 -365.309925) (xy 413.09261 -365.271216) (xy 413.058524 -365.227073)
			(xy 413.031228 -365.178438) (xy 413.011305 -365.126347) (xy 412.999179 -365.07191) (xy 412.995108 -365.016288)
			(xy 412.009639 -365.016288) (xy 412.608014 -365.614458) (xy 412.634684 -365.60887) (xy 412.653954 -365.605069)
			(xy 412.693022 -365.600997) (xy 412.712662 -365.600742) (xy 412.73992 -365.601102) (xy 412.793882 -365.608856)
			(xy 412.846192 -365.624211) (xy 412.895783 -365.646854) (xy 412.941647 -365.676325) (xy 412.98285 -365.712023)
			(xy 413.018552 -365.753222) (xy 413.048028 -365.799083) (xy 413.070676 -365.848673) (xy 413.086036 -365.90098)
			(xy 413.093795 -365.954942) (xy 413.093795 -366.009458) (xy 413.086036 -366.06342) (xy 413.070676 -366.115727)
			(xy 413.048028 -366.165317) (xy 413.018552 -366.211178) (xy 412.98285 -366.252377) (xy 412.941647 -366.288075)
			(xy 412.895783 -366.317546) (xy 412.846192 -366.340189) (xy 412.793882 -366.355544) (xy 412.73992 -366.363298)
			(xy 412.712662 -366.363758) (xy 412.684458 -366.363242) (xy 412.628666 -366.354938) (xy 412.574707 -366.338502)
			(xy 412.523759 -366.314292) (xy 412.500064 -366.298988) (xy 412.472253 -366.296109) (xy 412.418188 -366.281881)
			(xy 412.367451 -366.2584) (xy 412.321614 -366.226394) (xy 412.301436 -366.20704) (xy 411.325568 -365.231172)
			(xy 411.308236 -365.213179) (xy 411.278884 -365.172754) (xy 411.256226 -365.128231) (xy 411.240819 -365.080709)
			(xy 411.233045 -365.031361) (xy 411.232604 -365.006382) (xy 409.29306 -365.006382) (xy 409.29306 -371.73789)
			(xy 410.217874 -372.662704) (xy 410.22885 -372.67293) (xy 410.255294 -372.687066) (xy 410.284702 -372.692913)
			(xy 410.314542 -372.689968) (xy 410.34224 -372.678485) (xy 410.36541 -372.659454) (xy 410.382055 -372.634514)
			(xy 410.39074 -372.605815) (xy 410.391356 -372.590822) (xy 410.391356 -365.968788) (xy 410.391842 -365.941555)
			(xy 410.399593 -365.887643) (xy 410.414938 -365.835383) (xy 410.437564 -365.785839) (xy 410.467011 -365.740019)
			(xy 410.502678 -365.698856) (xy 410.543841 -365.663189) (xy 410.589661 -365.633742) (xy 410.639205 -365.611116)
			(xy 410.691465 -365.595771) (xy 410.745377 -365.58802) (xy 410.799843 -365.58802) (xy 410.853755 -365.595771)
			(xy 410.906015 -365.611116) (xy 410.955559 -365.633742) (xy 411.001379 -365.663189) (xy 411.042542 -365.698856)
			(xy 411.078209 -365.740019) (xy 411.107656 -365.785839) (xy 411.130282 -365.835383) (xy 411.145627 -365.887643)
			(xy 411.153378 -365.941555) (xy 411.153864 -365.968788) (xy 411.153864 -366.54486) (xy 413.801814 -366.54486)
			(xy 413.802256 -366.518544) (xy 413.809478 -366.466409) (xy 413.823793 -366.41576) (xy 413.844929 -366.367558)
			(xy 413.872487 -366.322717) (xy 413.905943 -366.282086) (xy 413.925004 -366.263936) (xy 413.935064 -366.254162)
			(xy 413.949759 -366.230278) (xy 413.957391 -366.203294) (xy 413.957384 -366.175252) (xy 413.949737 -366.148272)
			(xy 413.935029 -366.124396) (xy 413.925004 -366.114584) (xy 413.905918 -366.096456) (xy 413.87244 -366.055834)
			(xy 413.84487 -366.010993) (xy 413.823733 -365.962784) (xy 413.80943 -365.912125) (xy 413.802234 -365.85998)
			(xy 413.801814 -365.83366) (xy 413.8023 -365.806409) (xy 413.810056 -365.752461) (xy 413.825411 -365.700166)
			(xy 413.848053 -365.650589) (xy 413.877519 -365.604739) (xy 413.91321 -365.563548) (xy 413.954401 -365.527857)
			(xy 414.000251 -365.498391) (xy 414.049828 -365.475749) (xy 414.102123 -365.460394) (xy 414.156071 -365.452638)
			(xy 414.210573 -365.452638) (xy 414.264521 -365.460394) (xy 414.316816 -365.475749) (xy 414.366393 -365.498391)
			(xy 414.412243 -365.527857) (xy 414.453434 -365.563548) (xy 414.489125 -365.604739) (xy 414.518591 -365.650589)
			(xy 414.541233 -365.700166) (xy 414.556588 -365.752461) (xy 414.564344 -365.806409) (xy 414.56449 -365.81461)
			(xy 415.42716 -365.81461) (xy 415.427646 -365.787359) (xy 415.435402 -365.733411) (xy 415.450757 -365.681116)
			(xy 415.473399 -365.631539) (xy 415.502865 -365.585689) (xy 415.538556 -365.544498) (xy 415.579747 -365.508807)
			(xy 415.625597 -365.479341) (xy 415.675174 -365.456699) (xy 415.727469 -365.441344) (xy 415.781417 -365.433588)
			(xy 415.835919 -365.433588) (xy 415.889867 -365.441344) (xy 415.942162 -365.456699) (xy 415.991739 -365.479341)
			(xy 416.037589 -365.508807) (xy 416.07878 -365.544498) (xy 416.114471 -365.585689) (xy 416.143937 -365.631539)
			(xy 416.166579 -365.681116) (xy 416.181934 -365.733411) (xy 416.18969 -365.787359) (xy 416.190176 -365.81461)
			(xy 416.189939 -365.833277) (xy 416.18625 -365.870429) (xy 416.18281 -365.888778) (xy 416.180493 -365.903048)
			(xy 416.183021 -365.931832) (xy 416.193516 -365.958754) (xy 416.211135 -365.981656) (xy 416.234467 -365.998701)
			(xy 416.261641 -366.008525) (xy 416.276028 -366.009936) (xy 416.304683 -366.012287) (xy 416.360849 -366.024579)
			(xy 416.414535 -366.045157) (xy 416.464527 -366.073556) (xy 416.509692 -366.109134) (xy 416.549008 -366.151085)
			(xy 416.581587 -366.198459) (xy 416.606689 -366.250185) (xy 416.623747 -366.305091) (xy 416.632375 -366.361935)
			(xy 416.632898 -366.390682) (xy 416.632412 -366.417933) (xy 416.624656 -366.471881) (xy 416.609301 -366.524176)
			(xy 416.586659 -366.573753) (xy 416.57813 -366.587024) (xy 423.490136 -366.587024) (xy 423.490687 -366.558579)
			(xy 423.499137 -366.502321) (xy 423.515853 -366.447943) (xy 423.540465 -366.396652) (xy 423.572425 -366.349589)
			(xy 423.611023 -366.307797) (xy 423.632884 -366.28959) (xy 423.644312 -366.279599) (xy 423.66133 -366.25449)
			(xy 423.670235 -366.225493) (xy 423.670243 -366.19516) (xy 423.661353 -366.166158) (xy 423.644348 -366.14104)
			(xy 423.632884 -366.131094) (xy 423.610998 -366.112915) (xy 423.572397 -366.071118) (xy 423.540436 -366.02405)
			(xy 423.515824 -365.972754) (xy 423.499109 -365.918371) (xy 423.49066 -365.862107) (xy 423.490136 -365.83366)
			(xy 423.490622 -365.806409) (xy 423.498378 -365.752461) (xy 423.513733 -365.700166) (xy 423.536375 -365.650589)
			(xy 423.565841 -365.604739) (xy 423.601532 -365.563548) (xy 423.642723 -365.527857) (xy 423.688573 -365.498391)
			(xy 423.73815 -365.475749) (xy 423.790445 -365.460394) (xy 423.844393 -365.452638) (xy 423.898895 -365.452638)
			(xy 423.952843 -365.460394) (xy 424.005138 -365.475749) (xy 424.054715 -365.498391) (xy 424.100565 -365.527857)
			(xy 424.141756 -365.563548) (xy 424.177447 -365.604739) (xy 424.206913 -365.650589) (xy 424.229555 -365.700166)
			(xy 424.24491 -365.752461) (xy 424.252666 -365.806409) (xy 424.252812 -365.81461) (xy 425.115482 -365.81461)
			(xy 425.115968 -365.787359) (xy 425.123724 -365.733411) (xy 425.139079 -365.681116) (xy 425.161721 -365.631539)
			(xy 425.191187 -365.585689) (xy 425.226878 -365.544498) (xy 425.268069 -365.508807) (xy 425.313919 -365.479341)
			(xy 425.363496 -365.456699) (xy 425.415791 -365.441344) (xy 425.469739 -365.433588) (xy 425.524241 -365.433588)
			(xy 425.578189 -365.441344) (xy 425.630484 -365.456699) (xy 425.680061 -365.479341) (xy 425.725911 -365.508807)
			(xy 425.767102 -365.544498) (xy 425.802793 -365.585689) (xy 425.832259 -365.631539) (xy 425.854901 -365.681116)
			(xy 425.870256 -365.733411) (xy 425.878012 -365.787359) (xy 425.878498 -365.81461) (xy 425.878261 -365.833277)
			(xy 425.874571 -365.870429) (xy 425.871132 -365.888778) (xy 425.868794 -365.903046) (xy 425.871323 -365.931834)
			(xy 425.88182 -365.958759) (xy 425.899444 -365.981662) (xy 425.922781 -365.998707) (xy 425.94996 -366.008527)
			(xy 425.96435 -366.009936) (xy 425.993007 -366.012269) (xy 426.049173 -366.024563) (xy 426.10286 -366.045144)
			(xy 426.152851 -366.073546) (xy 426.198016 -366.109126) (xy 426.237332 -366.151079) (xy 426.26991 -366.198455)
			(xy 426.295011 -366.250182) (xy 426.312069 -366.305089) (xy 426.320697 -366.361934) (xy 426.32122 -366.390682)
			(xy 426.320734 -366.417933) (xy 426.312978 -366.471881) (xy 426.297623 -366.524176) (xy 426.274981 -366.573753)
			(xy 426.245515 -366.619603) (xy 426.209824 -366.660794) (xy 426.168633 -366.696485) (xy 426.122783 -366.725951)
			(xy 426.073206 -366.748593) (xy 426.020911 -366.763948) (xy 425.966963 -366.771704) (xy 425.912461 -366.771704)
			(xy 425.858513 -366.763948) (xy 425.806218 -366.748593) (xy 425.756641 -366.725951) (xy 425.710791 -366.696485)
			(xy 425.6696 -366.660794) (xy 425.633909 -366.619603) (xy 425.604443 -366.573753) (xy 425.581801 -366.524176)
			(xy 425.566446 -366.471881) (xy 425.55869 -366.417933) (xy 425.558204 -366.390682) (xy 425.55844 -366.372015)
			(xy 425.56213 -366.334863) (xy 425.56557 -366.316514) (xy 425.567914 -366.302247) (xy 425.565383 -366.273459)
			(xy 425.554885 -366.246533) (xy 425.53726 -366.22363) (xy 425.513922 -366.206585) (xy 425.486742 -366.196765)
			(xy 425.472352 -366.195356) (xy 425.443694 -366.19303) (xy 425.387527 -366.180735) (xy 425.33384 -366.160154)
			(xy 425.283849 -366.131752) (xy 425.238684 -366.096171) (xy 425.199367 -366.054217) (xy 425.16679 -366.00684)
			(xy 425.141688 -365.955112) (xy 425.124631 -365.900204) (xy 425.116004 -365.843358) (xy 425.115482 -365.81461)
			(xy 424.252812 -365.81461) (xy 424.253152 -365.83366) (xy 424.252665 -365.862107) (xy 424.244202 -365.918369)
			(xy 424.227473 -365.972748) (xy 424.20285 -366.024038) (xy 424.170879 -366.0711) (xy 424.13227 -366.112889)
			(xy 424.110404 -366.131094) (xy 424.098893 -366.140996) (xy 424.081878 -366.166131) (xy 424.072984 -366.19515)
			(xy 424.072992 -366.225502) (xy 424.081901 -366.254517) (xy 424.098929 -366.279643) (xy 424.110404 -366.28959)
			(xy 424.13228 -366.307781) (xy 424.170882 -366.349575) (xy 424.202845 -366.396641) (xy 424.227458 -366.447934)
			(xy 424.244176 -366.502315) (xy 424.246446 -366.517428) (xy 424.505626 -366.517428) (xy 424.509697 -366.461806)
			(xy 424.521823 -366.407369) (xy 424.541746 -366.355278) (xy 424.569042 -366.306643) (xy 424.603128 -366.2625)
			(xy 424.643277 -366.223791) (xy 424.688635 -366.19134) (xy 424.738235 -366.165839) (xy 424.791019 -366.147832)
			(xy 424.845862 -366.137702) (xy 424.901596 -366.135665) (xy 424.957033 -366.141765) (xy 425.01099 -366.155871)
			(xy 425.062319 -366.177683) (xy 425.109925 -366.206737) (xy 425.152793 -366.242412) (xy 425.19001 -366.283949)
			(xy 425.220783 -366.330462) (xy 425.244455 -366.380959) (xy 425.260523 -366.434366) (xy 425.268643 -366.489542)
			(xy 425.269152 -366.517428) (xy 425.268643 -366.545314) (xy 425.260523 -366.60049) (xy 425.244455 -366.653897)
			(xy 425.220783 -366.704394) (xy 425.19001 -366.750907) (xy 425.152793 -366.792444) (xy 425.109925 -366.828119)
			(xy 425.062319 -366.857173) (xy 425.01099 -366.878985) (xy 424.957033 -366.893091) (xy 424.901596 -366.899191)
			(xy 424.845862 -366.897154) (xy 424.791019 -366.887024) (xy 424.738235 -366.869017) (xy 424.688635 -366.843516)
			(xy 424.643277 -366.811065) (xy 424.603128 -366.772356) (xy 424.569042 -366.728213) (xy 424.541746 -366.679578)
			(xy 424.521823 -366.627487) (xy 424.509697 -366.57305) (xy 424.505626 -366.517428) (xy 424.246446 -366.517428)
			(xy 424.252627 -366.558577) (xy 424.253152 -366.587024) (xy 424.252666 -366.614275) (xy 424.24491 -366.668223)
			(xy 424.229555 -366.720518) (xy 424.206913 -366.770095) (xy 424.177447 -366.815945) (xy 424.141756 -366.857136)
			(xy 424.100565 -366.892827) (xy 424.054715 -366.922293) (xy 424.005138 -366.944935) (xy 423.952843 -366.96029)
			(xy 423.898895 -366.968046) (xy 423.844393 -366.968046) (xy 423.790445 -366.96029) (xy 423.73815 -366.944935)
			(xy 423.688573 -366.922293) (xy 423.642723 -366.892827) (xy 423.601532 -366.857136) (xy 423.565841 -366.815945)
			(xy 423.536375 -366.770095) (xy 423.513733 -366.720518) (xy 423.498378 -366.668223) (xy 423.490622 -366.614275)
			(xy 423.490136 -366.587024) (xy 416.57813 -366.587024) (xy 416.557193 -366.619603) (xy 416.521502 -366.660794)
			(xy 416.480311 -366.696485) (xy 416.434461 -366.725951) (xy 416.384884 -366.748593) (xy 416.332589 -366.763948)
			(xy 416.278641 -366.771704) (xy 416.224139 -366.771704) (xy 416.170191 -366.763948) (xy 416.117896 -366.748593)
			(xy 416.068319 -366.725951) (xy 416.022469 -366.696485) (xy 415.981278 -366.660794) (xy 415.945587 -366.619603)
			(xy 415.916121 -366.573753) (xy 415.893479 -366.524176) (xy 415.878124 -366.471881) (xy 415.870368 -366.417933)
			(xy 415.869882 -366.390682) (xy 415.870116 -366.372015) (xy 415.873808 -366.334863) (xy 415.877248 -366.316514)
			(xy 415.879613 -366.302249) (xy 415.877082 -366.273457) (xy 415.86658 -366.246528) (xy 415.848951 -366.223623)
			(xy 415.825608 -366.206579) (xy 415.798422 -366.196762) (xy 415.78403 -366.195356) (xy 415.755378 -366.192963)
			(xy 415.699213 -366.180679) (xy 415.645527 -366.160108) (xy 415.595534 -366.131715) (xy 415.550368 -366.096142)
			(xy 415.51105 -366.054196) (xy 415.478471 -366.006825) (xy 415.453368 -365.955102) (xy 415.43631 -365.900198)
			(xy 415.427682 -365.843356) (xy 415.42716 -365.81461) (xy 414.56449 -365.81461) (xy 414.56483 -365.83366)
			(xy 414.564387 -365.859976) (xy 414.557164 -365.91211) (xy 414.542848 -365.962758) (xy 414.521711 -366.01096)
			(xy 414.494155 -366.055802) (xy 414.4607 -366.096434) (xy 414.44164 -366.114584) (xy 414.431657 -366.124432)
			(xy 414.416951 -366.148293) (xy 414.409305 -366.175259) (xy 414.409298 -366.203287) (xy 414.416929 -366.230257)
			(xy 414.431622 -366.254126) (xy 414.44164 -366.263936) (xy 414.460725 -366.282065) (xy 414.494205 -366.322685)
			(xy 414.521776 -366.367527) (xy 414.542914 -366.415735) (xy 414.557217 -366.466394) (xy 414.564259 -366.517428)
			(xy 414.817304 -366.517428) (xy 414.821375 -366.461806) (xy 414.833501 -366.407369) (xy 414.853424 -366.355278)
			(xy 414.88072 -366.306643) (xy 414.914806 -366.2625) (xy 414.954955 -366.223791) (xy 415.000313 -366.19134)
			(xy 415.049913 -366.165839) (xy 415.102697 -366.147832) (xy 415.15754 -366.137702) (xy 415.213274 -366.135665)
			(xy 415.268711 -366.141765) (xy 415.322668 -366.155871) (xy 415.373997 -366.177683) (xy 415.421603 -366.206737)
			(xy 415.464471 -366.242412) (xy 415.501688 -366.283949) (xy 415.532461 -366.330462) (xy 415.556133 -366.380959)
			(xy 415.572201 -366.434366) (xy 415.580321 -366.489542) (xy 415.58083 -366.517428) (xy 415.580321 -366.545314)
			(xy 415.572201 -366.60049) (xy 415.556133 -366.653897) (xy 415.532461 -366.704394) (xy 415.501688 -366.750907)
			(xy 415.464471 -366.792444) (xy 415.421603 -366.828119) (xy 415.373997 -366.857173) (xy 415.322668 -366.878985)
			(xy 415.268711 -366.893091) (xy 415.213274 -366.899191) (xy 415.15754 -366.897154) (xy 415.102697 -366.887024)
			(xy 415.049913 -366.869017) (xy 415.000313 -366.843516) (xy 414.954955 -366.811065) (xy 414.914806 -366.772356)
			(xy 414.88072 -366.728213) (xy 414.853424 -366.679578) (xy 414.833501 -366.627487) (xy 414.821375 -366.57305)
			(xy 414.817304 -366.517428) (xy 414.564259 -366.517428) (xy 414.564412 -366.51854) (xy 414.56483 -366.54486)
			(xy 414.564344 -366.572111) (xy 414.556588 -366.626059) (xy 414.541233 -366.678354) (xy 414.518591 -366.727931)
			(xy 414.489125 -366.773781) (xy 414.453434 -366.814972) (xy 414.412243 -366.850663) (xy 414.366393 -366.880129)
			(xy 414.316816 -366.902771) (xy 414.264521 -366.918126) (xy 414.210573 -366.925882) (xy 414.156071 -366.925882)
			(xy 414.102123 -366.918126) (xy 414.049828 -366.902771) (xy 414.000251 -366.880129) (xy 413.954401 -366.850663)
			(xy 413.91321 -366.814972) (xy 413.877519 -366.773781) (xy 413.848053 -366.727931) (xy 413.825411 -366.678354)
			(xy 413.810056 -366.626059) (xy 413.8023 -366.572111) (xy 413.801814 -366.54486) (xy 411.153864 -366.54486)
			(xy 411.153864 -372.299218) (xy 413.591022 -372.299218) (xy 413.594749 -372.24597) (xy 413.605863 -372.193761)
			(xy 413.624146 -372.143611) (xy 413.649242 -372.096499) (xy 413.68066 -372.053346) (xy 413.717787 -372.014993)
			(xy 413.738568 -371.99824) (xy 413.750345 -371.988311) (xy 413.767866 -371.962997) (xy 413.777047 -371.933611)
			(xy 413.777053 -371.902825) (xy 413.767883 -371.873436) (xy 413.75037 -371.848116) (xy 413.738568 -371.83822)
			(xy 413.716087 -371.820026) (xy 413.676354 -371.778006) (xy 413.643415 -371.730471) (xy 413.618027 -371.678511)
			(xy 413.600769 -371.623314) (xy 413.592038 -371.566146) (xy 413.591502 -371.53723) (xy 413.591985 -371.50986)
			(xy 413.599799 -371.455682) (xy 413.615284 -371.403179) (xy 413.638122 -371.353432) (xy 413.667843 -371.307464)
			(xy 413.685482 -371.286532) (xy 413.694691 -371.275184) (xy 413.706874 -371.248634) (xy 413.711053 -371.219723)
			(xy 413.706887 -371.19081) (xy 413.694716 -371.164255) (xy 413.685482 -371.152928) (xy 413.667873 -371.131971)
			(xy 413.63815 -371.086006) (xy 413.615306 -371.036264) (xy 413.599809 -370.983766) (xy 413.591979 -370.929591)
			(xy 413.591975 -370.874854) (xy 413.599799 -370.820679) (xy 413.61529 -370.768179) (xy 413.638128 -370.718434)
			(xy 413.667845 -370.672466) (xy 413.685482 -370.651532) (xy 413.694691 -370.640184) (xy 413.706874 -370.613634)
			(xy 413.711053 -370.584723) (xy 413.706887 -370.55581) (xy 413.694716 -370.529255) (xy 413.685482 -370.517928)
			(xy 413.66784 -370.496999) (xy 413.638129 -370.451025) (xy 413.615294 -370.401277) (xy 413.599804 -370.348775)
			(xy 413.591976 -370.294599) (xy 413.591502 -370.26723) (xy 413.591983 -370.239977) (xy 413.599736 -370.186027)
			(xy 413.615089 -370.133728) (xy 413.637729 -370.084148) (xy 413.667195 -370.038294) (xy 413.702887 -369.997101)
			(xy 413.744078 -369.961407) (xy 413.78993 -369.931938) (xy 413.83951 -369.909296) (xy 413.891807 -369.893941)
			(xy 413.945757 -369.886185) (xy 413.97301 -369.885722) (xy 414.000381 -369.886177) (xy 414.05456 -369.893997)
			(xy 414.107064 -369.909488) (xy 414.156811 -369.932332) (xy 414.202777 -369.962059) (xy 414.223708 -369.979702)
			(xy 414.235036 -369.988938) (xy 414.261593 -370.001114) (xy 414.29051 -370.005287) (xy 414.319427 -370.001114)
			(xy 414.345984 -369.988938) (xy 414.357312 -369.979702) (xy 414.378267 -369.962091) (xy 414.424233 -369.932375)
			(xy 414.473975 -369.909533) (xy 414.526471 -369.894036) (xy 414.580642 -369.8862) (xy 414.60801 -369.885722)
			(xy 414.636925 -369.886297) (xy 414.694094 -369.895013) (xy 414.749292 -369.912259) (xy 414.801254 -369.93764)
			(xy 414.848789 -369.970574) (xy 414.890808 -370.010307) (xy 414.909 -370.032788) (xy 414.918897 -370.044593)
			(xy 414.944221 -370.062112) (xy 414.973614 -370.071288) (xy 415.004406 -370.071288) (xy 415.033799 -370.062112)
			(xy 415.059123 -370.044593) (xy 415.06902 -370.032788) (xy 415.087197 -370.010292) (xy 415.12922 -369.970559)
			(xy 415.176758 -369.937621) (xy 415.228722 -369.912235) (xy 415.283922 -369.894981) (xy 415.341093 -369.886255)
			(xy 415.37001 -369.885722) (xy 415.397264 -369.886146) (xy 415.451218 -369.893905) (xy 415.503519 -369.909264)
			(xy 415.553101 -369.931909) (xy 415.598956 -369.961381) (xy 415.640149 -369.997079) (xy 415.675843 -370.038276)
			(xy 415.70531 -370.084134) (xy 415.72795 -370.133719) (xy 415.743304 -370.186021) (xy 415.751057 -370.239975)
			(xy 415.751518 -370.26723) (xy 415.75109 -370.294602) (xy 415.743266 -370.348783) (xy 415.727769 -370.401288)
			(xy 415.704918 -370.451034) (xy 415.675184 -370.496998) (xy 415.657538 -370.517928) (xy 415.648269 -370.529232)
			(xy 415.636091 -370.555798) (xy 415.631922 -370.584723) (xy 415.636104 -370.613646) (xy 415.648294 -370.640206)
			(xy 415.657538 -370.651532) (xy 415.67521 -370.67244) (xy 415.704936 -370.718411) (xy 415.727782 -370.768162)
			(xy 415.743277 -370.820668) (xy 415.751104 -370.87485) (xy 415.7511 -370.929595) (xy 415.743267 -370.983777)
			(xy 415.727766 -371.036281) (xy 415.704914 -371.086028) (xy 415.675182 -371.131996) (xy 415.657538 -371.152928)
			(xy 415.648269 -371.164232) (xy 415.636091 -371.190798) (xy 415.631922 -371.219723) (xy 415.636104 -371.248646)
			(xy 415.648294 -371.275206) (xy 415.657538 -371.286532) (xy 415.675165 -371.307474) (xy 415.704877 -371.353444)
			(xy 415.727715 -371.40319) (xy 415.743209 -371.455688) (xy 415.751042 -371.509862) (xy 415.751518 -371.53723)
			(xy 415.75098 -371.566147) (xy 415.74226 -371.623318) (xy 415.725008 -371.678518) (xy 415.69962 -371.730481)
			(xy 415.666678 -371.778015) (xy 415.626937 -371.820031) (xy 415.604452 -371.83822) (xy 415.592613 -371.848083)
			(xy 415.575089 -371.873414) (xy 415.565913 -371.902817) (xy 415.565919 -371.933619) (xy 415.575106 -371.963019)
			(xy 415.592639 -371.988344) (xy 415.604452 -371.99824) (xy 415.625264 -372.014958) (xy 415.662394 -372.053316)
			(xy 415.693814 -372.096475) (xy 415.718912 -372.143593) (xy 415.737196 -372.193749) (xy 415.748311 -372.245964)
			(xy 415.75026 -372.273818) (xy 416.956522 -372.273818) (xy 416.960249 -372.22057) (xy 416.971363 -372.168361)
			(xy 416.989646 -372.118211) (xy 417.014742 -372.071099) (xy 417.04616 -372.027946) (xy 417.083287 -371.989593)
			(xy 417.104068 -371.97284) (xy 417.115845 -371.962911) (xy 417.133366 -371.937597) (xy 417.142547 -371.908211)
			(xy 417.142553 -371.877425) (xy 417.133383 -371.848036) (xy 417.11587 -371.822716) (xy 417.104068 -371.81282)
			(xy 417.081587 -371.794626) (xy 417.041854 -371.752606) (xy 417.008915 -371.705071) (xy 416.983527 -371.653111)
			(xy 416.966269 -371.597914) (xy 416.957538 -371.540746) (xy 416.957002 -371.51183) (xy 416.957485 -371.48446)
			(xy 416.965299 -371.430282) (xy 416.980784 -371.377779) (xy 417.003622 -371.328032) (xy 417.033343 -371.282064)
			(xy 417.050982 -371.261132) (xy 417.060191 -371.249784) (xy 417.072374 -371.223234) (xy 417.076553 -371.194323)
			(xy 417.072387 -371.16541) (xy 417.060216 -371.138855) (xy 417.050982 -371.127528) (xy 417.033373 -371.106571)
			(xy 417.00365 -371.060606) (xy 416.980806 -371.010864) (xy 416.965309 -370.958366) (xy 416.957479 -370.904191)
			(xy 416.957475 -370.849454) (xy 416.965299 -370.795279) (xy 416.98079 -370.742779) (xy 417.003628 -370.693034)
			(xy 417.033345 -370.647066) (xy 417.050982 -370.626132) (xy 417.060191 -370.614784) (xy 417.072374 -370.588234)
			(xy 417.076553 -370.559323) (xy 417.072387 -370.53041) (xy 417.060216 -370.503855) (xy 417.050982 -370.492528)
			(xy 417.03334 -370.471599) (xy 417.003629 -370.425625) (xy 416.980794 -370.375877) (xy 416.965304 -370.323375)
			(xy 416.957476 -370.269199) (xy 416.957002 -370.24183) (xy 416.957488 -370.214579) (xy 416.965244 -370.160631)
			(xy 416.980599 -370.108336) (xy 417.003241 -370.058759) (xy 417.032707 -370.012909) (xy 417.068398 -369.971718)
			(xy 417.109589 -369.936027) (xy 417.155439 -369.906561) (xy 417.205016 -369.883919) (xy 417.257311 -369.868564)
			(xy 417.311259 -369.860808) (xy 417.365761 -369.860808) (xy 417.419709 -369.868564) (xy 417.472004 -369.883919)
			(xy 417.521581 -369.906561) (xy 417.567431 -369.936027) (xy 417.608622 -369.971718) (xy 417.644313 -370.012909)
			(xy 417.669658 -370.052346) (xy 419.301422 -370.052346) (xy 419.301948 -370.023176) (xy 419.310856 -369.96552)
			(xy 419.32844 -369.909892) (xy 419.35429 -369.857592) (xy 419.387803 -369.809837) (xy 419.428198 -369.767744)
			(xy 419.451028 -369.749578) (xy 419.461394 -369.741142) (xy 419.47769 -369.719968) (xy 419.487936 -369.695292)
			(xy 419.491432 -369.668804) (xy 419.487938 -369.642315) (xy 419.477693 -369.617638) (xy 419.4614 -369.596464)
			(xy 419.451028 -369.588034) (xy 419.428198 -369.569867) (xy 419.387796 -369.527782) (xy 419.35428 -369.480029)
			(xy 419.328434 -369.427727) (xy 419.310862 -369.372096) (xy 419.301975 -369.314436) (xy 419.301422 -369.285266)
			(xy 419.301846 -369.258013) (xy 419.309608 -369.204061) (xy 419.324969 -369.151763) (xy 419.347616 -369.102184)
			(xy 419.377089 -369.056332) (xy 419.412787 -369.015142) (xy 419.453984 -368.979451) (xy 419.49984 -368.949986)
			(xy 419.549423 -368.927347) (xy 419.601724 -368.911995) (xy 419.655676 -368.904242) (xy 419.68293 -368.903758)
			(xy 419.711846 -368.904305) (xy 419.769017 -368.913025) (xy 419.824216 -368.930276) (xy 419.876178 -368.955662)
			(xy 419.923713 -368.988602) (xy 419.96573 -369.02834) (xy 419.98392 -369.050824) (xy 419.993817 -369.062629)
			(xy 420.019141 -369.080148) (xy 420.048534 -369.089324) (xy 420.079326 -369.089324) (xy 420.108719 -369.080148)
			(xy 420.134043 -369.062629) (xy 420.14394 -369.050824) (xy 420.162115 -369.028326) (xy 420.204137 -368.988591)
			(xy 420.251675 -368.955653) (xy 420.30364 -368.930267) (xy 420.358841 -368.913014) (xy 420.416013 -368.90429)
			(xy 420.44493 -368.903758) (xy 420.473478 -368.904268) (xy 420.529933 -368.912792) (xy 420.584489 -368.929632)
			(xy 420.635927 -368.95441) (xy 420.659814 -368.970052) (xy 420.670957 -368.977114) (xy 420.69581 -368.985923)
			(xy 420.722092 -368.988052) (xy 420.748038 -368.983358) (xy 420.771908 -368.972156) (xy 420.792099 -368.955198)
			(xy 420.800022 -368.944652) (xy 420.815446 -368.923649) (xy 420.851043 -368.885595) (xy 420.891486 -368.852737)
			(xy 420.936022 -368.825686) (xy 420.983824 -368.804944) (xy 421.034003 -368.790897) (xy 421.085626 -368.783806)
			(xy 421.11168 -368.783362) (xy 421.140598 -368.783871) (xy 421.19777 -368.792599) (xy 421.25297 -368.809857)
			(xy 421.304932 -368.83525) (xy 421.352466 -368.868197) (xy 421.394481 -368.907941) (xy 421.41267 -368.930428)
			(xy 421.422567 -368.942233) (xy 421.447891 -368.959752) (xy 421.477284 -368.968928) (xy 421.508076 -368.968928)
			(xy 421.537469 -368.959752) (xy 421.562793 -368.942233) (xy 421.57269 -368.930428) (xy 421.590894 -368.907955)
			(xy 421.63291 -368.868218) (xy 421.680442 -368.835277) (xy 421.732401 -368.809886) (xy 421.787597 -368.792628)
			(xy 421.844765 -368.783898) (xy 421.87368 -368.783362) (xy 421.900929 -368.783897) (xy 421.954874 -368.79165)
			(xy 422.007166 -368.807001) (xy 422.056741 -368.829637) (xy 422.10259 -368.859099) (xy 422.143779 -368.894785)
			(xy 422.179471 -368.93597) (xy 422.208939 -368.981815) (xy 422.231582 -369.031387) (xy 422.24694 -369.083677)
			(xy 422.2547 -369.137621) (xy 422.255188 -369.16487) (xy 422.254738 -369.190913) (xy 422.247655 -369.242514)
			(xy 422.233618 -369.292672) (xy 422.212886 -369.340454) (xy 422.185846 -369.384971) (xy 422.153001 -369.425395)
			(xy 422.134284 -369.443508) (xy 422.124324 -369.453453) (xy 422.109861 -369.477587) (xy 422.102521 -369.504749)
			(xy 422.102859 -369.532884) (xy 422.110849 -369.559862) (xy 422.125888 -369.583642) (xy 422.136062 -369.593368)
			(xy 422.155664 -369.611509) (xy 422.190054 -369.652374) (xy 422.218408 -369.697637) (xy 422.240172 -369.746412)
			(xy 422.25492 -369.797746) (xy 422.262364 -369.850635) (xy 422.262808 -369.87734) (xy 422.262337 -369.905111)
			(xy 422.254279 -369.960065) (xy 422.238337 -370.01327) (xy 422.214849 -370.063601) (xy 422.184312 -370.109994)
			(xy 422.147371 -370.15147) (xy 422.12641 -370.169694) (xy 422.115726 -370.179181) (xy 422.099744 -370.202854)
			(xy 422.090956 -370.230032) (xy 422.090053 -370.258581) (xy 422.097104 -370.28626) (xy 422.111557 -370.310897)
			(xy 422.121584 -370.321078) (xy 422.139964 -370.339133) (xy 422.172132 -370.37938) (xy 422.198597 -370.423587)
			(xy 422.218876 -370.470952) (xy 422.232603 -370.520613) (xy 422.239527 -370.571668) (xy 422.239948 -370.59743)
			(xy 422.239512 -370.624801) (xy 422.231689 -370.678982) (xy 422.216194 -370.731486) (xy 422.193345 -370.781233)
			(xy 422.163613 -370.827198) (xy 422.145968 -370.848128) (xy 422.136705 -370.859435) (xy 422.124535 -370.886001)
			(xy 422.120369 -370.914923) (xy 422.124548 -370.943843) (xy 422.136729 -370.970403) (xy 422.145968 -370.981732)
			(xy 422.163638 -371.002641) (xy 422.193362 -371.048613) (xy 422.216206 -371.098363) (xy 422.2317 -371.150869)
			(xy 422.239526 -371.20505) (xy 422.239523 -371.259795) (xy 422.231691 -371.313976) (xy 422.21619 -371.36648)
			(xy 422.19334 -371.416227) (xy 422.163611 -371.462195) (xy 422.145968 -371.483128) (xy 422.136705 -371.494435)
			(xy 422.124535 -371.521001) (xy 422.120369 -371.549923) (xy 422.124548 -371.578843) (xy 422.136729 -371.605403)
			(xy 422.145968 -371.616732) (xy 422.163638 -371.637641) (xy 422.193362 -371.683613) (xy 422.216206 -371.733363)
			(xy 422.2317 -371.785869) (xy 422.235289 -371.810718) (xy 423.31665 -371.810718) (xy 423.31665 -371.726022)
			(xy 423.324701 -371.641708) (xy 423.34073 -371.558542) (xy 423.364591 -371.477275) (xy 423.39607 -371.398645)
			(xy 423.434881 -371.323364) (xy 423.480671 -371.252112) (xy 423.533027 -371.185536) (xy 423.591475 -371.124238)
			(xy 423.655485 -371.068773) (xy 423.724477 -371.019644) (xy 423.797827 -370.977295) (xy 423.87487 -370.942111)
			(xy 423.954909 -370.914409) (xy 424.037218 -370.894441) (xy 424.121053 -370.882388) (xy 424.205654 -370.878358)
			(xy 424.290255 -370.882388) (xy 424.37409 -370.894441) (xy 424.456399 -370.914409) (xy 424.536438 -370.942111)
			(xy 424.613481 -370.977295) (xy 424.686831 -371.019644) (xy 424.755823 -371.068773) (xy 424.819833 -371.124238)
			(xy 424.878281 -371.185536) (xy 424.930637 -371.252112) (xy 424.976427 -371.323364) (xy 425.015238 -371.398645)
			(xy 425.046717 -371.477275) (xy 425.070578 -371.558542) (xy 425.086607 -371.641708) (xy 425.094658 -371.726022)
			(xy 425.095162 -371.76837) (xy 425.841163 -371.76837) (xy 425.845199 -371.684923) (xy 425.857271 -371.602255)
			(xy 425.877264 -371.521138) (xy 425.904993 -371.442329) (xy 425.940199 -371.366564) (xy 425.982553 -371.294551)
			(xy 426.031659 -371.226962) (xy 426.08706 -371.164428) (xy 426.148237 -371.107533) (xy 426.21462 -371.056807)
			(xy 426.285588 -371.012726) (xy 426.36048 -370.9757) (xy 426.438596 -370.946074) (xy 426.519206 -370.924126)
			(xy 426.601558 -370.910061) (xy 426.684884 -370.904009) (xy 426.768404 -370.906028) (xy 426.85134 -370.916098)
			(xy 426.932916 -370.934126) (xy 427.012372 -370.959943) (xy 427.088965 -370.993308) (xy 427.161981 -371.033909)
			(xy 427.230737 -371.081368) (xy 427.294591 -371.135241) (xy 427.352948 -371.195026) (xy 427.405263 -371.260163)
			(xy 427.451046 -371.330046) (xy 427.489871 -371.404021) (xy 427.521376 -371.481398) (xy 427.545265 -371.561455)
			(xy 427.561316 -371.643443) (xy 427.569379 -371.726598) (xy 427.569884 -371.76837) (xy 427.569379 -371.810142)
			(xy 427.561316 -371.893297) (xy 427.545265 -371.975285) (xy 427.521376 -372.055342) (xy 427.489871 -372.132719)
			(xy 427.451046 -372.206694) (xy 427.405263 -372.276577) (xy 427.352948 -372.341714) (xy 427.294591 -372.401499)
			(xy 427.230737 -372.455372) (xy 427.161981 -372.502831) (xy 427.088965 -372.543432) (xy 427.012372 -372.576797)
			(xy 426.932916 -372.602614) (xy 426.85134 -372.620642) (xy 426.768404 -372.630712) (xy 426.684884 -372.632731)
			(xy 426.601558 -372.626679) (xy 426.519206 -372.612614) (xy 426.438596 -372.590666) (xy 426.36048 -372.56104)
			(xy 426.285588 -372.524014) (xy 426.21462 -372.479933) (xy 426.148237 -372.429207) (xy 426.08706 -372.372312)
			(xy 426.031659 -372.309778) (xy 425.982553 -372.242189) (xy 425.940199 -372.170176) (xy 425.904993 -372.094411)
			(xy 425.877264 -372.015602) (xy 425.857271 -371.934485) (xy 425.845199 -371.851817) (xy 425.841163 -371.76837)
			(xy 425.095162 -371.76837) (xy 425.094658 -371.810718) (xy 425.086607 -371.895032) (xy 425.070578 -371.978198)
			(xy 425.046717 -372.059465) (xy 425.015238 -372.138095) (xy 424.976427 -372.213376) (xy 424.930637 -372.284628)
			(xy 424.878281 -372.351204) (xy 424.819833 -372.412502) (xy 424.755823 -372.467967) (xy 424.686831 -372.517096)
			(xy 424.613481 -372.559445) (xy 424.536438 -372.594629) (xy 424.456399 -372.622331) (xy 424.37409 -372.642299)
			(xy 424.290255 -372.654352) (xy 424.205654 -372.658383) (xy 424.121053 -372.654352) (xy 424.037218 -372.642299)
			(xy 423.954909 -372.622331) (xy 423.87487 -372.594629) (xy 423.797827 -372.559445) (xy 423.724477 -372.517096)
			(xy 423.655485 -372.467967) (xy 423.591475 -372.412502) (xy 423.533027 -372.351204) (xy 423.480671 -372.284628)
			(xy 423.434881 -372.213376) (xy 423.39607 -372.138095) (xy 423.364591 -372.059465) (xy 423.34073 -371.978198)
			(xy 423.324701 -371.895032) (xy 423.31665 -371.810718) (xy 422.235289 -371.810718) (xy 422.239526 -371.84005)
			(xy 422.239523 -371.894795) (xy 422.231691 -371.948976) (xy 422.21619 -372.00148) (xy 422.19334 -372.051227)
			(xy 422.163611 -372.097195) (xy 422.145968 -372.118128) (xy 422.136705 -372.129435) (xy 422.124535 -372.156001)
			(xy 422.120369 -372.184923) (xy 422.124548 -372.213843) (xy 422.136729 -372.240403) (xy 422.145968 -372.251732)
			(xy 422.163584 -372.272683) (xy 422.1933 -372.31865) (xy 422.216141 -372.368393) (xy 422.231638 -372.420889)
			(xy 422.239471 -372.475062) (xy 422.239948 -372.50243) (xy 422.23945 -372.52968) (xy 422.231691 -372.583625)
			(xy 422.216334 -372.635917) (xy 422.193692 -372.685492) (xy 422.164226 -372.73134) (xy 422.128536 -372.772529)
			(xy 422.087348 -372.80822) (xy 422.041501 -372.837687) (xy 421.991927 -372.86033) (xy 421.939635 -372.875689)
			(xy 421.88569 -372.88345) (xy 421.85844 -372.883938) (xy 421.829523 -372.883415) (xy 421.772351 -372.87469)
			(xy 421.717151 -372.857435) (xy 421.665189 -372.832044) (xy 421.617655 -372.7991) (xy 421.575639 -372.759358)
			(xy 421.55745 -372.736872) (xy 421.547553 -372.725067) (xy 421.522229 -372.707548) (xy 421.492836 -372.698372)
			(xy 421.462044 -372.698372) (xy 421.432651 -372.707548) (xy 421.407327 -372.725067) (xy 421.39743 -372.736872)
			(xy 421.379215 -372.759335) (xy 421.337201 -372.799073) (xy 421.289671 -372.832015) (xy 421.237715 -372.857407)
			(xy 421.182521 -372.874668) (xy 421.125355 -372.883401) (xy 421.09644 -372.883938) (xy 421.069189 -372.883408)
			(xy 421.015243 -372.875657) (xy 420.962948 -372.860307) (xy 420.91337 -372.837672) (xy 420.867518 -372.808211)
			(xy 420.826326 -372.772524) (xy 420.790631 -372.731338) (xy 420.761162 -372.685492) (xy 420.738517 -372.635918)
			(xy 420.723158 -372.583626) (xy 420.715397 -372.52968) (xy 420.714932 -372.50243) (xy 420.715408 -372.47506)
			(xy 420.723222 -372.420881) (xy 420.738708 -372.368378) (xy 420.761548 -372.318631) (xy 420.791271 -372.272664)
			(xy 420.808912 -372.251732) (xy 420.818119 -372.240383) (xy 420.830298 -372.213833) (xy 420.834476 -372.184923)
			(xy 420.830311 -372.156011) (xy 420.818144 -372.129455) (xy 420.808912 -372.118128) (xy 420.791301 -372.097171)
			(xy 420.761576 -372.051207) (xy 420.73873 -372.001465) (xy 420.723232 -371.948967) (xy 420.715401 -371.894792)
			(xy 420.715398 -371.840054) (xy 420.723223 -371.785878) (xy 420.738714 -371.733378) (xy 420.761555 -371.683632)
			(xy 420.791274 -371.637665) (xy 420.808912 -371.616732) (xy 420.818119 -371.605383) (xy 420.830298 -371.578833)
			(xy 420.834476 -371.549923) (xy 420.830311 -371.521011) (xy 420.818144 -371.494455) (xy 420.808912 -371.483128)
			(xy 420.791301 -371.462171) (xy 420.761576 -371.416207) (xy 420.73873 -371.366465) (xy 420.723232 -371.313967)
			(xy 420.715401 -371.259792) (xy 420.715398 -371.205054) (xy 420.723223 -371.150878) (xy 420.738714 -371.098378)
			(xy 420.761555 -371.048632) (xy 420.791274 -371.002665) (xy 420.808912 -370.981732) (xy 420.818119 -370.970383)
			(xy 420.830298 -370.943833) (xy 420.834476 -370.914923) (xy 420.830311 -370.886011) (xy 420.818144 -370.859455)
			(xy 420.808912 -370.848128) (xy 420.791274 -370.827195) (xy 420.761562 -370.781222) (xy 420.738726 -370.731475)
			(xy 420.723234 -370.678975) (xy 420.715406 -370.624799) (xy 420.714932 -370.59743) (xy 420.71516 -370.578375)
			(xy 420.718982 -370.540457) (xy 420.722552 -370.521738) (xy 420.724834 -370.508255) (xy 420.723002 -370.480984)
			(xy 420.713998 -370.455177) (xy 420.698467 -370.432685) (xy 420.677525 -370.41512) (xy 420.652672 -370.403744)
			(xy 420.625691 -370.399371) (xy 420.598517 -370.402315) (xy 420.585646 -370.40693) (xy 420.563174 -370.415447)
			(xy 420.516636 -370.42744) (xy 420.468959 -370.433487) (xy 420.44493 -370.433854) (xy 420.416013 -370.433332)
			(xy 420.358841 -370.424606) (xy 420.303642 -370.40735) (xy 420.25168 -370.381959) (xy 420.204146 -370.349015)
			(xy 420.16213 -370.309274) (xy 420.14394 -370.286788) (xy 420.134043 -370.274983) (xy 420.108719 -370.257464)
			(xy 420.079326 -370.248288) (xy 420.048534 -370.248288) (xy 420.019141 -370.257464) (xy 419.993817 -370.274983)
			(xy 419.98392 -370.286788) (xy 419.965715 -370.309259) (xy 419.923698 -370.348996) (xy 419.876166 -370.381937)
			(xy 419.824208 -370.407327) (xy 419.769013 -370.424586) (xy 419.711845 -370.433318) (xy 419.68293 -370.433854)
			(xy 419.655682 -370.433294) (xy 419.601739 -370.425543) (xy 419.549448 -370.410194) (xy 419.499874 -370.387559)
			(xy 419.454026 -370.358101) (xy 419.412837 -370.322417) (xy 419.377145 -370.281235) (xy 419.347677 -370.235392)
			(xy 419.325033 -370.185823) (xy 419.309673 -370.133535) (xy 419.301911 -370.079594) (xy 419.301422 -370.052346)
			(xy 417.669658 -370.052346) (xy 417.673779 -370.058759) (xy 417.696421 -370.108336) (xy 417.711776 -370.160631)
			(xy 417.719532 -370.214579) (xy 417.720018 -370.24183) (xy 417.71959 -370.269202) (xy 417.711766 -370.323383)
			(xy 417.696269 -370.375888) (xy 417.673418 -370.425634) (xy 417.643684 -370.471598) (xy 417.626038 -370.492528)
			(xy 417.616769 -370.503832) (xy 417.604591 -370.530398) (xy 417.600422 -370.559323) (xy 417.604604 -370.588246)
			(xy 417.616794 -370.614806) (xy 417.626038 -370.626132) (xy 417.64371 -370.64704) (xy 417.673436 -370.693011)
			(xy 417.696282 -370.742762) (xy 417.711777 -370.795268) (xy 417.719604 -370.84945) (xy 417.7196 -370.904195)
			(xy 417.711767 -370.958377) (xy 417.696266 -371.010881) (xy 417.673414 -371.060628) (xy 417.643682 -371.106596)
			(xy 417.626038 -371.127528) (xy 417.616769 -371.138832) (xy 417.604591 -371.165398) (xy 417.600422 -371.194323)
			(xy 417.604604 -371.223246) (xy 417.616794 -371.249806) (xy 417.626038 -371.261132) (xy 417.643665 -371.282074)
			(xy 417.673377 -371.328044) (xy 417.696215 -371.37779) (xy 417.711709 -371.430288) (xy 417.719542 -371.484462)
			(xy 417.720018 -371.51183) (xy 417.71948 -371.540747) (xy 417.71076 -371.597918) (xy 417.693508 -371.653118)
			(xy 417.66812 -371.705081) (xy 417.635178 -371.752615) (xy 417.595437 -371.794631) (xy 417.572952 -371.81282)
			(xy 417.561113 -371.822683) (xy 417.543589 -371.848014) (xy 417.534413 -371.877417) (xy 417.534419 -371.908219)
			(xy 417.543606 -371.937619) (xy 417.561139 -371.962944) (xy 417.572952 -371.97284) (xy 417.593764 -371.989558)
			(xy 417.630894 -372.027916) (xy 417.662314 -372.071075) (xy 417.687412 -372.118193) (xy 417.705696 -372.168349)
			(xy 417.716811 -372.220564) (xy 417.720538 -372.273818) (xy 417.716805 -372.327073) (xy 417.705686 -372.379287)
			(xy 417.687397 -372.429441) (xy 417.662295 -372.476556) (xy 417.63087 -372.519712) (xy 417.593737 -372.558066)
			(xy 417.572952 -372.57482) (xy 417.561113 -372.584683) (xy 417.543589 -372.610014) (xy 417.534413 -372.639417)
			(xy 417.534419 -372.670219) (xy 417.543606 -372.699619) (xy 417.561139 -372.724944) (xy 417.572952 -372.73484)
			(xy 417.595465 -372.752995) (xy 417.635196 -372.795024) (xy 417.66813 -372.842567) (xy 417.693513 -372.894535)
			(xy 417.710763 -372.949738) (xy 417.719486 -373.006912) (xy 417.720018 -373.03583) (xy 417.719532 -373.063081)
			(xy 417.711776 -373.117029) (xy 417.696421 -373.169324) (xy 417.673779 -373.218901) (xy 417.644313 -373.264751)
			(xy 417.608622 -373.305942) (xy 417.567431 -373.341633) (xy 417.521581 -373.371099) (xy 417.472004 -373.393741)
			(xy 417.419709 -373.409096) (xy 417.365761 -373.416852) (xy 417.311259 -373.416852) (xy 417.257311 -373.409096)
			(xy 417.205016 -373.393741) (xy 417.155439 -373.371099) (xy 417.109589 -373.341633) (xy 417.068398 -373.305942)
			(xy 417.032707 -373.264751) (xy 417.003241 -373.218901) (xy 416.980599 -373.169324) (xy 416.965244 -373.117029)
			(xy 416.957488 -373.063081) (xy 416.957002 -373.03583) (xy 416.957541 -373.006914) (xy 416.966266 -372.949744)
			(xy 416.98352 -372.894545) (xy 417.008907 -372.842583) (xy 417.041847 -372.795049) (xy 417.081584 -372.753031)
			(xy 417.104068 -372.73484) (xy 417.115845 -372.724911) (xy 417.133366 -372.699597) (xy 417.142547 -372.670211)
			(xy 417.142553 -372.639425) (xy 417.133383 -372.610036) (xy 417.11587 -372.584716) (xy 417.104068 -372.57482)
			(xy 417.083314 -372.558031) (xy 417.046184 -372.519683) (xy 417.014761 -372.476532) (xy 416.989661 -372.429423)
			(xy 416.971373 -372.379275) (xy 416.960254 -372.327067) (xy 416.956522 -372.273818) (xy 415.75026 -372.273818)
			(xy 415.752038 -372.299218) (xy 415.748305 -372.352473) (xy 415.737186 -372.404687) (xy 415.718897 -372.454841)
			(xy 415.693795 -372.501956) (xy 415.66237 -372.545112) (xy 415.625237 -372.583466) (xy 415.604452 -372.60022)
			(xy 415.592613 -372.610083) (xy 415.575089 -372.635414) (xy 415.565913 -372.664817) (xy 415.565919 -372.695619)
			(xy 415.575106 -372.725019) (xy 415.592639 -372.750344) (xy 415.604452 -372.76024) (xy 415.626965 -372.778395)
			(xy 415.666696 -372.820424) (xy 415.69963 -372.867967) (xy 415.725013 -372.919935) (xy 415.742263 -372.975138)
			(xy 415.750986 -373.032312) (xy 415.751518 -373.06123) (xy 415.75105 -373.088482) (xy 415.74329 -373.142429)
			(xy 415.727931 -373.194724) (xy 415.705287 -373.244301) (xy 415.675819 -373.29015) (xy 415.640126 -373.33134)
			(xy 415.598934 -373.367031) (xy 415.553083 -373.396497) (xy 415.503505 -373.419138) (xy 415.45121 -373.434494)
			(xy 415.397262 -373.442252) (xy 415.37001 -373.442738) (xy 415.341092 -373.442236) (xy 415.283919 -373.433507)
			(xy 415.228719 -373.416247) (xy 415.176757 -373.390853) (xy 415.129224 -373.357905) (xy 415.087209 -373.31816)
			(xy 415.06902 -373.295672) (xy 415.059123 -373.283867) (xy 415.033799 -373.266348) (xy 415.004406 -373.257172)
			(xy 414.973614 -373.257172) (xy 414.944221 -373.266348) (xy 414.918897 -373.283867) (xy 414.909 -373.295672)
			(xy 414.890802 -373.31815) (xy 414.848784 -373.357886) (xy 414.801251 -373.390827) (xy 414.749291 -373.416217)
			(xy 414.694095 -373.433474) (xy 414.636926 -373.442203) (xy 414.60801 -373.442738) (xy 414.580639 -373.442281)
			(xy 414.526459 -373.434463) (xy 414.473955 -373.418973) (xy 414.424209 -373.396129) (xy 414.378243 -373.366401)
			(xy 414.357312 -373.348758) (xy 414.345984 -373.339522) (xy 414.319427 -373.327346) (xy 414.29051 -373.323173)
			(xy 414.261593 -373.327346) (xy 414.235036 -373.339522) (xy 414.223708 -373.348758) (xy 414.202778 -373.3664)
			(xy 414.156806 -373.396113) (xy 414.107058 -373.418949) (xy 414.054556 -373.434439) (xy 414.000379 -373.442265)
			(xy 413.97301 -373.442738) (xy 413.94576 -373.442213) (xy 413.891816 -373.434458) (xy 413.839524 -373.419106)
			(xy 413.789948 -373.396468) (xy 413.744099 -373.367006) (xy 413.70291 -373.331318) (xy 413.667218 -373.290133)
			(xy 413.637751 -373.244287) (xy 413.615108 -373.194714) (xy 413.59975 -373.142423) (xy 413.59199 -373.08848)
			(xy 413.591502 -373.06123) (xy 413.592041 -373.032314) (xy 413.600766 -372.975144) (xy 413.61802 -372.919945)
			(xy 413.643407 -372.867983) (xy 413.676347 -372.820449) (xy 413.716084 -372.778431) (xy 413.738568 -372.76024)
			(xy 413.750345 -372.750311) (xy 413.767866 -372.724997) (xy 413.777047 -372.695611) (xy 413.777053 -372.664825)
			(xy 413.767883 -372.635436) (xy 413.75037 -372.610116) (xy 413.738568 -372.60022) (xy 413.717814 -372.583431)
			(xy 413.680684 -372.545083) (xy 413.649261 -372.501932) (xy 413.624161 -372.454823) (xy 413.605873 -372.404675)
			(xy 413.594754 -372.352467) (xy 413.591022 -372.299218) (xy 411.153864 -372.299218) (xy 411.153864 -373.598694)
			(xy 411.888222 -374.333052) (xy 416.088785 -374.333052) (xy 416.088785 -374.278548) (xy 416.096542 -374.224599)
			(xy 416.111899 -374.172302) (xy 416.134542 -374.122724) (xy 416.16401 -374.076873) (xy 416.199704 -374.035683)
			(xy 416.240897 -373.999992) (xy 416.286751 -373.970527) (xy 416.336331 -373.947888) (xy 416.388628 -373.932536)
			(xy 416.442578 -373.924783) (xy 416.46983 -373.924322) (xy 416.498745 -373.924882) (xy 416.555915 -373.933601)
			(xy 416.611113 -373.95085) (xy 416.663076 -373.976234) (xy 416.710611 -374.009171) (xy 416.752629 -374.048905)
			(xy 416.77082 -374.071388) (xy 416.780717 -374.083193) (xy 416.806041 -374.100712) (xy 416.835434 -374.109888)
			(xy 416.866226 -374.109888) (xy 416.895619 -374.100712) (xy 416.920943 -374.083193) (xy 416.93084 -374.071388)
			(xy 416.949005 -374.048883) (xy 416.991031 -374.00915) (xy 417.038571 -373.976213) (xy 417.090537 -373.950829)
			(xy 417.145739 -373.933577) (xy 417.202913 -373.924854) (xy 417.23183 -373.924322) (xy 417.259082 -373.92475)
			(xy 417.313031 -373.93251) (xy 417.365326 -373.947869) (xy 417.414903 -373.970514) (xy 417.460754 -373.999983)
			(xy 417.501943 -374.035678) (xy 417.537635 -374.07687) (xy 417.5671 -374.122723) (xy 417.589741 -374.172302)
			(xy 417.605096 -374.224599) (xy 417.612852 -374.278548) (xy 417.612852 -374.333052) (xy 417.605096 -374.387001)
			(xy 417.589741 -374.439298) (xy 417.5671 -374.488877) (xy 417.537635 -374.53473) (xy 417.501943 -374.575922)
			(xy 417.460754 -374.611617) (xy 417.414903 -374.641086) (xy 417.365326 -374.663731) (xy 417.313031 -374.67909)
			(xy 417.259082 -374.68685) (xy 417.23183 -374.687338) (xy 417.202913 -374.686822) (xy 417.14574 -374.678096)
			(xy 417.09054 -374.660839) (xy 417.038578 -374.635447) (xy 416.991045 -374.602502) (xy 416.949029 -374.562759)
			(xy 416.93084 -374.540272) (xy 416.920943 -374.528467) (xy 416.895619 -374.510948) (xy 416.866226 -374.501772)
			(xy 416.835434 -374.501772) (xy 416.806041 -374.510948) (xy 416.780717 -374.528467) (xy 416.77082 -374.540272)
			(xy 416.752611 -374.56274) (xy 416.710596 -374.602478) (xy 416.663065 -374.635419) (xy 416.611107 -374.66081)
			(xy 416.555912 -374.67807) (xy 416.498745 -374.686802) (xy 416.46983 -374.687338) (xy 416.442578 -374.686817)
			(xy 416.388628 -374.679064) (xy 416.336331 -374.663712) (xy 416.286751 -374.641073) (xy 416.240897 -374.611608)
			(xy 416.199704 -374.575917) (xy 416.16401 -374.534727) (xy 416.134542 -374.488876) (xy 416.111899 -374.439298)
			(xy 416.096542 -374.387001) (xy 416.088785 -374.333052) (xy 411.888222 -374.333052) (xy 413.725614 -376.170444)
			(xy 427.300644 -376.170444)
		)
		(stroke
			(width 0)
			(type solid)
		)
		(fill yes)
		(layer "In15.Cu")
		(net "GND")
	)
	(gr_poly
		(pts
			(xy 413.694118 -184.085992) (xy 424.842432 -184.085992) (xy 424.842432 -181.193948) (xy 424.842686 -181.184296)
			(xy 424.842686 -181.062376) (xy 424.928538 -180.976524) (xy 424.929046 -180.975762) (xy 424.932856 -180.971952)
			(xy 424.93565 -180.969158) (xy 425.69765 -180.207158) (xy 425.703238 -180.201824) (xy 425.703746 -180.201316)
			(xy 425.790868 -180.114194) (xy 425.912788 -180.114194) (xy 425.92244 -180.11394) (xy 430.518316 -180.11394)
			(xy 430.531016 -180.081682) (xy 430.541274 -180.056857) (xy 430.567755 -180.010124) (xy 430.600528 -179.967566)
			(xy 430.638945 -179.930025) (xy 430.682247 -179.898242) (xy 430.729579 -179.872846) (xy 430.780004 -179.854339)
			(xy 430.832527 -179.843086) (xy 430.886108 -179.83931) (xy 430.939689 -179.843086) (xy 430.992212 -179.854339)
			(xy 431.042637 -179.872846) (xy 431.089969 -179.898242) (xy 431.133271 -179.930025) (xy 431.171688 -179.967566)
			(xy 431.204461 -180.010124) (xy 431.230942 -180.056857) (xy 431.2412 -180.081682) (xy 431.2539 -180.11394)
			(xy 431.597308 -180.11394) (xy 432.039776 -179.671472) (xy 432.039776 -179.613306) (xy 432.006248 -179.601114)
			(xy 431.98142 -179.591731) (xy 431.934421 -179.56707) (xy 431.891295 -179.536131) (xy 431.852877 -179.499511)
			(xy 431.819907 -179.457917) (xy 431.806096 -179.435252) (xy 431.79802 -179.422531) (xy 431.775889 -179.402106)
			(xy 431.748765 -179.389018) (xy 431.719004 -179.384405) (xy 431.68919 -179.388666) (xy 431.661914 -179.401433)
			(xy 431.639542 -179.421595) (xy 431.631344 -179.434236) (xy 431.616481 -179.458093) (xy 431.580847 -179.501559)
			(xy 431.539215 -179.539321) (xy 431.492488 -179.570559) (xy 431.441681 -179.594596) (xy 431.387895 -179.610911)
			(xy 431.332295 -179.61915) (xy 431.304192 -179.619656) (xy 431.276126 -179.619165) (xy 431.220599 -179.61095)
			(xy 431.166876 -179.594685) (xy 431.116118 -179.57072) (xy 431.06942 -179.539574) (xy 431.027793 -179.501919)
			(xy 430.992135 -179.458569) (xy 430.977294 -179.434744) (xy 430.973992 -179.42941) (xy 430.452276 -178.90744)
			(xy 430.432154 -178.886589) (xy 430.39806 -178.839737) (xy 430.371716 -178.788128) (xy 430.353771 -178.733032)
			(xy 430.344668 -178.675808) (xy 430.344072 -178.646836) (xy 430.344072 -173.032928) (xy 430.344633 -173.003955)
			(xy 430.353743 -172.946729) (xy 430.371698 -172.891635) (xy 430.398053 -172.840028) (xy 430.43216 -172.793183)
			(xy 430.452276 -172.772324) (xy 435.538372 -167.685974) (xy 435.538372 -162.654742) (xy 433.868576 -160.984692)
			(xy 433.848451 -160.963842) (xy 433.81435 -160.916991) (xy 433.787999 -160.865383) (xy 433.770046 -160.810287)
			(xy 433.760936 -160.753061) (xy 433.760372 -160.724088) (xy 433.760372 -153.602182) (xy 427.049946 -146.891756)
			(xy 419.05428 -146.891756) (xy 419.025305 -146.891199) (xy 418.968075 -146.882096) (xy 418.912974 -146.864149)
			(xy 418.861361 -146.8378) (xy 418.814507 -146.803698) (xy 418.793676 -146.783552) (xy 416.990276 -144.980152)
			(xy 416.970153 -144.959301) (xy 416.936057 -144.91245) (xy 416.909712 -144.86084) (xy 416.891765 -144.805745)
			(xy 416.882661 -144.74852) (xy 416.882072 -144.719548) (xy 416.882072 -142.557246) (xy 416.880802 -142.55115)
			(xy 416.875479 -142.528471) (xy 416.869747 -142.48224) (xy 416.869372 -142.458948) (xy 416.869858 -142.431697)
			(xy 416.877614 -142.377749) (xy 416.892969 -142.325454) (xy 416.915611 -142.275877) (xy 416.945077 -142.230027)
			(xy 416.980768 -142.188836) (xy 417.021959 -142.153145) (xy 417.067809 -142.123679) (xy 417.117386 -142.101037)
			(xy 417.169681 -142.085682) (xy 417.223629 -142.077926) (xy 417.278131 -142.077926) (xy 417.332079 -142.085682)
			(xy 417.384374 -142.101037) (xy 417.433951 -142.123679) (xy 417.479801 -142.153145) (xy 417.520992 -142.188836)
			(xy 417.556683 -142.230027) (xy 417.586149 -142.275877) (xy 417.608791 -142.325454) (xy 417.624146 -142.377749)
			(xy 417.631902 -142.431697) (xy 417.632388 -142.458948) (xy 417.632007 -142.48224) (xy 417.626274 -142.52847)
			(xy 417.620958 -142.55115) (xy 417.619688 -142.557246) (xy 417.619688 -143.788892) (xy 427.194218 -143.788892)
			(xy 427.194673 -143.762513) (xy 427.201927 -143.710255) (xy 427.21631 -143.659495) (xy 427.237546 -143.6112)
			(xy 427.265233 -143.566289) (xy 427.298841 -143.525621) (xy 427.33773 -143.489969) (xy 427.381159 -143.460013)
			(xy 427.40453 -143.44777) (xy 427.416899 -143.441083) (xy 427.437636 -143.422108) (xy 427.452403 -143.398191)
			(xy 427.460078 -143.371151) (xy 427.460077 -143.343042) (xy 427.4524 -143.316003) (xy 427.437631 -143.292087)
			(xy 427.416893 -143.273113) (xy 427.40453 -143.266414) (xy 427.38114 -143.254209) (xy 427.337718 -143.224239)
			(xy 427.298835 -143.188577) (xy 427.265232 -143.147902) (xy 427.237548 -143.102988) (xy 427.216311 -143.054691)
			(xy 427.201924 -143.00393) (xy 427.194662 -142.951672) (xy 427.194218 -142.925292) (xy 427.194704 -142.898041)
			(xy 427.20246 -142.844093) (xy 427.217815 -142.791798) (xy 427.240457 -142.742221) (xy 427.269923 -142.696371)
			(xy 427.305614 -142.65518) (xy 427.346805 -142.619489) (xy 427.392655 -142.590023) (xy 427.442232 -142.567381)
			(xy 427.494527 -142.552026) (xy 427.548475 -142.54427) (xy 427.602977 -142.54427) (xy 427.656925 -142.552026)
			(xy 427.70922 -142.567381) (xy 427.758797 -142.590023) (xy 427.804647 -142.619489) (xy 427.845838 -142.65518)
			(xy 427.881529 -142.696371) (xy 427.910995 -142.742221) (xy 427.933637 -142.791798) (xy 427.948992 -142.844093)
			(xy 427.956748 -142.898041) (xy 427.957234 -142.925292) (xy 427.956737 -142.95167) (xy 427.949487 -143.003924)
			(xy 427.935108 -143.054682) (xy 427.913877 -143.102976) (xy 427.886196 -143.147886) (xy 427.852595 -143.188555)
			(xy 427.813712 -143.224209) (xy 427.770289 -143.254169) (xy 427.746922 -143.266414) (xy 427.734572 -143.273128)
			(xy 427.713846 -143.292103) (xy 427.699087 -143.316014) (xy 427.691415 -143.343047) (xy 427.691415 -143.371146)
			(xy 427.699084 -143.398179) (xy 427.713841 -143.422092) (xy 427.734566 -143.441068) (xy 427.746922 -143.44777)
			(xy 427.770294 -143.460009) (xy 427.813717 -143.489972) (xy 427.852602 -143.525628) (xy 427.886208 -143.566298)
			(xy 427.913894 -143.611207) (xy 427.935135 -143.6595) (xy 427.949524 -143.710258) (xy 427.956788 -143.762513)
			(xy 427.957234 -143.788892) (xy 427.956748 -143.816143) (xy 427.948992 -143.870091) (xy 427.933637 -143.922386)
			(xy 427.910995 -143.971963) (xy 427.881529 -144.017813) (xy 427.845838 -144.059004) (xy 427.804647 -144.094695)
			(xy 427.758797 -144.124161) (xy 427.70922 -144.146803) (xy 427.656925 -144.162158) (xy 427.602977 -144.169914)
			(xy 427.548475 -144.169914) (xy 427.494527 -144.162158) (xy 427.442232 -144.146803) (xy 427.392655 -144.124161)
			(xy 427.346805 -144.094695) (xy 427.305614 -144.059004) (xy 427.269923 -144.017813) (xy 427.240457 -143.971963)
			(xy 427.217815 -143.922386) (xy 427.20246 -143.870091) (xy 427.194704 -143.816143) (xy 427.194218 -143.788892)
			(xy 417.619688 -143.788892) (xy 417.619688 -144.566894) (xy 419.206934 -146.15414) (xy 427.2026 -146.15414)
			(xy 427.231575 -146.154695) (xy 427.288807 -146.163795) (xy 427.34391 -146.18174) (xy 427.395526 -146.208087)
			(xy 427.442382 -146.242187) (xy 427.463204 -146.262344) (xy 434.389784 -153.188924) (xy 434.40991 -153.209774)
			(xy 434.444013 -153.256623) (xy 434.470365 -153.308232) (xy 434.488316 -153.363328) (xy 434.497426 -153.420555)
			(xy 434.497988 -153.449528) (xy 434.497988 -160.571434) (xy 436.167784 -162.241484) (xy 436.187912 -162.262333)
			(xy 436.22202 -162.309181) (xy 436.248378 -162.360789) (xy 436.266335 -162.415886) (xy 436.275451 -162.473114)
			(xy 436.275988 -162.502088) (xy 436.275988 -167.838628) (xy 436.275431 -167.867602) (xy 436.266325 -167.92483)
			(xy 436.248374 -167.979928) (xy 436.222021 -168.031538) (xy 436.187915 -168.078386) (xy 436.167784 -168.099232)
			(xy 431.081688 -173.185582) (xy 431.081688 -178.082956) (xy 431.082196 -178.0983) (xy 431.091286 -178.12761)
			(xy 431.108687 -178.152886) (xy 431.132822 -178.171839) (xy 431.161503 -178.182751) (xy 431.192132 -178.184634)
			(xy 431.207164 -178.181508) (xy 431.229303 -178.17649) (xy 431.274382 -178.171142) (xy 431.29708 -178.17084)
			(xy 431.324333 -178.171302) (xy 431.378283 -178.179057) (xy 431.430581 -178.194412) (xy 431.48016 -178.217054)
			(xy 431.526012 -178.246522) (xy 431.567203 -178.282216) (xy 431.602895 -178.32341) (xy 431.63236 -178.369264)
			(xy 431.654998 -178.418846) (xy 431.670349 -178.471144) (xy 431.6781 -178.525095) (xy 431.678588 -178.552348)
			(xy 431.678023 -178.582077) (xy 431.668804 -178.640815) (xy 431.650582 -178.69741) (xy 431.623798 -178.750493)
			(xy 431.5891 -178.798776) (xy 431.568606 -178.820318) (xy 431.559491 -178.830137) (xy 431.54629 -178.853442)
			(xy 431.539601 -178.879377) (xy 431.539883 -178.906159) (xy 431.547118 -178.931947) (xy 431.560807 -178.954968)
			(xy 431.57013 -178.96459) (xy 431.58827 -178.982779) (xy 431.619996 -179.023179) (xy 431.633376 -179.045108)
			(xy 431.641456 -179.057827) (xy 431.663594 -179.078248) (xy 431.69072 -179.091334) (xy 431.720482 -179.095949)
			(xy 431.750297 -179.091694) (xy 431.77758 -179.078937) (xy 431.799962 -179.058785) (xy 431.808128 -179.046124)
			(xy 431.82195 -179.023904) (xy 431.854738 -178.983122) (xy 431.892797 -178.947208) (xy 431.93541 -178.916837)
			(xy 431.981777 -178.89258) (xy 432.006248 -178.88331) (xy 432.039776 -178.871118) (xy 432.039776 -172.884084)
			(xy 436.417466 -168.506394) (xy 436.417466 -161.85134) (xy 435.345332 -160.779206) (xy 435.345332 -153.69286)
			(xy 430.79289 -149.140418) (xy 430.790096 -149.137624) (xy 430.786286 -149.133814) (xy 430.785778 -149.133052)
			(xy 430.699926 -149.0472) (xy 430.699926 -148.92528) (xy 430.699672 -148.915628) (xy 430.699672 -133.67258)
			(xy 430.562004 -133.534912) (xy 430.497488 -133.470396) (xy 429.985678 -132.958332) (xy 428.20971 -132.958332)
			(xy 428.078138 -132.958332) (xy 427.992286 -132.87248) (xy 427.991524 -132.871972) (xy 427.989238 -132.869686)
			(xy 427.985936 -132.866384) (xy 427.025308 -131.905756) (xy 422.300908 -131.905756) (xy 422.293542 -131.905502)
			(xy 422.169336 -131.905502) (xy 422.083484 -131.81965) (xy 422.082722 -131.819142) (xy 422.076372 -131.812792)
			(xy 422.076118 -131.812538) (xy 421.274748 -131.011168) (xy 415.487612 -131.011168) (xy 415.480246 -131.010914)
			(xy 415.35604 -131.010914) (xy 415.270188 -130.925062) (xy 415.269426 -130.924554) (xy 415.263076 -130.918204)
			(xy 415.262822 -130.91795) (xy 410.594048 -126.249176) (xy 410.583083 -126.238957) (xy 410.556666 -126.224824)
			(xy 410.527286 -126.218961) (xy 410.497469 -126.221873) (xy 410.469778 -126.233309) (xy 410.446595 -126.252286)
			(xy 410.429913 -126.277171) (xy 410.421168 -126.305825) (xy 410.420566 -126.320804) (xy 410.420566 -131.54914)
			(xy 420.687752 -131.54914) (xy 420.691823 -131.493518) (xy 420.703949 -131.439081) (xy 420.723872 -131.38699)
			(xy 420.751168 -131.338355) (xy 420.785254 -131.294212) (xy 420.825403 -131.255503) (xy 420.870761 -131.223052)
			(xy 420.920361 -131.197551) (xy 420.973145 -131.179544) (xy 421.027988 -131.169414) (xy 421.083722 -131.167377)
			(xy 421.139159 -131.173477) (xy 421.193116 -131.187583) (xy 421.244445 -131.209395) (xy 421.292051 -131.238449)
			(xy 421.334919 -131.274124) (xy 421.372136 -131.315661) (xy 421.402909 -131.362174) (xy 421.426581 -131.412671)
			(xy 421.442649 -131.466078) (xy 421.450769 -131.521254) (xy 421.451278 -131.54914) (xy 421.450769 -131.577026)
			(xy 421.442649 -131.632202) (xy 421.426581 -131.685609) (xy 421.402909 -131.736106) (xy 421.372136 -131.782619)
			(xy 421.334919 -131.824156) (xy 421.292051 -131.859831) (xy 421.244445 -131.888885) (xy 421.193116 -131.910697)
			(xy 421.139159 -131.924803) (xy 421.083722 -131.930903) (xy 421.027988 -131.928866) (xy 420.973145 -131.918736)
			(xy 420.920361 -131.900729) (xy 420.870761 -131.875228) (xy 420.825403 -131.842777) (xy 420.785254 -131.804068)
			(xy 420.751168 -131.759925) (xy 420.723872 -131.71129) (xy 420.703949 -131.659199) (xy 420.691823 -131.604762)
			(xy 420.687752 -131.54914) (xy 410.420566 -131.54914) (xy 410.420566 -132.947918) (xy 422.728642 -132.947918)
			(xy 422.732713 -132.892296) (xy 422.744839 -132.837859) (xy 422.764762 -132.785768) (xy 422.792058 -132.737133)
			(xy 422.826144 -132.69299) (xy 422.866293 -132.654281) (xy 422.911651 -132.62183) (xy 422.961251 -132.596329)
			(xy 423.014035 -132.578322) (xy 423.068878 -132.568192) (xy 423.124612 -132.566155) (xy 423.180049 -132.572255)
			(xy 423.234006 -132.586361) (xy 423.285335 -132.608173) (xy 423.332941 -132.637227) (xy 423.375809 -132.672902)
			(xy 423.413026 -132.714439) (xy 423.443799 -132.760952) (xy 423.467471 -132.811449) (xy 423.483539 -132.864856)
			(xy 423.491659 -132.920032) (xy 423.492168 -132.947918) (xy 423.491659 -132.975804) (xy 423.483539 -133.03098)
			(xy 423.471466 -133.071108) (xy 425.474382 -133.071108) (xy 425.478453 -133.015486) (xy 425.490579 -132.961049)
			(xy 425.510502 -132.908958) (xy 425.537798 -132.860323) (xy 425.571884 -132.81618) (xy 425.612033 -132.777471)
			(xy 425.657391 -132.74502) (xy 425.706991 -132.719519) (xy 425.759775 -132.701512) (xy 425.814618 -132.691382)
			(xy 425.870352 -132.689345) (xy 425.925789 -132.695445) (xy 425.979746 -132.709551) (xy 426.031075 -132.731363)
			(xy 426.078681 -132.760417) (xy 426.121549 -132.796092) (xy 426.158766 -132.837629) (xy 426.189539 -132.884142)
			(xy 426.213211 -132.934639) (xy 426.229279 -132.988046) (xy 426.237399 -133.043222) (xy 426.237908 -133.071108)
			(xy 426.237399 -133.098994) (xy 426.229279 -133.15417) (xy 426.213211 -133.207577) (xy 426.189539 -133.258074)
			(xy 426.158766 -133.304587) (xy 426.121549 -133.346124) (xy 426.078681 -133.381799) (xy 426.031075 -133.410853)
			(xy 425.979746 -133.432665) (xy 425.925789 -133.446771) (xy 425.870352 -133.452871) (xy 425.814618 -133.450834)
			(xy 425.759775 -133.440704) (xy 425.706991 -133.422697) (xy 425.657391 -133.397196) (xy 425.612033 -133.364745)
			(xy 425.571884 -133.326036) (xy 425.537798 -133.281893) (xy 425.510502 -133.233258) (xy 425.490579 -133.181167)
			(xy 425.478453 -133.12673) (xy 425.474382 -133.071108) (xy 423.471466 -133.071108) (xy 423.467471 -133.084387)
			(xy 423.443799 -133.134884) (xy 423.413026 -133.181397) (xy 423.375809 -133.222934) (xy 423.332941 -133.258609)
			(xy 423.285335 -133.287663) (xy 423.234006 -133.309475) (xy 423.180049 -133.323581) (xy 423.124612 -133.329681)
			(xy 423.068878 -133.327644) (xy 423.014035 -133.317514) (xy 422.961251 -133.299507) (xy 422.911651 -133.274006)
			(xy 422.866293 -133.241555) (xy 422.826144 -133.202846) (xy 422.792058 -133.158703) (xy 422.764762 -133.110068)
			(xy 422.744839 -133.057977) (xy 422.732713 -133.00354) (xy 422.728642 -132.947918) (xy 410.420566 -132.947918)
			(xy 410.420566 -133.478778) (xy 429.131728 -133.478778) (xy 429.135799 -133.423156) (xy 429.147925 -133.368719)
			(xy 429.167848 -133.316628) (xy 429.195144 -133.267993) (xy 429.22923 -133.22385) (xy 429.269379 -133.185141)
			(xy 429.314737 -133.15269) (xy 429.364337 -133.127189) (xy 429.417121 -133.109182) (xy 429.471964 -133.099052)
			(xy 429.527698 -133.097015) (xy 429.583135 -133.103115) (xy 429.637092 -133.117221) (xy 429.688421 -133.139033)
			(xy 429.736027 -133.168087) (xy 429.778895 -133.203762) (xy 429.816112 -133.245299) (xy 429.846885 -133.291812)
			(xy 429.870557 -133.342309) (xy 429.886625 -133.395716) (xy 429.894745 -133.450892) (xy 429.895254 -133.478778)
			(xy 429.894745 -133.506664) (xy 429.886625 -133.56184) (xy 429.870557 -133.615247) (xy 429.846885 -133.665744)
			(xy 429.816112 -133.712257) (xy 429.778895 -133.753794) (xy 429.736027 -133.789469) (xy 429.688421 -133.818523)
			(xy 429.637092 -133.840335) (xy 429.583135 -133.854441) (xy 429.527698 -133.860541) (xy 429.471964 -133.858504)
			(xy 429.417121 -133.848374) (xy 429.364337 -133.830367) (xy 429.314737 -133.804866) (xy 429.269379 -133.772415)
			(xy 429.22923 -133.733706) (xy 429.195144 -133.689563) (xy 429.167848 -133.640928) (xy 429.147925 -133.588837)
			(xy 429.135799 -133.5344) (xy 429.131728 -133.478778) (xy 410.420566 -133.478778) (xy 410.420566 -134.747762)
			(xy 429.158398 -134.747762) (xy 429.162469 -134.69214) (xy 429.174595 -134.637703) (xy 429.194518 -134.585612)
			(xy 429.221814 -134.536977) (xy 429.2559 -134.492834) (xy 429.296049 -134.454125) (xy 429.341407 -134.421674)
			(xy 429.391007 -134.396173) (xy 429.443791 -134.378166) (xy 429.498634 -134.368036) (xy 429.554368 -134.365999)
			(xy 429.609805 -134.372099) (xy 429.663762 -134.386205) (xy 429.715091 -134.408017) (xy 429.762697 -134.437071)
			(xy 429.805565 -134.472746) (xy 429.842782 -134.514283) (xy 429.873555 -134.560796) (xy 429.897227 -134.611293)
			(xy 429.913295 -134.6647) (xy 429.921415 -134.719876) (xy 429.921924 -134.747762) (xy 429.921415 -134.775648)
			(xy 429.913295 -134.830824) (xy 429.897227 -134.884231) (xy 429.873555 -134.934728) (xy 429.842782 -134.981241)
			(xy 429.805565 -135.022778) (xy 429.762697 -135.058453) (xy 429.715091 -135.087507) (xy 429.663762 -135.109319)
			(xy 429.609805 -135.123425) (xy 429.554368 -135.129525) (xy 429.498634 -135.127488) (xy 429.443791 -135.117358)
			(xy 429.391007 -135.099351) (xy 429.341407 -135.07385) (xy 429.296049 -135.041399) (xy 429.2559 -135.00269)
			(xy 429.221814 -134.958547) (xy 429.194518 -134.909912) (xy 429.174595 -134.857821) (xy 429.162469 -134.803384)
			(xy 429.158398 -134.747762) (xy 410.420566 -134.747762) (xy 410.420566 -135.142478) (xy 419.188136 -135.142478)
			(xy 419.192207 -135.086856) (xy 419.204333 -135.032419) (xy 419.224256 -134.980328) (xy 419.251552 -134.931693)
			(xy 419.285638 -134.88755) (xy 419.325787 -134.848841) (xy 419.371145 -134.81639) (xy 419.420745 -134.790889)
			(xy 419.473529 -134.772882) (xy 419.528372 -134.762752) (xy 419.584106 -134.760715) (xy 419.639543 -134.766815)
			(xy 419.6935 -134.780921) (xy 419.744829 -134.802733) (xy 419.792435 -134.831787) (xy 419.835303 -134.867462)
			(xy 419.87252 -134.908999) (xy 419.903293 -134.955512) (xy 419.926965 -135.006009) (xy 419.943033 -135.059416)
			(xy 419.951153 -135.114592) (xy 419.951662 -135.142478) (xy 419.951153 -135.170364) (xy 419.943033 -135.22554)
			(xy 419.926965 -135.278947) (xy 419.903293 -135.329444) (xy 419.87252 -135.375957) (xy 419.835303 -135.417494)
			(xy 419.792435 -135.453169) (xy 419.744829 -135.482223) (xy 419.6935 -135.504035) (xy 419.639543 -135.518141)
			(xy 419.584106 -135.524241) (xy 419.528372 -135.522204) (xy 419.473529 -135.512074) (xy 419.420745 -135.494067)
			(xy 419.371145 -135.468566) (xy 419.325787 -135.436115) (xy 419.285638 -135.397406) (xy 419.251552 -135.353263)
			(xy 419.224256 -135.304628) (xy 419.204333 -135.252537) (xy 419.192207 -135.1981) (xy 419.188136 -135.142478)
			(xy 410.420566 -135.142478) (xy 410.420566 -137.724388) (xy 421.191942 -137.724388) (xy 421.196013 -137.668766)
			(xy 421.208139 -137.614329) (xy 421.228062 -137.562238) (xy 421.255358 -137.513603) (xy 421.289444 -137.46946)
			(xy 421.329593 -137.430751) (xy 421.374951 -137.3983) (xy 421.424551 -137.372799) (xy 421.477335 -137.354792)
			(xy 421.532178 -137.344662) (xy 421.587912 -137.342625) (xy 421.643349 -137.348725) (xy 421.697306 -137.362831)
			(xy 421.748635 -137.384643) (xy 421.796241 -137.413697) (xy 421.839109 -137.449372) (xy 421.876326 -137.490909)
			(xy 421.907099 -137.537422) (xy 421.930771 -137.587919) (xy 421.946839 -137.641326) (xy 421.954959 -137.696502)
			(xy 421.955468 -137.724388) (xy 421.954959 -137.752274) (xy 421.946839 -137.80745) (xy 421.930771 -137.860857)
			(xy 421.907099 -137.911354) (xy 421.876326 -137.957867) (xy 421.839109 -137.999404) (xy 421.796241 -138.035079)
			(xy 421.748635 -138.064133) (xy 421.697306 -138.085945) (xy 421.643349 -138.100051) (xy 421.587912 -138.106151)
			(xy 421.532178 -138.104114) (xy 421.477335 -138.093984) (xy 421.424551 -138.075977) (xy 421.374951 -138.050476)
			(xy 421.329593 -138.018025) (xy 421.289444 -137.979316) (xy 421.255358 -137.935173) (xy 421.228062 -137.886538)
			(xy 421.208139 -137.834447) (xy 421.196013 -137.78001) (xy 421.191942 -137.724388) (xy 410.420566 -137.724388)
			(xy 410.420566 -138.575288) (xy 419.00043 -138.575288) (xy 419.004501 -138.519666) (xy 419.016627 -138.465229)
			(xy 419.03655 -138.413138) (xy 419.063846 -138.364503) (xy 419.097932 -138.32036) (xy 419.138081 -138.281651)
			(xy 419.183439 -138.2492) (xy 419.233039 -138.223699) (xy 419.285823 -138.205692) (xy 419.340666 -138.195562)
			(xy 419.3964 -138.193525) (xy 419.451837 -138.199625) (xy 419.505794 -138.213731) (xy 419.557123 -138.235543)
			(xy 419.604729 -138.264597) (xy 419.647597 -138.300272) (xy 419.684814 -138.341809) (xy 419.715587 -138.388322)
			(xy 419.739259 -138.438819) (xy 419.755327 -138.492226) (xy 419.763447 -138.547402) (xy 419.763956 -138.575288)
			(xy 419.763447 -138.603174) (xy 419.755327 -138.65835) (xy 419.739259 -138.711757) (xy 419.715587 -138.762254)
			(xy 419.684814 -138.808767) (xy 419.647597 -138.850304) (xy 419.604729 -138.885979) (xy 419.557123 -138.915033)
			(xy 419.505794 -138.936845) (xy 419.451837 -138.950951) (xy 419.3964 -138.957051) (xy 419.340666 -138.955014)
			(xy 419.285823 -138.944884) (xy 419.233039 -138.926877) (xy 419.183439 -138.901376) (xy 419.138081 -138.868925)
			(xy 419.097932 -138.830216) (xy 419.063846 -138.786073) (xy 419.03655 -138.737438) (xy 419.016627 -138.685347)
			(xy 419.004501 -138.63091) (xy 419.00043 -138.575288) (xy 410.420566 -138.575288) (xy 410.420566 -139.48664)
			(xy 417.582602 -139.48664) (xy 417.586673 -139.431018) (xy 417.598799 -139.376581) (xy 417.618722 -139.32449)
			(xy 417.646018 -139.275855) (xy 417.680104 -139.231712) (xy 417.720253 -139.193003) (xy 417.765611 -139.160552)
			(xy 417.815211 -139.135051) (xy 417.867995 -139.117044) (xy 417.922838 -139.106914) (xy 417.978572 -139.104877)
			(xy 418.034009 -139.110977) (xy 418.087966 -139.125083) (xy 418.139295 -139.146895) (xy 418.186901 -139.175949)
			(xy 418.229769 -139.211624) (xy 418.266986 -139.253161) (xy 418.297759 -139.299674) (xy 418.321431 -139.350171)
			(xy 418.337499 -139.403578) (xy 418.345619 -139.458754) (xy 418.346128 -139.48664) (xy 418.345619 -139.514526)
			(xy 418.343667 -139.527788) (xy 419.538402 -139.527788) (xy 419.542473 -139.472166) (xy 419.554599 -139.417729)
			(xy 419.574522 -139.365638) (xy 419.601818 -139.317003) (xy 419.635904 -139.27286) (xy 419.676053 -139.234151)
			(xy 419.721411 -139.2017) (xy 419.771011 -139.176199) (xy 419.823795 -139.158192) (xy 419.878638 -139.148062)
			(xy 419.934372 -139.146025) (xy 419.989809 -139.152125) (xy 420.043766 -139.166231) (xy 420.095095 -139.188043)
			(xy 420.142701 -139.217097) (xy 420.185569 -139.252772) (xy 420.222786 -139.294309) (xy 420.253559 -139.340822)
			(xy 420.277231 -139.391319) (xy 420.293299 -139.444726) (xy 420.301419 -139.499902) (xy 420.301928 -139.527788)
			(xy 420.301419 -139.555674) (xy 420.293299 -139.61085) (xy 420.277231 -139.664257) (xy 420.253559 -139.714754)
			(xy 420.222786 -139.761267) (xy 420.185569 -139.802804) (xy 420.142701 -139.838479) (xy 420.095095 -139.867533)
			(xy 420.043766 -139.889345) (xy 419.989809 -139.903451) (xy 419.934372 -139.909551) (xy 419.878638 -139.907514)
			(xy 419.823795 -139.897384) (xy 419.771011 -139.879377) (xy 419.721411 -139.853876) (xy 419.676053 -139.821425)
			(xy 419.635904 -139.782716) (xy 419.601818 -139.738573) (xy 419.574522 -139.689938) (xy 419.554599 -139.637847)
			(xy 419.542473 -139.58341) (xy 419.538402 -139.527788) (xy 418.343667 -139.527788) (xy 418.337499 -139.569702)
			(xy 418.321431 -139.623109) (xy 418.297759 -139.673606) (xy 418.266986 -139.720119) (xy 418.229769 -139.761656)
			(xy 418.186901 -139.797331) (xy 418.139295 -139.826385) (xy 418.087966 -139.848197) (xy 418.034009 -139.862303)
			(xy 417.978572 -139.868403) (xy 417.922838 -139.866366) (xy 417.867995 -139.856236) (xy 417.815211 -139.838229)
			(xy 417.765611 -139.812728) (xy 417.720253 -139.780277) (xy 417.680104 -139.741568) (xy 417.646018 -139.697425)
			(xy 417.618722 -139.64879) (xy 417.598799 -139.596699) (xy 417.586673 -139.542262) (xy 417.582602 -139.48664)
			(xy 410.420566 -139.48664) (xy 410.420566 -145.176748) (xy 415.772092 -145.176748) (xy 415.772092 -142.027148)
			(xy 415.772738 -142.002152) (xy 415.782536 -141.953129) (xy 415.801706 -141.906958) (xy 415.829513 -141.865412)
			(xy 415.846768 -141.847316) (xy 417.370768 -140.323316) (xy 417.388844 -140.306037) (xy 417.430395 -140.278231)
			(xy 417.476572 -140.259063) (xy 417.525602 -140.249272) (xy 417.5506 -140.24864) (xy 421.38727 -140.24864)
			(xy 422.640252 -138.995658) (xy 422.640252 -137.268458) (xy 422.236392 -136.864344) (xy 422.215056 -136.864344)
			(xy 422.187782 -136.863834) (xy 422.133781 -136.856144) (xy 422.081426 -136.84084) (xy 422.031785 -136.818234)
			(xy 421.985869 -136.788789) (xy 421.944616 -136.753103) (xy 421.908867 -136.711905) (xy 421.87935 -136.666036)
			(xy 421.856667 -136.616429) (xy 421.841282 -136.564098) (xy 421.833507 -136.510109) (xy 421.83304 -136.482836)
			(xy 421.833608 -136.452923) (xy 421.842966 -136.393832) (xy 421.861444 -136.33693) (xy 421.888587 -136.283615)
			(xy 421.905684 -136.259062) (xy 421.913053 -136.248163) (xy 421.922569 -136.223647) (xy 421.925501 -136.197514)
			(xy 421.921655 -136.171499) (xy 421.911287 -136.147331) (xy 421.895086 -136.126617) (xy 421.884856 -136.118346)
			(xy 421.861799 -136.100243) (xy 421.82107 -136.058082) (xy 421.787274 -136.010185) (xy 421.761205 -135.95768)
			(xy 421.74348 -135.901803) (xy 421.734514 -135.843872) (xy 421.73398 -135.814562) (xy 421.734348 -135.789347)
			(xy 421.740953 -135.739351) (xy 421.754095 -135.690663) (xy 421.763444 -135.667242) (xy 421.768303 -135.654323)
			(xy 421.771724 -135.626947) (xy 421.767685 -135.599656) (xy 421.756483 -135.574444) (xy 421.738935 -135.553155)
			(xy 421.716326 -135.537346) (xy 421.690307 -135.528172) (xy 421.676576 -135.52678) (xy 421.647954 -135.524335)
			(xy 421.591854 -135.51199) (xy 421.538238 -135.491375) (xy 421.488318 -135.462958) (xy 421.443221 -135.427378)
			(xy 421.403967 -135.385441) (xy 421.371442 -135.338094) (xy 421.346381 -135.286407) (xy 421.329351 -135.231548)
			(xy 421.320736 -135.174755) (xy 421.320214 -135.146034) (xy 421.3207 -135.118783) (xy 421.328456 -135.064835)
			(xy 421.343811 -135.01254) (xy 421.366453 -134.962963) (xy 421.395919 -134.917113) (xy 421.43161 -134.875922)
			(xy 421.472801 -134.840231) (xy 421.518651 -134.810765) (xy 421.568228 -134.788123) (xy 421.620523 -134.772768)
			(xy 421.674471 -134.765012) (xy 421.728973 -134.765012) (xy 421.782921 -134.772768) (xy 421.835216 -134.788123)
			(xy 421.884793 -134.810765) (xy 421.930643 -134.840231) (xy 421.971834 -134.875922) (xy 422.007525 -134.917113)
			(xy 422.036991 -134.962963) (xy 422.059633 -135.01254) (xy 422.074988 -135.064835) (xy 422.082744 -135.118783)
			(xy 422.08323 -135.146034) (xy 422.08286 -135.171249) (xy 422.076256 -135.221245) (xy 422.063114 -135.269932)
			(xy 422.053766 -135.293354) (xy 422.048903 -135.306273) (xy 422.045481 -135.333649) (xy 422.049519 -135.360942)
			(xy 422.060722 -135.386154) (xy 422.07827 -135.407444) (xy 422.100882 -135.423252) (xy 422.126902 -135.432425)
			(xy 422.140634 -135.433816) (xy 422.169256 -135.436256) (xy 422.225356 -135.448603) (xy 422.278972 -135.469218)
			(xy 422.328892 -135.497637) (xy 422.373988 -135.533217) (xy 422.413242 -135.575154) (xy 422.445767 -135.622501)
			(xy 422.470828 -135.674189) (xy 422.487858 -135.729048) (xy 422.496474 -135.785841) (xy 422.496996 -135.814562)
			(xy 422.496421 -135.844475) (xy 422.487063 -135.903565) (xy 422.468587 -135.960466) (xy 422.441447 -136.013782)
			(xy 422.424352 -136.038336) (xy 422.417 -136.049244) (xy 422.407492 -136.073757) (xy 422.404562 -136.099886)
			(xy 422.408405 -136.125896) (xy 422.418765 -136.150062) (xy 422.434956 -136.170778) (xy 422.44518 -136.179052)
			(xy 422.46826 -136.197196) (xy 422.509051 -136.239415) (xy 422.542884 -136.287392) (xy 422.568959 -136.339989)
			(xy 422.586659 -136.395963) (xy 422.595564 -136.45399) (xy 422.596056 -136.483344) (xy 422.596056 -136.50468)
			(xy 423.074592 -136.983216) (xy 423.091847 -137.001312) (xy 423.119658 -137.042857) (xy 423.138831 -137.089028)
			(xy 423.147027 -137.130028) (xy 428.753016 -137.130028) (xy 428.753463 -137.103293) (xy 428.760925 -137.050348)
			(xy 428.775708 -136.998963) (xy 428.797521 -136.950146) (xy 428.825937 -136.904853) (xy 428.860399 -136.863971)
			(xy 428.880016 -136.845802) (xy 428.890822 -136.835406) (xy 428.906368 -136.809781) (xy 428.913789 -136.780743)
			(xy 428.912443 -136.750802) (xy 428.902446 -136.722547) (xy 428.893986 -136.710166) (xy 428.876517 -136.68545)
			(xy 428.848814 -136.631639) (xy 428.829949 -136.574132) (xy 428.820397 -136.514367) (xy 428.819818 -136.484106)
			(xy 428.82029 -136.455888) (xy 428.828576 -136.400063) (xy 428.844998 -136.34607) (xy 428.869197 -136.295085)
			(xy 428.900645 -136.248223) (xy 428.938655 -136.206507) (xy 428.982397 -136.170847) (xy 429.030917 -136.142022)
			(xy 429.083154 -136.120661) (xy 429.137969 -136.107232) (xy 429.16602 -136.104122) (xy 429.180402 -136.102296)
			(xy 429.207356 -136.091662) (xy 429.230235 -136.073881) (xy 429.247195 -136.050386) (xy 429.256869 -136.023073)
			(xy 429.258478 -135.994141) (xy 429.255682 -135.979916) (xy 429.250944 -135.958447) (xy 429.245847 -135.914777)
			(xy 429.245522 -135.892794) (xy 429.246008 -135.865543) (xy 429.253764 -135.811595) (xy 429.269119 -135.7593)
			(xy 429.291761 -135.709723) (xy 429.321227 -135.663873) (xy 429.356918 -135.622682) (xy 429.398109 -135.586991)
			(xy 429.443959 -135.557525) (xy 429.493536 -135.534883) (xy 429.545831 -135.519528) (xy 429.599779 -135.511772)
			(xy 429.654281 -135.511772) (xy 429.708229 -135.519528) (xy 429.760524 -135.534883) (xy 429.810101 -135.557525)
			(xy 429.855951 -135.586991) (xy 429.897142 -135.622682) (xy 429.932833 -135.663873) (xy 429.962299 -135.709723)
			(xy 429.984941 -135.7593) (xy 430.000296 -135.811595) (xy 430.008052 -135.865543) (xy 430.008538 -135.892794)
			(xy 430.008015 -135.92101) (xy 429.999731 -135.97683) (xy 429.983312 -136.030819) (xy 429.959117 -136.081801)
			(xy 429.927675 -136.128661) (xy 429.889671 -136.170376) (xy 429.845935 -136.206037) (xy 429.797423 -136.234864)
			(xy 429.745192 -136.256229) (xy 429.690384 -136.269664) (xy 429.662336 -136.272778) (xy 429.64796 -136.274645)
			(xy 429.621005 -136.285266) (xy 429.598123 -136.303038) (xy 429.58116 -136.326525) (xy 429.571485 -136.353834)
			(xy 429.569877 -136.382761) (xy 429.572674 -136.396984) (xy 429.577413 -136.418453) (xy 429.582509 -136.462123)
			(xy 429.582834 -136.484106) (xy 429.582359 -136.51084) (xy 429.574905 -136.563785) (xy 429.560129 -136.61517)
			(xy 429.538321 -136.663988) (xy 429.509909 -136.709281) (xy 429.47545 -136.750163) (xy 429.455834 -136.768332)
			(xy 429.444998 -136.778702) (xy 429.429448 -136.804333) (xy 429.422029 -136.83338) (xy 429.423384 -136.863329)
			(xy 429.433395 -136.891588) (xy 429.441864 -136.903968) (xy 429.459298 -136.928708) (xy 429.487011 -136.982509)
			(xy 429.505885 -137.04001) (xy 429.515448 -137.099769) (xy 429.516032 -137.130028) (xy 429.515546 -137.157279)
			(xy 429.50779 -137.211227) (xy 429.492435 -137.263522) (xy 429.469793 -137.313099) (xy 429.440327 -137.358949)
			(xy 429.404636 -137.40014) (xy 429.363445 -137.435831) (xy 429.317595 -137.465297) (xy 429.268018 -137.487939)
			(xy 429.215723 -137.503294) (xy 429.161775 -137.51105) (xy 429.107273 -137.51105) (xy 429.053325 -137.503294)
			(xy 429.00103 -137.487939) (xy 428.951453 -137.465297) (xy 428.905603 -137.435831) (xy 428.864412 -137.40014)
			(xy 428.828721 -137.358949) (xy 428.799255 -137.313099) (xy 428.776613 -137.263522) (xy 428.761258 -137.211227)
			(xy 428.753502 -137.157279) (xy 428.753016 -137.130028) (xy 423.147027 -137.130028) (xy 423.148631 -137.138052)
			(xy 423.149268 -137.163048) (xy 423.149268 -138.143996) (xy 428.762158 -138.143996) (xy 428.766229 -138.088374)
			(xy 428.778355 -138.033937) (xy 428.798278 -137.981846) (xy 428.825574 -137.933211) (xy 428.85966 -137.889068)
			(xy 428.899809 -137.850359) (xy 428.945167 -137.817908) (xy 428.994767 -137.792407) (xy 429.047551 -137.7744)
			(xy 429.102394 -137.76427) (xy 429.158128 -137.762233) (xy 429.213565 -137.768333) (xy 429.267522 -137.782439)
			(xy 429.318851 -137.804251) (xy 429.366457 -137.833305) (xy 429.409325 -137.86898) (xy 429.446542 -137.910517)
			(xy 429.477315 -137.95703) (xy 429.500987 -138.007527) (xy 429.517055 -138.060934) (xy 429.525175 -138.11611)
			(xy 429.525684 -138.143996) (xy 429.525175 -138.171882) (xy 429.517055 -138.227058) (xy 429.500987 -138.280465)
			(xy 429.477315 -138.330962) (xy 429.446542 -138.377475) (xy 429.409325 -138.419012) (xy 429.366457 -138.454687)
			(xy 429.318851 -138.483741) (xy 429.267522 -138.505553) (xy 429.213565 -138.519659) (xy 429.158128 -138.525759)
			(xy 429.102394 -138.523722) (xy 429.047551 -138.513592) (xy 428.994767 -138.495585) (xy 428.945167 -138.470084)
			(xy 428.899809 -138.437633) (xy 428.85966 -138.398924) (xy 428.825574 -138.354781) (xy 428.798278 -138.306146)
			(xy 428.778355 -138.254055) (xy 428.766229 -138.199618) (xy 428.762158 -138.143996) (xy 423.149268 -138.143996)
			(xy 423.149268 -139.101068) (xy 423.148615 -139.126063) (xy 423.138816 -139.175085) (xy 423.119648 -139.221256)
			(xy 423.091845 -139.262803) (xy 423.074592 -139.2809) (xy 422.657524 -139.697968) (xy 423.5229 -139.697968)
			(xy 423.526971 -139.642346) (xy 423.539097 -139.587909) (xy 423.55902 -139.535818) (xy 423.586316 -139.487183)
			(xy 423.620402 -139.44304) (xy 423.660551 -139.404331) (xy 423.705909 -139.37188) (xy 423.755509 -139.346379)
			(xy 423.808293 -139.328372) (xy 423.863136 -139.318242) (xy 423.91887 -139.316205) (xy 423.974307 -139.322305)
			(xy 424.028264 -139.336411) (xy 424.079593 -139.358223) (xy 424.127199 -139.387277) (xy 424.170067 -139.422952)
			(xy 424.207284 -139.464489) (xy 424.238057 -139.511002) (xy 424.261729 -139.561499) (xy 424.277797 -139.614906)
			(xy 424.285917 -139.670082) (xy 424.286426 -139.697968) (xy 424.285917 -139.725854) (xy 424.277797 -139.78103)
			(xy 424.261729 -139.834437) (xy 424.238057 -139.884934) (xy 424.207284 -139.931447) (xy 424.170067 -139.972984)
			(xy 424.127199 -140.008659) (xy 424.079593 -140.037713) (xy 424.028264 -140.059525) (xy 423.974307 -140.073631)
			(xy 423.91887 -140.079731) (xy 423.863136 -140.077694) (xy 423.808293 -140.067564) (xy 423.755509 -140.049557)
			(xy 423.705909 -140.024056) (xy 423.660551 -139.991605) (xy 423.620402 -139.952896) (xy 423.586316 -139.908753)
			(xy 423.55902 -139.860118) (xy 423.539097 -139.808027) (xy 423.526971 -139.75359) (xy 423.5229 -139.697968)
			(xy 422.657524 -139.697968) (xy 422.091104 -140.264388) (xy 426.322996 -140.264388) (xy 426.327067 -140.208766)
			(xy 426.339193 -140.154329) (xy 426.359116 -140.102238) (xy 426.386412 -140.053603) (xy 426.420498 -140.00946)
			(xy 426.460647 -139.970751) (xy 426.506005 -139.9383) (xy 426.555605 -139.912799) (xy 426.608389 -139.894792)
			(xy 426.663232 -139.884662) (xy 426.718966 -139.882625) (xy 426.774403 -139.888725) (xy 426.82836 -139.902831)
			(xy 426.879689 -139.924643) (xy 426.927295 -139.953697) (xy 426.970163 -139.989372) (xy 427.00738 -140.030909)
			(xy 427.038153 -140.077422) (xy 427.061825 -140.127919) (xy 427.077893 -140.181326) (xy 427.086013 -140.236502)
			(xy 427.086522 -140.264388) (xy 427.086013 -140.292274) (xy 427.077893 -140.34745) (xy 427.061825 -140.400857)
			(xy 427.038153 -140.451354) (xy 427.00738 -140.497867) (xy 426.970163 -140.539404) (xy 426.927295 -140.575079)
			(xy 426.879689 -140.604133) (xy 426.82836 -140.625945) (xy 426.774403 -140.640051) (xy 426.718966 -140.646151)
			(xy 426.663232 -140.644114) (xy 426.608389 -140.633984) (xy 426.555605 -140.615977) (xy 426.506005 -140.590476)
			(xy 426.460647 -140.558025) (xy 426.420498 -140.519316) (xy 426.386412 -140.475173) (xy 426.359116 -140.426538)
			(xy 426.339193 -140.374447) (xy 426.327067 -140.32001) (xy 426.322996 -140.264388) (xy 422.091104 -140.264388)
			(xy 421.672512 -140.68298) (xy 421.654402 -140.70022) (xy 421.612862 -140.728034) (xy 421.566696 -140.747212)
			(xy 421.517675 -140.757016) (xy 421.49268 -140.757656) (xy 417.65601 -140.757656) (xy 417.387213 -141.026453)
			(xy 422.148465 -141.026453) (xy 422.148465 -140.971947) (xy 422.156222 -140.917997) (xy 422.171578 -140.8657)
			(xy 422.194221 -140.816121) (xy 422.223689 -140.770269) (xy 422.259382 -140.729077) (xy 422.300575 -140.693384)
			(xy 422.346428 -140.663917) (xy 422.396008 -140.641276) (xy 422.448305 -140.625921) (xy 422.502255 -140.618165)
			(xy 422.529508 -140.617702) (xy 422.555887 -140.618166) (xy 422.608144 -140.625419) (xy 422.658903 -140.639801)
			(xy 422.707198 -140.661037) (xy 422.752108 -140.688722) (xy 422.792777 -140.722329) (xy 422.82843 -140.761217)
			(xy 422.858387 -140.804644) (xy 422.87063 -140.828014) (xy 422.877332 -140.840373) (xy 422.896307 -140.861101)
			(xy 422.920221 -140.875863) (xy 422.947257 -140.883535) (xy 422.975359 -140.883535) (xy 423.002395 -140.875863)
			(xy 423.026309 -140.861101) (xy 423.045284 -140.840373) (xy 423.051986 -140.828014) (xy 423.064228 -140.804644)
			(xy 423.094189 -140.761219) (xy 423.129844 -140.722332) (xy 423.170513 -140.688725) (xy 423.215422 -140.661038)
			(xy 423.263715 -140.639798) (xy 423.314473 -140.62541) (xy 423.366729 -140.618147) (xy 423.393108 -140.617702)
			(xy 423.42036 -140.618168) (xy 423.474308 -140.625926) (xy 423.526603 -140.641282) (xy 423.576181 -140.663924)
			(xy 423.622031 -140.693392) (xy 423.663222 -140.729084) (xy 423.698913 -140.770275) (xy 423.728379 -140.816126)
			(xy 423.751021 -140.865704) (xy 423.766376 -140.918) (xy 423.774132 -140.971948) (xy 423.774132 -141.026452)
			(xy 423.766376 -141.0804) (xy 423.751021 -141.132696) (xy 423.728379 -141.182274) (xy 423.698913 -141.228125)
			(xy 423.663222 -141.269316) (xy 423.622031 -141.305008) (xy 423.576181 -141.334476) (xy 423.526603 -141.357118)
			(xy 423.474308 -141.372474) (xy 423.42036 -141.380232) (xy 423.393108 -141.380718) (xy 423.36673 -141.38023)
			(xy 423.314475 -141.372979) (xy 423.263716 -141.3586) (xy 423.215422 -141.337367) (xy 423.170512 -141.309686)
			(xy 423.129843 -141.276083) (xy 423.094189 -141.237198) (xy 423.06423 -141.193774) (xy 423.051986 -141.170406)
			(xy 423.045284 -141.158047) (xy 423.026309 -141.137319) (xy 423.002395 -141.122557) (xy 422.975359 -141.114885)
			(xy 422.947257 -141.114885) (xy 422.920221 -141.122557) (xy 422.896307 -141.137319) (xy 422.877332 -141.158047)
			(xy 422.87063 -141.170406) (xy 422.858385 -141.193774) (xy 422.828423 -141.237198) (xy 422.792768 -141.276084)
			(xy 422.752099 -141.30969) (xy 422.707191 -141.337377) (xy 422.658899 -141.358618) (xy 422.608141 -141.373008)
			(xy 422.555887 -141.380272) (xy 422.529508 -141.380718) (xy 422.502255 -141.380235) (xy 422.448305 -141.372479)
			(xy 422.396008 -141.357124) (xy 422.346428 -141.334483) (xy 422.300575 -141.305016) (xy 422.259382 -141.269323)
			(xy 422.223689 -141.228131) (xy 422.194221 -141.182279) (xy 422.171578 -141.1327) (xy 422.156222 -141.080403)
			(xy 422.148465 -141.026453) (xy 417.387213 -141.026453) (xy 416.998658 -141.415008) (xy 426.048422 -141.415008)
			(xy 426.052493 -141.359386) (xy 426.064619 -141.304949) (xy 426.084542 -141.252858) (xy 426.111838 -141.204223)
			(xy 426.145924 -141.16008) (xy 426.186073 -141.121371) (xy 426.231431 -141.08892) (xy 426.281031 -141.063419)
			(xy 426.333815 -141.045412) (xy 426.388658 -141.035282) (xy 426.444392 -141.033245) (xy 426.499829 -141.039345)
			(xy 426.553786 -141.053451) (xy 426.605115 -141.075263) (xy 426.652721 -141.104317) (xy 426.695589 -141.139992)
			(xy 426.732806 -141.181529) (xy 426.763579 -141.228042) (xy 426.787251 -141.278539) (xy 426.803319 -141.331946)
			(xy 426.811439 -141.387122) (xy 426.811948 -141.415008) (xy 426.811439 -141.442894) (xy 426.803319 -141.49807)
			(xy 426.787251 -141.551477) (xy 426.763579 -141.601974) (xy 426.732806 -141.648487) (xy 426.695589 -141.690024)
			(xy 426.652721 -141.725699) (xy 426.605115 -141.754753) (xy 426.553786 -141.776565) (xy 426.499829 -141.790671)
			(xy 426.444392 -141.796771) (xy 426.388658 -141.794734) (xy 426.333815 -141.784604) (xy 426.281031 -141.766597)
			(xy 426.231431 -141.741096) (xy 426.186073 -141.708645) (xy 426.145924 -141.669936) (xy 426.111838 -141.625793)
			(xy 426.084542 -141.577158) (xy 426.064619 -141.525067) (xy 426.052493 -141.47063) (xy 426.048422 -141.415008)
			(xy 416.998658 -141.415008) (xy 416.281108 -142.132558) (xy 416.281108 -145.071338) (xy 419.81501 -148.60524)
			(xy 422.5544 -148.60524) (xy 422.579396 -148.605871) (xy 422.628419 -148.615676) (xy 422.67459 -148.634851)
			(xy 422.716136 -148.66266) (xy 422.734232 -148.679916) (xy 423.343832 -149.289516) (xy 423.361077 -149.307622)
			(xy 423.388892 -149.349162) (xy 423.408069 -149.39533) (xy 423.417871 -149.444352) (xy 423.418508 -149.469348)
			(xy 423.418508 -151.018748) (xy 423.976292 -151.018748) (xy 423.976778 -150.991497) (xy 423.984534 -150.937549)
			(xy 423.999889 -150.885254) (xy 424.022531 -150.835677) (xy 424.051997 -150.789827) (xy 424.087688 -150.748636)
			(xy 424.128879 -150.712945) (xy 424.174729 -150.683479) (xy 424.224306 -150.660837) (xy 424.276601 -150.645482)
			(xy 424.330549 -150.637726) (xy 424.385051 -150.637726) (xy 424.438999 -150.645482) (xy 424.491294 -150.660837)
			(xy 424.540871 -150.683479) (xy 424.586721 -150.712945) (xy 424.627912 -150.748636) (xy 424.663603 -150.789827)
			(xy 424.693069 -150.835677) (xy 424.715711 -150.885254) (xy 424.731066 -150.937549) (xy 424.738822 -150.991497)
			(xy 424.739308 -151.018748) (xy 424.739308 -151.019002) (xy 424.739877 -151.034449) (xy 424.749157 -151.063917)
			(xy 424.766809 -151.089273) (xy 424.791224 -151.108204) (xy 424.820177 -151.118986) (xy 424.835574 -151.120348)
			(xy 424.864452 -151.122457) (xy 424.921128 -151.134291) (xy 424.975366 -151.154551) (xy 425.025922 -151.182773)
			(xy 425.071634 -151.218307) (xy 425.111453 -151.26034) (xy 425.144465 -151.307905) (xy 425.169913 -151.359911)
			(xy 425.187213 -151.415165) (xy 425.195968 -151.472399) (xy 425.196508 -151.501348) (xy 425.196022 -151.528599)
			(xy 425.188266 -151.582547) (xy 425.172911 -151.634842) (xy 425.150269 -151.684419) (xy 425.120803 -151.730269)
			(xy 425.085112 -151.77146) (xy 425.043921 -151.807151) (xy 424.998071 -151.836617) (xy 424.948494 -151.859259)
			(xy 424.896199 -151.874614) (xy 424.842251 -151.88237) (xy 424.787749 -151.88237) (xy 424.733801 -151.874614)
			(xy 424.681506 -151.859259) (xy 424.631929 -151.836617) (xy 424.586079 -151.807151) (xy 424.544888 -151.77146)
			(xy 424.509197 -151.730269) (xy 424.479731 -151.684419) (xy 424.457089 -151.634842) (xy 424.441734 -151.582547)
			(xy 424.433978 -151.528599) (xy 424.433492 -151.501348) (xy 424.433492 -151.501094) (xy 424.432927 -151.485647)
			(xy 424.423646 -151.456178) (xy 424.405993 -151.430823) (xy 424.381577 -151.411891) (xy 424.352623 -151.40111)
			(xy 424.337226 -151.399748) (xy 424.308348 -151.397643) (xy 424.251671 -151.385809) (xy 424.197432 -151.365548)
			(xy 424.146877 -151.337326) (xy 424.101165 -151.301791) (xy 424.061346 -151.259758) (xy 424.028333 -151.212193)
			(xy 424.002885 -151.160186) (xy 423.985586 -151.104931) (xy 423.976832 -151.047698) (xy 423.976292 -151.018748)
			(xy 423.418508 -151.018748) (xy 423.418508 -151.221948) (xy 423.41786 -151.246944) (xy 423.408062 -151.295967)
			(xy 423.388893 -151.342138) (xy 423.361087 -151.383684) (xy 423.343832 -151.40178) (xy 422.353232 -152.39238)
			(xy 422.335156 -152.409658) (xy 422.293605 -152.437465) (xy 422.247427 -152.456632) (xy 422.198398 -152.466424)
			(xy 422.1734 -152.467056) (xy 421.74541 -152.467056) (xy 421.660574 -152.551638) (xy 421.715184 -152.606248)
			(xy 421.741346 -152.601676) (xy 421.757784 -152.598949) (xy 421.790979 -152.596026) (xy 421.80764 -152.595834)
			(xy 421.834892 -152.596239) (xy 421.888842 -152.604001) (xy 421.941137 -152.619361) (xy 421.990715 -152.642007)
			(xy 422.036565 -152.671477) (xy 422.077755 -152.707173) (xy 422.113447 -152.748367) (xy 422.142912 -152.79422)
			(xy 422.165553 -152.8438) (xy 422.180908 -152.896097) (xy 422.188664 -152.950048) (xy 422.188664 -152.956514)
			(xy 422.32402 -152.956514) (xy 422.328091 -152.900892) (xy 422.340217 -152.846455) (xy 422.36014 -152.794364)
			(xy 422.387436 -152.745729) (xy 422.421522 -152.701586) (xy 422.461671 -152.662877) (xy 422.507029 -152.630426)
			(xy 422.556629 -152.604925) (xy 422.609413 -152.586918) (xy 422.664256 -152.576788) (xy 422.71999 -152.574751)
			(xy 422.775427 -152.580851) (xy 422.829384 -152.594957) (xy 422.880713 -152.616769) (xy 422.928319 -152.645823)
			(xy 422.971187 -152.681498) (xy 423.008404 -152.723035) (xy 423.039177 -152.769548) (xy 423.062849 -152.820045)
			(xy 423.078917 -152.873452) (xy 423.087037 -152.928628) (xy 423.087546 -152.956514) (xy 423.087037 -152.9844)
			(xy 423.078917 -153.039576) (xy 423.062849 -153.092983) (xy 423.039177 -153.14348) (xy 423.008404 -153.189993)
			(xy 422.971187 -153.23153) (xy 422.928319 -153.267205) (xy 422.880713 -153.296259) (xy 422.829384 -153.318071)
			(xy 422.775427 -153.332177) (xy 422.71999 -153.338277) (xy 422.664256 -153.33624) (xy 422.609413 -153.32611)
			(xy 422.556629 -153.308103) (xy 422.507029 -153.282602) (xy 422.461671 -153.250151) (xy 422.421522 -153.211442)
			(xy 422.387436 -153.167299) (xy 422.36014 -153.118664) (xy 422.340217 -153.066573) (xy 422.328091 -153.012136)
			(xy 422.32402 -152.956514) (xy 422.188664 -152.956514) (xy 422.188664 -153.004552) (xy 422.180908 -153.058503)
			(xy 422.165553 -153.1108) (xy 422.142912 -153.16038) (xy 422.113447 -153.206233) (xy 422.077755 -153.247427)
			(xy 422.036565 -153.283123) (xy 421.990715 -153.312593) (xy 421.941137 -153.335239) (xy 421.888842 -153.350599)
			(xy 421.834892 -153.358361) (xy 421.80764 -153.35885) (xy 421.779699 -153.358345) (xy 421.72441 -153.350219)
			(xy 421.670901 -153.334107) (xy 421.620319 -153.310353) (xy 421.573747 -153.279468) (xy 421.532185 -153.242113)
			(xy 421.496523 -153.199089) (xy 421.467526 -153.151319) (xy 421.445816 -153.099826) (xy 421.431858 -153.045715)
			(xy 421.428418 -153.017982) (xy 421.426367 -153.003794) (xy 421.415578 -152.977252) (xy 421.397842 -152.954752)
			(xy 421.374553 -152.938064) (xy 421.347546 -152.928502) (xy 421.318946 -152.926817) (xy 421.291003 -152.933143)
			(xy 421.265916 -152.946981) (xy 421.255444 -152.956768) (xy 421.120824 -153.091388) (xy 421.120824 -153.54046)
			(xy 423.60037 -153.54046) (xy 423.604441 -153.484838) (xy 423.616567 -153.430401) (xy 423.63649 -153.37831)
			(xy 423.663786 -153.329675) (xy 423.697872 -153.285532) (xy 423.738021 -153.246823) (xy 423.783379 -153.214372)
			(xy 423.832979 -153.188871) (xy 423.885763 -153.170864) (xy 423.940606 -153.160734) (xy 423.99634 -153.158697)
			(xy 424.051777 -153.164797) (xy 424.105734 -153.178903) (xy 424.157063 -153.200715) (xy 424.204669 -153.229769)
			(xy 424.247537 -153.265444) (xy 424.284754 -153.306981) (xy 424.315527 -153.353494) (xy 424.339199 -153.403991)
			(xy 424.355267 -153.457398) (xy 424.363387 -153.512574) (xy 424.363896 -153.54046) (xy 424.363387 -153.568346)
			(xy 424.355267 -153.623522) (xy 424.339199 -153.676929) (xy 424.315527 -153.727426) (xy 424.284754 -153.773939)
			(xy 424.247537 -153.815476) (xy 424.204669 -153.851151) (xy 424.157063 -153.880205) (xy 424.105734 -153.902017)
			(xy 424.051777 -153.916123) (xy 423.99634 -153.922223) (xy 423.940606 -153.920186) (xy 423.885763 -153.910056)
			(xy 423.832979 -153.892049) (xy 423.783379 -153.866548) (xy 423.738021 -153.834097) (xy 423.697872 -153.795388)
			(xy 423.663786 -153.751245) (xy 423.63649 -153.70261) (xy 423.616567 -153.650519) (xy 423.604441 -153.596082)
			(xy 423.60037 -153.54046) (xy 421.120824 -153.54046) (xy 421.120824 -154.925854) (xy 421.450453 -154.925854)
			(xy 421.450453 -154.871346) (xy 421.458211 -154.817394) (xy 421.473568 -154.765094) (xy 421.496212 -154.715513)
			(xy 421.525681 -154.669659) (xy 421.561377 -154.628465) (xy 421.602572 -154.592772) (xy 421.648427 -154.563304)
			(xy 421.698009 -154.540662) (xy 421.750309 -154.525307) (xy 421.804262 -154.517552) (xy 421.831516 -154.51709)
			(xy 421.861892 -154.517675) (xy 421.921876 -154.527306) (xy 421.979575 -154.54632) (xy 422.033532 -154.574239)
			(xy 422.082383 -154.610355) (xy 422.104058 -154.631644) (xy 422.113809 -154.640955) (xy 422.137082 -154.65455)
			(xy 422.163099 -154.661592) (xy 422.190051 -154.661592) (xy 422.216068 -154.65455) (xy 422.239341 -154.640955)
			(xy 422.249092 -154.631644) (xy 422.270748 -154.610335) (xy 422.319604 -154.574222) (xy 422.373566 -154.546308)
			(xy 422.43127 -154.527299) (xy 422.491257 -154.517676) (xy 422.521634 -154.51709) (xy 422.548884 -154.517582)
			(xy 422.602827 -154.525342) (xy 422.655118 -154.5407) (xy 422.70469 -154.563343) (xy 422.750536 -154.592811)
			(xy 422.791722 -154.628502) (xy 422.82741 -154.669691) (xy 422.856873 -154.71554) (xy 422.879511 -154.765114)
			(xy 422.894865 -154.817406) (xy 422.90262 -154.87135) (xy 422.90262 -154.92585) (xy 422.894865 -154.979794)
			(xy 422.879511 -155.032086) (xy 422.856873 -155.08166) (xy 422.82741 -155.127509) (xy 422.791722 -155.168698)
			(xy 422.750536 -155.204389) (xy 422.70469 -155.233857) (xy 422.655118 -155.2565) (xy 422.602827 -155.271858)
			(xy 422.548884 -155.279618) (xy 422.521634 -155.280106) (xy 422.491257 -155.279554) (xy 422.431272 -155.269915)
			(xy 422.373572 -155.250893) (xy 422.319615 -155.222967) (xy 422.270766 -155.186844) (xy 422.249092 -155.165552)
			(xy 422.239364 -155.156194) (xy 422.216103 -155.142518) (xy 422.190067 -155.135431) (xy 422.163083 -155.135431)
			(xy 422.137047 -155.142518) (xy 422.113786 -155.156194) (xy 422.104058 -155.165552) (xy 422.082379 -155.186837)
			(xy 422.033529 -155.222953) (xy 421.979573 -155.250871) (xy 421.921874 -155.269886) (xy 421.861891 -155.279516)
			(xy 421.831516 -155.280106) (xy 421.804262 -155.279648) (xy 421.750309 -155.271893) (xy 421.698009 -155.256538)
			(xy 421.648427 -155.233896) (xy 421.602572 -155.204428) (xy 421.561377 -155.168735) (xy 421.525681 -155.127541)
			(xy 421.496212 -155.081687) (xy 421.473568 -155.032106) (xy 421.458211 -154.979806) (xy 421.450453 -154.925854)
			(xy 421.120824 -154.925854) (xy 421.120824 -154.932634) (xy 421.140433 -154.950823) (xy 421.174937 -154.991688)
			(xy 421.203398 -155.036969) (xy 421.225259 -155.085781) (xy 421.240091 -155.137166) (xy 421.247605 -155.190119)
			(xy 421.248078 -155.21686) (xy 421.247592 -155.244111) (xy 421.239836 -155.298059) (xy 421.224481 -155.350354)
			(xy 421.201839 -155.399931) (xy 421.172373 -155.445781) (xy 421.136682 -155.486972) (xy 421.095491 -155.522663)
			(xy 421.049641 -155.552129) (xy 421.000064 -155.574771) (xy 420.947769 -155.590126) (xy 420.893821 -155.597882)
			(xy 420.839319 -155.597882) (xy 420.785371 -155.590126) (xy 420.733076 -155.574771) (xy 420.683499 -155.552129)
			(xy 420.637649 -155.522663) (xy 420.596458 -155.486972) (xy 420.560767 -155.445781) (xy 420.531301 -155.399931)
			(xy 420.508659 -155.350354) (xy 420.493304 -155.298059) (xy 420.485548 -155.244111) (xy 420.485062 -155.21686)
			(xy 420.485517 -155.190115) (xy 420.493012 -155.137154) (xy 420.507833 -155.085759) (xy 420.529692 -155.036939)
			(xy 420.558158 -154.991653) (xy 420.592673 -154.95079) (xy 420.612316 -154.932634) (xy 420.612316 -152.985978)
			(xy 420.612942 -152.960995) (xy 420.622683 -152.911989) (xy 420.641786 -152.865819) (xy 420.669519 -152.824257)
			(xy 420.686738 -152.806146) (xy 421.460168 -152.032716) (xy 421.478244 -152.015437) (xy 421.519795 -151.987631)
			(xy 421.565972 -151.968463) (xy 421.615002 -151.958672) (xy 421.64 -151.95804) (xy 422.06799 -151.95804)
			(xy 422.909492 -151.116538) (xy 422.909492 -149.574758) (xy 422.44899 -149.114256) (xy 419.7096 -149.114256)
			(xy 419.684604 -149.113626) (xy 419.63558 -149.103821) (xy 419.58941 -149.084645) (xy 419.547864 -149.056836)
			(xy 419.529768 -149.03958) (xy 415.846768 -145.35658) (xy 415.829521 -145.338476) (xy 415.801706 -145.296935)
			(xy 415.78253 -145.250767) (xy 415.772729 -145.201744) (xy 415.772092 -145.176748) (xy 410.420566 -145.176748)
			(xy 410.420566 -147.99564) (xy 410.446852 -147.996656) (xy 410.498711 -148.005468) (xy 410.548709 -148.021812)
			(xy 410.59576 -148.045333) (xy 410.638839 -148.075519) (xy 410.677009 -148.111713) (xy 410.70944 -148.153129)
			(xy 410.735427 -148.198864) (xy 410.754403 -148.247924) (xy 410.765957 -148.299242) (xy 410.769836 -148.351701)
			(xy 410.765956 -148.40416) (xy 410.754403 -148.455478) (xy 410.735426 -148.504538) (xy 410.709439 -148.550273)
			(xy 410.677008 -148.591688) (xy 410.638838 -148.627882) (xy 410.595758 -148.658068) (xy 410.548708 -148.681589)
			(xy 410.498709 -148.697933) (xy 410.44685 -148.706745) (xy 410.420566 -148.707856) (xy 410.420566 -150.423949)
			(xy 420.30348 -150.423949) (xy 420.30348 -150.369451) (xy 420.311235 -150.315508) (xy 420.326587 -150.263217)
			(xy 420.349225 -150.213643) (xy 420.378687 -150.167796) (xy 420.414373 -150.126607) (xy 420.455557 -150.090915)
			(xy 420.501401 -150.061448) (xy 420.550972 -150.038804) (xy 420.603261 -150.023445) (xy 420.657203 -150.015683)
			(xy 420.684452 -150.015194) (xy 420.711821 -150.01569) (xy 420.765999 -150.023501) (xy 420.818502 -150.038983)
			(xy 420.868249 -150.061818) (xy 420.914217 -150.091536) (xy 420.93515 -150.109174) (xy 420.946478 -150.11841)
			(xy 420.973035 -150.130586) (xy 421.001952 -150.134759) (xy 421.030869 -150.130586) (xy 421.057426 -150.11841)
			(xy 421.068754 -150.109174) (xy 421.089687 -150.091533) (xy 421.135655 -150.061809) (xy 421.185401 -150.038963)
			(xy 421.237903 -150.023467) (xy 421.292081 -150.015638) (xy 421.346823 -150.015638) (xy 421.401001 -150.023467)
			(xy 421.453503 -150.038963) (xy 421.503249 -150.061809) (xy 421.549217 -150.091533) (xy 421.57015 -150.109174)
			(xy 421.581478 -150.11841) (xy 421.608035 -150.130586) (xy 421.636952 -150.134759) (xy 421.665869 -150.130586)
			(xy 421.692426 -150.11841) (xy 421.703754 -150.109174) (xy 421.724689 -150.091539) (xy 421.770662 -150.061827)
			(xy 421.820408 -150.038991) (xy 421.872908 -150.023499) (xy 421.927083 -150.015669) (xy 421.954452 -150.015194)
			(xy 421.981707 -150.01565) (xy 422.035664 -150.023402) (xy 422.087968 -150.038753) (xy 422.137554 -150.061393)
			(xy 422.183413 -150.09086) (xy 422.224612 -150.126554) (xy 422.260311 -150.167748) (xy 422.289784 -150.213604)
			(xy 422.31243 -150.263187) (xy 422.327788 -150.315489) (xy 422.335547 -150.369445) (xy 422.335547 -150.423955)
			(xy 422.327788 -150.477911) (xy 422.31243 -150.530213) (xy 422.289784 -150.579796) (xy 422.260311 -150.625652)
			(xy 422.224612 -150.666846) (xy 422.183413 -150.70254) (xy 422.137554 -150.732007) (xy 422.087968 -150.754647)
			(xy 422.035664 -150.769998) (xy 421.981707 -150.77775) (xy 421.954452 -150.77821) (xy 421.927083 -150.777711)
			(xy 421.872905 -150.769901) (xy 421.820403 -150.754419) (xy 421.770655 -150.731585) (xy 421.724687 -150.701868)
			(xy 421.703754 -150.68423) (xy 421.692426 -150.674994) (xy 421.665869 -150.662818) (xy 421.636952 -150.658645)
			(xy 421.608035 -150.662818) (xy 421.581478 -150.674994) (xy 421.57015 -150.68423) (xy 421.549217 -150.701871)
			(xy 421.503249 -150.731595) (xy 421.453503 -150.754441) (xy 421.401001 -150.769937) (xy 421.346823 -150.777766)
			(xy 421.292081 -150.777766) (xy 421.237903 -150.769937) (xy 421.185401 -150.754441) (xy 421.135655 -150.731595)
			(xy 421.089687 -150.701871) (xy 421.068754 -150.68423) (xy 421.057426 -150.674994) (xy 421.030869 -150.662818)
			(xy 421.001952 -150.658645) (xy 420.973035 -150.662818) (xy 420.946478 -150.674994) (xy 420.93515 -150.68423)
			(xy 420.914214 -150.701864) (xy 420.868242 -150.731575) (xy 420.818495 -150.754412) (xy 420.765996 -150.769904)
			(xy 420.711821 -150.777735) (xy 420.684452 -150.77821) (xy 420.657203 -150.777717) (xy 420.603261 -150.769955)
			(xy 420.550972 -150.754596) (xy 420.501401 -150.731952) (xy 420.455557 -150.702485) (xy 420.414373 -150.666793)
			(xy 420.378687 -150.625604) (xy 420.349225 -150.579757) (xy 420.326587 -150.530183) (xy 420.311235 -150.477892)
			(xy 420.30348 -150.423949) (xy 410.420566 -150.423949) (xy 410.420566 -151.116284) (xy 418.675564 -151.116284)
			(xy 418.679635 -151.060662) (xy 418.691761 -151.006225) (xy 418.711684 -150.954134) (xy 418.73898 -150.905499)
			(xy 418.773066 -150.861356) (xy 418.813215 -150.822647) (xy 418.858573 -150.790196) (xy 418.908173 -150.764695)
			(xy 418.960957 -150.746688) (xy 419.0158 -150.736558) (xy 419.071534 -150.734521) (xy 419.126971 -150.740621)
			(xy 419.180928 -150.754727) (xy 419.232257 -150.776539) (xy 419.279863 -150.805593) (xy 419.322731 -150.841268)
			(xy 419.359948 -150.882805) (xy 419.390721 -150.929318) (xy 419.414393 -150.979815) (xy 419.430461 -151.033222)
			(xy 419.438581 -151.088398) (xy 419.43909 -151.116284) (xy 419.439044 -151.118824) (xy 419.681658 -151.118824)
			(xy 419.685729 -151.063202) (xy 419.697855 -151.008765) (xy 419.717778 -150.956674) (xy 419.745074 -150.908039)
			(xy 419.77916 -150.863896) (xy 419.819309 -150.825187) (xy 419.864667 -150.792736) (xy 419.914267 -150.767235)
			(xy 419.967051 -150.749228) (xy 420.021894 -150.739098) (xy 420.077628 -150.737061) (xy 420.133065 -150.743161)
			(xy 420.187022 -150.757267) (xy 420.238351 -150.779079) (xy 420.285957 -150.808133) (xy 420.328825 -150.843808)
			(xy 420.366042 -150.885345) (xy 420.396815 -150.931858) (xy 420.420487 -150.982355) (xy 420.436555 -151.035762)
			(xy 420.444675 -151.090938) (xy 420.445184 -151.118824) (xy 420.444675 -151.14671) (xy 420.436555 -151.201886)
			(xy 420.420487 -151.255293) (xy 420.396815 -151.30579) (xy 420.366042 -151.352303) (xy 420.328825 -151.39384)
			(xy 420.285957 -151.429515) (xy 420.238351 -151.458569) (xy 420.187022 -151.480381) (xy 420.133065 -151.494487)
			(xy 420.077628 -151.500587) (xy 420.021894 -151.49855) (xy 419.967051 -151.48842) (xy 419.914267 -151.470413)
			(xy 419.864667 -151.444912) (xy 419.819309 -151.412461) (xy 419.77916 -151.373752) (xy 419.745074 -151.329609)
			(xy 419.717778 -151.280974) (xy 419.697855 -151.228883) (xy 419.685729 -151.174446) (xy 419.681658 -151.118824)
			(xy 419.439044 -151.118824) (xy 419.438581 -151.14417) (xy 419.430461 -151.199346) (xy 419.414393 -151.252753)
			(xy 419.390721 -151.30325) (xy 419.359948 -151.349763) (xy 419.322731 -151.3913) (xy 419.279863 -151.426975)
			(xy 419.232257 -151.456029) (xy 419.180928 -151.477841) (xy 419.126971 -151.491947) (xy 419.071534 -151.498047)
			(xy 419.0158 -151.49601) (xy 418.960957 -151.48588) (xy 418.908173 -151.467873) (xy 418.858573 -151.442372)
			(xy 418.813215 -151.409921) (xy 418.773066 -151.371212) (xy 418.73898 -151.327069) (xy 418.711684 -151.278434)
			(xy 418.691761 -151.226343) (xy 418.679635 -151.171906) (xy 418.675564 -151.116284) (xy 410.420566 -151.116284)
			(xy 410.420566 -152.03297) (xy 418.678358 -152.03297) (xy 418.682429 -151.977348) (xy 418.694555 -151.922911)
			(xy 418.714478 -151.87082) (xy 418.741774 -151.822185) (xy 418.77586 -151.778042) (xy 418.816009 -151.739333)
			(xy 418.861367 -151.706882) (xy 418.910967 -151.681381) (xy 418.963751 -151.663374) (xy 419.018594 -151.653244)
			(xy 419.074328 -151.651207) (xy 419.129765 -151.657307) (xy 419.183722 -151.671413) (xy 419.235051 -151.693225)
			(xy 419.282657 -151.722279) (xy 419.325525 -151.757954) (xy 419.362742 -151.799491) (xy 419.393515 -151.846004)
			(xy 419.417187 -151.896501) (xy 419.433255 -151.949908) (xy 419.441375 -152.005084) (xy 419.441884 -152.03297)
			(xy 419.441787 -152.038304) (xy 419.676578 -152.038304) (xy 419.680649 -151.982682) (xy 419.692775 -151.928245)
			(xy 419.712698 -151.876154) (xy 419.739994 -151.827519) (xy 419.77408 -151.783376) (xy 419.814229 -151.744667)
			(xy 419.859587 -151.712216) (xy 419.909187 -151.686715) (xy 419.961971 -151.668708) (xy 420.016814 -151.658578)
			(xy 420.072548 -151.656541) (xy 420.127985 -151.662641) (xy 420.181942 -151.676747) (xy 420.233271 -151.698559)
			(xy 420.280877 -151.727613) (xy 420.323745 -151.763288) (xy 420.360962 -151.804825) (xy 420.391735 -151.851338)
			(xy 420.415407 -151.901835) (xy 420.431475 -151.955242) (xy 420.439595 -152.010418) (xy 420.440104 -152.038304)
			(xy 420.439595 -152.06619) (xy 420.431475 -152.121366) (xy 420.415407 -152.174773) (xy 420.391735 -152.22527)
			(xy 420.360962 -152.271783) (xy 420.323745 -152.31332) (xy 420.280877 -152.348995) (xy 420.233271 -152.378049)
			(xy 420.181942 -152.399861) (xy 420.127985 -152.413967) (xy 420.072548 -152.420067) (xy 420.016814 -152.41803)
			(xy 419.961971 -152.4079) (xy 419.909187 -152.389893) (xy 419.859587 -152.364392) (xy 419.814229 -152.331941)
			(xy 419.77408 -152.293232) (xy 419.739994 -152.249089) (xy 419.712698 -152.200454) (xy 419.692775 -152.148363)
			(xy 419.680649 -152.093926) (xy 419.676578 -152.038304) (xy 419.441787 -152.038304) (xy 419.441375 -152.060856)
			(xy 419.433255 -152.116032) (xy 419.417187 -152.169439) (xy 419.393515 -152.219936) (xy 419.362742 -152.266449)
			(xy 419.325525 -152.307986) (xy 419.282657 -152.343661) (xy 419.235051 -152.372715) (xy 419.183722 -152.394527)
			(xy 419.129765 -152.408633) (xy 419.074328 -152.414733) (xy 419.018594 -152.412696) (xy 418.963751 -152.402566)
			(xy 418.910967 -152.384559) (xy 418.861367 -152.359058) (xy 418.816009 -152.326607) (xy 418.77586 -152.287898)
			(xy 418.741774 -152.243755) (xy 418.714478 -152.19512) (xy 418.694555 -152.143029) (xy 418.682429 -152.088592)
			(xy 418.678358 -152.03297) (xy 410.420566 -152.03297) (xy 410.420566 -155.499308) (xy 417.524182 -155.499308)
			(xy 417.528253 -155.443686) (xy 417.540379 -155.389249) (xy 417.560302 -155.337158) (xy 417.587598 -155.288523)
			(xy 417.621684 -155.24438) (xy 417.661833 -155.205671) (xy 417.707191 -155.17322) (xy 417.756791 -155.147719)
			(xy 417.809575 -155.129712) (xy 417.864418 -155.119582) (xy 417.920152 -155.117545) (xy 417.975589 -155.123645)
			(xy 418.029546 -155.137751) (xy 418.080875 -155.159563) (xy 418.128481 -155.188617) (xy 418.171349 -155.224292)
			(xy 418.208566 -155.265829) (xy 418.239339 -155.312342) (xy 418.263011 -155.362839) (xy 418.279079 -155.416246)
			(xy 418.287199 -155.471422) (xy 418.287708 -155.499308) (xy 418.287199 -155.527194) (xy 418.279079 -155.58237)
			(xy 418.263011 -155.635777) (xy 418.239339 -155.686274) (xy 418.208566 -155.732787) (xy 418.171349 -155.774324)
			(xy 418.128481 -155.809999) (xy 418.080875 -155.839053) (xy 418.029546 -155.860865) (xy 417.975589 -155.874971)
			(xy 417.920152 -155.881071) (xy 417.864418 -155.879034) (xy 417.809575 -155.868904) (xy 417.756791 -155.850897)
			(xy 417.707191 -155.825396) (xy 417.661833 -155.792945) (xy 417.621684 -155.754236) (xy 417.587598 -155.710093)
			(xy 417.560302 -155.661458) (xy 417.540379 -155.609367) (xy 417.528253 -155.55493) (xy 417.524182 -155.499308)
			(xy 410.420566 -155.499308) (xy 410.420566 -155.972256) (xy 423.64482 -155.972256) (xy 423.648891 -155.916634)
			(xy 423.661017 -155.862197) (xy 423.68094 -155.810106) (xy 423.708236 -155.761471) (xy 423.742322 -155.717328)
			(xy 423.782471 -155.678619) (xy 423.827829 -155.646168) (xy 423.877429 -155.620667) (xy 423.930213 -155.60266)
			(xy 423.985056 -155.59253) (xy 424.04079 -155.590493) (xy 424.096227 -155.596593) (xy 424.150184 -155.610699)
			(xy 424.201513 -155.632511) (xy 424.249119 -155.661565) (xy 424.291987 -155.69724) (xy 424.329204 -155.738777)
			(xy 424.359977 -155.78529) (xy 424.383649 -155.835787) (xy 424.399717 -155.889194) (xy 424.407837 -155.94437)
			(xy 424.408346 -155.972256) (xy 424.407837 -156.000142) (xy 424.399717 -156.055318) (xy 424.383649 -156.108725)
			(xy 424.359977 -156.159222) (xy 424.329204 -156.205735) (xy 424.291987 -156.247272) (xy 424.249119 -156.282947)
			(xy 424.201513 -156.312001) (xy 424.150184 -156.333813) (xy 424.096227 -156.347919) (xy 424.04079 -156.354019)
			(xy 423.985056 -156.351982) (xy 423.930213 -156.341852) (xy 423.877429 -156.323845) (xy 423.827829 -156.298344)
			(xy 423.782471 -156.265893) (xy 423.742322 -156.227184) (xy 423.708236 -156.183041) (xy 423.68094 -156.134406)
			(xy 423.661017 -156.082315) (xy 423.648891 -156.027878) (xy 423.64482 -155.972256) (xy 410.420566 -155.972256)
			(xy 410.420566 -156.960062) (xy 422.378122 -156.960062) (xy 422.382193 -156.90444) (xy 422.394319 -156.850003)
			(xy 422.414242 -156.797912) (xy 422.441538 -156.749277) (xy 422.475624 -156.705134) (xy 422.515773 -156.666425)
			(xy 422.561131 -156.633974) (xy 422.610731 -156.608473) (xy 422.663515 -156.590466) (xy 422.718358 -156.580336)
			(xy 422.774092 -156.578299) (xy 422.829529 -156.584399) (xy 422.883486 -156.598505) (xy 422.934815 -156.620317)
			(xy 422.982421 -156.649371) (xy 423.025289 -156.685046) (xy 423.062506 -156.726583) (xy 423.093279 -156.773096)
			(xy 423.116951 -156.823593) (xy 423.133019 -156.877) (xy 423.133431 -156.879798) (xy 423.523662 -156.879798)
			(xy 423.527733 -156.824176) (xy 423.539859 -156.769739) (xy 423.559782 -156.717648) (xy 423.587078 -156.669013)
			(xy 423.621164 -156.62487) (xy 423.661313 -156.586161) (xy 423.706671 -156.55371) (xy 423.756271 -156.528209)
			(xy 423.809055 -156.510202) (xy 423.863898 -156.500072) (xy 423.919632 -156.498035) (xy 423.975069 -156.504135)
			(xy 424.029026 -156.518241) (xy 424.080355 -156.540053) (xy 424.127961 -156.569107) (xy 424.170829 -156.604782)
			(xy 424.208046 -156.646319) (xy 424.238819 -156.692832) (xy 424.262491 -156.743329) (xy 424.278559 -156.796736)
			(xy 424.286679 -156.851912) (xy 424.287188 -156.879798) (xy 424.286679 -156.907684) (xy 424.278559 -156.96286)
			(xy 424.262512 -157.016196) (xy 426.587415 -157.016196) (xy 426.591451 -156.932749) (xy 426.603523 -156.850081)
			(xy 426.623516 -156.768964) (xy 426.651245 -156.690155) (xy 426.686451 -156.61439) (xy 426.728805 -156.542377)
			(xy 426.777911 -156.474788) (xy 426.833312 -156.412254) (xy 426.894489 -156.355359) (xy 426.960872 -156.304633)
			(xy 427.03184 -156.260552) (xy 427.106732 -156.223526) (xy 427.184848 -156.1939) (xy 427.265458 -156.171952)
			(xy 427.34781 -156.157887) (xy 427.431136 -156.151835) (xy 427.514656 -156.153854) (xy 427.597592 -156.163924)
			(xy 427.679168 -156.181952) (xy 427.758624 -156.207769) (xy 427.835217 -156.241134) (xy 427.908233 -156.281735)
			(xy 427.976989 -156.329194) (xy 428.040843 -156.383067) (xy 428.0992 -156.442852) (xy 428.151515 -156.507989)
			(xy 428.197298 -156.577872) (xy 428.236123 -156.651847) (xy 428.267628 -156.729224) (xy 428.291517 -156.809281)
			(xy 428.307568 -156.891269) (xy 428.315631 -156.974424) (xy 428.316136 -157.016196) (xy 428.315631 -157.057968)
			(xy 428.307568 -157.141123) (xy 428.291517 -157.223111) (xy 428.267628 -157.303168) (xy 428.236123 -157.380545)
			(xy 428.197298 -157.45452) (xy 428.151515 -157.524403) (xy 428.0992 -157.58954) (xy 428.040843 -157.649325)
			(xy 427.976989 -157.703198) (xy 427.908233 -157.750657) (xy 427.835217 -157.791258) (xy 427.758624 -157.824623)
			(xy 427.679168 -157.85044) (xy 427.597592 -157.868468) (xy 427.514656 -157.878538) (xy 427.431136 -157.880557)
			(xy 427.34781 -157.874505) (xy 427.265458 -157.86044) (xy 427.184848 -157.838492) (xy 427.106732 -157.808866)
			(xy 427.03184 -157.77184) (xy 426.960872 -157.727759) (xy 426.894489 -157.677033) (xy 426.833312 -157.620138)
			(xy 426.777911 -157.557604) (xy 426.728805 -157.490015) (xy 426.686451 -157.418002) (xy 426.651245 -157.342237)
			(xy 426.623516 -157.263428) (xy 426.603523 -157.182311) (xy 426.591451 -157.099643) (xy 426.587415 -157.016196)
			(xy 424.262512 -157.016196) (xy 424.262491 -157.016267) (xy 424.238819 -157.066764) (xy 424.208046 -157.113277)
			(xy 424.170829 -157.154814) (xy 424.127961 -157.190489) (xy 424.080355 -157.219543) (xy 424.029026 -157.241355)
			(xy 423.975069 -157.255461) (xy 423.919632 -157.261561) (xy 423.863898 -157.259524) (xy 423.809055 -157.249394)
			(xy 423.756271 -157.231387) (xy 423.706671 -157.205886) (xy 423.661313 -157.173435) (xy 423.621164 -157.134726)
			(xy 423.587078 -157.090583) (xy 423.559782 -157.041948) (xy 423.539859 -156.989857) (xy 423.527733 -156.93542)
			(xy 423.523662 -156.879798) (xy 423.133431 -156.879798) (xy 423.141139 -156.932176) (xy 423.141648 -156.960062)
			(xy 423.141139 -156.987948) (xy 423.133019 -157.043124) (xy 423.116951 -157.096531) (xy 423.093279 -157.147028)
			(xy 423.062506 -157.193541) (xy 423.025289 -157.235078) (xy 422.982421 -157.270753) (xy 422.934815 -157.299807)
			(xy 422.883486 -157.321619) (xy 422.829529 -157.335725) (xy 422.774092 -157.341825) (xy 422.718358 -157.339788)
			(xy 422.663515 -157.329658) (xy 422.610731 -157.311651) (xy 422.561131 -157.28615) (xy 422.515773 -157.253699)
			(xy 422.475624 -157.21499) (xy 422.441538 -157.170847) (xy 422.414242 -157.122212) (xy 422.394319 -157.070121)
			(xy 422.382193 -157.015684) (xy 422.378122 -156.960062) (xy 410.420566 -156.960062) (xy 410.420566 -157.648148)
			(xy 419.535862 -157.648148) (xy 419.539933 -157.592526) (xy 419.552059 -157.538089) (xy 419.571982 -157.485998)
			(xy 419.599278 -157.437363) (xy 419.633364 -157.39322) (xy 419.673513 -157.354511) (xy 419.718871 -157.32206)
			(xy 419.768471 -157.296559) (xy 419.821255 -157.278552) (xy 419.876098 -157.268422) (xy 419.931832 -157.266385)
			(xy 419.987269 -157.272485) (xy 420.041226 -157.286591) (xy 420.092555 -157.308403) (xy 420.140161 -157.337457)
			(xy 420.183029 -157.373132) (xy 420.220246 -157.414669) (xy 420.251019 -157.461182) (xy 420.274691 -157.511679)
			(xy 420.290759 -157.565086) (xy 420.298879 -157.620262) (xy 420.299388 -157.648148) (xy 420.298879 -157.676034)
			(xy 420.290759 -157.73121) (xy 420.274691 -157.784617) (xy 420.251019 -157.835114) (xy 420.220246 -157.881627)
			(xy 420.183029 -157.923164) (xy 420.140161 -157.958839) (xy 420.092555 -157.987893) (xy 420.041226 -158.009705)
			(xy 419.987269 -158.023811) (xy 419.931832 -158.029911) (xy 419.876098 -158.027874) (xy 419.821255 -158.017744)
			(xy 419.768471 -157.999737) (xy 419.718871 -157.974236) (xy 419.673513 -157.941785) (xy 419.633364 -157.903076)
			(xy 419.599278 -157.858933) (xy 419.571982 -157.810298) (xy 419.552059 -157.758207) (xy 419.539933 -157.70377)
			(xy 419.535862 -157.648148) (xy 410.420566 -157.648148) (xy 410.420566 -161.520378) (xy 417.4998 -161.520378)
			(xy 417.500317 -161.493048) (xy 417.50828 -161.438971) (xy 417.524061 -161.386638) (xy 417.547322 -161.337175)
			(xy 417.577563 -161.291642) (xy 417.614133 -161.251018) (xy 417.656249 -161.216176) (xy 417.679378 -161.201608)
			(xy 417.691578 -161.19365) (xy 417.711251 -161.172189) (xy 417.724061 -161.146045) (xy 417.728962 -161.117347)
			(xy 417.725556 -161.088434) (xy 417.720272 -161.074862) (xy 417.710777 -161.051654) (xy 417.697428 -161.00332)
			(xy 417.690702 -160.95363) (xy 417.6903 -160.928558) (xy 417.690724 -160.903489) (xy 417.697474 -160.853806)
			(xy 417.710806 -160.805471) (xy 417.720272 -160.782254) (xy 417.725563 -160.768687) (xy 417.728937 -160.739773)
			(xy 417.724027 -160.711079) (xy 417.711231 -160.68493) (xy 417.691587 -160.663447) (xy 417.679378 -160.655508)
			(xy 417.656281 -160.640887) (xy 417.61416 -160.60605) (xy 417.57758 -160.565433) (xy 417.547327 -160.519907)
			(xy 417.52405 -160.470451) (xy 417.508247 -160.418124) (xy 417.500259 -160.36405) (xy 417.500256 -160.309389)
			(xy 417.508238 -160.255314) (xy 417.524036 -160.202986) (xy 417.547308 -160.153527) (xy 417.577556 -160.107998)
			(xy 417.614131 -160.067377) (xy 417.656249 -160.032536) (xy 417.679378 -160.017968) (xy 417.691605 -160.010048)
			(xy 417.711279 -159.988577) (xy 417.724084 -159.962423) (xy 417.728979 -159.933716) (xy 417.725563 -159.904796)
			(xy 417.720272 -159.891222) (xy 417.710796 -159.868007) (xy 417.69744 -159.819677) (xy 417.690706 -159.769989)
			(xy 417.6903 -159.744918) (xy 417.690766 -159.718075) (xy 417.698468 -159.664945) (xy 417.713716 -159.61347)
			(xy 417.736193 -159.564717) (xy 417.765435 -159.519694) (xy 417.800836 -159.479334) (xy 417.841662 -159.444472)
			(xy 417.887069 -159.415831) (xy 417.936117 -159.394002) (xy 417.961826 -159.38627) (xy 417.976329 -159.38162)
			(xy 418.0019 -159.365103) (xy 418.021469 -159.341785) (xy 418.033299 -159.313737) (xy 418.03634 -159.283448)
			(xy 418.030322 -159.253608) (xy 418.023548 -159.239966) (xy 418.00892 -159.211818) (xy 417.988191 -159.151868)
			(xy 417.977691 -159.08931) (xy 417.977066 -159.057594) (xy 417.977291 -159.039575) (xy 417.980722 -159.0037)
			(xy 417.983924 -158.985966) (xy 417.986322 -158.970764) (xy 417.982784 -158.940201) (xy 417.97031 -158.912077)
			(xy 417.95003 -158.888941) (xy 417.923782 -158.872889) (xy 417.908994 -158.868618) (xy 417.881967 -158.861164)
			(xy 417.830242 -158.839542) (xy 417.782237 -158.810585) (xy 417.738984 -158.774917) (xy 417.701416 -158.733305)
			(xy 417.670339 -158.686645) (xy 417.646423 -158.63594) (xy 417.630183 -158.582282) (xy 417.621967 -158.526825)
			(xy 417.621466 -158.498794) (xy 417.621972 -158.471544) (xy 417.629729 -158.417598) (xy 417.645083 -158.365305)
			(xy 417.667723 -158.31573) (xy 417.697188 -158.269881) (xy 417.732877 -158.228691) (xy 417.774065 -158.193)
			(xy 417.819912 -158.163533) (xy 417.869487 -158.14089) (xy 417.921779 -158.125533) (xy 417.975724 -158.117774)
			(xy 418.002974 -158.117286) (xy 418.030548 -158.117774) (xy 418.085119 -158.125723) (xy 418.137979 -158.141444)
			(xy 418.188024 -158.16461) (xy 418.234215 -158.194738) (xy 418.275587 -158.231201) (xy 418.293804 -158.251906)
			(xy 418.303702 -158.262804) (xy 418.328352 -158.278879) (xy 418.35656 -158.287263) (xy 418.385988 -158.287263)
			(xy 418.414196 -158.278879) (xy 418.438846 -158.262804) (xy 418.448744 -158.251906) (xy 418.466959 -158.2312)
			(xy 418.50833 -158.194735) (xy 418.55452 -158.164608) (xy 418.604567 -158.141445) (xy 418.657428 -158.125729)
			(xy 418.712 -158.117789) (xy 418.767148 -158.117789) (xy 418.82172 -158.125729) (xy 418.874581 -158.141445)
			(xy 418.924628 -158.164608) (xy 418.970818 -158.194735) (xy 419.012189 -158.2312) (xy 419.030404 -158.251906)
			(xy 419.040302 -158.262804) (xy 419.064952 -158.278879) (xy 419.09316 -158.287263) (xy 419.122588 -158.287263)
			(xy 419.150796 -158.278879) (xy 419.175446 -158.262804) (xy 419.185344 -158.251906) (xy 419.203582 -158.23122)
			(xy 419.244945 -158.194747) (xy 419.291129 -158.164612) (xy 419.341172 -158.141442) (xy 419.39403 -158.12572)
			(xy 419.448601 -158.117775) (xy 419.476174 -158.117286) (xy 419.503426 -158.117779) (xy 419.557375 -158.125533)
			(xy 419.609672 -158.140885) (xy 419.659252 -158.163524) (xy 419.705105 -158.192989) (xy 419.746298 -158.22868)
			(xy 419.781992 -158.269869) (xy 419.81146 -158.31572) (xy 419.834104 -158.365298) (xy 419.84946 -158.417593)
			(xy 419.857218 -158.471542) (xy 419.857682 -158.498794) (xy 419.857167 -158.52665) (xy 419.849043 -158.581766)
			(xy 419.832998 -158.635117) (xy 419.80937 -158.685571) (xy 419.778663 -158.732056) (xy 419.741526 -158.773585)
			(xy 419.69875 -158.809278) (xy 419.651241 -158.838376) (xy 419.600008 -158.860262) (xy 419.573202 -158.867856)
			(xy 419.559077 -158.872105) (xy 419.53393 -158.887501) (xy 419.514215 -158.909425) (xy 419.501566 -158.93606)
			(xy 419.497034 -158.965195) (xy 419.498526 -158.97987) (xy 419.5002 -158.992886) (xy 419.501977 -159.019071)
			(xy 419.502082 -159.032194) (xy 419.501988 -159.046343) (xy 419.499954 -159.074566) (xy 419.498018 -159.088582)
			(xy 419.496394 -159.101927) (xy 419.4995 -159.128623) (xy 419.509476 -159.153579) (xy 419.525629 -159.17506)
			(xy 419.546835 -159.191572) (xy 419.57162 -159.201966) (xy 419.584886 -159.204152) (xy 419.612039 -159.208237)
			(xy 419.664868 -159.223214) (xy 419.715004 -159.245609) (xy 419.761412 -159.274958) (xy 419.803135 -159.310656)
			(xy 419.839311 -159.351965) (xy 419.869192 -159.398033) (xy 419.892162 -159.447908) (xy 419.907746 -159.500561)
			(xy 419.915622 -159.554903) (xy 419.915688 -159.558666) (xy 426.563024 -159.558666) (xy 426.563024 -159.47397)
			(xy 426.571075 -159.389656) (xy 426.587104 -159.30649) (xy 426.610965 -159.225223) (xy 426.642444 -159.146593)
			(xy 426.681255 -159.071312) (xy 426.727045 -159.00006) (xy 426.779401 -158.933484) (xy 426.837849 -158.872186)
			(xy 426.901859 -158.816721) (xy 426.970851 -158.767592) (xy 427.044201 -158.725243) (xy 427.121244 -158.690059)
			(xy 427.201283 -158.662357) (xy 427.283592 -158.642389) (xy 427.367427 -158.630336) (xy 427.452028 -158.626306)
			(xy 427.536629 -158.630336) (xy 427.620464 -158.642389) (xy 427.702773 -158.662357) (xy 427.782812 -158.690059)
			(xy 427.859855 -158.725243) (xy 427.933205 -158.767592) (xy 428.002197 -158.816721) (xy 428.066207 -158.872186)
			(xy 428.124655 -158.933484) (xy 428.177011 -159.00006) (xy 428.222801 -159.071312) (xy 428.261612 -159.146593)
			(xy 428.293091 -159.225223) (xy 428.316952 -159.30649) (xy 428.332981 -159.389656) (xy 428.341032 -159.47397)
			(xy 428.341536 -159.516318) (xy 428.341032 -159.558666) (xy 428.332981 -159.64298) (xy 428.316952 -159.726146)
			(xy 428.293091 -159.807413) (xy 428.261612 -159.886043) (xy 428.222801 -159.961324) (xy 428.177011 -160.032576)
			(xy 428.124655 -160.099152) (xy 428.066207 -160.16045) (xy 428.002197 -160.215915) (xy 427.933205 -160.265044)
			(xy 427.859855 -160.307393) (xy 427.782812 -160.342577) (xy 427.702773 -160.370279) (xy 427.620464 -160.390247)
			(xy 427.536629 -160.4023) (xy 427.452028 -160.406331) (xy 427.367427 -160.4023) (xy 427.283592 -160.390247)
			(xy 427.201283 -160.370279) (xy 427.121244 -160.342577) (xy 427.044201 -160.307393) (xy 426.970851 -160.265044)
			(xy 426.901859 -160.215915) (xy 426.837849 -160.16045) (xy 426.779401 -160.099152) (xy 426.727045 -160.032576)
			(xy 426.681255 -159.961324) (xy 426.642444 -159.886043) (xy 426.610965 -159.807413) (xy 426.587104 -159.726146)
			(xy 426.571075 -159.64298) (xy 426.563024 -159.558666) (xy 419.915688 -159.558666) (xy 419.916102 -159.582358)
			(xy 419.915606 -159.60961) (xy 419.907854 -159.66356) (xy 419.892503 -159.715858) (xy 419.869865 -159.765438)
			(xy 419.840401 -159.811292) (xy 419.804711 -159.852485) (xy 419.763521 -159.888179) (xy 419.71767 -159.917648)
			(xy 419.668092 -159.940291) (xy 419.615795 -159.955647) (xy 419.561846 -159.963403) (xy 419.534594 -159.963866)
			(xy 419.507019 -159.963416) (xy 419.452445 -159.955462) (xy 419.399584 -159.939735) (xy 419.349538 -159.916562)
			(xy 419.303349 -159.886426) (xy 419.261979 -159.849955) (xy 419.243764 -159.829246) (xy 419.233866 -159.818348)
			(xy 419.209216 -159.802273) (xy 419.181008 -159.793889) (xy 419.15158 -159.793889) (xy 419.123372 -159.802273)
			(xy 419.098722 -159.818348) (xy 419.088824 -159.829246) (xy 419.070614 -159.849958) (xy 419.029244 -159.886426)
			(xy 418.983053 -159.916557) (xy 418.933005 -159.939722) (xy 418.880143 -159.955439) (xy 418.825569 -159.96338)
			(xy 418.797994 -159.963866) (xy 418.771493 -159.963405) (xy 418.719002 -159.956063) (xy 418.668034 -159.941521)
			(xy 418.619572 -159.920059) (xy 418.574549 -159.892091) (xy 418.5539 -159.875474) (xy 418.541717 -159.866082)
			(xy 418.51333 -159.854285) (xy 418.482719 -159.851451) (xy 418.452648 -159.857838) (xy 418.425831 -159.872868)
			(xy 418.404689 -159.895186) (xy 418.397436 -159.908748) (xy 418.385321 -159.93243) (xy 418.355402 -159.976413)
			(xy 418.319535 -160.015696) (xy 418.278448 -160.049482) (xy 418.255958 -160.063688) (xy 418.243751 -160.071635)
			(xy 418.224085 -160.093102) (xy 418.211281 -160.119249) (xy 418.206381 -160.147947) (xy 418.209783 -160.176861)
			(xy 418.215064 -160.190434) (xy 418.22456 -160.213641) (xy 418.237908 -160.261976) (xy 418.244633 -160.311666)
			(xy 418.245036 -160.336738) (xy 418.244615 -160.361807) (xy 418.237865 -160.411491) (xy 418.224531 -160.459825)
			(xy 418.215064 -160.483042) (xy 418.209854 -160.496631) (xy 418.206485 -160.525525) (xy 418.211389 -160.554198)
			(xy 418.224168 -160.58033) (xy 418.243789 -160.601805) (xy 418.255958 -160.609788) (xy 418.27905 -160.624416)
			(xy 418.321167 -160.659255) (xy 418.357742 -160.699872) (xy 418.387993 -160.745397) (xy 418.411268 -160.794852)
			(xy 418.427069 -160.847177) (xy 418.435057 -160.901249) (xy 418.43506 -160.955908) (xy 418.427078 -161.00998)
			(xy 418.411283 -161.062307) (xy 418.388014 -161.111765) (xy 418.357769 -161.157294) (xy 418.321198 -161.197915)
			(xy 418.279085 -161.232759) (xy 418.255958 -161.247328) (xy 418.243724 -161.255237) (xy 418.224058 -161.276714)
			(xy 418.211257 -161.302871) (xy 418.206364 -161.331578) (xy 418.209777 -161.360499) (xy 418.215064 -161.374074)
			(xy 418.224541 -161.397289) (xy 418.237896 -161.445619) (xy 418.244629 -161.495307) (xy 418.245036 -161.520378)
			(xy 418.244515 -161.548263) (xy 418.236203 -161.60341) (xy 418.219765 -161.656702) (xy 418.195567 -161.706948)
			(xy 418.164151 -161.753027) (xy 418.126218 -161.793909) (xy 418.082616 -161.828681) (xy 418.034318 -161.856566)
			(xy 417.982403 -161.876941) (xy 417.928032 -161.889351) (xy 417.872418 -161.893519) (xy 417.816804 -161.889351)
			(xy 417.762433 -161.876941) (xy 417.710518 -161.856566) (xy 417.66222 -161.828681) (xy 417.618618 -161.793909)
			(xy 417.580685 -161.753027) (xy 417.549269 -161.706948) (xy 417.525071 -161.656702) (xy 417.508633 -161.60341)
			(xy 417.500321 -161.548263) (xy 417.4998 -161.520378) (xy 410.420566 -161.520378) (xy 410.420566 -162.451542)
			(xy 419.315646 -162.451542) (xy 419.316217 -162.424294) (xy 419.323967 -162.370352) (xy 419.339314 -162.318061)
			(xy 419.361947 -162.268487) (xy 419.391405 -162.222639) (xy 419.427087 -162.18145) (xy 419.468269 -162.145757)
			(xy 419.51411 -162.116289) (xy 419.563679 -162.093645) (xy 419.615966 -162.078285) (xy 419.669906 -162.070523)
			(xy 419.697154 -162.070034) (xy 419.727059 -162.070571) (xy 419.786138 -162.079883) (xy 419.814756 -162.088576)
			(xy 419.82866 -162.09263) (xy 419.857597 -162.09354) (xy 419.885621 -162.086274) (xy 419.910469 -162.071418)
			(xy 419.930134 -162.050171) (xy 419.943028 -162.024251) (xy 419.946074 -162.01009) (xy 419.951204 -161.984008)
			(xy 419.967775 -161.933501) (xy 419.991201 -161.885784) (xy 420.021027 -161.841784) (xy 420.056674 -161.802352)
			(xy 420.097452 -161.768253) (xy 420.142571 -161.740148) (xy 420.191156 -161.718581) (xy 420.242265 -161.703971)
			(xy 420.294908 -161.696601) (xy 420.321486 -161.696146) (xy 420.348736 -161.6967) (xy 420.402682 -161.704455)
			(xy 420.454975 -161.719808) (xy 420.504551 -161.742447) (xy 420.550401 -161.771911) (xy 420.59159 -161.8076)
			(xy 420.627281 -161.848788) (xy 420.656747 -161.894636) (xy 420.679387 -161.944211) (xy 420.694742 -161.996504)
			(xy 420.702499 -162.05045) (xy 420.702499 -162.10495) (xy 420.694742 -162.158896) (xy 420.679387 -162.211189)
			(xy 420.656747 -162.260764) (xy 420.627281 -162.306612) (xy 420.59159 -162.3478) (xy 420.550401 -162.383489)
			(xy 420.504551 -162.412953) (xy 420.454975 -162.435592) (xy 420.402682 -162.450945) (xy 420.348736 -162.4587)
			(xy 420.321486 -162.459162) (xy 420.291581 -162.458639) (xy 420.232502 -162.449318) (xy 420.203884 -162.44062)
			(xy 420.189967 -162.436614) (xy 420.161038 -162.435695) (xy 420.133019 -162.442952) (xy 420.108173 -162.457799)
			(xy 420.088508 -162.479036) (xy 420.075613 -162.504949) (xy 420.072566 -162.519106) (xy 420.06599 -162.551947)
			(xy 420.042863 -162.614798) (xy 420.026592 -162.644074) (xy 420.019587 -162.657057) (xy 420.012541 -162.685688)
			(xy 420.013975 -162.715137) (xy 420.023771 -162.742948) (xy 420.04111 -162.766795) (xy 420.064544 -162.78469)
			(xy 420.078154 -162.790378) (xy 420.104942 -162.801047) (xy 420.155182 -162.829341) (xy 420.20059 -162.864876)
			(xy 420.240131 -162.906842) (xy 420.272903 -162.954283) (xy 420.298159 -163.006117) (xy 420.315323 -163.061162)
			(xy 420.324005 -163.118164) (xy 420.324534 -163.146994) (xy 420.324113 -163.170616) (xy 425.480988 -163.170616)
			(xy 425.48147 -163.143364) (xy 425.489225 -163.089414) (xy 425.504579 -163.037116) (xy 425.527219 -162.987537)
			(xy 425.556685 -162.941684) (xy 425.592377 -162.900491) (xy 425.633568 -162.864797) (xy 425.679419 -162.835329)
			(xy 425.728998 -162.812686) (xy 425.781294 -162.797329) (xy 425.835244 -162.789572) (xy 425.862496 -162.789108)
			(xy 425.890642 -162.789598) (xy 425.946324 -162.797875) (xy 426.000186 -162.814237) (xy 426.051064 -162.838327)
			(xy 426.097854 -162.869626) (xy 426.119036 -162.888168) (xy 426.130841 -162.8982) (xy 426.15893 -162.911235)
			(xy 426.189633 -162.915257) (xy 426.220131 -162.909897) (xy 426.247624 -162.895647) (xy 426.25899 -162.88512)
			(xy 426.280551 -162.864437) (xy 426.328964 -162.829427) (xy 426.382244 -162.802395) (xy 426.439087 -162.784001)
			(xy 426.498103 -162.774696) (xy 426.527976 -162.774122) (xy 426.556122 -162.77462) (xy 426.611803 -162.782895)
			(xy 426.665666 -162.799254) (xy 426.716544 -162.823343) (xy 426.763334 -162.85464) (xy 426.784516 -162.873182)
			(xy 426.796337 -162.883193) (xy 426.82442 -162.896228) (xy 426.855118 -162.900253) (xy 426.885612 -162.894899)
			(xy 426.913103 -162.880657) (xy 426.92447 -162.870134) (xy 426.946042 -162.849463) (xy 426.994452 -162.814451)
			(xy 427.047729 -162.787416) (xy 427.10457 -162.76902) (xy 427.163584 -162.759712) (xy 427.193456 -162.759136)
			(xy 427.22071 -162.759596) (xy 427.274663 -162.767348) (xy 427.326964 -162.782701) (xy 427.376547 -162.805342)
			(xy 427.422402 -162.834809) (xy 427.463596 -162.870504) (xy 427.499291 -162.911698) (xy 427.528758 -162.957553)
			(xy 427.551399 -163.007136) (xy 427.566752 -163.059437) (xy 427.574504 -163.11339) (xy 427.574964 -163.140644)
			(xy 427.57445 -163.169383) (xy 427.565822 -163.22621) (xy 427.548769 -163.2811) (xy 427.523676 -163.332812)
			(xy 427.49111 -163.380175) (xy 427.47184 -163.401502) (xy 427.461724 -163.413001) (xy 427.448385 -163.44056)
			(xy 427.443809 -163.470832) (xy 427.448405 -163.501102) (xy 427.461761 -163.528652) (xy 427.47184 -163.540186)
			(xy 427.491156 -163.561474) (xy 427.523723 -163.608842) (xy 427.548814 -163.66056) (xy 427.565863 -163.715457)
			(xy 427.574482 -163.77229) (xy 427.574477 -163.829774) (xy 427.565849 -163.886606) (xy 427.548791 -163.9415)
			(xy 427.52369 -163.993213) (xy 427.491116 -164.040576) (xy 427.47184 -164.061902) (xy 427.461724 -164.073401)
			(xy 427.448385 -164.10096) (xy 427.443809 -164.131232) (xy 427.448405 -164.161502) (xy 427.461761 -164.189052)
			(xy 427.47184 -164.200586) (xy 427.491156 -164.221874) (xy 427.523723 -164.269242) (xy 427.548814 -164.32096)
			(xy 427.565863 -164.375857) (xy 427.574482 -164.43269) (xy 427.574477 -164.490174) (xy 427.565849 -164.547006)
			(xy 427.548791 -164.6019) (xy 427.52369 -164.653613) (xy 427.491116 -164.700976) (xy 427.47184 -164.722302)
			(xy 427.461724 -164.733801) (xy 427.448385 -164.76136) (xy 427.443809 -164.791632) (xy 427.448405 -164.821902)
			(xy 427.461761 -164.849452) (xy 427.47184 -164.860986) (xy 427.491156 -164.882274) (xy 427.523723 -164.929642)
			(xy 427.548814 -164.98136) (xy 427.565863 -165.036257) (xy 427.574482 -165.09309) (xy 427.574477 -165.150574)
			(xy 427.565849 -165.207406) (xy 427.548791 -165.2623) (xy 427.52369 -165.314013) (xy 427.491116 -165.361376)
			(xy 427.47184 -165.382702) (xy 427.461724 -165.394201) (xy 427.448385 -165.42176) (xy 427.443809 -165.452032)
			(xy 427.448405 -165.482302) (xy 427.461761 -165.509852) (xy 427.47184 -165.521386) (xy 427.491156 -165.542674)
			(xy 427.523723 -165.590042) (xy 427.548814 -165.64176) (xy 427.565863 -165.696657) (xy 427.574482 -165.75349)
			(xy 427.574477 -165.810974) (xy 427.565849 -165.867806) (xy 427.548791 -165.9227) (xy 427.52369 -165.974413)
			(xy 427.491116 -166.021776) (xy 427.47184 -166.043102) (xy 427.461724 -166.054601) (xy 427.448385 -166.08216)
			(xy 427.443809 -166.112432) (xy 427.448405 -166.142702) (xy 427.461761 -166.170252) (xy 427.47184 -166.181786)
			(xy 427.491128 -166.203098) (xy 427.523693 -166.250464) (xy 427.548782 -166.302179) (xy 427.565829 -166.357073)
			(xy 427.574446 -166.413904) (xy 427.57457 -166.4208) (xy 430.96942 -166.4208) (xy 430.969965 -166.392062)
			(xy 430.978586 -166.335237) (xy 430.995632 -166.280347) (xy 431.020718 -166.228635) (xy 431.053277 -166.181271)
			(xy 431.072544 -166.159942) (xy 431.082618 -166.148409) (xy 431.095963 -166.120863) (xy 431.100549 -166.0906)
			(xy 431.095963 -166.060337) (xy 431.082618 -166.032791) (xy 431.072544 -166.021258) (xy 431.053272 -165.999932)
			(xy 431.020705 -165.95257) (xy 430.995612 -165.900858) (xy 430.978561 -165.845967) (xy 430.969938 -165.789139)
			(xy 430.969938 -165.731661) (xy 430.978561 -165.674833) (xy 430.995612 -165.619942) (xy 431.020705 -165.56823)
			(xy 431.053272 -165.520868) (xy 431.072544 -165.499542) (xy 431.082618 -165.488009) (xy 431.095963 -165.460463)
			(xy 431.100549 -165.4302) (xy 431.095963 -165.399937) (xy 431.082618 -165.372391) (xy 431.072544 -165.360858)
			(xy 431.053272 -165.339532) (xy 431.020705 -165.29217) (xy 430.995612 -165.240458) (xy 430.978561 -165.185567)
			(xy 430.969938 -165.128739) (xy 430.969938 -165.071261) (xy 430.978561 -165.014433) (xy 430.995612 -164.959542)
			(xy 431.020705 -164.90783) (xy 431.053272 -164.860468) (xy 431.072544 -164.839142) (xy 431.082618 -164.827609)
			(xy 431.095963 -164.800063) (xy 431.100549 -164.7698) (xy 431.095963 -164.739537) (xy 431.082618 -164.711991)
			(xy 431.072544 -164.700458) (xy 431.053272 -164.679132) (xy 431.020705 -164.63177) (xy 430.995612 -164.580058)
			(xy 430.978561 -164.525167) (xy 430.969938 -164.468339) (xy 430.969938 -164.410861) (xy 430.978561 -164.354033)
			(xy 430.995612 -164.299142) (xy 431.020705 -164.24743) (xy 431.053272 -164.200068) (xy 431.072544 -164.178742)
			(xy 431.082618 -164.167209) (xy 431.095963 -164.139663) (xy 431.100549 -164.1094) (xy 431.095963 -164.079137)
			(xy 431.082618 -164.051591) (xy 431.072544 -164.040058) (xy 431.053274 -164.01873) (xy 431.020708 -163.971368)
			(xy 430.995615 -163.919657) (xy 430.978564 -163.864766) (xy 430.969941 -163.807939) (xy 430.96942 -163.7792)
			(xy 430.96983 -163.753378) (xy 430.976782 -163.702204) (xy 430.990572 -163.652435) (xy 431.010949 -163.604981)
			(xy 431.037539 -163.560709) (xy 431.069858 -163.520427) (xy 431.088292 -163.50234) (xy 431.09798 -163.492559)
			(xy 431.112152 -163.468967) (xy 431.119503 -163.442447) (xy 431.1195 -163.414926) (xy 431.112141 -163.388407)
			(xy 431.097962 -163.36482) (xy 431.088292 -163.35502) (xy 431.069869 -163.336925) (xy 431.037565 -163.296636)
			(xy 431.010985 -163.252362) (xy 430.990611 -163.204911) (xy 430.976815 -163.155148) (xy 430.96985 -163.10398)
			(xy 430.96942 -163.07816) (xy 430.969941 -163.049421) (xy 430.978567 -162.992595) (xy 430.995619 -162.937705)
			(xy 431.020711 -162.885993) (xy 431.053274 -162.83863) (xy 431.072544 -162.817302) (xy 431.082657 -162.8058)
			(xy 431.095999 -162.778243) (xy 431.100577 -162.747971) (xy 431.095981 -162.717701) (xy 431.082624 -162.690151)
			(xy 431.072544 -162.678618) (xy 431.053255 -162.657306) (xy 431.020691 -162.60994) (xy 430.995602 -162.558225)
			(xy 430.978556 -162.503331) (xy 430.969938 -162.4465) (xy 430.96942 -162.41776) (xy 430.969841 -162.390506)
			(xy 430.977603 -162.336555) (xy 430.992965 -162.284257) (xy 431.015613 -162.234678) (xy 431.045086 -162.188827)
			(xy 431.080784 -162.147636) (xy 431.121981 -162.111945) (xy 431.167838 -162.08248) (xy 431.217421 -162.059841)
			(xy 431.269722 -162.044489) (xy 431.323674 -162.036736) (xy 431.350928 -162.036252) (xy 431.379073 -162.036771)
			(xy 431.434754 -162.04504) (xy 431.488617 -162.061394) (xy 431.539495 -162.085478) (xy 431.586286 -162.116772)
			(xy 431.607468 -162.135312) (xy 431.619251 -162.145371) (xy 431.647348 -162.158396) (xy 431.678057 -162.16241)
			(xy 431.708558 -162.157044) (xy 431.736054 -162.142792) (xy 431.747422 -162.132264) (xy 431.76902 -162.111621)
			(xy 431.817422 -162.076604) (xy 431.870692 -162.049563) (xy 431.927528 -162.031161) (xy 431.986538 -162.021846)
			(xy 432.016408 -162.021266) (xy 432.045147 -162.021794) (xy 432.101973 -162.030417) (xy 432.156864 -162.047466)
			(xy 432.208576 -162.072557) (xy 432.255939 -162.10512) (xy 432.277266 -162.12439) (xy 432.2888 -162.134462)
			(xy 432.316346 -162.147804) (xy 432.346608 -162.152389) (xy 432.37687 -162.147804) (xy 432.404416 -162.134462)
			(xy 432.41595 -162.12439) (xy 432.437282 -162.105124) (xy 432.484642 -162.072556) (xy 432.536352 -162.047461)
			(xy 432.591242 -162.03041) (xy 432.648069 -162.021787) (xy 432.676808 -162.021266) (xy 432.704058 -162.02177)
			(xy 432.758004 -162.029527) (xy 432.810297 -162.044882) (xy 432.859872 -162.067522) (xy 432.905721 -162.096987)
			(xy 432.946911 -162.132676) (xy 432.982602 -162.173864) (xy 433.012069 -162.219712) (xy 433.034712 -162.269286)
			(xy 433.050069 -162.321578) (xy 433.057828 -162.375524) (xy 433.058316 -162.402774) (xy 433.057772 -162.431512)
			(xy 433.049154 -162.488338) (xy 433.032108 -162.543229) (xy 433.007021 -162.594941) (xy 432.974461 -162.642304)
			(xy 432.955192 -162.663632) (xy 432.945149 -162.675188) (xy 432.931809 -162.702727) (xy 432.927221 -162.732981)
			(xy 432.931798 -162.763237) (xy 432.945127 -162.790781) (xy 432.955192 -162.802316) (xy 432.974455 -162.823649)
			(xy 433.007022 -162.87101) (xy 433.032115 -162.92272) (xy 433.049167 -162.977609) (xy 433.057793 -163.034436)
			(xy 433.058316 -163.063174) (xy 433.057878 -163.088995) (xy 433.05093 -163.140167) (xy 433.037145 -163.189935)
			(xy 433.016773 -163.237389) (xy 432.990188 -163.281662) (xy 432.957875 -163.321945) (xy 432.939444 -163.340034)
			(xy 432.92978 -163.349838) (xy 432.915601 -163.373422) (xy 432.908243 -163.399937) (xy 432.908242 -163.427455)
			(xy 432.915598 -163.453971) (xy 432.929774 -163.477556) (xy 432.939444 -163.487354) (xy 432.957891 -163.505427)
			(xy 432.990194 -163.545719) (xy 433.016773 -163.589997) (xy 433.037143 -163.637453) (xy 433.050933 -163.68722)
			(xy 433.05789 -163.738393) (xy 433.058316 -163.764214) (xy 433.057796 -163.792953) (xy 433.049172 -163.84978)
			(xy 433.032121 -163.904671) (xy 433.007029 -163.956383) (xy 432.974463 -164.003745) (xy 432.955192 -164.025072)
			(xy 432.94511 -164.036597) (xy 432.931774 -164.064147) (xy 432.927194 -164.09441) (xy 432.93178 -164.124673)
			(xy 432.945121 -164.15222) (xy 432.955192 -164.163756) (xy 432.974476 -164.185071) (xy 433.007039 -164.232436)
			(xy 433.032129 -164.28415) (xy 433.049177 -164.339042) (xy 433.057798 -164.395871) (xy 433.057797 -164.45335)
			(xy 433.049173 -164.510178) (xy 433.032122 -164.565069) (xy 433.007029 -164.616782) (xy 432.974463 -164.664145)
			(xy 432.955192 -164.685472) (xy 432.94511 -164.696997) (xy 432.931774 -164.724547) (xy 432.927194 -164.75481)
			(xy 432.93178 -164.785073) (xy 432.945121 -164.81262) (xy 432.955192 -164.824156) (xy 432.974476 -164.845471)
			(xy 433.007039 -164.892836) (xy 433.032129 -164.94455) (xy 433.049177 -164.999442) (xy 433.057798 -165.056271)
			(xy 433.057797 -165.11375) (xy 433.049173 -165.170578) (xy 433.032122 -165.225469) (xy 433.007029 -165.277182)
			(xy 432.974463 -165.324545) (xy 432.955192 -165.345872) (xy 432.94511 -165.357397) (xy 432.931774 -165.384947)
			(xy 432.927194 -165.41521) (xy 432.93178 -165.445473) (xy 432.945121 -165.47302) (xy 432.955192 -165.484556)
			(xy 432.974474 -165.505873) (xy 433.007038 -165.553238) (xy 433.032128 -165.604952) (xy 433.049176 -165.659845)
			(xy 433.057796 -165.716674) (xy 433.058316 -165.745414) (xy 433.057835 -165.772665) (xy 433.050077 -165.826613)
			(xy 433.034721 -165.878907) (xy 433.012078 -165.928484) (xy 432.982611 -165.974334) (xy 432.946919 -166.015524)
			(xy 432.905729 -166.051215) (xy 432.859879 -166.080681) (xy 432.810301 -166.103323) (xy 432.758007 -166.118678)
			(xy 432.704059 -166.126436) (xy 432.676808 -166.126922) (xy 432.649163 -166.126403) (xy 432.594453 -166.118406)
			(xy 432.541471 -166.102593) (xy 432.491328 -166.079296) (xy 432.445074 -166.049002) (xy 432.40368 -166.012347)
			(xy 432.38547 -165.99154) (xy 432.377861 -165.983437) (xy 432.35771 -165.974116) (xy 432.335506 -165.974116)
			(xy 432.315355 -165.983437) (xy 432.307746 -165.99154) (xy 432.294792 -166.006272) (xy 432.28471 -166.017797)
			(xy 432.271374 -166.045347) (xy 432.266794 -166.07561) (xy 432.27138 -166.105873) (xy 432.284721 -166.13342)
			(xy 432.294792 -166.144956) (xy 432.314074 -166.166273) (xy 432.346638 -166.213638) (xy 432.371728 -166.265352)
			(xy 432.388776 -166.320245) (xy 432.397396 -166.377074) (xy 432.397916 -166.405814) (xy 432.397371 -166.4341)
			(xy 432.389016 -166.490053) (xy 432.372492 -166.544159) (xy 432.34816 -166.595232) (xy 432.316555 -166.642153)
			(xy 432.29784 -166.66337) (xy 432.28775 -166.675307) (xy 432.274637 -166.703659) (xy 432.270696 -166.734646)
			(xy 432.276295 -166.765378) (xy 432.290912 -166.792984) (xy 432.30165 -166.80434) (xy 432.322827 -166.826023)
			(xy 432.358792 -166.874803) (xy 432.386591 -166.928657) (xy 432.405522 -166.98623) (xy 432.415111 -167.046071)
			(xy 432.415696 -167.076374) (xy 432.41522 -167.103627) (xy 432.407467 -167.157578) (xy 432.392113 -167.209876)
			(xy 432.369473 -167.259457) (xy 432.340007 -167.305311) (xy 432.304314 -167.346504) (xy 432.263122 -167.382198)
			(xy 432.217269 -167.411666) (xy 432.167689 -167.434308) (xy 432.115392 -167.449664) (xy 432.061441 -167.457419)
			(xy 432.034188 -167.457882) (xy 432.006043 -167.457345) (xy 431.950364 -167.449079) (xy 431.896502 -167.432729)
			(xy 431.845623 -167.408649) (xy 431.798831 -167.37736) (xy 431.777648 -167.358822) (xy 431.765855 -167.348775)
			(xy 431.737762 -167.335744) (xy 431.707055 -167.331725) (xy 431.676555 -167.337089) (xy 431.649061 -167.351341)
			(xy 431.637694 -167.36187) (xy 431.616095 -167.382511) (xy 431.567692 -167.417527) (xy 431.514422 -167.444567)
			(xy 431.457587 -167.462971) (xy 431.398578 -167.472287) (xy 431.368708 -167.472868) (xy 431.341454 -167.472437)
			(xy 431.287499 -167.46468) (xy 431.235198 -167.449323) (xy 431.185616 -167.426679) (xy 431.139761 -167.397208)
			(xy 431.098567 -167.361511) (xy 431.062873 -167.320314) (xy 431.033406 -167.274456) (xy 431.010766 -167.224872)
			(xy 430.995413 -167.172569) (xy 430.987661 -167.118615) (xy 430.9872 -167.09136) (xy 430.987726 -167.063073)
			(xy 430.996085 -167.007119) (xy 431.012613 -166.953013) (xy 431.036949 -166.90194) (xy 431.068559 -166.85502)
			(xy 431.087276 -166.833804) (xy 431.09739 -166.821886) (xy 431.110498 -166.793527) (xy 431.114434 -166.762534)
			(xy 431.108828 -166.7318) (xy 431.094206 -166.704191) (xy 431.083466 -166.692834) (xy 431.062279 -166.67116)
			(xy 431.026315 -166.622378) (xy 430.998518 -166.568521) (xy 430.979589 -166.510947) (xy 430.970003 -166.451103)
			(xy 430.96942 -166.4208) (xy 427.57457 -166.4208) (xy 427.574964 -166.442644) (xy 427.574563 -166.469898)
			(xy 427.566799 -166.523851) (xy 427.551436 -166.57615) (xy 427.528787 -166.625731) (xy 427.499312 -166.671583)
			(xy 427.463612 -166.712774) (xy 427.422412 -166.748465) (xy 427.376553 -166.777929) (xy 427.326968 -166.800567)
			(xy 427.274665 -166.815918) (xy 427.22071 -166.823669) (xy 427.193456 -166.824152) (xy 427.16531 -166.823641)
			(xy 427.10963 -166.815371) (xy 427.055766 -166.799015) (xy 427.004888 -166.774928) (xy 426.958098 -166.743633)
			(xy 426.936916 -166.725092) (xy 426.925069 -166.715116) (xy 426.896995 -166.702081) (xy 426.866306 -166.698051)
			(xy 426.835818 -166.703395) (xy 426.80833 -166.717624) (xy 426.796962 -166.72814) (xy 426.775372 -166.748791)
			(xy 426.726968 -166.783807) (xy 426.673695 -166.810846) (xy 426.616858 -166.829247) (xy 426.557847 -166.838559)
			(xy 426.527976 -166.839138) (xy 426.499237 -166.838619) (xy 426.44241 -166.829993) (xy 426.38752 -166.812942)
			(xy 426.335808 -166.78785) (xy 426.288445 -166.755284) (xy 426.267118 -166.736014) (xy 426.255584 -166.725942)
			(xy 426.228038 -166.7126) (xy 426.197776 -166.708015) (xy 426.167514 -166.7126) (xy 426.139968 -166.725942)
			(xy 426.128434 -166.736014) (xy 426.10711 -166.755288) (xy 426.059748 -166.787856) (xy 426.008036 -166.812948)
			(xy 425.953144 -166.829998) (xy 425.896315 -166.838619) (xy 425.867576 -166.839138) (xy 425.840326 -166.838645)
			(xy 425.78638 -166.830886) (xy 425.734087 -166.815529) (xy 425.684512 -166.792887) (xy 425.638663 -166.763421)
			(xy 425.597474 -166.727731) (xy 425.561782 -166.686542) (xy 425.532316 -166.640694) (xy 425.509673 -166.591119)
			(xy 425.494316 -166.538826) (xy 425.486556 -166.48488) (xy 425.486068 -166.45763) (xy 425.486619 -166.428892)
			(xy 425.495236 -166.372066) (xy 425.51228 -166.317176) (xy 425.537366 -166.265464) (xy 425.569924 -166.2181)
			(xy 425.589192 -166.196772) (xy 425.599232 -166.185214) (xy 425.612575 -166.157676) (xy 425.617164 -166.127422)
			(xy 425.612588 -166.097166) (xy 425.599257 -166.069623) (xy 425.589192 -166.058088) (xy 425.569952 -166.036735)
			(xy 425.537389 -165.989376) (xy 425.512298 -165.937668) (xy 425.495247 -165.882782) (xy 425.486622 -165.825959)
			(xy 425.486619 -165.768485) (xy 425.495237 -165.711661) (xy 425.512282 -165.656773) (xy 425.537367 -165.605062)
			(xy 425.569925 -165.557699) (xy 425.589192 -165.536372) (xy 425.599232 -165.524814) (xy 425.612575 -165.497276)
			(xy 425.617164 -165.467022) (xy 425.612588 -165.436766) (xy 425.599257 -165.409223) (xy 425.589192 -165.397688)
			(xy 425.569952 -165.376335) (xy 425.537389 -165.328976) (xy 425.512298 -165.277268) (xy 425.495247 -165.222382)
			(xy 425.486622 -165.165559) (xy 425.486619 -165.108085) (xy 425.495237 -165.051261) (xy 425.512282 -164.996373)
			(xy 425.537367 -164.944662) (xy 425.569925 -164.897299) (xy 425.589192 -164.875972) (xy 425.599232 -164.864414)
			(xy 425.612575 -164.836876) (xy 425.617164 -164.806622) (xy 425.612588 -164.776366) (xy 425.599257 -164.748823)
			(xy 425.589192 -164.737288) (xy 425.569952 -164.715935) (xy 425.537389 -164.668576) (xy 425.512298 -164.616868)
			(xy 425.495247 -164.561982) (xy 425.486622 -164.505159) (xy 425.486619 -164.447685) (xy 425.495237 -164.390861)
			(xy 425.512282 -164.335973) (xy 425.537367 -164.284262) (xy 425.569925 -164.236899) (xy 425.589192 -164.215572)
			(xy 425.599232 -164.204014) (xy 425.612575 -164.176476) (xy 425.617164 -164.146222) (xy 425.612588 -164.115966)
			(xy 425.599257 -164.088423) (xy 425.589192 -164.076888) (xy 425.569945 -164.05554) (xy 425.537373 -164.008185)
			(xy 425.512276 -163.956479) (xy 425.49522 -163.901592) (xy 425.486592 -163.844768) (xy 425.486068 -163.81603)
			(xy 425.486539 -163.788401) (xy 425.494478 -163.733716) (xy 425.510222 -163.680748) (xy 425.533443 -163.630605)
			(xy 425.563654 -163.584337) (xy 425.581572 -163.5633) (xy 425.590996 -163.551771) (xy 425.603448 -163.524742)
			(xy 425.607576 -163.495271) (xy 425.603028 -163.465862) (xy 425.590191 -163.439014) (xy 425.580556 -163.427664)
			(xy 425.561911 -163.406478) (xy 425.530459 -163.35962) (xy 425.506249 -163.308641) (xy 425.489809 -163.254654)
			(xy 425.481497 -163.198834) (xy 425.480988 -163.170616) (xy 420.324113 -163.170616) (xy 420.324048 -163.174245)
			(xy 420.316292 -163.228193) (xy 420.300937 -163.280488) (xy 420.278295 -163.330065) (xy 420.248829 -163.375915)
			(xy 420.213138 -163.417106) (xy 420.171947 -163.452797) (xy 420.126097 -163.482263) (xy 420.07652 -163.504905)
			(xy 420.024225 -163.52026) (xy 419.970277 -163.528016) (xy 419.915775 -163.528016) (xy 419.861827 -163.52026)
			(xy 419.809532 -163.504905) (xy 419.759955 -163.482263) (xy 419.714105 -163.452797) (xy 419.672914 -163.417106)
			(xy 419.637223 -163.375915) (xy 419.607757 -163.330065) (xy 419.585115 -163.280488) (xy 419.56976 -163.228193)
			(xy 419.562004 -163.174245) (xy 419.561518 -163.146994) (xy 419.56191 -163.121758) (xy 419.568529 -163.071724)
			(xy 419.581704 -163.023004) (xy 419.601202 -162.976452) (xy 419.613588 -162.954462) (xy 419.620627 -162.941499)
			(xy 419.627653 -162.912862) (xy 419.626205 -162.883412) (xy 419.616403 -162.855603) (xy 419.599064 -162.831754)
			(xy 419.575634 -162.813852) (xy 419.562026 -162.808158) (xy 419.535269 -162.797416) (xy 419.485027 -162.769136)
			(xy 419.439617 -162.733613) (xy 419.400072 -162.691658) (xy 419.367296 -162.644228) (xy 419.342035 -162.592402)
			(xy 419.324865 -162.537365) (xy 419.316178 -162.480369) (xy 419.315646 -162.451542) (xy 410.420566 -162.451542)
			(xy 410.420566 -164.19025) (xy 419.374572 -164.19025) (xy 419.374572 -164.13575) (xy 419.382328 -164.081803)
			(xy 419.397682 -164.02951) (xy 419.420321 -163.979933) (xy 419.449786 -163.934084) (xy 419.485475 -163.892893)
			(xy 419.526663 -163.857201) (xy 419.572511 -163.827734) (xy 419.622085 -163.805091) (xy 419.674378 -163.789733)
			(xy 419.728324 -163.781974) (xy 419.755574 -163.781486) (xy 419.785261 -163.782065) (xy 419.843919 -163.79126)
			(xy 419.900444 -163.809431) (xy 419.953471 -163.836139) (xy 420.001721 -163.870741) (xy 420.044027 -163.912399)
			(xy 420.062152 -163.935918) (xy 420.070578 -163.946525) (xy 420.091891 -163.963232) (xy 420.116845 -163.973751)
			(xy 420.143686 -163.977341) (xy 420.170527 -163.973751) (xy 420.195481 -163.963232) (xy 420.216794 -163.946525)
			(xy 420.22522 -163.935918) (xy 420.243349 -163.912402) (xy 420.285654 -163.870741) (xy 420.333902 -163.836136)
			(xy 420.386928 -163.809424) (xy 420.443453 -163.79125) (xy 420.502111 -163.782051) (xy 420.531798 -163.781486)
			(xy 420.559051 -163.781961) (xy 420.613001 -163.789718) (xy 420.665298 -163.805073) (xy 420.714878 -163.827715)
			(xy 420.76073 -163.857183) (xy 420.801923 -163.892876) (xy 420.837616 -163.934068) (xy 420.867084 -163.979921)
			(xy 420.889726 -164.0295) (xy 420.905082 -164.081797) (xy 420.912839 -164.135747) (xy 420.912839 -164.190253)
			(xy 420.905082 -164.244203) (xy 420.889726 -164.2965) (xy 420.867084 -164.346079) (xy 420.837616 -164.391932)
			(xy 420.801923 -164.433124) (xy 420.76073 -164.468817) (xy 420.714878 -164.498285) (xy 420.665298 -164.520927)
			(xy 420.613001 -164.536282) (xy 420.559051 -164.544039) (xy 420.531798 -164.544502) (xy 420.50211 -164.543948)
			(xy 420.443451 -164.534749) (xy 420.386925 -164.516573) (xy 420.333898 -164.48986) (xy 420.285649 -164.455254)
			(xy 420.243344 -164.413591) (xy 420.22522 -164.39007) (xy 420.216794 -164.379463) (xy 420.195481 -164.362756)
			(xy 420.170527 -164.352237) (xy 420.143686 -164.348647) (xy 420.116845 -164.352237) (xy 420.091891 -164.362756)
			(xy 420.070578 -164.379463) (xy 420.062152 -164.39007) (xy 420.044036 -164.413597) (xy 420.001729 -164.455258)
			(xy 419.953478 -164.489861) (xy 419.900449 -164.516572) (xy 419.843922 -164.534744) (xy 419.785262 -164.543939)
			(xy 419.755574 -164.544502) (xy 419.728324 -164.544026) (xy 419.674378 -164.536267) (xy 419.622085 -164.520909)
			(xy 419.572511 -164.498266) (xy 419.526663 -164.468799) (xy 419.485475 -164.433107) (xy 419.449786 -164.391916)
			(xy 419.420321 -164.346067) (xy 419.397682 -164.29649) (xy 419.382328 -164.244197) (xy 419.374572 -164.19025)
			(xy 410.420566 -164.19025) (xy 410.420566 -164.770816) (xy 410.457142 -164.781484) (xy 410.482894 -164.789522)
			(xy 410.531805 -164.812279) (xy 410.576725 -164.842151) (xy 410.616627 -164.878455) (xy 410.650598 -164.920361)
			(xy 410.663244 -164.941953) (xy 418.557175 -164.941953) (xy 418.564931 -164.888006) (xy 418.580286 -164.835711)
			(xy 418.602926 -164.786133) (xy 418.632392 -164.740282) (xy 418.668083 -164.699091) (xy 418.709272 -164.663399)
			(xy 418.755122 -164.633932) (xy 418.804699 -164.61129) (xy 418.856994 -164.595934) (xy 418.910941 -164.588176)
			(xy 418.965444 -164.588175) (xy 419.019392 -164.595931) (xy 419.071687 -164.611285) (xy 419.121265 -164.633925)
			(xy 419.167116 -164.66339) (xy 419.208307 -164.699081) (xy 419.243999 -164.74027) (xy 419.273467 -164.78612)
			(xy 419.296109 -164.835697) (xy 419.311466 -164.887991) (xy 419.319224 -164.941939) (xy 419.31971 -164.96919)
			(xy 419.319282 -164.994581) (xy 419.312524 -165.044913) (xy 419.306248 -165.06952) (xy 419.302808 -165.084167)
			(xy 419.303729 -165.114225) (xy 419.31336 -165.142715) (xy 419.330866 -165.167167) (xy 419.354731 -165.185465)
			(xy 419.38289 -165.196023) (xy 419.412902 -165.197929) (xy 419.42766 -165.194996) (xy 419.449255 -165.190239)
			(xy 419.49318 -165.18514) (xy 419.51529 -165.184836) (xy 419.542541 -165.185267) (xy 419.59649 -165.193022)
			(xy 419.648785 -165.208376) (xy 419.698364 -165.231015) (xy 419.744216 -165.26048) (xy 419.785408 -165.29617)
			(xy 419.821101 -165.337359) (xy 419.85057 -165.383209) (xy 419.873213 -165.432785) (xy 419.888571 -165.48508)
			(xy 419.896331 -165.539027) (xy 419.896334 -165.59353) (xy 419.88858 -165.647479) (xy 419.873228 -165.699775)
			(xy 419.85059 -165.749354) (xy 419.821127 -165.795207) (xy 419.785438 -165.8364) (xy 419.74425 -165.872094)
			(xy 419.698401 -165.901564) (xy 419.648825 -165.924209) (xy 419.596532 -165.939569) (xy 419.542584 -165.94733)
			(xy 419.488081 -165.947335) (xy 419.434132 -165.939583) (xy 419.381836 -165.924232) (xy 419.332256 -165.901596)
			(xy 419.286403 -165.872134) (xy 419.245208 -165.836446) (xy 419.209512 -165.795259) (xy 419.180041 -165.749411)
			(xy 419.157395 -165.699836) (xy 419.142034 -165.647543) (xy 419.134271 -165.593595) (xy 419.133782 -165.566344)
			(xy 419.134216 -165.540953) (xy 419.14097 -165.490622) (xy 419.147244 -165.466014) (xy 419.150657 -165.451361)
			(xy 419.149744 -165.421304) (xy 419.14012 -165.392815) (xy 419.122618 -165.368362) (xy 419.098755 -165.350064)
			(xy 419.070599 -165.339507) (xy 419.040588 -165.337604) (xy 419.025832 -165.340538) (xy 419.004238 -165.345297)
			(xy 418.960312 -165.350394) (xy 418.938202 -165.350698) (xy 418.910951 -165.350224) (xy 418.857003 -165.342468)
			(xy 418.804708 -165.327113) (xy 418.755131 -165.304473) (xy 418.70928 -165.275007) (xy 418.668089 -165.239315)
			(xy 418.632397 -165.198125) (xy 418.602931 -165.152275) (xy 418.580289 -165.102698) (xy 418.564933 -165.050404)
			(xy 418.557176 -164.996456) (xy 418.557175 -164.941953) (xy 410.663244 -164.941953) (xy 410.677861 -164.966911)
			(xy 410.697794 -165.017039) (xy 410.709939 -165.0696) (xy 410.714019 -165.123391) (xy 410.709941 -165.177182)
			(xy 410.697799 -165.229744) (xy 410.677869 -165.279873) (xy 410.650608 -165.326424) (xy 410.616639 -165.368332)
			(xy 410.576739 -165.404638) (xy 410.531821 -165.434513) (xy 410.482911 -165.457272) (xy 410.457142 -165.465252)
			(xy 410.420566 -165.47592) (xy 410.420566 -165.787957) (xy 416.453709 -165.787957) (xy 416.453709 -165.733443)
			(xy 416.461468 -165.679483) (xy 416.476827 -165.627176) (xy 416.499474 -165.577588) (xy 416.528948 -165.531728)
			(xy 416.56465 -165.49053) (xy 416.605851 -165.454832) (xy 416.651713 -165.425361) (xy 416.701302 -165.402717)
			(xy 416.75361 -165.387362) (xy 416.807571 -165.379607) (xy 416.834828 -165.379146) (xy 416.862199 -165.379584)
			(xy 416.91638 -165.387407) (xy 416.968884 -165.402902) (xy 417.01863 -165.42575) (xy 417.064596 -165.455481)
			(xy 417.085526 -165.473126) (xy 417.096854 -165.482362) (xy 417.123411 -165.494538) (xy 417.152328 -165.498711)
			(xy 417.181245 -165.494538) (xy 417.207802 -165.482362) (xy 417.21913 -165.473126) (xy 417.240081 -165.45551)
			(xy 417.286048 -165.425794) (xy 417.335791 -165.402953) (xy 417.388287 -165.387457) (xy 417.44246 -165.379623)
			(xy 417.469828 -165.379146) (xy 417.497075 -165.379726) (xy 417.551013 -165.387485) (xy 417.603298 -165.402841)
			(xy 417.652865 -165.425481) (xy 417.698707 -165.454944) (xy 417.739889 -165.490631) (xy 417.775573 -165.531816)
			(xy 417.805033 -165.577659) (xy 417.827669 -165.627228) (xy 417.843021 -165.679515) (xy 417.850776 -165.733453)
			(xy 417.850776 -165.787947) (xy 417.843021 -165.841885) (xy 417.827669 -165.894172) (xy 417.805033 -165.943741)
			(xy 417.775573 -165.989584) (xy 417.739889 -166.030769) (xy 417.698707 -166.066456) (xy 417.652865 -166.095919)
			(xy 417.603298 -166.118559) (xy 417.551013 -166.133915) (xy 417.497075 -166.141674) (xy 417.469828 -166.142162)
			(xy 417.442458 -166.141689) (xy 417.388279 -166.133874) (xy 417.335775 -166.118387) (xy 417.286028 -166.095547)
			(xy 417.240062 -166.065823) (xy 417.21913 -166.048182) (xy 417.207802 -166.038946) (xy 417.181245 -166.02677)
			(xy 417.152328 -166.022597) (xy 417.123411 -166.02677) (xy 417.096854 -166.038946) (xy 417.085526 -166.048182)
			(xy 417.064593 -166.06582) (xy 417.01862 -166.095532) (xy 416.968873 -166.118369) (xy 416.916373 -166.13386)
			(xy 416.862197 -166.141688) (xy 416.834828 -166.142162) (xy 416.807571 -166.141793) (xy 416.75361 -166.134038)
			(xy 416.701302 -166.118683) (xy 416.651713 -166.096039) (xy 416.605851 -166.066568) (xy 416.56465 -166.03087)
			(xy 416.528948 -165.989672) (xy 416.499474 -165.943812) (xy 416.476827 -165.894224) (xy 416.461468 -165.841917)
			(xy 416.453709 -165.787957) (xy 410.420566 -165.787957) (xy 410.420566 -166.718996) (xy 410.450792 -166.727886)
			(xy 410.475605 -166.735108) (xy 410.52299 -166.755728) (xy 410.566896 -166.782981) (xy 410.606402 -166.816295)
			(xy 410.640678 -166.854969) (xy 410.669002 -166.898192) (xy 410.690782 -166.945055) (xy 410.705558 -166.994574)
			(xy 410.713022 -167.045709) (xy 410.713428 -167.071548) (xy 410.712852 -167.100576) (xy 410.70343 -167.157861)
			(xy 410.684844 -167.212861) (xy 410.657586 -167.264119) (xy 410.622377 -167.310278) (xy 410.601668 -167.330628)
			(xy 410.591151 -167.342181) (xy 410.577054 -167.370043) (xy 410.572009 -167.400859) (xy 410.576486 -167.431762)
			(xy 410.590069 -167.459878) (xy 410.600398 -167.471598) (xy 410.620262 -167.490857) (xy 410.65438 -167.534409)
			(xy 410.681355 -167.582712) (xy 410.700539 -167.634605) (xy 410.711469 -167.68884) (xy 410.713174 -167.716454)
			(xy 410.713428 -167.722042) (xy 410.713428 -167.731948) (xy 410.712991 -167.757417) (xy 410.705729 -167.807834)
			(xy 410.691359 -167.856703) (xy 410.670176 -167.903026) (xy 410.64261 -167.94586) (xy 410.609225 -167.984332)
			(xy 410.5707 -168.017655) (xy 410.527821 -168.045152) (xy 410.481463 -168.06626) (xy 410.457142 -168.073832)
			(xy 410.420566 -168.084754) (xy 410.420566 -170.156378) (xy 417.4998 -170.156378) (xy 417.500317 -170.129048)
			(xy 417.50828 -170.074971) (xy 417.524061 -170.022638) (xy 417.547322 -169.973175) (xy 417.577563 -169.927642)
			(xy 417.614133 -169.887018) (xy 417.656249 -169.852176) (xy 417.679378 -169.837608) (xy 417.691578 -169.82965)
			(xy 417.711251 -169.808189) (xy 417.724061 -169.782045) (xy 417.728962 -169.753347) (xy 417.725556 -169.724434)
			(xy 417.720272 -169.710862) (xy 417.710777 -169.687654) (xy 417.697428 -169.63932) (xy 417.690702 -169.58963)
			(xy 417.6903 -169.564558) (xy 417.690724 -169.539489) (xy 417.697474 -169.489806) (xy 417.710806 -169.441471)
			(xy 417.720272 -169.418254) (xy 417.725563 -169.404687) (xy 417.728937 -169.375773) (xy 417.724027 -169.347079)
			(xy 417.711231 -169.32093) (xy 417.691587 -169.299447) (xy 417.679378 -169.291508) (xy 417.656281 -169.276887)
			(xy 417.61416 -169.24205) (xy 417.57758 -169.201433) (xy 417.547327 -169.155907) (xy 417.52405 -169.106451)
			(xy 417.508247 -169.054124) (xy 417.500259 -169.00005) (xy 417.500256 -168.945389) (xy 417.508238 -168.891314)
			(xy 417.524036 -168.838986) (xy 417.547308 -168.789527) (xy 417.577556 -168.743998) (xy 417.614131 -168.703377)
			(xy 417.656249 -168.668536) (xy 417.679378 -168.653968) (xy 417.691605 -168.646048) (xy 417.711279 -168.624577)
			(xy 417.724084 -168.598423) (xy 417.728979 -168.569716) (xy 417.725563 -168.540796) (xy 417.720272 -168.527222)
			(xy 417.710796 -168.504007) (xy 417.69744 -168.455677) (xy 417.690706 -168.405989) (xy 417.6903 -168.380918)
			(xy 417.690766 -168.354075) (xy 417.698468 -168.300945) (xy 417.713716 -168.24947) (xy 417.736193 -168.200717)
			(xy 417.765435 -168.155694) (xy 417.800836 -168.115334) (xy 417.841662 -168.080472) (xy 417.887069 -168.051831)
			(xy 417.936117 -168.030002) (xy 417.961826 -168.02227) (xy 417.976329 -168.01762) (xy 418.0019 -168.001103)
			(xy 418.021469 -167.977785) (xy 418.033299 -167.949737) (xy 418.03634 -167.919448) (xy 418.030322 -167.889608)
			(xy 418.023548 -167.875966) (xy 418.00892 -167.847818) (xy 417.988191 -167.787868) (xy 417.977691 -167.72531)
			(xy 417.977066 -167.693594) (xy 417.977291 -167.675575) (xy 417.980722 -167.6397) (xy 417.983924 -167.621966)
			(xy 417.986322 -167.606764) (xy 417.982784 -167.576201) (xy 417.97031 -167.548077) (xy 417.95003 -167.524941)
			(xy 417.923782 -167.508889) (xy 417.908994 -167.504618) (xy 417.881967 -167.497164) (xy 417.830242 -167.475542)
			(xy 417.782237 -167.446585) (xy 417.738984 -167.410917) (xy 417.701416 -167.369305) (xy 417.670339 -167.322645)
			(xy 417.646423 -167.27194) (xy 417.630183 -167.218282) (xy 417.621967 -167.162825) (xy 417.621466 -167.134794)
			(xy 417.621972 -167.107544) (xy 417.629729 -167.053598) (xy 417.645083 -167.001305) (xy 417.667723 -166.95173)
			(xy 417.697188 -166.905881) (xy 417.732877 -166.864691) (xy 417.774065 -166.829) (xy 417.819912 -166.799533)
			(xy 417.869487 -166.77689) (xy 417.921779 -166.761533) (xy 417.975724 -166.753774) (xy 418.002974 -166.753286)
			(xy 418.030548 -166.753774) (xy 418.085119 -166.761723) (xy 418.137979 -166.777444) (xy 418.188024 -166.80061)
			(xy 418.234215 -166.830738) (xy 418.275587 -166.867201) (xy 418.293804 -166.887906) (xy 418.303702 -166.898804)
			(xy 418.328352 -166.914879) (xy 418.35656 -166.923263) (xy 418.385988 -166.923263) (xy 418.414196 -166.914879)
			(xy 418.438846 -166.898804) (xy 418.448744 -166.887906) (xy 418.466959 -166.8672) (xy 418.50833 -166.830735)
			(xy 418.55452 -166.800608) (xy 418.604567 -166.777445) (xy 418.657428 -166.761729) (xy 418.712 -166.753789)
			(xy 418.767148 -166.753789) (xy 418.82172 -166.761729) (xy 418.874581 -166.777445) (xy 418.924628 -166.800608)
			(xy 418.970818 -166.830735) (xy 419.012189 -166.8672) (xy 419.030404 -166.887906) (xy 419.040302 -166.898804)
			(xy 419.064952 -166.914879) (xy 419.09316 -166.923263) (xy 419.122588 -166.923263) (xy 419.150796 -166.914879)
			(xy 419.175446 -166.898804) (xy 419.185344 -166.887906) (xy 419.203582 -166.86722) (xy 419.244945 -166.830747)
			(xy 419.291129 -166.800612) (xy 419.341172 -166.777442) (xy 419.39403 -166.76172) (xy 419.448601 -166.753775)
			(xy 419.476174 -166.753286) (xy 419.503426 -166.753779) (xy 419.557375 -166.761533) (xy 419.609672 -166.776885)
			(xy 419.659252 -166.799524) (xy 419.705105 -166.828989) (xy 419.746298 -166.86468) (xy 419.781992 -166.905869)
			(xy 419.81146 -166.95172) (xy 419.834104 -167.001298) (xy 419.84946 -167.053593) (xy 419.857218 -167.107542)
			(xy 419.857682 -167.134794) (xy 419.857167 -167.16265) (xy 419.849043 -167.217766) (xy 419.832998 -167.271117)
			(xy 419.80937 -167.321571) (xy 419.778663 -167.368056) (xy 419.741526 -167.409585) (xy 419.69875 -167.445278)
			(xy 419.651241 -167.474376) (xy 419.600008 -167.496262) (xy 419.573202 -167.503856) (xy 419.559077 -167.508105)
			(xy 419.53393 -167.523501) (xy 419.514215 -167.545425) (xy 419.501566 -167.57206) (xy 419.497034 -167.601195)
			(xy 419.498526 -167.61587) (xy 419.5002 -167.628886) (xy 419.501977 -167.655071) (xy 419.502082 -167.668194)
			(xy 419.501988 -167.682343) (xy 419.499954 -167.710566) (xy 419.498018 -167.724582) (xy 419.496394 -167.737927)
			(xy 419.4995 -167.764623) (xy 419.509476 -167.789579) (xy 419.525629 -167.81106) (xy 419.546835 -167.827572)
			(xy 419.57162 -167.837966) (xy 419.584886 -167.840152) (xy 419.612039 -167.844237) (xy 419.664868 -167.859214)
			(xy 419.715004 -167.881609) (xy 419.761412 -167.910958) (xy 419.803135 -167.946656) (xy 419.839311 -167.987965)
			(xy 419.869192 -168.034033) (xy 419.892162 -168.083908) (xy 419.907746 -168.136561) (xy 419.915622 -168.190903)
			(xy 419.916102 -168.218358) (xy 419.915606 -168.24561) (xy 419.907854 -168.29956) (xy 419.892503 -168.351858)
			(xy 419.869865 -168.401438) (xy 419.840401 -168.447292) (xy 419.804711 -168.488485) (xy 419.763521 -168.524179)
			(xy 419.71767 -168.553648) (xy 419.668092 -168.576291) (xy 419.615795 -168.591647) (xy 419.561846 -168.599403)
			(xy 419.534594 -168.599866) (xy 419.507019 -168.599416) (xy 419.452445 -168.591462) (xy 419.399584 -168.575735)
			(xy 419.349538 -168.552562) (xy 419.303349 -168.522426) (xy 419.261979 -168.485955) (xy 419.243764 -168.465246)
			(xy 419.233866 -168.454348) (xy 419.209216 -168.438273) (xy 419.181008 -168.429889) (xy 419.15158 -168.429889)
			(xy 419.123372 -168.438273) (xy 419.098722 -168.454348) (xy 419.088824 -168.465246) (xy 419.070614 -168.485958)
			(xy 419.029244 -168.522426) (xy 418.983053 -168.552557) (xy 418.933005 -168.575722) (xy 418.880143 -168.591439)
			(xy 418.825569 -168.59938) (xy 418.797994 -168.599866) (xy 418.771493 -168.599405) (xy 418.719002 -168.592063)
			(xy 418.668034 -168.577521) (xy 418.619572 -168.556059) (xy 418.574549 -168.528091) (xy 418.5539 -168.511474)
			(xy 418.541717 -168.502082) (xy 418.51333 -168.490285) (xy 418.482719 -168.487451) (xy 418.452648 -168.493838)
			(xy 418.425831 -168.508868) (xy 418.404689 -168.531186) (xy 418.397436 -168.544748) (xy 418.385321 -168.56843)
			(xy 418.355402 -168.612413) (xy 418.319535 -168.651696) (xy 418.278448 -168.685482) (xy 418.255958 -168.699688)
			(xy 418.243751 -168.707635) (xy 418.224085 -168.729102) (xy 418.211281 -168.755249) (xy 418.206381 -168.783947)
			(xy 418.209783 -168.812861) (xy 418.215064 -168.826434) (xy 418.22456 -168.849641) (xy 418.237908 -168.897976)
			(xy 418.244633 -168.947666) (xy 418.245036 -168.972738) (xy 418.244615 -168.997807) (xy 418.237865 -169.047491)
			(xy 418.224531 -169.095825) (xy 418.215064 -169.119042) (xy 418.209854 -169.132631) (xy 418.206485 -169.161525)
			(xy 418.211389 -169.190198) (xy 418.224168 -169.21633) (xy 418.243789 -169.237805) (xy 418.255958 -169.245788)
			(xy 418.27905 -169.260416) (xy 418.321167 -169.295255) (xy 418.357742 -169.335872) (xy 418.387993 -169.381397)
			(xy 418.411268 -169.430852) (xy 418.427069 -169.483177) (xy 418.435057 -169.537249) (xy 418.43506 -169.591908)
			(xy 418.427078 -169.64598) (xy 418.411283 -169.698307) (xy 418.388014 -169.747765) (xy 418.357769 -169.793294)
			(xy 418.321198 -169.833915) (xy 418.279085 -169.868759) (xy 418.255958 -169.883328) (xy 418.243724 -169.891237)
			(xy 418.224058 -169.912714) (xy 418.211257 -169.938871) (xy 418.208732 -169.953686) (xy 426.587415 -169.953686)
			(xy 426.591451 -169.870239) (xy 426.603523 -169.787571) (xy 426.623516 -169.706454) (xy 426.651245 -169.627645)
			(xy 426.686451 -169.55188) (xy 426.728805 -169.479867) (xy 426.777911 -169.412278) (xy 426.833312 -169.349744)
			(xy 426.894489 -169.292849) (xy 426.960872 -169.242123) (xy 427.03184 -169.198042) (xy 427.106732 -169.161016)
			(xy 427.184848 -169.13139) (xy 427.265458 -169.109442) (xy 427.34781 -169.095377) (xy 427.431136 -169.089325)
			(xy 427.514656 -169.091344) (xy 427.597592 -169.101414) (xy 427.679168 -169.119442) (xy 427.758624 -169.145259)
			(xy 427.835217 -169.178624) (xy 427.908233 -169.219225) (xy 427.976989 -169.266684) (xy 428.040843 -169.320557)
			(xy 428.0992 -169.380342) (xy 428.151515 -169.445479) (xy 428.197298 -169.515362) (xy 428.236123 -169.589337)
			(xy 428.267628 -169.666714) (xy 428.291517 -169.746771) (xy 428.307568 -169.828759) (xy 428.315631 -169.911914)
			(xy 428.316136 -169.953686) (xy 428.315631 -169.995458) (xy 428.307568 -170.078613) (xy 428.291517 -170.160601)
			(xy 428.267628 -170.240658) (xy 428.236123 -170.318035) (xy 428.197298 -170.39201) (xy 428.151515 -170.461893)
			(xy 428.0992 -170.52703) (xy 428.040843 -170.586815) (xy 427.976989 -170.640688) (xy 427.908233 -170.688147)
			(xy 427.835217 -170.728748) (xy 427.758624 -170.762113) (xy 427.679168 -170.78793) (xy 427.597592 -170.805958)
			(xy 427.514656 -170.816028) (xy 427.431136 -170.818047) (xy 427.34781 -170.811995) (xy 427.265458 -170.79793)
			(xy 427.184848 -170.775982) (xy 427.106732 -170.746356) (xy 427.03184 -170.70933) (xy 426.960872 -170.665249)
			(xy 426.894489 -170.614523) (xy 426.833312 -170.557628) (xy 426.777911 -170.495094) (xy 426.728805 -170.427505)
			(xy 426.686451 -170.355492) (xy 426.651245 -170.279727) (xy 426.623516 -170.200918) (xy 426.603523 -170.119801)
			(xy 426.591451 -170.037133) (xy 426.587415 -169.953686) (xy 418.208732 -169.953686) (xy 418.206364 -169.967578)
			(xy 418.209777 -169.996499) (xy 418.215064 -170.010074) (xy 418.224541 -170.033289) (xy 418.237896 -170.081619)
			(xy 418.244629 -170.131307) (xy 418.245036 -170.156378) (xy 418.244515 -170.184263) (xy 418.236203 -170.23941)
			(xy 418.219765 -170.292702) (xy 418.195567 -170.342948) (xy 418.164151 -170.389027) (xy 418.126218 -170.429909)
			(xy 418.082616 -170.464681) (xy 418.034318 -170.492566) (xy 417.982403 -170.512941) (xy 417.928032 -170.525351)
			(xy 417.872418 -170.529519) (xy 417.816804 -170.525351) (xy 417.762433 -170.512941) (xy 417.710518 -170.492566)
			(xy 417.66222 -170.464681) (xy 417.618618 -170.429909) (xy 417.580685 -170.389027) (xy 417.549269 -170.342948)
			(xy 417.525071 -170.292702) (xy 417.508633 -170.23941) (xy 417.500321 -170.184263) (xy 417.4998 -170.156378)
			(xy 410.420566 -170.156378) (xy 410.420566 -171.087542) (xy 419.315646 -171.087542) (xy 419.316217 -171.060294)
			(xy 419.323967 -171.006352) (xy 419.339314 -170.954061) (xy 419.361947 -170.904487) (xy 419.391405 -170.858639)
			(xy 419.427087 -170.81745) (xy 419.468269 -170.781757) (xy 419.51411 -170.752289) (xy 419.563679 -170.729645)
			(xy 419.615966 -170.714285) (xy 419.669906 -170.706523) (xy 419.697154 -170.706034) (xy 419.727059 -170.706571)
			(xy 419.786138 -170.715883) (xy 419.814756 -170.724576) (xy 419.82866 -170.72863) (xy 419.857597 -170.72954)
			(xy 419.885621 -170.722274) (xy 419.910469 -170.707418) (xy 419.930134 -170.686171) (xy 419.943028 -170.660251)
			(xy 419.946074 -170.64609) (xy 419.951204 -170.620008) (xy 419.967775 -170.569501) (xy 419.991201 -170.521784)
			(xy 420.021027 -170.477784) (xy 420.056674 -170.438352) (xy 420.097452 -170.404253) (xy 420.142571 -170.376148)
			(xy 420.191156 -170.354581) (xy 420.242265 -170.339971) (xy 420.294908 -170.332601) (xy 420.321486 -170.332146)
			(xy 420.348736 -170.3327) (xy 420.402682 -170.340455) (xy 420.454975 -170.355808) (xy 420.504551 -170.378447)
			(xy 420.550401 -170.407911) (xy 420.59159 -170.4436) (xy 420.627281 -170.484788) (xy 420.656747 -170.530636)
			(xy 420.679387 -170.580211) (xy 420.694742 -170.632504) (xy 420.702499 -170.68645) (xy 420.702499 -170.74095)
			(xy 420.694742 -170.794896) (xy 420.679387 -170.847189) (xy 420.656747 -170.896764) (xy 420.627281 -170.942612)
			(xy 420.59159 -170.9838) (xy 420.550401 -171.019489) (xy 420.504551 -171.048953) (xy 420.454975 -171.071592)
			(xy 420.402682 -171.086945) (xy 420.348736 -171.0947) (xy 420.321486 -171.095162) (xy 420.291581 -171.094639)
			(xy 420.232502 -171.085318) (xy 420.203884 -171.07662) (xy 420.189967 -171.072614) (xy 420.161038 -171.071695)
			(xy 420.133019 -171.078952) (xy 420.108173 -171.093799) (xy 420.088508 -171.115036) (xy 420.075613 -171.140949)
			(xy 420.072566 -171.155106) (xy 420.06599 -171.187947) (xy 420.042863 -171.250798) (xy 420.026592 -171.280074)
			(xy 420.019587 -171.293057) (xy 420.012541 -171.321688) (xy 420.013975 -171.351137) (xy 420.023771 -171.378948)
			(xy 420.04111 -171.402795) (xy 420.064544 -171.42069) (xy 420.078154 -171.426378) (xy 420.104942 -171.437047)
			(xy 420.155182 -171.465341) (xy 420.20059 -171.500876) (xy 420.240131 -171.542842) (xy 420.272903 -171.590283)
			(xy 420.298159 -171.642117) (xy 420.315323 -171.697162) (xy 420.324005 -171.754164) (xy 420.324534 -171.782994)
			(xy 420.324048 -171.810245) (xy 420.316292 -171.864193) (xy 420.300937 -171.916488) (xy 420.278295 -171.966065)
			(xy 420.248829 -172.011915) (xy 420.213138 -172.053106) (xy 420.171947 -172.088797) (xy 420.126097 -172.118263)
			(xy 420.07652 -172.140905) (xy 420.024225 -172.15626) (xy 419.970277 -172.164016) (xy 419.915775 -172.164016)
			(xy 419.861827 -172.15626) (xy 419.809532 -172.140905) (xy 419.759955 -172.118263) (xy 419.714105 -172.088797)
			(xy 419.672914 -172.053106) (xy 419.637223 -172.011915) (xy 419.607757 -171.966065) (xy 419.585115 -171.916488)
			(xy 419.56976 -171.864193) (xy 419.562004 -171.810245) (xy 419.561518 -171.782994) (xy 419.56191 -171.757758)
			(xy 419.568529 -171.707724) (xy 419.581704 -171.659004) (xy 419.601202 -171.612452) (xy 419.613588 -171.590462)
			(xy 419.620627 -171.577499) (xy 419.627653 -171.548862) (xy 419.626205 -171.519412) (xy 419.616403 -171.491603)
			(xy 419.599064 -171.467754) (xy 419.575634 -171.449852) (xy 419.562026 -171.444158) (xy 419.535269 -171.433416)
			(xy 419.485027 -171.405136) (xy 419.439617 -171.369613) (xy 419.400072 -171.327658) (xy 419.367296 -171.280228)
			(xy 419.342035 -171.228402) (xy 419.324865 -171.173365) (xy 419.316178 -171.116369) (xy 419.315646 -171.087542)
			(xy 410.420566 -171.087542) (xy 410.420566 -172.82625) (xy 419.374572 -172.82625) (xy 419.374572 -172.77175)
			(xy 419.382328 -172.717803) (xy 419.397682 -172.66551) (xy 419.420321 -172.615933) (xy 419.449786 -172.570084)
			(xy 419.485475 -172.528893) (xy 419.526663 -172.493201) (xy 419.572511 -172.463734) (xy 419.622085 -172.441091)
			(xy 419.674378 -172.425733) (xy 419.728324 -172.417974) (xy 419.755574 -172.417486) (xy 419.78151 -172.417935)
			(xy 419.832905 -172.42496) (xy 419.882874 -172.438884) (xy 419.930495 -172.459451) (xy 419.97489 -172.48628)
			(xy 419.987115 -172.496156) (xy 426.563024 -172.496156) (xy 426.563024 -172.41146) (xy 426.571075 -172.327146)
			(xy 426.587104 -172.24398) (xy 426.610965 -172.162713) (xy 426.642444 -172.084083) (xy 426.681255 -172.008802)
			(xy 426.727045 -171.93755) (xy 426.779401 -171.870974) (xy 426.837849 -171.809676) (xy 426.901859 -171.754211)
			(xy 426.970851 -171.705082) (xy 427.044201 -171.662733) (xy 427.121244 -171.627549) (xy 427.201283 -171.599847)
			(xy 427.283592 -171.579879) (xy 427.367427 -171.567826) (xy 427.452028 -171.563796) (xy 427.536629 -171.567826)
			(xy 427.620464 -171.579879) (xy 427.702773 -171.599847) (xy 427.782812 -171.627549) (xy 427.859855 -171.662733)
			(xy 427.933205 -171.705082) (xy 428.002197 -171.754211) (xy 428.066207 -171.809676) (xy 428.124655 -171.870974)
			(xy 428.177011 -171.93755) (xy 428.222801 -172.008802) (xy 428.261612 -172.084083) (xy 428.293091 -172.162713)
			(xy 428.316952 -172.24398) (xy 428.332981 -172.327146) (xy 428.341032 -172.41146) (xy 428.341536 -172.453808)
			(xy 428.341032 -172.496156) (xy 428.332981 -172.58047) (xy 428.316952 -172.663636) (xy 428.293091 -172.744903)
			(xy 428.261612 -172.823533) (xy 428.222801 -172.898814) (xy 428.177011 -172.970066) (xy 428.124655 -173.036642)
			(xy 428.066207 -173.09794) (xy 428.002197 -173.153405) (xy 427.933205 -173.202534) (xy 427.859855 -173.244883)
			(xy 427.782812 -173.280067) (xy 427.702773 -173.307769) (xy 427.620464 -173.327737) (xy 427.536629 -173.33979)
			(xy 427.452028 -173.343821) (xy 427.367427 -173.33979) (xy 427.283592 -173.327737) (xy 427.201283 -173.307769)
			(xy 427.121244 -173.280067) (xy 427.044201 -173.244883) (xy 426.970851 -173.202534) (xy 426.901859 -173.153405)
			(xy 426.837849 -173.09794) (xy 426.779401 -173.036642) (xy 426.727045 -172.970066) (xy 426.681255 -172.898814)
			(xy 426.642444 -172.823533) (xy 426.610965 -172.744903) (xy 426.587104 -172.663636) (xy 426.571075 -172.58047)
			(xy 426.563024 -172.496156) (xy 419.987115 -172.496156) (xy 420.015241 -172.518878) (xy 420.050803 -172.556642)
			(xy 420.066216 -172.577506) (xy 420.075441 -172.589618) (xy 420.099609 -172.608114) (xy 420.128159 -172.618654)
			(xy 420.158548 -172.620298) (xy 420.188068 -172.6129) (xy 420.201344 -172.605446) (xy 420.223766 -172.592408)
			(xy 420.271398 -172.571875) (xy 420.321372 -172.557986) (xy 420.372767 -172.550998) (xy 420.398702 -172.550582)
			(xy 420.425952 -172.551088) (xy 420.479898 -172.558845) (xy 420.532192 -172.5742) (xy 420.581767 -172.59684)
			(xy 420.627616 -172.626306) (xy 420.668805 -172.661997) (xy 420.704495 -172.703186) (xy 420.733961 -172.749035)
			(xy 420.756601 -172.79861) (xy 420.771956 -172.850904) (xy 420.779712 -172.90485) (xy 420.779712 -172.95935)
			(xy 420.771956 -173.013296) (xy 420.756601 -173.06559) (xy 420.733961 -173.115165) (xy 420.704495 -173.161014)
			(xy 420.668805 -173.202203) (xy 420.627616 -173.237894) (xy 420.581767 -173.26736) (xy 420.532192 -173.29)
			(xy 420.479898 -173.305355) (xy 420.425952 -173.313112) (xy 420.398702 -173.313598) (xy 420.372765 -173.313174)
			(xy 420.321369 -173.306145) (xy 420.271399 -173.292217) (xy 420.223778 -173.271647) (xy 420.179382 -173.244813)
			(xy 420.139033 -173.212212) (xy 420.103472 -173.174444) (xy 420.08806 -173.153578) (xy 420.07886 -173.141445)
			(xy 420.054684 -173.122952) (xy 420.026127 -173.112417) (xy 419.995733 -173.110778) (xy 419.966209 -173.118181)
			(xy 419.952932 -173.125638) (xy 419.930497 -173.138654) (xy 419.88287 -173.15919) (xy 419.8329 -173.173085)
			(xy 419.781507 -173.180081) (xy 419.755574 -173.180502) (xy 419.728324 -173.180026) (xy 419.674378 -173.172267)
			(xy 419.622085 -173.156909) (xy 419.572511 -173.134266) (xy 419.526663 -173.104799) (xy 419.485475 -173.069107)
			(xy 419.449786 -173.027916) (xy 419.420321 -172.982067) (xy 419.397682 -172.93249) (xy 419.382328 -172.880197)
			(xy 419.374572 -172.82625) (xy 410.420566 -172.82625) (xy 410.420566 -173.406816) (xy 410.457142 -173.417484)
			(xy 410.482894 -173.425522) (xy 410.531805 -173.448279) (xy 410.576725 -173.478151) (xy 410.616627 -173.514455)
			(xy 410.650598 -173.556361) (xy 410.663244 -173.577953) (xy 418.557175 -173.577953) (xy 418.564931 -173.524006)
			(xy 418.580286 -173.471711) (xy 418.602926 -173.422133) (xy 418.632392 -173.376282) (xy 418.668083 -173.335091)
			(xy 418.709272 -173.299399) (xy 418.755122 -173.269932) (xy 418.804699 -173.24729) (xy 418.856994 -173.231934)
			(xy 418.910941 -173.224176) (xy 418.965444 -173.224175) (xy 419.019392 -173.231931) (xy 419.071687 -173.247285)
			(xy 419.121265 -173.269925) (xy 419.167116 -173.29939) (xy 419.208307 -173.335081) (xy 419.243999 -173.37627)
			(xy 419.273467 -173.42212) (xy 419.296109 -173.471697) (xy 419.311466 -173.523991) (xy 419.319224 -173.577939)
			(xy 419.31971 -173.60519) (xy 419.319282 -173.630581) (xy 419.312524 -173.680913) (xy 419.306248 -173.70552)
			(xy 419.302808 -173.720167) (xy 419.303729 -173.750225) (xy 419.31336 -173.778715) (xy 419.330866 -173.803167)
			(xy 419.354731 -173.821465) (xy 419.38289 -173.832023) (xy 419.412902 -173.833929) (xy 419.42766 -173.830996)
			(xy 419.449255 -173.826239) (xy 419.49318 -173.82114) (xy 419.51529 -173.820836) (xy 419.542541 -173.821267)
			(xy 419.59649 -173.829022) (xy 419.648785 -173.844376) (xy 419.698364 -173.867015) (xy 419.744216 -173.89648)
			(xy 419.785408 -173.93217) (xy 419.821101 -173.973359) (xy 419.85057 -174.019209) (xy 419.873213 -174.068785)
			(xy 419.888571 -174.12108) (xy 419.896331 -174.175027) (xy 419.896334 -174.22953) (xy 419.88858 -174.283479)
			(xy 419.873228 -174.335775) (xy 419.85059 -174.385354) (xy 419.821127 -174.431207) (xy 419.785438 -174.4724)
			(xy 419.74425 -174.508094) (xy 419.698401 -174.537564) (xy 419.648825 -174.560209) (xy 419.596532 -174.575569)
			(xy 419.542584 -174.58333) (xy 419.488081 -174.583335) (xy 419.434132 -174.575583) (xy 419.381836 -174.560232)
			(xy 419.332256 -174.537596) (xy 419.286403 -174.508134) (xy 419.245208 -174.472446) (xy 419.209512 -174.431259)
			(xy 419.180041 -174.385411) (xy 419.157395 -174.335836) (xy 419.142034 -174.283543) (xy 419.134271 -174.229595)
			(xy 419.133782 -174.202344) (xy 419.134216 -174.176953) (xy 419.14097 -174.126622) (xy 419.147244 -174.102014)
			(xy 419.150657 -174.087361) (xy 419.149744 -174.057304) (xy 419.14012 -174.028815) (xy 419.122618 -174.004362)
			(xy 419.098755 -173.986064) (xy 419.070599 -173.975507) (xy 419.040588 -173.973604) (xy 419.025832 -173.976538)
			(xy 419.004238 -173.981297) (xy 418.960312 -173.986394) (xy 418.938202 -173.986698) (xy 418.910951 -173.986224)
			(xy 418.857003 -173.978468) (xy 418.804708 -173.963113) (xy 418.755131 -173.940473) (xy 418.70928 -173.911007)
			(xy 418.668089 -173.875315) (xy 418.632397 -173.834125) (xy 418.602931 -173.788275) (xy 418.580289 -173.738698)
			(xy 418.564933 -173.686404) (xy 418.557176 -173.632456) (xy 418.557175 -173.577953) (xy 410.663244 -173.577953)
			(xy 410.677861 -173.602911) (xy 410.697794 -173.653039) (xy 410.709939 -173.7056) (xy 410.714019 -173.759391)
			(xy 410.709941 -173.813182) (xy 410.697799 -173.865744) (xy 410.677869 -173.915873) (xy 410.650608 -173.962424)
			(xy 410.616639 -174.004332) (xy 410.576739 -174.040638) (xy 410.531821 -174.070513) (xy 410.482911 -174.093272)
			(xy 410.457142 -174.101252) (xy 410.420566 -174.11192) (xy 410.420566 -174.423957) (xy 416.453709 -174.423957)
			(xy 416.453709 -174.369443) (xy 416.461468 -174.315483) (xy 416.476827 -174.263176) (xy 416.499474 -174.213588)
			(xy 416.528948 -174.167728) (xy 416.56465 -174.12653) (xy 416.605851 -174.090832) (xy 416.651713 -174.061361)
			(xy 416.701302 -174.038717) (xy 416.75361 -174.023362) (xy 416.807571 -174.015607) (xy 416.834828 -174.015146)
			(xy 416.862199 -174.015584) (xy 416.91638 -174.023407) (xy 416.968884 -174.038902) (xy 417.01863 -174.06175)
			(xy 417.064596 -174.091481) (xy 417.085526 -174.109126) (xy 417.096854 -174.118362) (xy 417.123411 -174.130538)
			(xy 417.152328 -174.134711) (xy 417.181245 -174.130538) (xy 417.207802 -174.118362) (xy 417.21913 -174.109126)
			(xy 417.240081 -174.09151) (xy 417.286048 -174.061794) (xy 417.335791 -174.038953) (xy 417.388287 -174.023457)
			(xy 417.44246 -174.015623) (xy 417.469828 -174.015146) (xy 417.497075 -174.015726) (xy 417.551013 -174.023485)
			(xy 417.603298 -174.038841) (xy 417.652865 -174.061481) (xy 417.698707 -174.090944) (xy 417.739889 -174.126631)
			(xy 417.775573 -174.167816) (xy 417.805033 -174.213659) (xy 417.827669 -174.263228) (xy 417.843021 -174.315515)
			(xy 417.850776 -174.369453) (xy 417.850776 -174.423947) (xy 417.843021 -174.477885) (xy 417.827669 -174.530172)
			(xy 417.805033 -174.579741) (xy 417.775573 -174.625584) (xy 417.739889 -174.666769) (xy 417.698707 -174.702456)
			(xy 417.652865 -174.731919) (xy 417.603298 -174.754559) (xy 417.551013 -174.769915) (xy 417.497075 -174.777674)
			(xy 417.469828 -174.778162) (xy 417.442458 -174.777689) (xy 417.388279 -174.769874) (xy 417.335775 -174.754387)
			(xy 417.286028 -174.731547) (xy 417.240062 -174.701823) (xy 417.21913 -174.684182) (xy 417.207802 -174.674946)
			(xy 417.181245 -174.66277) (xy 417.152328 -174.658597) (xy 417.123411 -174.66277) (xy 417.096854 -174.674946)
			(xy 417.085526 -174.684182) (xy 417.064593 -174.70182) (xy 417.01862 -174.731532) (xy 416.968873 -174.754369)
			(xy 416.916373 -174.76986) (xy 416.862197 -174.777688) (xy 416.834828 -174.778162) (xy 416.807571 -174.777793)
			(xy 416.75361 -174.770038) (xy 416.701302 -174.754683) (xy 416.651713 -174.732039) (xy 416.605851 -174.702568)
			(xy 416.56465 -174.66687) (xy 416.528948 -174.625672) (xy 416.499474 -174.579812) (xy 416.476827 -174.530224)
			(xy 416.461468 -174.477917) (xy 416.453709 -174.423957) (xy 410.420566 -174.423957) (xy 410.420566 -175.354996)
			(xy 410.450792 -175.363886) (xy 410.475605 -175.371108) (xy 410.52299 -175.391728) (xy 410.566896 -175.418981)
			(xy 410.606402 -175.452295) (xy 410.640678 -175.490969) (xy 410.669002 -175.534192) (xy 410.690782 -175.581055)
			(xy 410.705558 -175.630574) (xy 410.713022 -175.681709) (xy 410.713428 -175.707548) (xy 410.712852 -175.736576)
			(xy 410.70343 -175.793861) (xy 410.684844 -175.848861) (xy 410.657586 -175.900119) (xy 410.622377 -175.946278)
			(xy 410.601668 -175.966628) (xy 410.591151 -175.978181) (xy 410.577054 -176.006043) (xy 410.572009 -176.036859)
			(xy 410.576486 -176.067762) (xy 410.590069 -176.095878) (xy 410.600398 -176.107598) (xy 410.620262 -176.126857)
			(xy 410.65438 -176.170409) (xy 410.681355 -176.218712) (xy 410.700539 -176.270605) (xy 410.711469 -176.32484)
			(xy 410.713174 -176.352454) (xy 410.713428 -176.358042) (xy 410.713428 -176.367948) (xy 410.712991 -176.393417)
			(xy 410.705729 -176.443834) (xy 410.691359 -176.492703) (xy 410.670176 -176.539026) (xy 410.64261 -176.58186)
			(xy 410.609225 -176.620332) (xy 410.5707 -176.653655) (xy 410.527821 -176.681152) (xy 410.481463 -176.70226)
			(xy 410.457142 -176.709832) (xy 410.420566 -176.720754) (xy 410.420566 -178.792378) (xy 417.4998 -178.792378)
			(xy 417.500317 -178.765048) (xy 417.50828 -178.710971) (xy 417.524061 -178.658638) (xy 417.547322 -178.609175)
			(xy 417.577563 -178.563642) (xy 417.614133 -178.523018) (xy 417.656249 -178.488176) (xy 417.679378 -178.473608)
			(xy 417.691578 -178.46565) (xy 417.711251 -178.444189) (xy 417.724061 -178.418045) (xy 417.728962 -178.389347)
			(xy 417.725556 -178.360434) (xy 417.720272 -178.346862) (xy 417.710777 -178.323654) (xy 417.697428 -178.27532)
			(xy 417.690702 -178.22563) (xy 417.6903 -178.200558) (xy 417.690724 -178.175489) (xy 417.697474 -178.125806)
			(xy 417.710806 -178.077471) (xy 417.720272 -178.054254) (xy 417.725563 -178.040687) (xy 417.728937 -178.011773)
			(xy 417.724027 -177.983079) (xy 417.711231 -177.95693) (xy 417.691587 -177.935447) (xy 417.679378 -177.927508)
			(xy 417.656281 -177.912887) (xy 417.61416 -177.87805) (xy 417.57758 -177.837433) (xy 417.547327 -177.791907)
			(xy 417.52405 -177.742451) (xy 417.508247 -177.690124) (xy 417.500259 -177.63605) (xy 417.500256 -177.581389)
			(xy 417.508238 -177.527314) (xy 417.524036 -177.474986) (xy 417.547308 -177.425527) (xy 417.577556 -177.379998)
			(xy 417.614131 -177.339377) (xy 417.656249 -177.304536) (xy 417.679378 -177.289968) (xy 417.691605 -177.282048)
			(xy 417.711279 -177.260577) (xy 417.724084 -177.234423) (xy 417.728979 -177.205716) (xy 417.725563 -177.176796)
			(xy 417.720272 -177.163222) (xy 417.710796 -177.140007) (xy 417.69744 -177.091677) (xy 417.690706 -177.041989)
			(xy 417.6903 -177.016918) (xy 417.690766 -176.990075) (xy 417.698468 -176.936945) (xy 417.713716 -176.88547)
			(xy 417.736193 -176.836717) (xy 417.765435 -176.791694) (xy 417.800836 -176.751334) (xy 417.841662 -176.716472)
			(xy 417.887069 -176.687831) (xy 417.936117 -176.666002) (xy 417.961826 -176.65827) (xy 417.976329 -176.65362)
			(xy 418.0019 -176.637103) (xy 418.021469 -176.613785) (xy 418.033299 -176.585737) (xy 418.03634 -176.555448)
			(xy 418.030322 -176.525608) (xy 418.023548 -176.511966) (xy 418.00892 -176.483818) (xy 417.988191 -176.423868)
			(xy 417.977691 -176.36131) (xy 417.977066 -176.329594) (xy 417.977291 -176.311575) (xy 417.980722 -176.2757)
			(xy 417.983924 -176.257966) (xy 417.986322 -176.242764) (xy 417.982784 -176.212201) (xy 417.97031 -176.184077)
			(xy 417.95003 -176.160941) (xy 417.923782 -176.144889) (xy 417.908994 -176.140618) (xy 417.881967 -176.133164)
			(xy 417.830242 -176.111542) (xy 417.782237 -176.082585) (xy 417.738984 -176.046917) (xy 417.701416 -176.005305)
			(xy 417.670339 -175.958645) (xy 417.646423 -175.90794) (xy 417.630183 -175.854282) (xy 417.621967 -175.798825)
			(xy 417.621466 -175.770794) (xy 417.621972 -175.743544) (xy 417.629729 -175.689598) (xy 417.645083 -175.637305)
			(xy 417.667723 -175.58773) (xy 417.697188 -175.541881) (xy 417.732877 -175.500691) (xy 417.774065 -175.465)
			(xy 417.819912 -175.435533) (xy 417.869487 -175.41289) (xy 417.921779 -175.397533) (xy 417.975724 -175.389774)
			(xy 418.002974 -175.389286) (xy 418.030548 -175.389774) (xy 418.085119 -175.397723) (xy 418.137979 -175.413444)
			(xy 418.188024 -175.43661) (xy 418.234215 -175.466738) (xy 418.275587 -175.503201) (xy 418.293804 -175.523906)
			(xy 418.303702 -175.534804) (xy 418.328352 -175.550879) (xy 418.35656 -175.559263) (xy 418.385988 -175.559263)
			(xy 418.414196 -175.550879) (xy 418.438846 -175.534804) (xy 418.448744 -175.523906) (xy 418.466959 -175.5032)
			(xy 418.50833 -175.466735) (xy 418.55452 -175.436608) (xy 418.604567 -175.413445) (xy 418.657428 -175.397729)
			(xy 418.712 -175.389789) (xy 418.767148 -175.389789) (xy 418.82172 -175.397729) (xy 418.874581 -175.413445)
			(xy 418.924628 -175.436608) (xy 418.970818 -175.466735) (xy 419.012189 -175.5032) (xy 419.030404 -175.523906)
			(xy 419.040302 -175.534804) (xy 419.064952 -175.550879) (xy 419.09316 -175.559263) (xy 419.122588 -175.559263)
			(xy 419.150796 -175.550879) (xy 419.175446 -175.534804) (xy 419.185344 -175.523906) (xy 419.203582 -175.50322)
			(xy 419.244945 -175.466747) (xy 419.291129 -175.436612) (xy 419.341172 -175.413442) (xy 419.39403 -175.39772)
			(xy 419.448601 -175.389775) (xy 419.476174 -175.389286) (xy 419.503426 -175.389779) (xy 419.557375 -175.397533)
			(xy 419.609672 -175.412885) (xy 419.659252 -175.435524) (xy 419.705105 -175.464989) (xy 419.746298 -175.50068)
			(xy 419.781992 -175.541869) (xy 419.81146 -175.58772) (xy 419.834104 -175.637298) (xy 419.84946 -175.689593)
			(xy 419.857218 -175.743542) (xy 419.857682 -175.770794) (xy 419.857167 -175.79865) (xy 419.849043 -175.853766)
			(xy 419.832998 -175.907117) (xy 419.80937 -175.957571) (xy 419.778663 -176.004056) (xy 419.741526 -176.045585)
			(xy 419.69875 -176.081278) (xy 419.651241 -176.110376) (xy 419.600008 -176.132262) (xy 419.573202 -176.139856)
			(xy 419.559077 -176.144105) (xy 419.53393 -176.159501) (xy 419.514215 -176.181425) (xy 419.501566 -176.20806)
			(xy 419.497034 -176.237195) (xy 419.498526 -176.25187) (xy 419.5002 -176.264886) (xy 419.501977 -176.291071)
			(xy 419.502082 -176.304194) (xy 419.501988 -176.318343) (xy 419.499954 -176.346566) (xy 419.498018 -176.360582)
			(xy 419.496394 -176.373927) (xy 419.4995 -176.400623) (xy 419.509476 -176.425579) (xy 419.525629 -176.44706)
			(xy 419.546835 -176.463572) (xy 419.57162 -176.473966) (xy 419.584886 -176.476152) (xy 419.612039 -176.480237)
			(xy 419.664868 -176.495214) (xy 419.715004 -176.517609) (xy 419.761412 -176.546958) (xy 419.803135 -176.582656)
			(xy 419.839311 -176.623965) (xy 419.869192 -176.670033) (xy 419.892162 -176.719908) (xy 419.907746 -176.772561)
			(xy 419.915622 -176.826903) (xy 419.916102 -176.854358) (xy 419.915606 -176.88161) (xy 419.907854 -176.93556)
			(xy 419.892503 -176.987858) (xy 419.869865 -177.037438) (xy 419.840401 -177.083292) (xy 419.804711 -177.124485)
			(xy 419.763521 -177.160179) (xy 419.71767 -177.189648) (xy 419.668092 -177.212291) (xy 419.615795 -177.227647)
			(xy 419.561846 -177.235403) (xy 419.534594 -177.235866) (xy 419.507019 -177.235416) (xy 419.452445 -177.227462)
			(xy 419.399584 -177.211735) (xy 419.349538 -177.188562) (xy 419.303349 -177.158426) (xy 419.261979 -177.121955)
			(xy 419.243764 -177.101246) (xy 419.233866 -177.090348) (xy 419.209216 -177.074273) (xy 419.181008 -177.065889)
			(xy 419.15158 -177.065889) (xy 419.123372 -177.074273) (xy 419.098722 -177.090348) (xy 419.088824 -177.101246)
			(xy 419.070614 -177.121958) (xy 419.029244 -177.158426) (xy 418.983053 -177.188557) (xy 418.933005 -177.211722)
			(xy 418.880143 -177.227439) (xy 418.825569 -177.23538) (xy 418.797994 -177.235866) (xy 418.771493 -177.235405)
			(xy 418.719002 -177.228063) (xy 418.668034 -177.213521) (xy 418.619572 -177.192059) (xy 418.574549 -177.164091)
			(xy 418.5539 -177.147474) (xy 418.541717 -177.138082) (xy 418.51333 -177.126285) (xy 418.482719 -177.123451)
			(xy 418.452648 -177.129838) (xy 418.425831 -177.144868) (xy 418.404689 -177.167186) (xy 418.397436 -177.180748)
			(xy 418.385321 -177.20443) (xy 418.355402 -177.248413) (xy 418.319535 -177.287696) (xy 418.278448 -177.321482)
			(xy 418.255958 -177.335688) (xy 418.243751 -177.343635) (xy 418.224085 -177.365102) (xy 418.211281 -177.391249)
			(xy 418.206381 -177.419947) (xy 418.209783 -177.448861) (xy 418.215064 -177.462434) (xy 418.22456 -177.485641)
			(xy 418.237908 -177.533976) (xy 418.244633 -177.583666) (xy 418.245036 -177.608738) (xy 418.244615 -177.633807)
			(xy 418.237865 -177.683491) (xy 418.224531 -177.731825) (xy 418.215064 -177.755042) (xy 418.209854 -177.768631)
			(xy 418.206485 -177.797525) (xy 418.211389 -177.826198) (xy 418.224168 -177.85233) (xy 418.243789 -177.873805)
			(xy 418.255958 -177.881788) (xy 418.27905 -177.896416) (xy 418.321167 -177.931255) (xy 418.357742 -177.971872)
			(xy 418.387993 -178.017397) (xy 418.411268 -178.066852) (xy 418.427069 -178.119177) (xy 418.435057 -178.173249)
			(xy 418.43506 -178.227908) (xy 418.427078 -178.28198) (xy 418.411283 -178.334307) (xy 418.388014 -178.383765)
			(xy 418.357769 -178.429294) (xy 418.321198 -178.469915) (xy 418.279085 -178.504759) (xy 418.255958 -178.519328)
			(xy 418.243724 -178.527237) (xy 418.224058 -178.548714) (xy 418.211257 -178.574871) (xy 418.206364 -178.603578)
			(xy 418.209777 -178.632499) (xy 418.215064 -178.646074) (xy 418.224541 -178.669289) (xy 418.237896 -178.717619)
			(xy 418.244629 -178.767307) (xy 418.245036 -178.792378) (xy 418.244515 -178.820263) (xy 418.236203 -178.87541)
			(xy 418.219765 -178.928702) (xy 418.195567 -178.978948) (xy 418.164151 -179.025027) (xy 418.126218 -179.065909)
			(xy 418.082616 -179.100681) (xy 418.034318 -179.128566) (xy 417.982403 -179.148941) (xy 417.928032 -179.161351)
			(xy 417.872418 -179.165519) (xy 417.816804 -179.161351) (xy 417.762433 -179.148941) (xy 417.710518 -179.128566)
			(xy 417.66222 -179.100681) (xy 417.618618 -179.065909) (xy 417.580685 -179.025027) (xy 417.549269 -178.978948)
			(xy 417.525071 -178.928702) (xy 417.508633 -178.87541) (xy 417.500321 -178.820263) (xy 417.4998 -178.792378)
			(xy 410.420566 -178.792378) (xy 410.420566 -179.723542) (xy 419.315646 -179.723542) (xy 419.316217 -179.696294)
			(xy 419.323967 -179.642352) (xy 419.339314 -179.590061) (xy 419.361947 -179.540487) (xy 419.391405 -179.494639)
			(xy 419.427087 -179.45345) (xy 419.468269 -179.417757) (xy 419.51411 -179.388289) (xy 419.563679 -179.365645)
			(xy 419.615966 -179.350285) (xy 419.669906 -179.342523) (xy 419.697154 -179.342034) (xy 419.727059 -179.342571)
			(xy 419.786138 -179.351883) (xy 419.814756 -179.360576) (xy 419.82866 -179.36463) (xy 419.857597 -179.36554)
			(xy 419.885621 -179.358274) (xy 419.910469 -179.343418) (xy 419.930134 -179.322171) (xy 419.943028 -179.296251)
			(xy 419.946074 -179.28209) (xy 419.951204 -179.256008) (xy 419.967775 -179.205501) (xy 419.991201 -179.157784)
			(xy 420.021027 -179.113784) (xy 420.056674 -179.074352) (xy 420.097452 -179.040253) (xy 420.142571 -179.012148)
			(xy 420.191156 -178.990581) (xy 420.242265 -178.975971) (xy 420.294908 -178.968601) (xy 420.321486 -178.968146)
			(xy 420.348736 -178.9687) (xy 420.402682 -178.976455) (xy 420.454975 -178.991808) (xy 420.504551 -179.014447)
			(xy 420.550401 -179.043911) (xy 420.59159 -179.0796) (xy 420.627281 -179.120788) (xy 420.656747 -179.166636)
			(xy 420.679387 -179.216211) (xy 420.694742 -179.268504) (xy 420.702499 -179.32245) (xy 420.702499 -179.37695)
			(xy 420.694742 -179.430896) (xy 420.679387 -179.483189) (xy 420.656747 -179.532764) (xy 420.627281 -179.578612)
			(xy 420.59159 -179.6198) (xy 420.550401 -179.655489) (xy 420.504551 -179.684953) (xy 420.454975 -179.707592)
			(xy 420.402682 -179.722945) (xy 420.348736 -179.7307) (xy 420.321486 -179.731162) (xy 420.291581 -179.730639)
			(xy 420.232502 -179.721318) (xy 420.203884 -179.71262) (xy 420.189967 -179.708614) (xy 420.161038 -179.707695)
			(xy 420.133019 -179.714952) (xy 420.108173 -179.729799) (xy 420.088508 -179.751036) (xy 420.075613 -179.776949)
			(xy 420.072566 -179.791106) (xy 420.06599 -179.823947) (xy 420.042863 -179.886798) (xy 420.026592 -179.916074)
			(xy 420.019587 -179.929057) (xy 420.012541 -179.957688) (xy 420.013975 -179.987137) (xy 420.023771 -180.014948)
			(xy 420.04111 -180.038795) (xy 420.064544 -180.05669) (xy 420.078154 -180.062378) (xy 420.104942 -180.073047)
			(xy 420.155182 -180.101341) (xy 420.20059 -180.136876) (xy 420.240131 -180.178842) (xy 420.272903 -180.226283)
			(xy 420.298159 -180.278117) (xy 420.315323 -180.333162) (xy 420.324005 -180.390164) (xy 420.324534 -180.418994)
			(xy 420.324048 -180.446245) (xy 420.316292 -180.500193) (xy 420.300937 -180.552488) (xy 420.278295 -180.602065)
			(xy 420.248829 -180.647915) (xy 420.213138 -180.689106) (xy 420.171947 -180.724797) (xy 420.126097 -180.754263)
			(xy 420.07652 -180.776905) (xy 420.024225 -180.79226) (xy 419.970277 -180.800016) (xy 419.915775 -180.800016)
			(xy 419.861827 -180.79226) (xy 419.809532 -180.776905) (xy 419.759955 -180.754263) (xy 419.714105 -180.724797)
			(xy 419.672914 -180.689106) (xy 419.637223 -180.647915) (xy 419.607757 -180.602065) (xy 419.585115 -180.552488)
			(xy 419.56976 -180.500193) (xy 419.562004 -180.446245) (xy 419.561518 -180.418994) (xy 419.56191 -180.393758)
			(xy 419.568529 -180.343724) (xy 419.581704 -180.295004) (xy 419.601202 -180.248452) (xy 419.613588 -180.226462)
			(xy 419.620627 -180.213499) (xy 419.627653 -180.184862) (xy 419.626205 -180.155412) (xy 419.616403 -180.127603)
			(xy 419.599064 -180.103754) (xy 419.575634 -180.085852) (xy 419.562026 -180.080158) (xy 419.535269 -180.069416)
			(xy 419.485027 -180.041136) (xy 419.439617 -180.005613) (xy 419.400072 -179.963658) (xy 419.367296 -179.916228)
			(xy 419.342035 -179.864402) (xy 419.324865 -179.809365) (xy 419.316178 -179.752369) (xy 419.315646 -179.723542)
			(xy 410.420566 -179.723542) (xy 410.420566 -181.46225) (xy 419.374572 -181.46225) (xy 419.374572 -181.40775)
			(xy 419.382328 -181.353803) (xy 419.397682 -181.30151) (xy 419.420321 -181.251933) (xy 419.449786 -181.206084)
			(xy 419.485475 -181.164893) (xy 419.526663 -181.129201) (xy 419.572511 -181.099734) (xy 419.622085 -181.077091)
			(xy 419.674378 -181.061733) (xy 419.728324 -181.053974) (xy 419.755574 -181.053486) (xy 419.785261 -181.054065)
			(xy 419.843919 -181.06326) (xy 419.900444 -181.081431) (xy 419.953471 -181.108139) (xy 420.001721 -181.142741)
			(xy 420.044027 -181.184399) (xy 420.062152 -181.207918) (xy 420.070578 -181.218525) (xy 420.091891 -181.235232)
			(xy 420.116845 -181.245751) (xy 420.143686 -181.249341) (xy 420.170527 -181.245751) (xy 420.195481 -181.235232)
			(xy 420.216794 -181.218525) (xy 420.22522 -181.207918) (xy 420.243349 -181.184402) (xy 420.285654 -181.142741)
			(xy 420.333902 -181.108136) (xy 420.386928 -181.081424) (xy 420.443453 -181.06325) (xy 420.502111 -181.054051)
			(xy 420.531798 -181.053486) (xy 420.559051 -181.053961) (xy 420.613001 -181.061718) (xy 420.665298 -181.077073)
			(xy 420.714878 -181.099715) (xy 420.76073 -181.129183) (xy 420.801923 -181.164876) (xy 420.837616 -181.206068)
			(xy 420.867084 -181.251921) (xy 420.889726 -181.3015) (xy 420.905082 -181.353797) (xy 420.912839 -181.407747)
			(xy 420.912839 -181.462253) (xy 420.905082 -181.516203) (xy 420.889726 -181.5685) (xy 420.867084 -181.618079)
			(xy 420.837616 -181.663932) (xy 420.801923 -181.705124) (xy 420.76073 -181.740817) (xy 420.714878 -181.770285)
			(xy 420.665298 -181.792927) (xy 420.613001 -181.808282) (xy 420.559051 -181.816039) (xy 420.531798 -181.816502)
			(xy 420.50211 -181.815948) (xy 420.443451 -181.806749) (xy 420.386925 -181.788573) (xy 420.333898 -181.76186)
			(xy 420.285649 -181.727254) (xy 420.243344 -181.685591) (xy 420.22522 -181.66207) (xy 420.216794 -181.651463)
			(xy 420.195481 -181.634756) (xy 420.170527 -181.624237) (xy 420.143686 -181.620647) (xy 420.116845 -181.624237)
			(xy 420.091891 -181.634756) (xy 420.070578 -181.651463) (xy 420.062152 -181.66207) (xy 420.044036 -181.685597)
			(xy 420.001729 -181.727258) (xy 419.953478 -181.761861) (xy 419.900449 -181.788572) (xy 419.843922 -181.806744)
			(xy 419.785262 -181.815939) (xy 419.755574 -181.816502) (xy 419.728324 -181.816026) (xy 419.674378 -181.808267)
			(xy 419.622085 -181.792909) (xy 419.572511 -181.770266) (xy 419.526663 -181.740799) (xy 419.485475 -181.705107)
			(xy 419.449786 -181.663916) (xy 419.420321 -181.618067) (xy 419.397682 -181.56849) (xy 419.382328 -181.516197)
			(xy 419.374572 -181.46225) (xy 410.420566 -181.46225) (xy 410.420566 -182.042816) (xy 410.457142 -182.053484)
			(xy 410.482894 -182.061522) (xy 410.531805 -182.084279) (xy 410.576725 -182.114151) (xy 410.616627 -182.150455)
			(xy 410.650598 -182.192361) (xy 410.663244 -182.213953) (xy 418.557175 -182.213953) (xy 418.564931 -182.160006)
			(xy 418.580286 -182.107711) (xy 418.602926 -182.058133) (xy 418.632392 -182.012282) (xy 418.668083 -181.971091)
			(xy 418.709272 -181.935399) (xy 418.755122 -181.905932) (xy 418.804699 -181.88329) (xy 418.856994 -181.867934)
			(xy 418.910941 -181.860176) (xy 418.965444 -181.860175) (xy 419.019392 -181.867931) (xy 419.071687 -181.883285)
			(xy 419.121265 -181.905925) (xy 419.167116 -181.93539) (xy 419.208307 -181.971081) (xy 419.243999 -182.01227)
			(xy 419.273467 -182.05812) (xy 419.296109 -182.107697) (xy 419.311466 -182.159991) (xy 419.319224 -182.213939)
			(xy 419.31971 -182.24119) (xy 419.319282 -182.266581) (xy 419.312524 -182.316913) (xy 419.306248 -182.34152)
			(xy 419.302808 -182.356167) (xy 419.303729 -182.386225) (xy 419.31336 -182.414715) (xy 419.330866 -182.439167)
			(xy 419.354731 -182.457465) (xy 419.38289 -182.468023) (xy 419.412902 -182.469929) (xy 419.42766 -182.466996)
			(xy 419.449255 -182.462239) (xy 419.49318 -182.45714) (xy 419.51529 -182.456836) (xy 419.542541 -182.457267)
			(xy 419.59649 -182.465022) (xy 419.648785 -182.480376) (xy 419.698364 -182.503015) (xy 419.744216 -182.53248)
			(xy 419.785408 -182.56817) (xy 419.821101 -182.609359) (xy 419.85057 -182.655209) (xy 419.873213 -182.704785)
			(xy 419.888571 -182.75708) (xy 419.896331 -182.811027) (xy 419.896334 -182.86553) (xy 419.88858 -182.919479)
			(xy 419.873228 -182.971775) (xy 419.85059 -183.021354) (xy 419.821127 -183.067207) (xy 419.785438 -183.1084)
			(xy 419.74425 -183.144094) (xy 419.698401 -183.173564) (xy 419.648825 -183.196209) (xy 419.596532 -183.211569)
			(xy 419.542584 -183.21933) (xy 419.488081 -183.219335) (xy 419.434132 -183.211583) (xy 419.381836 -183.196232)
			(xy 419.332256 -183.173596) (xy 419.286403 -183.144134) (xy 419.245208 -183.108446) (xy 419.209512 -183.067259)
			(xy 419.180041 -183.021411) (xy 419.157395 -182.971836) (xy 419.142034 -182.919543) (xy 419.134271 -182.865595)
			(xy 419.133782 -182.838344) (xy 419.134216 -182.812953) (xy 419.14097 -182.762622) (xy 419.147244 -182.738014)
			(xy 419.150657 -182.723361) (xy 419.149744 -182.693304) (xy 419.14012 -182.664815) (xy 419.122618 -182.640362)
			(xy 419.098755 -182.622064) (xy 419.070599 -182.611507) (xy 419.040588 -182.609604) (xy 419.025832 -182.612538)
			(xy 419.004238 -182.617297) (xy 418.960312 -182.622394) (xy 418.938202 -182.622698) (xy 418.910951 -182.622224)
			(xy 418.857003 -182.614468) (xy 418.804708 -182.599113) (xy 418.755131 -182.576473) (xy 418.70928 -182.547007)
			(xy 418.668089 -182.511315) (xy 418.632397 -182.470125) (xy 418.602931 -182.424275) (xy 418.580289 -182.374698)
			(xy 418.564933 -182.322404) (xy 418.557176 -182.268456) (xy 418.557175 -182.213953) (xy 410.663244 -182.213953)
			(xy 410.677861 -182.238911) (xy 410.697794 -182.289039) (xy 410.709939 -182.3416) (xy 410.714019 -182.395391)
			(xy 410.709941 -182.449182) (xy 410.697799 -182.501744) (xy 410.677869 -182.551873) (xy 410.650608 -182.598424)
			(xy 410.616639 -182.640332) (xy 410.576739 -182.676638) (xy 410.531821 -182.706513) (xy 410.482911 -182.729272)
			(xy 410.457142 -182.737252) (xy 410.420566 -182.74792) (xy 410.420566 -183.059957) (xy 416.453709 -183.059957)
			(xy 416.453709 -183.005443) (xy 416.461468 -182.951483) (xy 416.476827 -182.899176) (xy 416.499474 -182.849588)
			(xy 416.528948 -182.803728) (xy 416.56465 -182.76253) (xy 416.605851 -182.726832) (xy 416.651713 -182.697361)
			(xy 416.701302 -182.674717) (xy 416.75361 -182.659362) (xy 416.807571 -182.651607) (xy 416.834828 -182.651146)
			(xy 416.862199 -182.651584) (xy 416.91638 -182.659407) (xy 416.968884 -182.674902) (xy 417.01863 -182.69775)
			(xy 417.064596 -182.727481) (xy 417.085526 -182.745126) (xy 417.096854 -182.754362) (xy 417.123411 -182.766538)
			(xy 417.152328 -182.770711) (xy 417.181245 -182.766538) (xy 417.207802 -182.754362) (xy 417.21913 -182.745126)
			(xy 417.240081 -182.72751) (xy 417.286048 -182.697794) (xy 417.335791 -182.674953) (xy 417.388287 -182.659457)
			(xy 417.44246 -182.651623) (xy 417.469828 -182.651146) (xy 417.497075 -182.651726) (xy 417.551013 -182.659485)
			(xy 417.603298 -182.674841) (xy 417.652865 -182.697481) (xy 417.698707 -182.726944) (xy 417.739889 -182.762631)
			(xy 417.775573 -182.803816) (xy 417.805033 -182.849659) (xy 417.827669 -182.899228) (xy 417.843021 -182.951515)
			(xy 417.850776 -183.005453) (xy 417.850776 -183.059947) (xy 417.843021 -183.113885) (xy 417.827669 -183.166172)
			(xy 417.805033 -183.215741) (xy 417.775573 -183.261584) (xy 417.739889 -183.302769) (xy 417.698707 -183.338456)
			(xy 417.652865 -183.367919) (xy 417.603298 -183.390559) (xy 417.551013 -183.405915) (xy 417.497075 -183.413674)
			(xy 417.469828 -183.414162) (xy 417.442458 -183.413689) (xy 417.388279 -183.405874) (xy 417.335775 -183.390387)
			(xy 417.286028 -183.367547) (xy 417.240062 -183.337823) (xy 417.21913 -183.320182) (xy 417.207802 -183.310946)
			(xy 417.181245 -183.29877) (xy 417.152328 -183.294597) (xy 417.123411 -183.29877) (xy 417.096854 -183.310946)
			(xy 417.085526 -183.320182) (xy 417.064593 -183.33782) (xy 417.01862 -183.367532) (xy 416.968873 -183.390369)
			(xy 416.916373 -183.40586) (xy 416.862197 -183.413688) (xy 416.834828 -183.414162) (xy 416.807571 -183.413793)
			(xy 416.75361 -183.406038) (xy 416.701302 -183.390683) (xy 416.651713 -183.368039) (xy 416.605851 -183.338568)
			(xy 416.56465 -183.30287) (xy 416.528948 -183.261672) (xy 416.499474 -183.215812) (xy 416.476827 -183.166224)
			(xy 416.461468 -183.113917) (xy 416.453709 -183.059957) (xy 410.420566 -183.059957) (xy 410.420566 -183.649366)
			(xy 411.00121 -184.23001) (xy 413.5501 -184.23001)
		)
		(stroke
			(width 0)
			(type solid)
		)
		(fill yes)
		(layer "In15.Cu")
		(net "GND")
	)
	(gr_poly
		(pts
			(xy 54.049676 -177.128932) (xy 54.052978 -177.12309) (xy 54.070432 -177.093474) (xy 54.112099 -177.038797)
			(xy 54.136036 -177.014124) (xy 55.010812 -176.139094) (xy 55.010812 -172.473874) (xy 54.589934 -172.052996)
			(xy 53.269388 -172.052996) (xy 53.2361 -172.05246) (xy 53.170098 -172.04374) (xy 53.105799 -172.026475)
			(xy 53.044306 -172.000962) (xy 52.98667 -171.967638) (xy 52.933879 -171.927073) (xy 52.909978 -171.903898)
			(xy 52.390548 -171.384722) (xy 52.334668 -171.440856) (xy 52.334668 -171.856146) (xy 52.334249 -171.881858)
			(xy 52.327341 -171.932816) (xy 52.313642 -171.982382) (xy 52.293402 -172.029656) (xy 52.266988 -172.073778)
			(xy 52.234881 -172.113947) (xy 52.216558 -172.13199) (xy 52.2079 -172.144462) (xy 52.188561 -172.167868)
			(xy 52.17795 -172.178726) (xy 50.893218 -173.463458) (xy 50.875235 -173.480817) (xy 50.834825 -173.510229)
			(xy 50.790307 -173.532948) (xy 50.742781 -173.548415) (xy 50.693418 -173.556247) (xy 50.668428 -173.556676)
			(xy 50.635154 -173.556676) (xy 50.62982 -173.557946) (xy 50.613076 -173.561385) (xy 50.579093 -173.565077)
			(xy 50.562002 -173.565312) (xy 48.01108 -173.565312) (xy 47.989716 -173.600926) (xy 47.939135 -173.666797)
			(xy 47.910242 -173.69663) (xy 47.066121 -174.540751) (xy 48.944772 -174.540751) (xy 48.944772 -174.486249)
			(xy 48.952528 -174.432302) (xy 48.967883 -174.380008) (xy 48.990523 -174.330431) (xy 49.019988 -174.28458)
			(xy 49.055678 -174.24339) (xy 49.096867 -174.207698) (xy 49.142717 -174.178231) (xy 49.192293 -174.155588)
			(xy 49.244586 -174.140231) (xy 49.298533 -174.132473) (xy 49.325784 -174.131986) (xy 49.350659 -174.132354)
			(xy 49.399986 -174.138825) (xy 49.448052 -174.151659) (xy 49.494039 -174.170637) (xy 49.537167 -174.195438)
			(xy 49.557178 -174.210218) (xy 49.569675 -174.219055) (xy 49.598406 -174.229566) (xy 49.62896 -174.231114)
			(xy 49.658606 -174.223559) (xy 49.684693 -174.207578) (xy 49.704889 -174.184599) (xy 49.71161 -174.170848)
			(xy 49.723254 -174.14601) (xy 49.752631 -174.099682) (xy 49.788337 -174.058036) (xy 49.829637 -174.021931)
			(xy 49.875681 -173.99211) (xy 49.925519 -173.969188) (xy 49.978125 -173.953636) (xy 50.032416 -173.945775)
			(xy 50.059844 -173.945296) (xy 50.087093 -173.945777) (xy 50.141037 -173.953538) (xy 50.193327 -173.968898)
			(xy 50.242899 -173.991541) (xy 50.288745 -174.021009) (xy 50.32993 -174.056701) (xy 50.365617 -174.097891)
			(xy 50.39508 -174.143739) (xy 50.417718 -174.193314) (xy 50.433071 -174.245606) (xy 50.440826 -174.29955)
			(xy 50.440826 -174.35405) (xy 50.433071 -174.407994) (xy 50.417718 -174.460286) (xy 50.39508 -174.509861)
			(xy 50.365617 -174.555709) (xy 50.32993 -174.596899) (xy 50.288745 -174.632591) (xy 50.242899 -174.662059)
			(xy 50.193327 -174.684702) (xy 50.141037 -174.700062) (xy 50.087093 -174.707823) (xy 50.059844 -174.708312)
			(xy 50.03497 -174.707929) (xy 49.985643 -174.701462) (xy 49.937577 -174.688631) (xy 49.89159 -174.669656)
			(xy 49.848462 -174.644859) (xy 49.82845 -174.63008) (xy 49.815931 -174.621277) (xy 49.787208 -174.610762)
			(xy 49.75666 -174.60921) (xy 49.72702 -174.616758) (xy 49.700935 -174.632732) (xy 49.68074 -174.655703)
			(xy 49.674018 -174.66945) (xy 49.662351 -174.694277) (xy 49.632977 -174.740604) (xy 49.597274 -174.78225)
			(xy 49.555977 -174.818355) (xy 49.509937 -174.848178) (xy 49.460103 -174.871102) (xy 49.407499 -174.886657)
			(xy 49.353211 -174.894521) (xy 49.325784 -174.895002) (xy 49.298533 -174.894527) (xy 49.244586 -174.886769)
			(xy 49.192293 -174.871412) (xy 49.142717 -174.848769) (xy 49.096867 -174.819302) (xy 49.055678 -174.78361)
			(xy 49.019988 -174.74242) (xy 48.990523 -174.696569) (xy 48.967883 -174.646992) (xy 48.952528 -174.594698)
			(xy 48.944772 -174.540751) (xy 47.066121 -174.540751) (xy 46.345348 -175.261524) (xy 51.230528 -175.261524)
			(xy 51.234599 -175.205902) (xy 51.246725 -175.151465) (xy 51.266648 -175.099374) (xy 51.293944 -175.050739)
			(xy 51.32803 -175.006596) (xy 51.368179 -174.967887) (xy 51.413537 -174.935436) (xy 51.463137 -174.909935)
			(xy 51.515921 -174.891928) (xy 51.570764 -174.881798) (xy 51.626498 -174.879761) (xy 51.681935 -174.885861)
			(xy 51.735892 -174.899967) (xy 51.787221 -174.921779) (xy 51.834827 -174.950833) (xy 51.877695 -174.986508)
			(xy 51.914912 -175.028045) (xy 51.945685 -175.074558) (xy 51.969357 -175.125055) (xy 51.985425 -175.178462)
			(xy 51.993545 -175.233638) (xy 51.994054 -175.261524) (xy 51.993957 -175.266858) (xy 52.228748 -175.266858)
			(xy 52.232819 -175.211236) (xy 52.244945 -175.156799) (xy 52.264868 -175.104708) (xy 52.292164 -175.056073)
			(xy 52.32625 -175.01193) (xy 52.366399 -174.973221) (xy 52.411757 -174.94077) (xy 52.461357 -174.915269)
			(xy 52.514141 -174.897262) (xy 52.568984 -174.887132) (xy 52.624718 -174.885095) (xy 52.680155 -174.891195)
			(xy 52.734112 -174.905301) (xy 52.785441 -174.927113) (xy 52.833047 -174.956167) (xy 52.875915 -174.991842)
			(xy 52.913132 -175.033379) (xy 52.943905 -175.079892) (xy 52.967577 -175.130389) (xy 52.983645 -175.183796)
			(xy 52.991765 -175.238972) (xy 52.992274 -175.266858) (xy 52.991765 -175.294744) (xy 52.983645 -175.34992)
			(xy 52.967577 -175.403327) (xy 52.943905 -175.453824) (xy 52.913132 -175.500337) (xy 52.875915 -175.541874)
			(xy 52.833047 -175.577549) (xy 52.785441 -175.606603) (xy 52.734112 -175.628415) (xy 52.680155 -175.642521)
			(xy 52.624718 -175.648621) (xy 52.568984 -175.646584) (xy 52.514141 -175.636454) (xy 52.461357 -175.618447)
			(xy 52.411757 -175.592946) (xy 52.366399 -175.560495) (xy 52.32625 -175.521786) (xy 52.292164 -175.477643)
			(xy 52.264868 -175.429008) (xy 52.244945 -175.376917) (xy 52.232819 -175.32248) (xy 52.228748 -175.266858)
			(xy 51.993957 -175.266858) (xy 51.993545 -175.28941) (xy 51.985425 -175.344586) (xy 51.969357 -175.397993)
			(xy 51.945685 -175.44849) (xy 51.914912 -175.495003) (xy 51.877695 -175.53654) (xy 51.834827 -175.572215)
			(xy 51.787221 -175.601269) (xy 51.735892 -175.623081) (xy 51.681935 -175.637187) (xy 51.626498 -175.643287)
			(xy 51.570764 -175.64125) (xy 51.515921 -175.63112) (xy 51.463137 -175.613113) (xy 51.413537 -175.587612)
			(xy 51.368179 -175.555161) (xy 51.32803 -175.516452) (xy 51.293944 -175.472309) (xy 51.266648 -175.423674)
			(xy 51.246725 -175.371583) (xy 51.234599 -175.317146) (xy 51.230528 -175.261524) (xy 46.345348 -175.261524)
			(xy 45.948346 -175.658526) (xy 45.922796 -175.683407) (xy 45.867043 -175.727886) (xy 45.806659 -175.765839)
			(xy 45.742404 -175.79679) (xy 45.675086 -175.820348) (xy 45.605553 -175.836216) (xy 45.53468 -175.844197)
			(xy 45.49902 -175.844708) (xy 40.907208 -175.844708) (xy 40.871547 -175.844227) (xy 40.800673 -175.83624)
			(xy 40.731139 -175.820365) (xy 40.66382 -175.796803) (xy 40.599565 -175.76585) (xy 40.539179 -175.727895)
			(xy 40.483425 -175.683416) (xy 40.457882 -175.658526) (xy 35.29076 -170.491404) (xy 35.265896 -170.465846)
			(xy 35.221454 -170.410083) (xy 35.183536 -170.349693) (xy 35.152621 -170.285436) (xy 35.129097 -170.218121)
			(xy 35.11326 -170.148594) (xy 35.105309 -170.077732) (xy 35.104832 -170.042078) (xy 35.104832 -157.6959)
			(xy 35.105302 -157.660248) (xy 35.113264 -157.589389) (xy 35.129111 -157.519867) (xy 35.152642 -157.452557)
			(xy 35.183563 -157.388306) (xy 35.221483 -157.32792) (xy 35.265927 -157.272161) (xy 35.29076 -157.246574)
			(xy 36.009072 -156.528516) (xy 36.009072 -140.659866) (xy 36.009538 -140.624212) (xy 36.017493 -140.553349)
			(xy 36.033332 -140.483822) (xy 36.056857 -140.416506) (xy 36.087771 -140.352247) (xy 36.125686 -140.291854)
			(xy 36.170124 -140.236086) (xy 36.195 -140.21054) (xy 43.18508 -133.220714) (xy 43.18508 -129.257806)
			(xy 43.18555 -129.222153) (xy 43.193511 -129.151293) (xy 43.209356 -129.081771) (xy 43.232885 -129.014459)
			(xy 43.263803 -128.950205) (xy 43.301722 -128.889818) (xy 43.346163 -128.834055) (xy 43.371008 -128.80848)
			(xy 44.438824 -127.740918) (xy 44.449065 -127.729937) (xy 44.463225 -127.703476) (xy 44.46909 -127.674043)
			(xy 44.466155 -127.644175) (xy 44.454671 -127.616448) (xy 44.435629 -127.593251) (xy 44.410671 -127.576584)
			(xy 44.381948 -127.567884) (xy 44.366942 -127.567436) (xy 42.052494 -127.567436) (xy 42.046398 -127.56896)
			(xy 42.023837 -127.574192) (xy 41.977862 -127.579795) (xy 41.954704 -127.580136) (xy 41.927449 -127.579673)
			(xy 41.873494 -127.571916) (xy 41.821191 -127.556559) (xy 41.771607 -127.533915) (xy 41.72575 -127.504445)
			(xy 41.684554 -127.468749) (xy 41.648857 -127.427553) (xy 41.619386 -127.381697) (xy 41.596742 -127.332112)
			(xy 41.581385 -127.27981) (xy 41.573627 -127.225855) (xy 41.573627 -127.171345) (xy 41.581385 -127.11739)
			(xy 41.596742 -127.065088) (xy 41.619386 -127.015503) (xy 41.648857 -126.969647) (xy 41.684554 -126.928451)
			(xy 41.72575 -126.892755) (xy 41.771607 -126.863285) (xy 41.821191 -126.840641) (xy 41.873494 -126.825284)
			(xy 41.927449 -126.817527) (xy 41.954704 -126.81712) (xy 41.977862 -126.81746) (xy 42.023836 -126.823065)
			(xy 42.046398 -126.828296) (xy 42.052494 -126.82982) (xy 44.158662 -126.82982) (xy 44.173639 -126.829295)
			(xy 44.202306 -126.820612) (xy 44.22722 -126.803984) (xy 44.246236 -126.780841) (xy 44.257717 -126.753176)
			(xy 44.260674 -126.723369) (xy 44.254854 -126.693986) (xy 44.240758 -126.667558) (xy 44.230544 -126.656592)
			(xy 43.021504 -125.447552) (xy 42.086784 -126.382272) (xy 42.065935 -126.402399) (xy 42.019086 -126.436504)
			(xy 41.967477 -126.462858) (xy 41.912381 -126.480811) (xy 41.855154 -126.489922) (xy 41.82618 -126.490476)
			(xy 40.914574 -126.490476) (xy 39.606728 -127.798322) (xy 40.5798 -127.798322) (xy 40.583871 -127.7427)
			(xy 40.595997 -127.688263) (xy 40.61592 -127.636172) (xy 40.643216 -127.587537) (xy 40.677302 -127.543394)
			(xy 40.717451 -127.504685) (xy 40.762809 -127.472234) (xy 40.812409 -127.446733) (xy 40.865193 -127.428726)
			(xy 40.920036 -127.418596) (xy 40.97577 -127.416559) (xy 41.031207 -127.422659) (xy 41.085164 -127.436765)
			(xy 41.136493 -127.458577) (xy 41.184099 -127.487631) (xy 41.226967 -127.523306) (xy 41.264184 -127.564843)
			(xy 41.294957 -127.611356) (xy 41.318629 -127.661853) (xy 41.334697 -127.71526) (xy 41.342817 -127.770436)
			(xy 41.343326 -127.798322) (xy 41.342817 -127.826208) (xy 41.334697 -127.881384) (xy 41.318629 -127.934791)
			(xy 41.294957 -127.985288) (xy 41.264184 -128.031801) (xy 41.226967 -128.073338) (xy 41.184099 -128.109013)
			(xy 41.136493 -128.138067) (xy 41.085164 -128.159879) (xy 41.031207 -128.173985) (xy 40.97577 -128.180085)
			(xy 40.920036 -128.178048) (xy 40.865193 -128.167918) (xy 40.812409 -128.149911) (xy 40.762809 -128.12441)
			(xy 40.717451 -128.091959) (xy 40.677302 -128.05325) (xy 40.643216 -128.009107) (xy 40.61592 -127.960472)
			(xy 40.595997 -127.908381) (xy 40.583871 -127.853944) (xy 40.5798 -127.798322) (xy 39.606728 -127.798322)
			(xy 39.088568 -128.316482) (xy 39.088568 -129.314194) (xy 39.095934 -129.32156) (xy 39.119196 -129.345118)
			(xy 39.157783 -129.398908) (xy 39.172642 -129.428494) (xy 39.172896 -129.429002) (xy 39.17696 -129.436876)
			(xy 39.181786 -129.449068) (xy 39.22492 -129.553208) (xy 40.257982 -129.553208) (xy 40.262053 -129.497586)
			(xy 40.274179 -129.443149) (xy 40.294102 -129.391058) (xy 40.321398 -129.342423) (xy 40.355484 -129.29828)
			(xy 40.395633 -129.259571) (xy 40.440991 -129.22712) (xy 40.490591 -129.201619) (xy 40.543375 -129.183612)
			(xy 40.598218 -129.173482) (xy 40.653952 -129.171445) (xy 40.709389 -129.177545) (xy 40.763346 -129.191651)
			(xy 40.814675 -129.213463) (xy 40.862281 -129.242517) (xy 40.905149 -129.278192) (xy 40.942366 -129.319729)
			(xy 40.973139 -129.366242) (xy 40.996811 -129.416739) (xy 41.012879 -129.470146) (xy 41.020999 -129.525322)
			(xy 41.021508 -129.553208) (xy 41.020999 -129.581094) (xy 41.012879 -129.63627) (xy 40.996811 -129.689677)
			(xy 40.973139 -129.740174) (xy 40.942366 -129.786687) (xy 40.905149 -129.828224) (xy 40.862281 -129.863899)
			(xy 40.814675 -129.892953) (xy 40.763346 -129.914765) (xy 40.709389 -129.928871) (xy 40.653952 -129.934971)
			(xy 40.598218 -129.932934) (xy 40.543375 -129.922804) (xy 40.490591 -129.904797) (xy 40.440991 -129.879296)
			(xy 40.395633 -129.846845) (xy 40.355484 -129.808136) (xy 40.321398 -129.763993) (xy 40.294102 -129.715358)
			(xy 40.274179 -129.663267) (xy 40.262053 -129.60883) (xy 40.257982 -129.553208) (xy 39.22492 -129.553208)
			(xy 39.291514 -129.71399) (xy 39.389812 -129.951988) (xy 39.398653 -129.974427) (xy 39.411095 -130.021023)
			(xy 39.417359 -130.068843) (xy 39.417752 -130.092958) (xy 39.417752 -130.680968) (xy 39.419276 -130.690366)
			(xy 39.420038 -130.692906) (xy 39.425011 -130.714859) (xy 39.430363 -130.759553) (xy 39.430706 -130.78206)
			(xy 39.430706 -130.782822) (xy 39.43022 -130.810073) (xy 39.422464 -130.864021) (xy 39.407109 -130.916316)
			(xy 39.384467 -130.965893) (xy 39.355001 -131.011743) (xy 39.31931 -131.052934) (xy 39.278119 -131.088625)
			(xy 39.232269 -131.118091) (xy 39.182692 -131.140733) (xy 39.130397 -131.156088) (xy 39.076449 -131.163844)
			(xy 39.021947 -131.163844) (xy 38.967999 -131.156088) (xy 38.915704 -131.140733) (xy 38.866127 -131.118091)
			(xy 38.820277 -131.088625) (xy 38.779086 -131.052934) (xy 38.743395 -131.011743) (xy 38.713929 -130.965893)
			(xy 38.691287 -130.916316) (xy 38.675932 -130.864021) (xy 38.668176 -130.810073) (xy 38.66769 -130.782822)
			(xy 38.668073 -130.759531) (xy 38.673809 -130.713301) (xy 38.67912 -130.69062) (xy 38.680644 -130.684524)
			(xy 38.680644 -130.441192) (xy 38.678804 -130.426357) (xy 38.667684 -130.398625) (xy 38.649034 -130.375282)
			(xy 38.62444 -130.358315) (xy 38.595996 -130.349168) (xy 38.566122 -130.34862) (xy 38.537361 -130.356717)
			(xy 38.524434 -130.36423) (xy 38.50386 -130.377692) (xy 38.48423 -130.389494) (xy 38.442717 -130.408854)
			(xy 38.421056 -130.4163) (xy 38.410536 -130.419633) (xy 38.389187 -130.425225) (xy 38.378384 -130.427476)
			(xy 38.365169 -130.430581) (xy 38.340923 -130.442768) (xy 38.320743 -130.460912) (xy 38.306055 -130.48373)
			(xy 38.297896 -130.509611) (xy 38.296842 -130.536728) (xy 38.302968 -130.563164) (xy 38.309042 -130.575304)
			(xy 38.311836 -130.580638) (xy 38.326206 -130.608641) (xy 38.346582 -130.668188) (xy 38.356906 -130.730272)
			(xy 38.357556 -130.76174) (xy 38.357556 -130.769106) (xy 38.356577 -130.796013) (xy 38.347986 -130.849164)
			(xy 38.332006 -130.900579) (xy 38.308954 -130.949236) (xy 38.279289 -130.994167) (xy 38.2436 -131.034481)
			(xy 38.202597 -131.069375) (xy 38.157094 -131.098155) (xy 38.107995 -131.120252) (xy 38.056278 -131.135223)
			(xy 38.002969 -131.142774) (xy 37.976048 -131.143248) (xy 37.948792 -131.142788) (xy 37.894834 -131.135037)
			(xy 37.842528 -131.119686) (xy 37.792939 -131.097047) (xy 37.747077 -131.06758) (xy 37.705875 -131.031887)
			(xy 37.670172 -130.990694) (xy 37.640696 -130.944839) (xy 37.618045 -130.895255) (xy 37.602681 -130.842953)
			(xy 37.594918 -130.788996) (xy 37.59454 -130.76174) (xy 37.594987 -130.735406) (xy 37.602237 -130.683238)
			(xy 37.616592 -130.632563) (xy 37.637778 -130.584343) (xy 37.665394 -130.539494) (xy 37.698914 -130.498869)
			(xy 37.737702 -130.463238) (xy 37.781021 -130.43328) (xy 37.828048 -130.409563) (xy 37.877889 -130.392537)
			(xy 37.903658 -130.38709) (xy 37.916705 -130.383698) (xy 37.940501 -130.371048) (xy 37.960148 -130.352602)
			(xy 37.974272 -130.32965) (xy 37.981884 -130.303798) (xy 37.982451 -130.276854) (xy 37.975934 -130.250705)
			(xy 37.969698 -130.238754) (xy 37.967412 -130.23469) (xy 37.967158 -130.234182) (xy 37.966396 -130.232404)
			(xy 37.965888 -130.231388) (xy 37.951976 -130.203793) (xy 37.932286 -130.145217) (xy 37.922307 -130.084232)
			(xy 37.921692 -130.053334) (xy 37.921692 -130.045968) (xy 37.922743 -130.017831) (xy 37.932098 -129.962308)
			(xy 37.949508 -129.908763) (xy 37.974596 -129.858356) (xy 38.006817 -129.812182) (xy 38.045472 -129.771242)
			(xy 38.089722 -129.736425) (xy 38.138607 -129.708487) (xy 38.191065 -129.688034) (xy 38.24596 -129.67551)
			(xy 38.27399 -129.672842) (xy 38.288137 -129.670579) (xy 38.314444 -129.659262) (xy 38.336565 -129.641074)
			(xy 38.352755 -129.617451) (xy 38.361736 -129.590258) (xy 38.3628 -129.56164) (xy 38.359842 -129.54762)
			(xy 38.359842 -129.547366) (xy 38.358826 -129.542286) (xy 38.355179 -129.523703) (xy 38.351239 -129.486037)
			(xy 38.350952 -129.467102) (xy 38.350952 -129.1209) (xy 38.350514 -129.10693) (xy 38.342938 -129.080037)
			(xy 38.328354 -129.056205) (xy 38.307854 -129.037221) (xy 38.282975 -129.024506) (xy 38.255581 -129.019013)
			(xy 38.227723 -129.021154) (xy 38.20149 -129.030768) (xy 38.189916 -129.038604) (xy 38.165328 -129.055702)
			(xy 38.111946 -129.082841) (xy 38.054981 -129.101312) (xy 37.99583 -129.110661) (xy 37.965888 -129.111248)
			(xy 37.938634 -129.110761) (xy 37.884682 -129.103003) (xy 37.832384 -129.087645) (xy 37.782803 -129.065001)
			(xy 37.736949 -129.035531) (xy 37.695756 -128.999836) (xy 37.660062 -128.958641) (xy 37.630594 -128.912787)
			(xy 37.607951 -128.863205) (xy 37.592595 -128.810906) (xy 37.584838 -128.756954) (xy 37.584838 -128.702446)
			(xy 37.592595 -128.648494) (xy 37.607951 -128.596195) (xy 37.630594 -128.546613) (xy 37.660062 -128.500759)
			(xy 37.695756 -128.459564) (xy 37.736949 -128.423869) (xy 37.782803 -128.394399) (xy 37.832384 -128.371755)
			(xy 37.884682 -128.356397) (xy 37.938634 -128.348639) (xy 37.965888 -128.348232) (xy 37.995831 -128.348815)
			(xy 38.054982 -128.358164) (xy 38.111949 -128.376634) (xy 38.165332 -128.403772) (xy 38.189916 -128.420876)
			(xy 38.201498 -128.4287) (xy 38.227734 -128.438306) (xy 38.255591 -128.440442) (xy 38.282986 -128.43495)
			(xy 38.307866 -128.422239) (xy 38.328372 -128.403262) (xy 38.342967 -128.379437) (xy 38.350559 -128.352549)
			(xy 38.350952 -128.33858) (xy 38.350952 -128.163828) (xy 38.351513 -128.134855) (xy 38.360623 -128.077629)
			(xy 38.378576 -128.022533) (xy 38.404931 -127.970926) (xy 38.439036 -127.924079) (xy 38.459156 -127.903224)
			(xy 40.501316 -125.861064) (xy 40.522164 -125.840935) (xy 40.569012 -125.806827) (xy 40.620621 -125.780471)
			(xy 40.675718 -125.762515) (xy 40.732946 -125.753403) (xy 40.76192 -125.75286) (xy 41.673526 -125.75286)
			(xy 41.689528 -125.736858) (xy 42.500296 -124.926344) (xy 41.204134 -123.630436) (xy 38.468046 -123.630436)
			(xy 38.453154 -123.63099) (xy 38.424653 -123.639647) (xy 38.399856 -123.656152) (xy 38.38087 -123.679103)
			(xy 38.369305 -123.706554) (xy 38.366143 -123.736172) (xy 38.371652 -123.765445) (xy 38.385366 -123.791888)
			(xy 38.395402 -123.802902) (xy 38.413231 -123.820912) (xy 38.444458 -123.860824) (xy 38.470126 -123.904519)
			(xy 38.489784 -123.951228) (xy 38.503084 -124.000129) (xy 38.509794 -124.05036) (xy 38.51021 -124.075698)
			(xy 38.509724 -124.102949) (xy 38.501968 -124.156897) (xy 38.486613 -124.209192) (xy 38.463971 -124.258769)
			(xy 38.434505 -124.304619) (xy 38.398814 -124.34581) (xy 38.357623 -124.381501) (xy 38.311773 -124.410967)
			(xy 38.262196 -124.433609) (xy 38.209901 -124.448964) (xy 38.155953 -124.45672) (xy 38.101451 -124.45672)
			(xy 38.047503 -124.448964) (xy 37.995208 -124.433609) (xy 37.945631 -124.410967) (xy 37.899781 -124.381501)
			(xy 37.85859 -124.34581) (xy 37.822899 -124.304619) (xy 37.793433 -124.258769) (xy 37.770791 -124.209192)
			(xy 37.755436 -124.156897) (xy 37.74768 -124.102949) (xy 37.747194 -124.075698) (xy 37.747609 -124.050359)
			(xy 37.754318 -124.000129) (xy 37.767619 -123.951228) (xy 37.787277 -123.904519) (xy 37.812945 -123.860824)
			(xy 37.844173 -123.820911) (xy 37.862002 -123.802902) (xy 37.872028 -123.791865) (xy 37.885777 -123.765422)
			(xy 37.891313 -123.736136) (xy 37.888164 -123.706499) (xy 37.876598 -123.679031) (xy 37.857599 -123.656067)
			(xy 37.832783 -123.639562) (xy 37.804259 -123.630919) (xy 37.789358 -123.630436) (xy 36.158932 -123.630436)
			(xy 35.002724 -124.786898) (xy 34.984738 -124.80425) (xy 34.944324 -124.833645) (xy 34.899805 -124.856349)
			(xy 34.85228 -124.871799) (xy 34.802921 -124.879616) (xy 34.777934 -124.880116) (xy 34.003996 -124.880116)
			(xy 33.979012 -124.879605) (xy 33.929664 -124.871755) (xy 33.882147 -124.856295) (xy 33.837627 -124.833605)
			(xy 33.797196 -124.804241) (xy 33.779206 -124.786898) (xy 33.273746 -124.281184) (xy 33.259776 -124.277628)
			(xy 33.232372 -124.270529) (xy 33.179879 -124.249339) (xy 33.131098 -124.220617) (xy 33.087102 -124.184995)
			(xy 33.048859 -124.143258) (xy 33.01721 -124.096323) (xy 32.992852 -124.045224) (xy 32.97632 -123.991083)
			(xy 32.967978 -123.935093) (xy 32.967422 -123.906788) (xy 32.967886 -123.879536) (xy 32.975645 -123.825588)
			(xy 32.991002 -123.773294) (xy 33.013646 -123.723717) (xy 33.043114 -123.677868) (xy 33.078809 -123.636679)
			(xy 33.120001 -123.600989) (xy 33.165854 -123.571526) (xy 33.215433 -123.548887) (xy 33.26773 -123.533536)
			(xy 33.321678 -123.525783) (xy 33.34893 -123.52528) (xy 33.377235 -123.525797) (xy 33.433223 -123.534167)
			(xy 33.487359 -123.550717) (xy 33.538456 -123.575085) (xy 33.585391 -123.606736) (xy 33.627134 -123.644975)
			(xy 33.662768 -123.688963) (xy 33.691511 -123.737733) (xy 33.712732 -123.790215) (xy 33.71977 -123.817634)
			(xy 33.723326 -123.831604) (xy 33.752028 -123.860306) (xy 33.763514 -123.869894) (xy 33.790611 -123.882547)
			(xy 33.820211 -123.886807) (xy 33.849777 -123.882309) (xy 33.876771 -123.869438) (xy 33.898878 -123.849298)
			(xy 33.914201 -123.823616) (xy 33.918398 -123.809252) (xy 33.91916 -123.80595) (xy 33.92043 -123.800108)
			(xy 33.927002 -123.774723) (xy 33.94616 -123.72591) (xy 33.971817 -123.680178) (xy 34.003488 -123.638386)
			(xy 34.04058 -123.60132) (xy 34.082393 -123.569676) (xy 34.128143 -123.54405) (xy 34.176968 -123.524924)
			(xy 34.20237 -123.518422) (xy 34.21634 -123.514866) (xy 35.075368 -122.655838) (xy 35.093353 -122.638484)
			(xy 35.133765 -122.609084) (xy 35.178284 -122.586377) (xy 35.22581 -122.570923) (xy 35.27517 -122.563104)
			(xy 35.300158 -122.56262) (xy 39.891462 -122.56262) (xy 39.906439 -122.562095) (xy 39.935106 -122.553412)
			(xy 39.96002 -122.536784) (xy 39.979036 -122.513641) (xy 39.990517 -122.485976) (xy 39.993474 -122.456169)
			(xy 39.987654 -122.426786) (xy 39.973558 -122.400358) (xy 39.963344 -122.389392) (xy 38.03777 -120.463818)
			(xy 28.489148 -120.463818) (xy 26.972514 -121.980452) (xy 33.357564 -121.980452) (xy 33.361635 -121.92483)
			(xy 33.373761 -121.870393) (xy 33.393684 -121.818302) (xy 33.42098 -121.769667) (xy 33.455066 -121.725524)
			(xy 33.495215 -121.686815) (xy 33.540573 -121.654364) (xy 33.590173 -121.628863) (xy 33.642957 -121.610856)
			(xy 33.6978 -121.600726) (xy 33.753534 -121.598689) (xy 33.808971 -121.604789) (xy 33.862928 -121.618895)
			(xy 33.914257 -121.640707) (xy 33.961863 -121.669761) (xy 34.004731 -121.705436) (xy 34.041948 -121.746973)
			(xy 34.072721 -121.793486) (xy 34.096393 -121.843983) (xy 34.112461 -121.89739) (xy 34.120581 -121.952566)
			(xy 34.12109 -121.980452) (xy 34.68065 -121.980452) (xy 34.684721 -121.92483) (xy 34.696847 -121.870393)
			(xy 34.71677 -121.818302) (xy 34.744066 -121.769667) (xy 34.778152 -121.725524) (xy 34.818301 -121.686815)
			(xy 34.863659 -121.654364) (xy 34.913259 -121.628863) (xy 34.966043 -121.610856) (xy 35.020886 -121.600726)
			(xy 35.07662 -121.598689) (xy 35.132057 -121.604789) (xy 35.186014 -121.618895) (xy 35.237343 -121.640707)
			(xy 35.284949 -121.669761) (xy 35.327817 -121.705436) (xy 35.365034 -121.746973) (xy 35.395807 -121.793486)
			(xy 35.419479 -121.843983) (xy 35.435547 -121.89739) (xy 35.443667 -121.952566) (xy 35.444176 -121.980452)
			(xy 35.443667 -122.008338) (xy 35.435547 -122.063514) (xy 35.419479 -122.116921) (xy 35.395807 -122.167418)
			(xy 35.365034 -122.213931) (xy 35.327817 -122.255468) (xy 35.284949 -122.291143) (xy 35.237343 -122.320197)
			(xy 35.186014 -122.342009) (xy 35.132057 -122.356115) (xy 35.07662 -122.362215) (xy 35.020886 -122.360178)
			(xy 34.966043 -122.350048) (xy 34.913259 -122.332041) (xy 34.863659 -122.30654) (xy 34.818301 -122.274089)
			(xy 34.778152 -122.23538) (xy 34.744066 -122.191237) (xy 34.71677 -122.142602) (xy 34.696847 -122.090511)
			(xy 34.684721 -122.036074) (xy 34.68065 -121.980452) (xy 34.12109 -121.980452) (xy 34.120581 -122.008338)
			(xy 34.112461 -122.063514) (xy 34.096393 -122.116921) (xy 34.072721 -122.167418) (xy 34.041948 -122.213931)
			(xy 34.004731 -122.255468) (xy 33.961863 -122.291143) (xy 33.914257 -122.320197) (xy 33.862928 -122.342009)
			(xy 33.808971 -122.356115) (xy 33.753534 -122.362215) (xy 33.6978 -122.360178) (xy 33.642957 -122.350048)
			(xy 33.590173 -122.332041) (xy 33.540573 -122.30654) (xy 33.495215 -122.274089) (xy 33.455066 -122.23538)
			(xy 33.42098 -122.191237) (xy 33.393684 -122.142602) (xy 33.373761 -122.090511) (xy 33.361635 -122.036074)
			(xy 33.357564 -121.980452) (xy 26.972514 -121.980452) (xy 25.752552 -123.200414) (xy 29.125416 -123.200414)
			(xy 29.129487 -123.144792) (xy 29.141613 -123.090355) (xy 29.161536 -123.038264) (xy 29.188832 -122.989629)
			(xy 29.222918 -122.945486) (xy 29.263067 -122.906777) (xy 29.308425 -122.874326) (xy 29.358025 -122.848825)
			(xy 29.410809 -122.830818) (xy 29.465652 -122.820688) (xy 29.521386 -122.818651) (xy 29.576823 -122.824751)
			(xy 29.63078 -122.838857) (xy 29.682109 -122.860669) (xy 29.729715 -122.889723) (xy 29.772583 -122.925398)
			(xy 29.8098 -122.966935) (xy 29.840573 -123.013448) (xy 29.864245 -123.063945) (xy 29.880313 -123.117352)
			(xy 29.888433 -123.172528) (xy 29.888942 -123.200414) (xy 29.888433 -123.2283) (xy 29.880313 -123.283476)
			(xy 29.864245 -123.336883) (xy 29.840573 -123.38738) (xy 29.8098 -123.433893) (xy 29.772583 -123.47543)
			(xy 29.729715 -123.511105) (xy 29.682109 -123.540159) (xy 29.63078 -123.561971) (xy 29.576823 -123.576077)
			(xy 29.521386 -123.582177) (xy 29.465652 -123.58014) (xy 29.410809 -123.57001) (xy 29.358025 -123.552003)
			(xy 29.308425 -123.526502) (xy 29.263067 -123.494051) (xy 29.222918 -123.455342) (xy 29.188832 -123.411199)
			(xy 29.161536 -123.362564) (xy 29.141613 -123.310473) (xy 29.129487 -123.256036) (xy 29.125416 -123.200414)
			(xy 25.752552 -123.200414) (xy 25.049988 -123.902978) (xy 26.902408 -123.902978) (xy 26.906479 -123.847356)
			(xy 26.918605 -123.792919) (xy 26.938528 -123.740828) (xy 26.965824 -123.692193) (xy 26.99991 -123.64805)
			(xy 27.040059 -123.609341) (xy 27.085417 -123.57689) (xy 27.135017 -123.551389) (xy 27.187801 -123.533382)
			(xy 27.242644 -123.523252) (xy 27.298378 -123.521215) (xy 27.353815 -123.527315) (xy 27.407772 -123.541421)
			(xy 27.459101 -123.563233) (xy 27.506707 -123.592287) (xy 27.549575 -123.627962) (xy 27.552247 -123.630944)
			(xy 31.385762 -123.630944) (xy 31.389833 -123.575322) (xy 31.401959 -123.520885) (xy 31.421882 -123.468794)
			(xy 31.449178 -123.420159) (xy 31.483264 -123.376016) (xy 31.523413 -123.337307) (xy 31.568771 -123.304856)
			(xy 31.618371 -123.279355) (xy 31.671155 -123.261348) (xy 31.725998 -123.251218) (xy 31.781732 -123.249181)
			(xy 31.837169 -123.255281) (xy 31.891126 -123.269387) (xy 31.942455 -123.291199) (xy 31.990061 -123.320253)
			(xy 32.032929 -123.355928) (xy 32.070146 -123.397465) (xy 32.100919 -123.443978) (xy 32.124591 -123.494475)
			(xy 32.140659 -123.547882) (xy 32.148779 -123.603058) (xy 32.149288 -123.630944) (xy 32.148779 -123.65883)
			(xy 32.140659 -123.714006) (xy 32.124591 -123.767413) (xy 32.100919 -123.81791) (xy 32.070146 -123.864423)
			(xy 32.032929 -123.90596) (xy 31.990061 -123.941635) (xy 31.942455 -123.970689) (xy 31.891126 -123.992501)
			(xy 31.837169 -124.006607) (xy 31.781732 -124.012707) (xy 31.725998 -124.01067) (xy 31.671155 -124.00054)
			(xy 31.618371 -123.982533) (xy 31.568771 -123.957032) (xy 31.523413 -123.924581) (xy 31.483264 -123.885872)
			(xy 31.449178 -123.841729) (xy 31.421882 -123.793094) (xy 31.401959 -123.741003) (xy 31.389833 -123.686566)
			(xy 31.385762 -123.630944) (xy 27.552247 -123.630944) (xy 27.586792 -123.669499) (xy 27.617565 -123.716012)
			(xy 27.641237 -123.766509) (xy 27.657305 -123.819916) (xy 27.665425 -123.875092) (xy 27.665934 -123.902978)
			(xy 27.665425 -123.930864) (xy 27.657305 -123.98604) (xy 27.641237 -124.039447) (xy 27.617565 -124.089944)
			(xy 27.586792 -124.136457) (xy 27.549575 -124.177994) (xy 27.506707 -124.213669) (xy 27.459101 -124.242723)
			(xy 27.407772 -124.264535) (xy 27.353815 -124.278641) (xy 27.298378 -124.284741) (xy 27.242644 -124.282704)
			(xy 27.187801 -124.272574) (xy 27.135017 -124.254567) (xy 27.085417 -124.229066) (xy 27.040059 -124.196615)
			(xy 26.99991 -124.157906) (xy 26.965824 -124.113763) (xy 26.938528 -124.065128) (xy 26.918605 -124.013037)
			(xy 26.906479 -123.9586) (xy 26.902408 -123.902978) (xy 25.049988 -123.902978) (xy 24.244046 -124.70892)
			(xy 26.256232 -124.70892) (xy 26.260303 -124.653298) (xy 26.272429 -124.598861) (xy 26.292352 -124.54677)
			(xy 26.319648 -124.498135) (xy 26.353734 -124.453992) (xy 26.393883 -124.415283) (xy 26.439241 -124.382832)
			(xy 26.488841 -124.357331) (xy 26.541625 -124.339324) (xy 26.596468 -124.329194) (xy 26.652202 -124.327157)
			(xy 26.707639 -124.333257) (xy 26.761596 -124.347363) (xy 26.812925 -124.369175) (xy 26.860531 -124.398229)
			(xy 26.903399 -124.433904) (xy 26.940616 -124.475441) (xy 26.971389 -124.521954) (xy 26.995061 -124.572451)
			(xy 27.011129 -124.625858) (xy 27.019249 -124.681034) (xy 27.019758 -124.70892) (xy 27.019249 -124.736806)
			(xy 27.011129 -124.791982) (xy 26.995061 -124.845389) (xy 26.971389 -124.895886) (xy 26.952414 -124.924566)
			(xy 31.371284 -124.924566) (xy 31.375355 -124.868944) (xy 31.387481 -124.814507) (xy 31.407404 -124.762416)
			(xy 31.4347 -124.713781) (xy 31.468786 -124.669638) (xy 31.508935 -124.630929) (xy 31.554293 -124.598478)
			(xy 31.603893 -124.572977) (xy 31.656677 -124.55497) (xy 31.71152 -124.54484) (xy 31.767254 -124.542803)
			(xy 31.822691 -124.548903) (xy 31.876648 -124.563009) (xy 31.927977 -124.584821) (xy 31.975583 -124.613875)
			(xy 32.018451 -124.64955) (xy 32.055668 -124.691087) (xy 32.086441 -124.7376) (xy 32.110113 -124.788097)
			(xy 32.126181 -124.841504) (xy 32.134301 -124.89668) (xy 32.13481 -124.924566) (xy 32.134301 -124.952452)
			(xy 32.126181 -125.007628) (xy 32.110113 -125.061035) (xy 32.086441 -125.111532) (xy 32.055668 -125.158045)
			(xy 32.018451 -125.199582) (xy 31.975583 -125.235257) (xy 31.927977 -125.264311) (xy 31.876648 -125.286123)
			(xy 31.822691 -125.300229) (xy 31.767254 -125.306329) (xy 31.71152 -125.304292) (xy 31.656677 -125.294162)
			(xy 31.603893 -125.276155) (xy 31.554293 -125.250654) (xy 31.508935 -125.218203) (xy 31.468786 -125.179494)
			(xy 31.4347 -125.135351) (xy 31.407404 -125.086716) (xy 31.387481 -125.034625) (xy 31.375355 -124.980188)
			(xy 31.371284 -124.924566) (xy 26.952414 -124.924566) (xy 26.940616 -124.942399) (xy 26.903399 -124.983936)
			(xy 26.860531 -125.019611) (xy 26.812925 -125.048665) (xy 26.761596 -125.070477) (xy 26.707639 -125.084583)
			(xy 26.652202 -125.090683) (xy 26.596468 -125.088646) (xy 26.541625 -125.078516) (xy 26.488841 -125.060509)
			(xy 26.439241 -125.035008) (xy 26.393883 -125.002557) (xy 26.353734 -124.963848) (xy 26.319648 -124.919705)
			(xy 26.292352 -124.87107) (xy 26.272429 -124.818979) (xy 26.260303 -124.764542) (xy 26.256232 -124.70892)
			(xy 24.244046 -124.70892) (xy 22.998684 -125.954282) (xy 31.145478 -125.954282) (xy 31.149549 -125.89866)
			(xy 31.161675 -125.844223) (xy 31.181598 -125.792132) (xy 31.208894 -125.743497) (xy 31.24298 -125.699354)
			(xy 31.283129 -125.660645) (xy 31.328487 -125.628194) (xy 31.378087 -125.602693) (xy 31.430871 -125.584686)
			(xy 31.485714 -125.574556) (xy 31.541448 -125.572519) (xy 31.596885 -125.578619) (xy 31.650842 -125.592725)
			(xy 31.651379 -125.592953) (xy 37.60644 -125.592953) (xy 37.60644 -125.538447) (xy 37.614197 -125.484496)
			(xy 37.629552 -125.432198) (xy 37.652194 -125.382617) (xy 37.681661 -125.336763) (xy 37.717354 -125.295569)
			(xy 37.758545 -125.259874) (xy 37.804398 -125.230404) (xy 37.853977 -125.20776) (xy 37.906274 -125.192401)
			(xy 37.960225 -125.184641) (xy 37.987478 -125.184154) (xy 38.014784 -125.184653) (xy 38.068836 -125.192463)
			(xy 38.121222 -125.207899) (xy 38.170873 -125.230644) (xy 38.216775 -125.260235) (xy 38.257989 -125.296067)
			(xy 38.293675 -125.337409) (xy 38.323104 -125.383415) (xy 38.345673 -125.433146) (xy 38.353746 -125.459236)
			(xy 38.358068 -125.472334) (xy 38.372585 -125.495772) (xy 38.392846 -125.514469) (xy 38.417371 -125.527061)
			(xy 38.444372 -125.53263) (xy 38.471878 -125.530769) (xy 38.497883 -125.521615) (xy 38.509448 -125.5141)
			(xy 38.533577 -125.497991) (xy 38.58567 -125.472456) (xy 38.641027 -125.455098) (xy 38.698373 -125.446316)
			(xy 38.72738 -125.445774) (xy 38.754633 -125.446272) (xy 38.808583 -125.454026) (xy 38.860881 -125.46938)
			(xy 38.910461 -125.49202) (xy 38.956315 -125.521486) (xy 38.997508 -125.557178) (xy 39.033202 -125.598369)
			(xy 39.06267 -125.644221) (xy 39.085313 -125.6938) (xy 39.10067 -125.746097) (xy 39.108427 -125.800048)
			(xy 39.108427 -125.854552) (xy 39.10067 -125.908503) (xy 39.085313 -125.9608) (xy 39.06267 -126.010379)
			(xy 39.033202 -126.056231) (xy 38.997508 -126.097422) (xy 38.956315 -126.133114) (xy 38.910461 -126.16258)
			(xy 38.860881 -126.18522) (xy 38.808583 -126.200574) (xy 38.754633 -126.208328) (xy 38.72738 -126.20879)
			(xy 38.700074 -126.208297) (xy 38.646024 -126.200482) (xy 38.593639 -126.185043) (xy 38.543989 -126.162295)
			(xy 38.498089 -126.132703) (xy 38.456875 -126.096871) (xy 38.421189 -126.055531) (xy 38.391759 -126.009527)
			(xy 38.369187 -125.959797) (xy 38.361112 -125.933708) (xy 38.356831 -125.920593) (xy 38.342313 -125.897145)
			(xy 38.322046 -125.87844) (xy 38.297511 -125.865846) (xy 38.2705 -125.86028) (xy 38.242985 -125.862151)
			(xy 38.216975 -125.87132) (xy 38.20541 -125.878844) (xy 38.181288 -125.894965) (xy 38.129193 -125.920499)
			(xy 38.073834 -125.937854) (xy 38.016486 -125.946631) (xy 37.987478 -125.94717) (xy 37.960225 -125.946759)
			(xy 37.906274 -125.938999) (xy 37.853977 -125.92364) (xy 37.804398 -125.900996) (xy 37.758545 -125.871526)
			(xy 37.717354 -125.835831) (xy 37.681661 -125.794637) (xy 37.652194 -125.748783) (xy 37.629552 -125.699202)
			(xy 37.614197 -125.646904) (xy 37.60644 -125.592953) (xy 31.651379 -125.592953) (xy 31.702171 -125.614537)
			(xy 31.749777 -125.643591) (xy 31.792645 -125.679266) (xy 31.829862 -125.720803) (xy 31.860635 -125.767316)
			(xy 31.884307 -125.817813) (xy 31.900375 -125.87122) (xy 31.908495 -125.926396) (xy 31.909004 -125.954282)
			(xy 31.908495 -125.982168) (xy 31.900375 -126.037344) (xy 31.893881 -126.05893) (xy 33.07918 -126.05893)
			(xy 33.083251 -126.003308) (xy 33.095377 -125.948871) (xy 33.1153 -125.89678) (xy 33.142596 -125.848145)
			(xy 33.176682 -125.804002) (xy 33.216831 -125.765293) (xy 33.262189 -125.732842) (xy 33.311789 -125.707341)
			(xy 33.364573 -125.689334) (xy 33.419416 -125.679204) (xy 33.47515 -125.677167) (xy 33.530587 -125.683267)
			(xy 33.584544 -125.697373) (xy 33.635873 -125.719185) (xy 33.683479 -125.748239) (xy 33.726347 -125.783914)
			(xy 33.763564 -125.825451) (xy 33.794337 -125.871964) (xy 33.818009 -125.922461) (xy 33.834077 -125.975868)
			(xy 33.842197 -126.031044) (xy 33.842706 -126.05893) (xy 33.842197 -126.086816) (xy 33.834077 -126.141992)
			(xy 33.818009 -126.195399) (xy 33.794337 -126.245896) (xy 33.784437 -126.26086) (xy 34.41141 -126.26086)
			(xy 34.415481 -126.205238) (xy 34.427607 -126.150801) (xy 34.44753 -126.09871) (xy 34.474826 -126.050075)
			(xy 34.508912 -126.005932) (xy 34.549061 -125.967223) (xy 34.594419 -125.934772) (xy 34.644019 -125.909271)
			(xy 34.696803 -125.891264) (xy 34.751646 -125.881134) (xy 34.80738 -125.879097) (xy 34.862817 -125.885197)
			(xy 34.916774 -125.899303) (xy 34.968103 -125.921115) (xy 35.015709 -125.950169) (xy 35.058577 -125.985844)
			(xy 35.095794 -126.027381) (xy 35.126567 -126.073894) (xy 35.150239 -126.124391) (xy 35.166307 -126.177798)
			(xy 35.174427 -126.232974) (xy 35.174936 -126.26086) (xy 35.174427 -126.288746) (xy 35.166307 -126.343922)
			(xy 35.150239 -126.397329) (xy 35.126567 -126.447826) (xy 35.095794 -126.494339) (xy 35.058577 -126.535876)
			(xy 35.015709 -126.571551) (xy 34.968103 -126.600605) (xy 34.916774 -126.622417) (xy 34.862817 -126.636523)
			(xy 34.80738 -126.642623) (xy 34.751646 -126.640586) (xy 34.696803 -126.630456) (xy 34.644019 -126.612449)
			(xy 34.594419 -126.586948) (xy 34.549061 -126.554497) (xy 34.508912 -126.515788) (xy 34.474826 -126.471645)
			(xy 34.44753 -126.42301) (xy 34.427607 -126.370919) (xy 34.415481 -126.316482) (xy 34.41141 -126.26086)
			(xy 33.784437 -126.26086) (xy 33.763564 -126.292409) (xy 33.726347 -126.333946) (xy 33.683479 -126.369621)
			(xy 33.635873 -126.398675) (xy 33.584544 -126.420487) (xy 33.530587 -126.434593) (xy 33.47515 -126.440693)
			(xy 33.419416 -126.438656) (xy 33.364573 -126.428526) (xy 33.311789 -126.410519) (xy 33.262189 -126.385018)
			(xy 33.216831 -126.352567) (xy 33.176682 -126.313858) (xy 33.142596 -126.269715) (xy 33.1153 -126.22108)
			(xy 33.095377 -126.168989) (xy 33.083251 -126.114552) (xy 33.07918 -126.05893) (xy 31.893881 -126.05893)
			(xy 31.884307 -126.090751) (xy 31.860635 -126.141248) (xy 31.829862 -126.187761) (xy 31.792645 -126.229298)
			(xy 31.749777 -126.264973) (xy 31.702171 -126.294027) (xy 31.650842 -126.315839) (xy 31.596885 -126.329945)
			(xy 31.541448 -126.336045) (xy 31.485714 -126.334008) (xy 31.430871 -126.323878) (xy 31.378087 -126.305871)
			(xy 31.328487 -126.28037) (xy 31.283129 -126.247919) (xy 31.24298 -126.20921) (xy 31.208894 -126.165067)
			(xy 31.181598 -126.116432) (xy 31.161675 -126.064341) (xy 31.149549 -126.009904) (xy 31.145478 -125.954282)
			(xy 22.998684 -125.954282) (xy 22.392132 -126.560834) (xy 27.732988 -126.560834) (xy 27.737059 -126.505212)
			(xy 27.749185 -126.450775) (xy 27.769108 -126.398684) (xy 27.796404 -126.350049) (xy 27.83049 -126.305906)
			(xy 27.870639 -126.267197) (xy 27.915997 -126.234746) (xy 27.965597 -126.209245) (xy 28.018381 -126.191238)
			(xy 28.073224 -126.181108) (xy 28.128958 -126.179071) (xy 28.184395 -126.185171) (xy 28.238352 -126.199277)
			(xy 28.289681 -126.221089) (xy 28.337287 -126.250143) (xy 28.380155 -126.285818) (xy 28.417372 -126.327355)
			(xy 28.448145 -126.373868) (xy 28.468635 -126.417578) (xy 29.186376 -126.417578) (xy 29.190447 -126.361956)
			(xy 29.202573 -126.307519) (xy 29.222496 -126.255428) (xy 29.249792 -126.206793) (xy 29.283878 -126.16265)
			(xy 29.324027 -126.123941) (xy 29.369385 -126.09149) (xy 29.418985 -126.065989) (xy 29.471769 -126.047982)
			(xy 29.526612 -126.037852) (xy 29.582346 -126.035815) (xy 29.637783 -126.041915) (xy 29.69174 -126.056021)
			(xy 29.743069 -126.077833) (xy 29.790675 -126.106887) (xy 29.833543 -126.142562) (xy 29.87076 -126.184099)
			(xy 29.901533 -126.230612) (xy 29.925205 -126.281109) (xy 29.941273 -126.334516) (xy 29.949393 -126.389692)
			(xy 29.949902 -126.417578) (xy 29.949393 -126.445464) (xy 29.941273 -126.50064) (xy 29.925205 -126.554047)
			(xy 29.901533 -126.604544) (xy 29.87076 -126.651057) (xy 29.833543 -126.692594) (xy 29.827359 -126.69774)
			(xy 35.487862 -126.69774) (xy 35.491933 -126.642118) (xy 35.504059 -126.587681) (xy 35.523982 -126.53559)
			(xy 35.551278 -126.486955) (xy 35.585364 -126.442812) (xy 35.625513 -126.404103) (xy 35.670871 -126.371652)
			(xy 35.720471 -126.346151) (xy 35.773255 -126.328144) (xy 35.828098 -126.318014) (xy 35.883832 -126.315977)
			(xy 35.939269 -126.322077) (xy 35.993226 -126.336183) (xy 36.044555 -126.357995) (xy 36.092161 -126.387049)
			(xy 36.135029 -126.422724) (xy 36.172246 -126.464261) (xy 36.203019 -126.510774) (xy 36.226691 -126.561271)
			(xy 36.242759 -126.614678) (xy 36.250879 -126.669854) (xy 36.251388 -126.69774) (xy 36.250879 -126.725626)
			(xy 36.242759 -126.780802) (xy 36.226691 -126.834209) (xy 36.203019 -126.884706) (xy 36.172246 -126.931219)
			(xy 36.135029 -126.972756) (xy 36.092161 -127.008431) (xy 36.044555 -127.037485) (xy 35.993226 -127.059297)
			(xy 35.939269 -127.073403) (xy 35.883832 -127.079503) (xy 35.828098 -127.077466) (xy 35.773255 -127.067336)
			(xy 35.720471 -127.049329) (xy 35.670871 -127.023828) (xy 35.625513 -126.991377) (xy 35.585364 -126.952668)
			(xy 35.551278 -126.908525) (xy 35.523982 -126.85989) (xy 35.504059 -126.807799) (xy 35.491933 -126.753362)
			(xy 35.487862 -126.69774) (xy 29.827359 -126.69774) (xy 29.790675 -126.728269) (xy 29.743069 -126.757323)
			(xy 29.69174 -126.779135) (xy 29.637783 -126.793241) (xy 29.582346 -126.799341) (xy 29.526612 -126.797304)
			(xy 29.471769 -126.787174) (xy 29.418985 -126.769167) (xy 29.369385 -126.743666) (xy 29.324027 -126.711215)
			(xy 29.283878 -126.672506) (xy 29.249792 -126.628363) (xy 29.222496 -126.579728) (xy 29.202573 -126.527637)
			(xy 29.190447 -126.4732) (xy 29.186376 -126.417578) (xy 28.468635 -126.417578) (xy 28.471817 -126.424365)
			(xy 28.487885 -126.477772) (xy 28.496005 -126.532948) (xy 28.496514 -126.560834) (xy 28.496005 -126.58872)
			(xy 28.487885 -126.643896) (xy 28.471817 -126.697303) (xy 28.448145 -126.7478) (xy 28.417372 -126.794313)
			(xy 28.380155 -126.83585) (xy 28.337287 -126.871525) (xy 28.289681 -126.900579) (xy 28.238352 -126.922391)
			(xy 28.184395 -126.936497) (xy 28.128958 -126.942597) (xy 28.073224 -126.94056) (xy 28.018381 -126.93043)
			(xy 27.965597 -126.912423) (xy 27.915997 -126.886922) (xy 27.870639 -126.854471) (xy 27.83049 -126.815762)
			(xy 27.796404 -126.771619) (xy 27.769108 -126.722984) (xy 27.749185 -126.670893) (xy 27.737059 -126.616456)
			(xy 27.732988 -126.560834) (xy 22.392132 -126.560834) (xy 20.986242 -127.966724) (xy 35.514532 -127.966724)
			(xy 35.518603 -127.911102) (xy 35.530729 -127.856665) (xy 35.550652 -127.804574) (xy 35.577948 -127.755939)
			(xy 35.612034 -127.711796) (xy 35.652183 -127.673087) (xy 35.697541 -127.640636) (xy 35.747141 -127.615135)
			(xy 35.799925 -127.597128) (xy 35.854768 -127.586998) (xy 35.910502 -127.584961) (xy 35.965939 -127.591061)
			(xy 36.019896 -127.605167) (xy 36.071225 -127.626979) (xy 36.118831 -127.656033) (xy 36.161699 -127.691708)
			(xy 36.198916 -127.733245) (xy 36.229689 -127.779758) (xy 36.253361 -127.830255) (xy 36.269429 -127.883662)
			(xy 36.277549 -127.938838) (xy 36.278058 -127.966724) (xy 36.277549 -127.99461) (xy 36.269429 -128.049786)
			(xy 36.253361 -128.103193) (xy 36.229689 -128.15369) (xy 36.198916 -128.200203) (xy 36.161699 -128.24174)
			(xy 36.118831 -128.277415) (xy 36.071225 -128.306469) (xy 36.019896 -128.328281) (xy 35.965939 -128.342387)
			(xy 35.910502 -128.348487) (xy 35.854768 -128.34645) (xy 35.799925 -128.33632) (xy 35.747141 -128.318313)
			(xy 35.697541 -128.292812) (xy 35.652183 -128.260361) (xy 35.612034 -128.221652) (xy 35.577948 -128.177509)
			(xy 35.550652 -128.128874) (xy 35.530729 -128.076783) (xy 35.518603 -128.022346) (xy 35.514532 -127.966724)
			(xy 20.986242 -127.966724) (xy 20.58797 -128.364996) (xy 25.623518 -128.364996) (xy 25.627589 -128.309374)
			(xy 25.639715 -128.254937) (xy 25.659638 -128.202846) (xy 25.686934 -128.154211) (xy 25.72102 -128.110068)
			(xy 25.761169 -128.071359) (xy 25.806527 -128.038908) (xy 25.856127 -128.013407) (xy 25.908911 -127.9954)
			(xy 25.963754 -127.98527) (xy 26.019488 -127.983233) (xy 26.074925 -127.989333) (xy 26.128882 -128.003439)
			(xy 26.180211 -128.025251) (xy 26.227817 -128.054305) (xy 26.270685 -128.08998) (xy 26.307902 -128.131517)
			(xy 26.338675 -128.17803) (xy 26.362347 -128.228527) (xy 26.378415 -128.281934) (xy 26.386535 -128.33711)
			(xy 26.387044 -128.364996) (xy 26.386547 -128.392219) (xy 27.67692 -128.392219) (xy 27.676924 -128.337725)
			(xy 27.684683 -128.283785) (xy 27.70004 -128.231499) (xy 27.722681 -128.18193) (xy 27.752145 -128.136088)
			(xy 27.787834 -128.094906) (xy 27.82902 -128.059221) (xy 27.874865 -128.029761) (xy 27.924436 -128.007126)
			(xy 27.976724 -127.991775) (xy 28.030665 -127.984021) (xy 28.085159 -127.984023) (xy 28.139099 -127.99178)
			(xy 28.191386 -128.007134) (xy 28.240956 -128.029773) (xy 28.286799 -128.059236) (xy 28.327983 -128.094923)
			(xy 28.363669 -128.136107) (xy 28.393131 -128.181951) (xy 28.415769 -128.231521) (xy 28.431122 -128.283809)
			(xy 28.438878 -128.337749) (xy 28.439364 -128.364996) (xy 28.43892 -128.391702) (xy 28.431524 -128.4446)
			(xy 28.424632 -128.470406) (xy 28.421138 -128.484151) (xy 28.421089 -128.512502) (xy 28.428848 -128.539771)
			(xy 28.443814 -128.563849) (xy 28.464831 -128.582877) (xy 28.490274 -128.595383) (xy 28.518178 -128.600401)
			(xy 28.532328 -128.599438) (xy 28.56992 -128.59766) (xy 28.59717 -128.598159) (xy 28.651116 -128.605917)
			(xy 28.703408 -128.621274) (xy 28.752984 -128.643915) (xy 28.798832 -128.67338) (xy 28.840022 -128.70907)
			(xy 28.875713 -128.750258) (xy 28.90518 -128.796106) (xy 28.927822 -128.84568) (xy 28.94318 -128.897972)
			(xy 28.943221 -128.898257) (xy 34.774519 -128.898257) (xy 34.774519 -128.843743) (xy 34.782278 -128.789784)
			(xy 34.797637 -128.737479) (xy 34.820284 -128.687892) (xy 34.849757 -128.642033) (xy 34.885458 -128.600835)
			(xy 34.926658 -128.565138) (xy 34.97252 -128.535668) (xy 35.022109 -128.513025) (xy 35.074416 -128.497671)
			(xy 35.128375 -128.489917) (xy 35.155632 -128.489456) (xy 35.183235 -128.48994) (xy 35.237867 -128.497876)
			(xy 35.290784 -128.513608) (xy 35.340879 -128.536805) (xy 35.387106 -128.566983) (xy 35.428498 -128.603512)
			(xy 35.46419 -128.645628) (xy 35.479228 -128.66878) (xy 35.486745 -128.680134) (xy 35.506723 -128.698627)
			(xy 35.530881 -128.711177) (xy 35.557498 -128.716889) (xy 35.584678 -128.715357) (xy 35.610485 -128.70669)
			(xy 35.633079 -128.691506) (xy 35.642296 -128.68148) (xy 35.660491 -128.661057) (xy 35.701733 -128.625128)
			(xy 35.747683 -128.595458) (xy 35.7974 -128.572655) (xy 35.849864 -128.557185) (xy 35.904 -128.549366)
			(xy 35.931348 -128.548892) (xy 35.9586 -128.549333) (xy 36.01255 -128.557096) (xy 36.064845 -128.572457)
			(xy 36.114423 -128.595104) (xy 36.160273 -128.624575) (xy 36.201463 -128.660271) (xy 36.237153 -128.701466)
			(xy 36.266619 -128.747319) (xy 36.289259 -128.7969) (xy 36.304614 -128.849197) (xy 36.31237 -128.903148)
			(xy 36.312856 -128.9304) (xy 36.312354 -128.959318) (xy 36.303624 -129.01649) (xy 36.286364 -129.07169)
			(xy 36.260969 -129.123652) (xy 36.228022 -129.171186) (xy 36.188277 -129.213201) (xy 36.16579 -129.23139)
			(xy 36.154505 -129.240742) (xy 36.137427 -129.264546) (xy 36.127817 -129.292223) (xy 36.12647 -129.321489)
			(xy 36.133495 -129.349931) (xy 36.148314 -129.375205) (xy 36.158678 -129.385568) (xy 36.177306 -129.403687)
			(xy 36.210021 -129.444059) (xy 36.236951 -129.4885) (xy 36.257598 -129.536186) (xy 36.271578 -129.586234)
			(xy 36.278634 -129.637716) (xy 36.279074 -129.663698) (xy 36.278643 -129.690952) (xy 36.270885 -129.744906)
			(xy 36.255528 -129.797207) (xy 36.232883 -129.846789) (xy 36.203412 -129.892644) (xy 36.167715 -129.933837)
			(xy 36.126518 -129.969531) (xy 36.080661 -129.998998) (xy 36.031077 -130.021639) (xy 35.978775 -130.036992)
			(xy 35.92482 -130.044745) (xy 35.897566 -130.045206) (xy 35.868794 -130.044675) (xy 35.811906 -130.035999)
			(xy 35.784282 -130.027934) (xy 35.770239 -130.023972) (xy 35.741071 -130.023495) (xy 35.712955 -130.031276)
			(xy 35.688183 -130.046681) (xy 35.66877 -130.068456) (xy 35.656298 -130.094827) (xy 35.651782 -130.123647)
			(xy 35.653218 -130.13817) (xy 35.654756 -130.150495) (xy 35.656405 -130.17528) (xy 35.65652 -130.1877)
			(xy 35.656045 -130.214953) (xy 35.648288 -130.268904) (xy 35.632931 -130.321202) (xy 35.610289 -130.370783)
			(xy 35.58082 -130.416636) (xy 35.545126 -130.457829) (xy 35.503933 -130.493523) (xy 35.458079 -130.52299)
			(xy 35.408499 -130.545633) (xy 35.3562 -130.560988) (xy 35.302249 -130.568745) (xy 35.247743 -130.568744)
			(xy 35.193792 -130.560987) (xy 35.141494 -130.54563) (xy 35.091914 -130.522987) (xy 35.046061 -130.493518)
			(xy 35.004868 -130.457823) (xy 34.969175 -130.41663) (xy 34.939708 -130.370776) (xy 34.917066 -130.321195)
			(xy 34.901711 -130.268896) (xy 34.893955 -130.214945) (xy 34.893956 -130.160439) (xy 34.901714 -130.106488)
			(xy 34.917071 -130.05419) (xy 34.939715 -130.00461) (xy 34.969185 -129.958757) (xy 35.00488 -129.917565)
			(xy 35.046073 -129.881873) (xy 35.091928 -129.852406) (xy 35.141509 -129.829764) (xy 35.193807 -129.81441)
			(xy 35.247759 -129.806654) (xy 35.275012 -129.806192) (xy 35.303784 -129.806728) (xy 35.360672 -129.815401)
			(xy 35.388296 -129.823464) (xy 35.402345 -129.827403) (xy 35.431511 -129.827886) (xy 35.459625 -129.820109)
			(xy 35.484397 -129.804708) (xy 35.50381 -129.782936) (xy 35.516281 -129.756567) (xy 35.520797 -129.72775)
			(xy 35.51936 -129.713228) (xy 35.517822 -129.700903) (xy 35.516173 -129.676118) (xy 35.516058 -129.663698)
			(xy 35.516553 -129.63478) (xy 35.525284 -129.577607) (xy 35.542545 -129.522406) (xy 35.567941 -129.470444)
			(xy 35.600889 -129.422911) (xy 35.640636 -129.380897) (xy 35.663124 -129.362708) (xy 35.67441 -129.353358)
			(xy 35.691486 -129.329553) (xy 35.701094 -129.301876) (xy 35.702441 -129.27261) (xy 35.695417 -129.244168)
			(xy 35.680599 -129.218894) (xy 35.670236 -129.20853) (xy 35.65251 -129.191376) (xy 35.62117 -129.153283)
			(xy 35.607752 -129.132584) (xy 35.600137 -129.121302) (xy 35.580177 -129.102818) (xy 35.556041 -129.09027)
			(xy 35.529445 -129.084551) (xy 35.502284 -129.086069) (xy 35.47649 -129.094714) (xy 35.453901 -129.109872)
			(xy 35.444684 -129.119884) (xy 35.426492 -129.14031) (xy 35.38525 -129.176239) (xy 35.339299 -129.20591)
			(xy 35.289582 -129.228714) (xy 35.237117 -129.244183) (xy 35.182981 -129.251999) (xy 35.155632 -129.252472)
			(xy 35.128375 -129.252083) (xy 35.074416 -129.244329) (xy 35.022109 -129.228975) (xy 34.97252 -129.206332)
			(xy 34.926658 -129.176862) (xy 34.885458 -129.141165) (xy 34.849757 -129.099967) (xy 34.820284 -129.054108)
			(xy 34.797637 -129.004521) (xy 34.782278 -128.952216) (xy 34.774519 -128.898257) (xy 28.943221 -128.898257)
			(xy 28.95094 -128.951918) (xy 28.951428 -128.979168) (xy 28.950983 -129.006005) (xy 28.943447 -129.059147)
			(xy 28.928534 -129.110708) (xy 28.906538 -129.159668) (xy 28.877895 -129.20506) (xy 28.843169 -129.245987)
			(xy 28.823412 -129.264156) (xy 28.812991 -129.274041) (xy 28.797685 -129.298332) (xy 28.789743 -129.325924)
			(xy 28.789794 -129.354636) (xy 28.797834 -129.382199) (xy 28.813226 -129.406436) (xy 28.823666 -129.416302)
			(xy 28.843522 -129.434453) (xy 28.878376 -129.475433) (xy 28.907127 -129.520903) (xy 28.929204 -129.569962)
			(xy 28.94417 -129.621636) (xy 28.951729 -129.674899) (xy 28.95219 -129.701798) (xy 28.951704 -129.729049)
			(xy 28.943948 -129.782997) (xy 28.928593 -129.835292) (xy 28.905951 -129.884869) (xy 28.876485 -129.930719)
			(xy 28.840794 -129.97191) (xy 28.799603 -130.007601) (xy 28.753753 -130.037067) (xy 28.704176 -130.059709)
			(xy 28.651881 -130.075064) (xy 28.597933 -130.08282) (xy 28.543431 -130.08282) (xy 28.489483 -130.075064)
			(xy 28.437188 -130.059709) (xy 28.387611 -130.037067) (xy 28.341761 -130.007601) (xy 28.30057 -129.97191)
			(xy 28.264879 -129.930719) (xy 28.235413 -129.884869) (xy 28.212771 -129.835292) (xy 28.197416 -129.782997)
			(xy 28.18966 -129.729049) (xy 28.189174 -129.701798) (xy 28.189663 -129.674963) (xy 28.19719 -129.621822)
			(xy 28.212094 -129.570262) (xy 28.234082 -129.521302) (xy 28.262718 -129.475909) (xy 28.297436 -129.43498)
			(xy 28.31719 -129.41681) (xy 28.327545 -129.406861) (xy 28.342854 -129.382587) (xy 28.350803 -129.355013)
			(xy 28.350764 -129.326315) (xy 28.342741 -129.298762) (xy 28.327366 -129.27453) (xy 28.316936 -129.264664)
			(xy 28.297112 -129.246479) (xy 28.262256 -129.205507) (xy 28.233501 -129.160043) (xy 28.211418 -129.110991)
			(xy 28.196444 -129.059324) (xy 28.188878 -129.006065) (xy 28.188412 -128.979168) (xy 28.188866 -128.952462)
			(xy 28.196255 -128.899564) (xy 28.203144 -128.873758) (xy 28.206593 -128.860001) (xy 28.206656 -128.831653)
			(xy 28.198909 -128.804385) (xy 28.183951 -128.780305) (xy 28.162938 -128.761277) (xy 28.137498 -128.748772)
			(xy 28.109597 -128.743759) (xy 28.095448 -128.744726) (xy 28.057856 -128.746504) (xy 28.030609 -128.745975)
			(xy 27.97667 -128.738213) (xy 27.924384 -128.722855) (xy 27.874816 -128.700212) (xy 27.828975 -128.670745)
			(xy 27.787794 -128.635055) (xy 27.752112 -128.593867) (xy 27.722654 -128.548021) (xy 27.70002 -128.498449)
			(xy 27.684671 -128.44616) (xy 27.67692 -128.392219) (xy 26.386547 -128.392219) (xy 26.386535 -128.392882)
			(xy 26.378415 -128.448058) (xy 26.362347 -128.501465) (xy 26.338675 -128.551962) (xy 26.307902 -128.598475)
			(xy 26.270685 -128.640012) (xy 26.227817 -128.675687) (xy 26.180211 -128.704741) (xy 26.128882 -128.726553)
			(xy 26.074925 -128.740659) (xy 26.019488 -128.746759) (xy 25.963754 -128.744722) (xy 25.908911 -128.734592)
			(xy 25.856127 -128.716585) (xy 25.806527 -128.691084) (xy 25.761169 -128.658633) (xy 25.72102 -128.619924)
			(xy 25.686934 -128.575781) (xy 25.659638 -128.527146) (xy 25.639715 -128.475055) (xy 25.627589 -128.420618)
			(xy 25.623518 -128.364996) (xy 20.58797 -128.364996) (xy 18.940526 -130.01244) (xy 18.940526 -130.936663)
			(xy 24.961212 -130.936663) (xy 24.968967 -130.882704) (xy 24.984323 -130.830398) (xy 25.006967 -130.780809)
			(xy 25.036438 -130.734948) (xy 25.072136 -130.693749) (xy 25.113334 -130.658049) (xy 25.159193 -130.628576)
			(xy 25.208781 -130.60593) (xy 25.261086 -130.590571) (xy 25.315045 -130.582813) (xy 25.369559 -130.582813)
			(xy 25.423518 -130.590572) (xy 25.475823 -130.605931) (xy 25.52541 -130.628578) (xy 25.571269 -130.658051)
			(xy 25.612467 -130.693752) (xy 25.648164 -130.734952) (xy 25.677635 -130.780813) (xy 25.700278 -130.830401)
			(xy 25.715093 -130.880866) (xy 27.573222 -130.880866) (xy 27.577293 -130.825244) (xy 27.589419 -130.770807)
			(xy 27.609342 -130.718716) (xy 27.636638 -130.670081) (xy 27.670724 -130.625938) (xy 27.710873 -130.587229)
			(xy 27.756231 -130.554778) (xy 27.805831 -130.529277) (xy 27.858615 -130.51127) (xy 27.913458 -130.50114)
			(xy 27.969192 -130.499103) (xy 28.024629 -130.505203) (xy 28.078586 -130.519309) (xy 28.129915 -130.541121)
			(xy 28.177521 -130.570175) (xy 28.220389 -130.60585) (xy 28.257606 -130.647387) (xy 28.288379 -130.6939)
			(xy 28.312051 -130.744397) (xy 28.328119 -130.797804) (xy 28.336239 -130.85298) (xy 28.336748 -130.880866)
			(xy 28.336239 -130.908752) (xy 28.328119 -130.963928) (xy 28.312051 -131.017335) (xy 28.288379 -131.067832)
			(xy 28.257606 -131.114345) (xy 28.220389 -131.155882) (xy 28.192535 -131.179062) (xy 34.962844 -131.179062)
			(xy 34.966915 -131.12344) (xy 34.979041 -131.069003) (xy 34.998964 -131.016912) (xy 35.02626 -130.968277)
			(xy 35.060346 -130.924134) (xy 35.100495 -130.885425) (xy 35.145853 -130.852974) (xy 35.195453 -130.827473)
			(xy 35.248237 -130.809466) (xy 35.30308 -130.799336) (xy 35.358814 -130.797299) (xy 35.414251 -130.803399)
			(xy 35.468208 -130.817505) (xy 35.519537 -130.839317) (xy 35.567143 -130.868371) (xy 35.610011 -130.904046)
			(xy 35.647228 -130.945583) (xy 35.678001 -130.992096) (xy 35.701673 -131.042593) (xy 35.717741 -131.096)
			(xy 35.725861 -131.151176) (xy 35.72637 -131.179062) (xy 35.725861 -131.206948) (xy 35.717741 -131.262124)
			(xy 35.701673 -131.315531) (xy 35.678001 -131.366028) (xy 35.647228 -131.412541) (xy 35.610011 -131.454078)
			(xy 35.567143 -131.489753) (xy 35.519537 -131.518807) (xy 35.468208 -131.540619) (xy 35.414251 -131.554725)
			(xy 35.358814 -131.560825) (xy 35.30308 -131.558788) (xy 35.248237 -131.548658) (xy 35.195453 -131.530651)
			(xy 35.145853 -131.50515) (xy 35.100495 -131.472699) (xy 35.060346 -131.43399) (xy 35.02626 -131.389847)
			(xy 34.998964 -131.341212) (xy 34.979041 -131.289121) (xy 34.966915 -131.234684) (xy 34.962844 -131.179062)
			(xy 28.192535 -131.179062) (xy 28.177521 -131.191557) (xy 28.129915 -131.220611) (xy 28.078586 -131.242423)
			(xy 28.024629 -131.256529) (xy 27.969192 -131.262629) (xy 27.913458 -131.260592) (xy 27.858615 -131.250462)
			(xy 27.805831 -131.232455) (xy 27.756231 -131.206954) (xy 27.710873 -131.174503) (xy 27.670724 -131.135794)
			(xy 27.636638 -131.091651) (xy 27.609342 -131.043016) (xy 27.589419 -130.990925) (xy 27.577293 -130.936488)
			(xy 27.573222 -130.880866) (xy 25.715093 -130.880866) (xy 25.715634 -130.882708) (xy 25.723389 -130.936667)
			(xy 25.72385 -130.963924) (xy 25.72318 -130.996583) (xy 25.712073 -131.060948) (xy 25.701752 -131.09194)
			(xy 25.697687 -131.10491) (xy 25.695635 -131.131995) (xy 25.700795 -131.158664) (xy 25.712802 -131.183029)
			(xy 25.730807 -131.203368) (xy 25.753536 -131.218241) (xy 25.779382 -131.226598) (xy 25.806516 -131.227846)
			(xy 25.819862 -131.22529) (xy 25.840537 -131.220891) (xy 25.882546 -131.216187) (xy 25.903682 -131.215892)
			(xy 25.930936 -131.216336) (xy 25.984891 -131.224091) (xy 26.037192 -131.239445) (xy 26.086776 -131.262087)
			(xy 26.132633 -131.291555) (xy 26.17383 -131.327249) (xy 26.209527 -131.368442) (xy 26.238999 -131.414297)
			(xy 26.261644 -131.463879) (xy 26.277003 -131.51618) (xy 26.284762 -131.570134) (xy 26.284764 -131.624642)
			(xy 26.277008 -131.678597) (xy 26.261653 -131.730898) (xy 26.23901 -131.780482) (xy 26.209542 -131.826338)
			(xy 26.173847 -131.867534) (xy 26.132653 -131.903231) (xy 26.086798 -131.932702) (xy 26.037215 -131.955346)
			(xy 25.984914 -131.970704) (xy 25.93096 -131.978463) (xy 25.876452 -131.978464) (xy 25.822497 -131.970707)
			(xy 25.770196 -131.955351) (xy 25.720613 -131.932707) (xy 25.674757 -131.903238) (xy 25.633562 -131.867543)
			(xy 25.597865 -131.826348) (xy 25.568396 -131.780492) (xy 25.545751 -131.730909) (xy 25.530394 -131.678608)
			(xy 25.522637 -131.624654) (xy 25.522174 -131.5974) (xy 25.522829 -131.564741) (xy 25.533946 -131.500375)
			(xy 25.544272 -131.469384) (xy 25.548512 -131.456463) (xy 25.550554 -131.429351) (xy 25.545376 -131.40266)
			(xy 25.533345 -131.378277) (xy 25.515313 -131.357929) (xy 25.492555 -131.343053) (xy 25.46668 -131.334703)
			(xy 25.439519 -131.333468) (xy 25.426162 -131.336034) (xy 25.405486 -131.340428) (xy 25.363478 -131.345136)
			(xy 25.342342 -131.345432) (xy 25.315085 -131.34499) (xy 25.261125 -131.337238) (xy 25.208818 -131.321884)
			(xy 25.159229 -131.299243) (xy 25.113366 -131.269775) (xy 25.072164 -131.23408) (xy 25.036462 -131.192884)
			(xy 25.006986 -131.147026) (xy 24.984337 -131.09744) (xy 24.968976 -131.045135) (xy 24.961214 -130.991177)
			(xy 24.961212 -130.936663) (xy 18.940526 -130.936663) (xy 18.940526 -132.264658) (xy 26.43708 -132.264658)
			(xy 26.441151 -132.209036) (xy 26.453277 -132.154599) (xy 26.4732 -132.102508) (xy 26.500496 -132.053873)
			(xy 26.534582 -132.00973) (xy 26.574731 -131.971021) (xy 26.620089 -131.93857) (xy 26.669689 -131.913069)
			(xy 26.722473 -131.895062) (xy 26.777316 -131.884932) (xy 26.83305 -131.882895) (xy 26.888487 -131.888995)
			(xy 26.942444 -131.903101) (xy 26.993773 -131.924913) (xy 27.041379 -131.953967) (xy 27.084247 -131.989642)
			(xy 27.121464 -132.031179) (xy 27.133766 -132.049774) (xy 37.591998 -132.049774) (xy 37.596069 -131.994152)
			(xy 37.608195 -131.939715) (xy 37.628118 -131.887624) (xy 37.655414 -131.838989) (xy 37.6895 -131.794846)
			(xy 37.729649 -131.756137) (xy 37.775007 -131.723686) (xy 37.824607 -131.698185) (xy 37.877391 -131.680178)
			(xy 37.932234 -131.670048) (xy 37.987968 -131.668011) (xy 38.043405 -131.674111) (xy 38.097362 -131.688217)
			(xy 38.148691 -131.710029) (xy 38.196297 -131.739083) (xy 38.239165 -131.774758) (xy 38.276382 -131.816295)
			(xy 38.307155 -131.862808) (xy 38.330827 -131.913305) (xy 38.346895 -131.966712) (xy 38.355015 -132.021888)
			(xy 38.355524 -132.049774) (xy 38.355015 -132.07766) (xy 38.346895 -132.132836) (xy 38.330827 -132.186243)
			(xy 38.307155 -132.23674) (xy 38.276382 -132.283253) (xy 38.239165 -132.32479) (xy 38.196297 -132.360465)
			(xy 38.148691 -132.389519) (xy 38.097362 -132.411331) (xy 38.043405 -132.425437) (xy 37.987968 -132.431537)
			(xy 37.932234 -132.4295) (xy 37.877391 -132.41937) (xy 37.824607 -132.401363) (xy 37.775007 -132.375862)
			(xy 37.729649 -132.343411) (xy 37.6895 -132.304702) (xy 37.655414 -132.260559) (xy 37.628118 -132.211924)
			(xy 37.608195 -132.159833) (xy 37.596069 -132.105396) (xy 37.591998 -132.049774) (xy 27.133766 -132.049774)
			(xy 27.152237 -132.077692) (xy 27.175909 -132.128189) (xy 27.191977 -132.181596) (xy 27.200097 -132.236772)
			(xy 27.200606 -132.264658) (xy 27.200097 -132.292544) (xy 27.191977 -132.34772) (xy 27.175909 -132.401127)
			(xy 27.152237 -132.451624) (xy 27.121464 -132.498137) (xy 27.090333 -132.532882) (xy 38.89832 -132.532882)
			(xy 38.902391 -132.47726) (xy 38.914517 -132.422823) (xy 38.93444 -132.370732) (xy 38.961736 -132.322097)
			(xy 38.995822 -132.277954) (xy 39.035971 -132.239245) (xy 39.081329 -132.206794) (xy 39.130929 -132.181293)
			(xy 39.183713 -132.163286) (xy 39.238556 -132.153156) (xy 39.29429 -132.151119) (xy 39.349727 -132.157219)
			(xy 39.403684 -132.171325) (xy 39.455013 -132.193137) (xy 39.502619 -132.222191) (xy 39.545487 -132.257866)
			(xy 39.582704 -132.299403) (xy 39.613477 -132.345916) (xy 39.637149 -132.396413) (xy 39.653217 -132.44982)
			(xy 39.661337 -132.504996) (xy 39.661846 -132.532882) (xy 39.661337 -132.560768) (xy 39.653217 -132.615944)
			(xy 39.637149 -132.669351) (xy 39.613477 -132.719848) (xy 39.582704 -132.766361) (xy 39.545487 -132.807898)
			(xy 39.502619 -132.843573) (xy 39.455013 -132.872627) (xy 39.403684 -132.894439) (xy 39.349727 -132.908545)
			(xy 39.29429 -132.914645) (xy 39.238556 -132.912608) (xy 39.183713 -132.902478) (xy 39.130929 -132.884471)
			(xy 39.081329 -132.85897) (xy 39.035971 -132.826519) (xy 38.995822 -132.78781) (xy 38.961736 -132.743667)
			(xy 38.93444 -132.695032) (xy 38.914517 -132.642941) (xy 38.902391 -132.588504) (xy 38.89832 -132.532882)
			(xy 27.090333 -132.532882) (xy 27.084247 -132.539674) (xy 27.041379 -132.575349) (xy 26.993773 -132.604403)
			(xy 26.942444 -132.626215) (xy 26.888487 -132.640321) (xy 26.83305 -132.646421) (xy 26.777316 -132.644384)
			(xy 26.722473 -132.634254) (xy 26.669689 -132.616247) (xy 26.620089 -132.590746) (xy 26.574731 -132.558295)
			(xy 26.534582 -132.519586) (xy 26.500496 -132.475443) (xy 26.4732 -132.426808) (xy 26.453277 -132.374717)
			(xy 26.441151 -132.32028) (xy 26.43708 -132.264658) (xy 18.940526 -132.264658) (xy 18.940526 -133.6802)
			(xy 24.987502 -133.6802) (xy 24.991573 -133.624578) (xy 25.003699 -133.570141) (xy 25.023622 -133.51805)
			(xy 25.050918 -133.469415) (xy 25.085004 -133.425272) (xy 25.125153 -133.386563) (xy 25.170511 -133.354112)
			(xy 25.220111 -133.328611) (xy 25.272895 -133.310604) (xy 25.327738 -133.300474) (xy 25.383472 -133.298437)
			(xy 25.438909 -133.304537) (xy 25.492866 -133.318643) (xy 25.544195 -133.340455) (xy 25.591801 -133.369509)
			(xy 25.634669 -133.405184) (xy 25.671886 -133.446721) (xy 25.702659 -133.493234) (xy 25.726331 -133.543731)
			(xy 25.742399 -133.597138) (xy 25.750519 -133.652314) (xy 25.751028 -133.6802) (xy 25.750519 -133.708086)
			(xy 25.742399 -133.763262) (xy 25.726331 -133.816669) (xy 25.702659 -133.867166) (xy 25.671886 -133.913679)
			(xy 25.634669 -133.955216) (xy 25.591801 -133.990891) (xy 25.544195 -134.019945) (xy 25.492866 -134.041757)
			(xy 25.438909 -134.055863) (xy 25.383472 -134.061963) (xy 25.327738 -134.059926) (xy 25.272895 -134.049796)
			(xy 25.220111 -134.031789) (xy 25.170511 -134.006288) (xy 25.125153 -133.973837) (xy 25.085004 -133.935128)
			(xy 25.050918 -133.890985) (xy 25.023622 -133.84235) (xy 25.003699 -133.790259) (xy 24.991573 -133.735822)
			(xy 24.987502 -133.6802) (xy 18.940526 -133.6802) (xy 18.940526 -134.187057) (xy 28.166707 -134.187057)
			(xy 28.166707 -134.132543) (xy 28.174466 -134.078583) (xy 28.189825 -134.026277) (xy 28.212472 -133.976689)
			(xy 28.241945 -133.930829) (xy 28.277646 -133.88963) (xy 28.318846 -133.853932) (xy 28.364708 -133.824461)
			(xy 28.414297 -133.801817) (xy 28.466605 -133.786461) (xy 28.520565 -133.778705) (xy 28.547822 -133.778244)
			(xy 28.5742 -133.778728) (xy 28.626454 -133.785982) (xy 28.677212 -133.800363) (xy 28.725505 -133.821597)
			(xy 28.770415 -133.84928) (xy 28.811084 -133.882882) (xy 28.846739 -133.921766) (xy 28.876699 -133.965189)
			(xy 28.888944 -133.988556) (xy 28.895646 -134.000915) (xy 28.914621 -134.021643) (xy 28.938535 -134.036405)
			(xy 28.965571 -134.044077) (xy 28.993673 -134.044077) (xy 29.020709 -134.036405) (xy 29.044623 -134.021643)
			(xy 29.063598 -134.000915) (xy 29.0703 -133.988556) (xy 29.082506 -133.965166) (xy 29.112475 -133.921743)
			(xy 29.148136 -133.88286) (xy 29.188811 -133.849256) (xy 29.233725 -133.821571) (xy 29.282022 -133.800334)
			(xy 29.332783 -133.785948) (xy 29.385042 -133.778688) (xy 29.411422 -133.778244) (xy 29.437962 -133.778742)
			(xy 29.490529 -133.786115) (xy 29.541566 -133.800702) (xy 29.59009 -133.822221) (xy 29.616575 -133.838696)
			(xy 38.067994 -133.838696) (xy 38.072065 -133.783074) (xy 38.084191 -133.728637) (xy 38.104114 -133.676546)
			(xy 38.13141 -133.627911) (xy 38.165496 -133.583768) (xy 38.205645 -133.545059) (xy 38.251003 -133.512608)
			(xy 38.300603 -133.487107) (xy 38.353387 -133.4691) (xy 38.40823 -133.45897) (xy 38.463964 -133.456933)
			(xy 38.519401 -133.463033) (xy 38.573358 -133.477139) (xy 38.624687 -133.498951) (xy 38.672293 -133.528005)
			(xy 38.715161 -133.56368) (xy 38.752378 -133.605217) (xy 38.783151 -133.65173) (xy 38.806823 -133.702227)
			(xy 38.822891 -133.755634) (xy 38.831011 -133.81081) (xy 38.83152 -133.838696) (xy 38.831011 -133.866582)
			(xy 38.822891 -133.921758) (xy 38.806823 -133.975165) (xy 38.783151 -134.025662) (xy 38.752378 -134.072175)
			(xy 38.715161 -134.113712) (xy 38.672293 -134.149387) (xy 38.624687 -134.178441) (xy 38.573358 -134.200253)
			(xy 38.519401 -134.214359) (xy 38.463964 -134.220459) (xy 38.40823 -134.218422) (xy 38.353387 -134.208292)
			(xy 38.300603 -134.190285) (xy 38.251003 -134.164784) (xy 38.205645 -134.132333) (xy 38.165496 -134.093624)
			(xy 38.13141 -134.049481) (xy 38.104114 -134.000846) (xy 38.084191 -133.948755) (xy 38.072065 -133.894318)
			(xy 38.067994 -133.838696) (xy 29.616575 -133.838696) (xy 29.635162 -133.850258) (xy 29.675915 -133.884271)
			(xy 29.71156 -133.923603) (xy 29.741411 -133.967495) (xy 29.75356 -133.991096) (xy 29.760607 -134.004333)
			(xy 29.781101 -134.026212) (xy 29.807058 -134.04121) (xy 29.836249 -134.048038) (xy 29.866165 -134.04611)
			(xy 29.894238 -134.035592) (xy 29.906468 -134.02691) (xy 29.931543 -134.008577) (xy 29.986405 -133.979453)
			(xy 30.045259 -133.9596) (xy 30.106552 -133.949541) (xy 30.137608 -133.948932) (xy 30.164862 -133.949338)
			(xy 30.218814 -133.957097) (xy 30.271114 -133.972454) (xy 30.320695 -133.995098) (xy 30.366549 -134.024568)
			(xy 30.407743 -134.060263) (xy 30.443437 -134.101457) (xy 30.472906 -134.147312) (xy 30.495549 -134.196894)
			(xy 30.510905 -134.249194) (xy 30.518662 -134.303146) (xy 30.518662 -134.357654) (xy 30.510905 -134.411606)
			(xy 30.495549 -134.463906) (xy 30.472906 -134.513488) (xy 30.443437 -134.559343) (xy 30.407743 -134.600537)
			(xy 30.366549 -134.636232) (xy 30.320695 -134.665702) (xy 30.271114 -134.688346) (xy 30.218814 -134.703703)
			(xy 30.164862 -134.711462) (xy 30.137608 -134.711948) (xy 30.111066 -134.711513) (xy 30.058496 -134.70413)
			(xy 30.007457 -134.689533) (xy 29.958933 -134.668005) (xy 29.913861 -134.639959) (xy 29.873109 -134.605939)
			(xy 29.837466 -134.566599) (xy 29.807618 -134.5227) (xy 29.79547 -134.499096) (xy 29.788388 -134.48588)
			(xy 29.767901 -134.464005) (xy 29.741952 -134.449007) (xy 29.71277 -134.442176) (xy 29.68286 -134.444097)
			(xy 29.654792 -134.454606) (xy 29.642562 -134.463282) (xy 29.617477 -134.4816) (xy 29.562619 -134.510728)
			(xy 29.503768 -134.530585) (xy 29.442477 -134.540648) (xy 29.411422 -134.54126) (xy 29.38504 -134.540875)
			(xy 29.332779 -134.533611) (xy 29.282017 -134.519218) (xy 29.23372 -134.497972) (xy 29.18881 -134.470275)
			(xy 29.148143 -134.436658) (xy 29.112493 -134.39776) (xy 29.082541 -134.354322) (xy 29.0703 -134.330948)
			(xy 29.063598 -134.318589) (xy 29.044623 -134.297861) (xy 29.020709 -134.283099) (xy 28.993673 -134.275427)
			(xy 28.965571 -134.275427) (xy 28.938535 -134.283099) (xy 28.914621 -134.297861) (xy 28.895646 -134.318589)
			(xy 28.888944 -134.330948) (xy 28.876706 -134.35432) (xy 28.846742 -134.397742) (xy 28.811085 -134.436626)
			(xy 28.770415 -134.470231) (xy 28.725505 -134.497917) (xy 28.677213 -134.519158) (xy 28.626456 -134.533548)
			(xy 28.574201 -134.540813) (xy 28.547822 -134.54126) (xy 28.520565 -134.540895) (xy 28.466605 -134.533139)
			(xy 28.414297 -134.517783) (xy 28.364708 -134.495139) (xy 28.318847 -134.465668) (xy 28.277646 -134.42997)
			(xy 28.241945 -134.388771) (xy 28.212472 -134.342911) (xy 28.189825 -134.293323) (xy 28.174466 -134.241017)
			(xy 28.166707 -134.187057) (xy 18.940526 -134.187057) (xy 18.940526 -135.140557) (xy 32.578423 -135.140557)
			(xy 32.578423 -135.086043) (xy 32.586182 -135.032083) (xy 32.601542 -134.979777) (xy 32.62419 -134.930189)
			(xy 32.653665 -134.88433) (xy 32.689366 -134.843133) (xy 32.730568 -134.807436) (xy 32.776431 -134.777967)
			(xy 32.826022 -134.755325) (xy 32.87833 -134.739972) (xy 32.932291 -134.73222) (xy 32.959548 -134.73176)
			(xy 32.98633 -134.732183) (xy 33.039367 -134.739689) (xy 33.090834 -134.754533) (xy 33.139722 -134.776423)
			(xy 33.185071 -134.804931) (xy 33.225992 -134.839496) (xy 33.26168 -134.87944) (xy 33.291437 -134.92398)
			(xy 33.303464 -134.947914) (xy 33.309986 -134.960369) (xy 33.328576 -134.98144) (xy 33.352213 -134.996636)
			(xy 33.379101 -135.004802) (xy 33.407196 -135.005317) (xy 33.434365 -134.998143) (xy 33.458543 -134.983824)
			(xy 33.477894 -134.963448) (xy 33.48482 -134.951216) (xy 33.497242 -134.928438) (xy 33.527358 -134.886189)
			(xy 33.562922 -134.848411) (xy 33.603278 -134.815801) (xy 33.647681 -134.788962) (xy 33.695312 -134.768389)
			(xy 33.745292 -134.75446) (xy 33.796698 -134.747434) (xy 33.82264 -134.747) (xy 33.84989 -134.747473)
			(xy 33.903834 -134.755234) (xy 33.956126 -134.770593) (xy 34.005699 -134.793237) (xy 34.051545 -134.822705)
			(xy 34.092731 -134.858397) (xy 34.128419 -134.899587) (xy 34.157883 -134.945436) (xy 34.180521 -134.995012)
			(xy 34.195875 -135.047305) (xy 34.20363 -135.10125) (xy 34.20363 -135.15575) (xy 34.195875 -135.209695)
			(xy 34.180521 -135.261988) (xy 34.157883 -135.311564) (xy 34.128419 -135.357413) (xy 34.092731 -135.398603)
			(xy 34.051545 -135.434295) (xy 34.005699 -135.463763) (xy 33.956126 -135.486407) (xy 33.903834 -135.501766)
			(xy 33.84989 -135.509527) (xy 33.82264 -135.510016) (xy 33.795859 -135.509561) (xy 33.742826 -135.502055)
			(xy 33.691361 -135.487213) (xy 33.642475 -135.465326) (xy 33.597127 -135.436823) (xy 33.556206 -135.402264)
			(xy 33.520515 -135.362326) (xy 33.490754 -135.317793) (xy 33.478724 -135.293862) (xy 33.472219 -135.281399)
			(xy 33.453623 -135.260331) (xy 33.429984 -135.245139) (xy 33.403095 -135.236976) (xy 33.374999 -135.236462)
			(xy 33.347829 -135.243636) (xy 33.32365 -135.257954) (xy 33.304296 -135.278328) (xy 33.297368 -135.29056)
			(xy 33.284913 -135.313319) (xy 33.254798 -135.355564) (xy 33.219236 -135.393339) (xy 33.178885 -135.425948)
			(xy 33.134487 -135.452788) (xy 33.086863 -135.473366) (xy 33.036889 -135.487301) (xy 32.985488 -135.494337)
			(xy 32.959548 -135.494776) (xy 32.932291 -135.49438) (xy 32.87833 -135.486628) (xy 32.826022 -135.471275)
			(xy 32.776431 -135.448633) (xy 32.730568 -135.419164) (xy 32.689366 -135.383467) (xy 32.653665 -135.34227)
			(xy 32.62419 -135.296411) (xy 32.601542 -135.246823) (xy 32.586182 -135.194517) (xy 32.578423 -135.140557)
			(xy 18.940526 -135.140557) (xy 18.940526 -137.279888) (xy 33.298892 -137.279888) (xy 33.299358 -137.253509)
			(xy 33.306612 -137.201253) (xy 33.320994 -137.150494) (xy 33.34223 -137.102199) (xy 33.369914 -137.057289)
			(xy 33.403521 -137.01662) (xy 33.442408 -136.980967) (xy 33.485835 -136.95101) (xy 33.509204 -136.938766)
			(xy 33.521569 -136.932079) (xy 33.542292 -136.913098) (xy 33.557047 -136.889181) (xy 33.564715 -136.862146)
			(xy 33.564714 -136.834044) (xy 33.557043 -136.807009) (xy 33.542285 -136.783094) (xy 33.52156 -136.764115)
			(xy 33.509204 -136.75741) (xy 33.48583 -136.745175) (xy 33.442405 -136.715213) (xy 33.403519 -136.679557)
			(xy 33.369913 -136.638886) (xy 33.342226 -136.593976) (xy 33.320987 -136.545682) (xy 33.306599 -136.494923)
			(xy 33.299336 -136.442667) (xy 33.298892 -136.416288) (xy 33.299378 -136.389037) (xy 33.307134 -136.335089)
			(xy 33.322489 -136.282794) (xy 33.345131 -136.233217) (xy 33.374597 -136.187367) (xy 33.410288 -136.146176)
			(xy 33.451479 -136.110485) (xy 33.497329 -136.081019) (xy 33.546906 -136.058377) (xy 33.599201 -136.043022)
			(xy 33.653149 -136.035266) (xy 33.707651 -136.035266) (xy 33.761599 -136.043022) (xy 33.813894 -136.058377)
			(xy 33.863471 -136.081019) (xy 33.909321 -136.110485) (xy 33.950512 -136.146176) (xy 33.986203 -136.187367)
			(xy 34.015669 -136.233217) (xy 34.038311 -136.282794) (xy 34.053666 -136.335089) (xy 34.061422 -136.389037)
			(xy 34.061908 -136.416288) (xy 34.061505 -136.442669) (xy 34.05424 -136.494928) (xy 34.039849 -136.545689)
			(xy 34.018604 -136.593984) (xy 33.99091 -136.638893) (xy 33.957296 -136.679561) (xy 33.918402 -136.715212)
			(xy 33.874968 -136.745168) (xy 33.851596 -136.75741) (xy 33.839252 -136.764132) (xy 33.818532 -136.783108)
			(xy 33.803777 -136.807018) (xy 33.796107 -136.834047) (xy 33.796106 -136.862143) (xy 33.803772 -136.889173)
			(xy 33.818525 -136.913084) (xy 33.839243 -136.932062) (xy 33.851596 -136.938766) (xy 33.87496 -136.951019)
			(xy 33.918385 -136.980979) (xy 33.957271 -137.016632) (xy 33.990878 -137.0573) (xy 34.018565 -137.102207)
			(xy 34.039807 -137.150499) (xy 34.054197 -137.201255) (xy 34.061462 -137.25351) (xy 34.061908 -137.279888)
			(xy 34.061422 -137.307139) (xy 34.053666 -137.361087) (xy 34.038311 -137.413382) (xy 34.015669 -137.462959)
			(xy 33.986203 -137.508809) (xy 33.950512 -137.55) (xy 33.909321 -137.585691) (xy 33.863471 -137.615157)
			(xy 33.813894 -137.637799) (xy 33.761599 -137.653154) (xy 33.707651 -137.66091) (xy 33.653149 -137.66091)
			(xy 33.599201 -137.653154) (xy 33.546906 -137.637799) (xy 33.497329 -137.615157) (xy 33.451479 -137.585691)
			(xy 33.410288 -137.55) (xy 33.374597 -137.508809) (xy 33.345131 -137.462959) (xy 33.322489 -137.413382)
			(xy 33.307134 -137.361087) (xy 33.299378 -137.307139) (xy 33.298892 -137.279888) (xy 18.940526 -137.279888)
			(xy 18.940526 -153.766012) (xy 24.445731 -153.766012) (xy 24.449724 -153.556271) (xy 24.4617 -153.346834)
			(xy 24.481641 -153.138005) (xy 24.509518 -152.930086) (xy 24.54529 -152.723379) (xy 24.588905 -152.518184)
			(xy 24.640301 -152.314799) (xy 24.699403 -152.113517) (xy 24.766125 -151.914631) (xy 24.84037 -151.71843)
			(xy 24.92203 -151.525198) (xy 25.010988 -151.335214) (xy 25.107115 -151.148755) (xy 25.21027 -150.966091)
			(xy 25.320305 -150.787486) (xy 25.437059 -150.6132) (xy 25.560364 -150.443485) (xy 25.690041 -150.278587)
			(xy 25.825902 -150.118746) (xy 25.967749 -149.964193) (xy 26.115378 -149.815153) (xy 26.268573 -149.67184)
			(xy 26.427114 -149.534464) (xy 26.590769 -149.403223) (xy 26.759303 -149.278308) (xy 26.932469 -149.1599)
			(xy 27.110019 -149.04817) (xy 27.291693 -148.94328) (xy 27.477228 -148.845383) (xy 27.666356 -148.754621)
			(xy 27.858803 -148.671124) (xy 28.054288 -148.595014) (xy 28.25253 -148.526402) (xy 28.45324 -148.465387)
			(xy 28.656127 -148.412058) (xy 28.860897 -148.366491) (xy 29.067254 -148.328752) (xy 29.274898 -148.298898)
			(xy 29.483528 -148.27697) (xy 29.692841 -148.263001) (xy 29.902535 -148.25701) (xy 30.112304 -148.259007)
			(xy 30.321846 -148.268989) (xy 30.530856 -148.286941) (xy 30.73903 -148.312837) (xy 30.946068 -148.346639)
			(xy 31.151669 -148.388299) (xy 31.355535 -148.437757) (xy 31.55737 -148.49494) (xy 31.756882 -148.559765)
			(xy 31.953781 -148.632139) (xy 32.147782 -148.711956) (xy 32.338604 -148.799102) (xy 32.52597 -148.893449)
			(xy 32.709608 -148.99486) (xy 32.889252 -149.10319) (xy 33.064642 -149.21828) (xy 33.235523 -149.339964)
			(xy 33.401647 -149.468065) (xy 33.562774 -149.602398) (xy 33.718671 -149.742767) (xy 33.86911 -149.88897)
			(xy 34.013874 -150.040794) (xy 34.152753 -150.19802) (xy 34.285546 -150.360419) (xy 34.41206 -150.527755)
			(xy 34.532112 -150.699787) (xy 34.645527 -150.876264) (xy 34.752141 -151.056932) (xy 34.8518 -151.241527)
			(xy 34.944359 -151.429782) (xy 35.029684 -151.621425) (xy 35.107651 -151.816177) (xy 35.178147 -152.013757)
			(xy 35.24107 -152.213876) (xy 35.296329 -152.416247) (xy 35.343843 -152.620574) (xy 35.383544 -152.826562)
			(xy 35.415374 -153.033913) (xy 35.439287 -153.242324) (xy 35.455248 -153.451495) (xy 35.463235 -153.661122)
			(xy 35.463734 -153.766012) (xy 35.463235 -153.870902) (xy 35.455248 -154.080529) (xy 35.439287 -154.2897)
			(xy 35.415374 -154.498111) (xy 35.383544 -154.705462) (xy 35.343843 -154.91145) (xy 35.296329 -155.115777)
			(xy 35.24107 -155.318148) (xy 35.178147 -155.518267) (xy 35.107651 -155.715847) (xy 35.029684 -155.910599)
			(xy 34.944359 -156.102242) (xy 34.8518 -156.290497) (xy 34.752141 -156.475092) (xy 34.645527 -156.65576)
			(xy 34.532112 -156.832237) (xy 34.41206 -157.004269) (xy 34.285546 -157.171605) (xy 34.152753 -157.334004)
			(xy 34.013874 -157.49123) (xy 33.86911 -157.643054) (xy 33.718671 -157.789257) (xy 33.562774 -157.929626)
			(xy 33.401647 -158.063959) (xy 33.235523 -158.19206) (xy 33.064642 -158.313744) (xy 32.889252 -158.428834)
			(xy 32.709608 -158.537164) (xy 32.52597 -158.638575) (xy 32.338604 -158.732922) (xy 32.147782 -158.820068)
			(xy 31.953781 -158.899885) (xy 31.756882 -158.972259) (xy 31.55737 -159.037084) (xy 31.355535 -159.094267)
			(xy 31.151669 -159.143725) (xy 30.946068 -159.185385) (xy 30.73903 -159.219187) (xy 30.530856 -159.245083)
			(xy 30.321846 -159.263035) (xy 30.112304 -159.273017) (xy 29.902535 -159.275014) (xy 29.692841 -159.269023)
			(xy 29.483528 -159.255054) (xy 29.274898 -159.233126) (xy 29.067254 -159.203272) (xy 28.860897 -159.165533)
			(xy 28.656127 -159.119966) (xy 28.45324 -159.066637) (xy 28.25253 -159.005622) (xy 28.054288 -158.93701)
			(xy 27.858803 -158.8609) (xy 27.666356 -158.777403) (xy 27.477228 -158.686641) (xy 27.291693 -158.588744)
			(xy 27.110019 -158.483854) (xy 26.932469 -158.372124) (xy 26.759303 -158.253716) (xy 26.590769 -158.128801)
			(xy 26.427114 -157.99756) (xy 26.268573 -157.860184) (xy 26.115378 -157.716871) (xy 25.967749 -157.567831)
			(xy 25.825902 -157.413278) (xy 25.690041 -157.253437) (xy 25.560364 -157.088539) (xy 25.437059 -156.918824)
			(xy 25.320305 -156.744538) (xy 25.21027 -156.565933) (xy 25.107115 -156.383269) (xy 25.010988 -156.19681)
			(xy 24.92203 -156.006826) (xy 24.84037 -155.813594) (xy 24.766125 -155.617393) (xy 24.699403 -155.418507)
			(xy 24.640301 -155.217225) (xy 24.588905 -155.01384) (xy 24.54529 -154.808645) (xy 24.509518 -154.601938)
			(xy 24.481641 -154.394019) (xy 24.4617 -154.18519) (xy 24.449724 -153.975753) (xy 24.445731 -153.766012)
			(xy 18.940526 -153.766012) (xy 18.940526 -159.601752) (xy 21.579562 -159.601752) (xy 21.579562 -159.547248)
			(xy 21.587318 -159.493299) (xy 21.602673 -159.441004) (xy 21.625314 -159.391425) (xy 21.654781 -159.345574)
			(xy 21.690472 -159.304382) (xy 21.731662 -159.268689) (xy 21.777513 -159.239221) (xy 21.827091 -159.216578)
			(xy 21.879386 -159.201221) (xy 21.933334 -159.193463) (xy 21.960586 -159.192976) (xy 21.986966 -159.19339)
			(xy 22.039225 -159.200653) (xy 22.089985 -159.215044) (xy 22.138279 -159.236288) (xy 22.183189 -159.26398)
			(xy 22.223857 -159.297592) (xy 22.259509 -159.336485) (xy 22.289465 -159.379917) (xy 22.301708 -159.403288)
			(xy 22.30841 -159.415647) (xy 22.327385 -159.436375) (xy 22.351299 -159.451137) (xy 22.378335 -159.458809)
			(xy 22.406437 -159.458809) (xy 22.433473 -159.451137) (xy 22.457387 -159.436375) (xy 22.476362 -159.415647)
			(xy 22.483064 -159.403288) (xy 22.495311 -159.379921) (xy 22.525273 -159.336497) (xy 22.560928 -159.297612)
			(xy 22.601596 -159.264006) (xy 22.646504 -159.236318) (xy 22.694796 -159.215077) (xy 22.745553 -159.200687)
			(xy 22.797807 -159.193422) (xy 22.824186 -159.192976) (xy 22.851438 -159.19347) (xy 22.905389 -159.201225)
			(xy 22.957686 -159.21658) (xy 23.007266 -159.23922) (xy 23.053119 -159.268687) (xy 23.094311 -159.304379)
			(xy 23.130005 -159.34557) (xy 23.159473 -159.391422) (xy 23.182116 -159.441001) (xy 23.197472 -159.493298)
			(xy 23.205229 -159.547248) (xy 23.205229 -159.601752) (xy 23.197472 -159.655702) (xy 23.182116 -159.707999)
			(xy 23.159473 -159.757578) (xy 23.130005 -159.80343) (xy 23.094311 -159.844621) (xy 23.053119 -159.880313)
			(xy 23.007266 -159.90978) (xy 22.957686 -159.93242) (xy 22.905389 -159.947775) (xy 22.851438 -159.95553)
			(xy 22.824186 -159.955992) (xy 22.797807 -159.955536) (xy 22.74555 -159.948282) (xy 22.69479 -159.933899)
			(xy 22.646494 -159.912662) (xy 22.601584 -159.884976) (xy 22.560916 -159.851368) (xy 22.525263 -159.812479)
			(xy 22.495307 -159.76905) (xy 22.483064 -159.74568) (xy 22.476362 -159.733321) (xy 22.457387 -159.712593)
			(xy 22.433473 -159.697831) (xy 22.406437 -159.690159) (xy 22.378335 -159.690159) (xy 22.351299 -159.697831)
			(xy 22.327385 -159.712593) (xy 22.30841 -159.733321) (xy 22.301708 -159.74568) (xy 22.289468 -159.769052)
			(xy 22.259507 -159.812477) (xy 22.223852 -159.851363) (xy 22.183183 -159.88497) (xy 22.138273 -159.912657)
			(xy 22.089979 -159.933897) (xy 22.039221 -159.948285) (xy 21.986965 -159.955548) (xy 21.960586 -159.955992)
			(xy 21.933334 -159.955537) (xy 21.879386 -159.947779) (xy 21.827091 -159.932422) (xy 21.777513 -159.909779)
			(xy 21.731662 -159.880311) (xy 21.690472 -159.844618) (xy 21.654781 -159.803426) (xy 21.625314 -159.757575)
			(xy 21.602673 -159.707996) (xy 21.587318 -159.655701) (xy 21.579562 -159.601752) (xy 18.940526 -159.601752)
			(xy 18.940526 -161.154364) (xy 25.594308 -161.154364) (xy 25.598379 -161.098742) (xy 25.610505 -161.044305)
			(xy 25.630428 -160.992214) (xy 25.657724 -160.943579) (xy 25.69181 -160.899436) (xy 25.731959 -160.860727)
			(xy 25.777317 -160.828276) (xy 25.826917 -160.802775) (xy 25.879701 -160.784768) (xy 25.934544 -160.774638)
			(xy 25.990278 -160.772601) (xy 26.045715 -160.778701) (xy 26.099672 -160.792807) (xy 26.151001 -160.814619)
			(xy 26.198607 -160.843673) (xy 26.241475 -160.879348) (xy 26.278692 -160.920885) (xy 26.309465 -160.967398)
			(xy 26.309713 -160.967928) (xy 26.570432 -160.967928) (xy 26.570946 -160.940755) (xy 26.578642 -160.886956)
			(xy 26.593896 -160.834795) (xy 26.6164 -160.785326) (xy 26.645697 -160.739553) (xy 26.681194 -160.698402)
			(xy 26.722173 -160.662705) (xy 26.767804 -160.633187) (xy 26.817163 -160.610444) (xy 26.86925 -160.594938)
			(xy 26.89606 -160.590484) (xy 26.90991 -160.587923) (xy 26.935569 -160.576339) (xy 26.957091 -160.558192)
			(xy 26.972845 -160.53486) (xy 26.981632 -160.508114) (xy 26.982786 -160.479985) (xy 26.97622 -160.45261)
			(xy 26.96972 -160.440116) (xy 26.958083 -160.418595) (xy 26.939749 -160.373234) (xy 26.927352 -160.325905)
			(xy 26.921095 -160.277381) (xy 26.920698 -160.252918) (xy 26.921172 -160.225665) (xy 26.928927 -160.171714)
			(xy 26.944281 -160.119416) (xy 26.966922 -160.069836) (xy 26.996388 -160.023982) (xy 27.032081 -159.982789)
			(xy 27.073273 -159.947096) (xy 27.119125 -159.917627) (xy 27.168705 -159.894985) (xy 27.221003 -159.879629)
			(xy 27.274953 -159.871873) (xy 27.302206 -159.87141) (xy 27.329163 -159.871906) (xy 27.38254 -159.879496)
			(xy 27.434317 -159.894525) (xy 27.483463 -159.916692) (xy 27.528999 -159.945556) (xy 27.570019 -159.980543)
			(xy 27.58821 -160.000442) (xy 27.5982 -160.011136) (xy 27.622961 -160.026717) (xy 27.651124 -160.034637)
			(xy 27.680377 -160.034246) (xy 27.708318 -160.025576) (xy 27.732653 -160.009339) (xy 27.742388 -159.99841)
			(xy 27.760611 -159.977409) (xy 27.802113 -159.940408) (xy 27.848545 -159.909821) (xy 27.898924 -159.886295)
			(xy 27.952183 -159.870329) (xy 28.007195 -159.86226) (xy 28.034996 -159.861758) (xy 28.062246 -159.862281)
			(xy 28.11619 -159.870036) (xy 28.168482 -159.885389) (xy 28.218057 -159.908028) (xy 28.263906 -159.93749)
			(xy 28.305095 -159.973178) (xy 28.340787 -160.014364) (xy 28.370254 -160.060209) (xy 28.392897 -160.109782)
			(xy 28.408255 -160.162073) (xy 28.416016 -160.216016) (xy 28.416504 -160.243266) (xy 28.41498 -160.278064)
			(xy 28.414165 -160.293081) (xy 28.420272 -160.322513) (xy 28.434692 -160.348886) (xy 28.456174 -160.369911)
			(xy 28.482851 -160.383762) (xy 28.49753 -160.38703) (xy 28.526432 -160.392984) (xy 28.582076 -160.412623)
			(xy 28.634041 -160.440578) (xy 28.681095 -160.476185) (xy 28.702 -160.497012) (xy 28.713208 -160.507706)
			(xy 28.740419 -160.522471) (xy 28.770798 -160.528431) (xy 28.801571 -160.525042) (xy 28.829926 -160.512612)
			(xy 28.841954 -160.502854) (xy 28.862902 -160.485138) (xy 28.908953 -160.455318) (xy 28.958804 -160.43241)
			(xy 29.011425 -160.416888) (xy 29.065728 -160.409072) (xy 29.09316 -160.40862) (xy 29.122313 -160.409181)
			(xy 29.179938 -160.41806) (xy 29.235541 -160.435603) (xy 29.287829 -160.4614) (xy 29.335584 -160.494852)
			(xy 29.377693 -160.535179) (xy 29.413177 -160.581443) (xy 29.427678 -160.60674) (xy 29.435187 -160.619327)
			(xy 29.455948 -160.639992) (xy 29.481718 -160.653918) (xy 29.510381 -160.659958) (xy 29.53958 -160.657617)
			(xy 29.566914 -160.647087) (xy 29.590137 -160.629234) (xy 29.599128 -160.617662) (xy 29.61455 -160.596998)
			(xy 29.650085 -160.559636) (xy 29.690329 -160.5274) (xy 29.734547 -160.500876) (xy 29.781933 -160.480549)
			(xy 29.831626 -160.466789) (xy 29.882719 -160.459845) (xy 29.9085 -160.45942) (xy 29.934856 -160.459881)
			(xy 29.987065 -160.467149) (xy 30.037778 -160.481532) (xy 30.086028 -160.502757) (xy 30.130899 -160.53042)
			(xy 30.171536 -160.563994) (xy 30.189678 -160.583118) (xy 30.198948 -160.592739) (xy 30.221445 -160.607141)
			(xy 30.246909 -160.615206) (xy 30.273594 -160.616381) (xy 30.299669 -160.610586) (xy 30.323344 -160.598219)
			(xy 30.333442 -160.589468) (xy 30.354685 -160.570621) (xy 30.4017 -160.53877) (xy 30.452918 -160.514243)
			(xy 30.507207 -160.497582) (xy 30.563366 -160.489155) (xy 30.59176 -160.48863) (xy 30.619017 -160.489014)
			(xy 30.672978 -160.496767) (xy 30.725286 -160.512121) (xy 30.774876 -160.534764) (xy 30.820739 -160.564234)
			(xy 30.861941 -160.599931) (xy 30.897642 -160.641129) (xy 30.927117 -160.686989) (xy 30.949765 -160.736576)
			(xy 30.965124 -160.788883) (xy 30.972883 -160.842843) (xy 30.972883 -160.897357) (xy 30.965124 -160.951317)
			(xy 30.949765 -161.003624) (xy 30.927117 -161.053211) (xy 30.897642 -161.099071) (xy 30.861941 -161.140269)
			(xy 30.826616 -161.170874) (xy 33.5186 -161.170874) (xy 33.522671 -161.115252) (xy 33.534797 -161.060815)
			(xy 33.55472 -161.008724) (xy 33.582016 -160.960089) (xy 33.616102 -160.915946) (xy 33.656251 -160.877237)
			(xy 33.701609 -160.844786) (xy 33.751209 -160.819285) (xy 33.803993 -160.801278) (xy 33.858836 -160.791148)
			(xy 33.91457 -160.789111) (xy 33.970007 -160.795211) (xy 34.023964 -160.809317) (xy 34.075293 -160.831129)
			(xy 34.122899 -160.860183) (xy 34.165767 -160.895858) (xy 34.202984 -160.937395) (xy 34.233757 -160.983908)
			(xy 34.257429 -161.034405) (xy 34.273497 -161.087812) (xy 34.281617 -161.142988) (xy 34.282126 -161.170874)
			(xy 34.281617 -161.19876) (xy 34.273497 -161.253936) (xy 34.257429 -161.307343) (xy 34.233757 -161.35784)
			(xy 34.202984 -161.404353) (xy 34.165767 -161.44589) (xy 34.122899 -161.481565) (xy 34.075293 -161.510619)
			(xy 34.023964 -161.532431) (xy 33.970007 -161.546537) (xy 33.91457 -161.552637) (xy 33.858836 -161.5506)
			(xy 33.803993 -161.54047) (xy 33.751209 -161.522463) (xy 33.701609 -161.496962) (xy 33.656251 -161.464511)
			(xy 33.616102 -161.425802) (xy 33.582016 -161.381659) (xy 33.55472 -161.333024) (xy 33.534797 -161.280933)
			(xy 33.522671 -161.226496) (xy 33.5186 -161.170874) (xy 30.826616 -161.170874) (xy 30.820739 -161.175966)
			(xy 30.774876 -161.205436) (xy 30.725286 -161.228079) (xy 30.672978 -161.243433) (xy 30.619017 -161.251186)
			(xy 30.59176 -161.251646) (xy 30.565402 -161.251223) (xy 30.513191 -161.243949) (xy 30.462478 -161.229559)
			(xy 30.414227 -161.208327) (xy 30.369357 -161.180657) (xy 30.328723 -161.147075) (xy 30.310582 -161.127948)
			(xy 30.301256 -161.118382) (xy 30.278778 -161.103969) (xy 30.253326 -161.095892) (xy 30.22665 -161.094705)
			(xy 30.200582 -161.100491) (xy 30.176913 -161.112851) (xy 30.166818 -161.121598) (xy 30.145586 -161.140458)
			(xy 30.098569 -161.172308) (xy 30.047348 -161.196834) (xy 29.993056 -161.213491) (xy 29.936895 -161.221913)
			(xy 29.9085 -161.222436) (xy 29.879345 -161.22193) (xy 29.821716 -161.213043) (xy 29.76611 -161.195493)
			(xy 29.713822 -161.169687) (xy 29.666068 -161.136226) (xy 29.62396 -161.09589) (xy 29.58848 -161.049617)
			(xy 29.573982 -161.024316) (xy 29.566526 -161.011692) (xy 29.545759 -160.991013) (xy 29.519977 -160.977081)
			(xy 29.491299 -160.971041) (xy 29.462087 -160.973391) (xy 29.434744 -160.983937) (xy 29.41152 -161.001811)
			(xy 29.402532 -161.013394) (xy 29.387061 -161.03402) (xy 29.351535 -161.071385) (xy 29.311301 -161.103626)
			(xy 29.267092 -161.130155) (xy 29.219712 -161.150488) (xy 29.170026 -161.164256) (xy 29.118939 -161.171207)
			(xy 29.09316 -161.171636) (xy 29.067638 -161.171269) (xy 29.017049 -161.164468) (xy 28.967819 -161.15098)
			(xy 28.920828 -161.131046) (xy 28.876916 -161.105023) (xy 28.836868 -161.073374) (xy 28.81884 -161.055304)
			(xy 28.807683 -161.044552) (xy 28.780455 -161.02979) (xy 28.750059 -161.02384) (xy 28.719275 -161.027244)
			(xy 28.690915 -161.039693) (xy 28.678886 -161.049462) (xy 28.657912 -161.067146) (xy 28.611869 -161.096973)
			(xy 28.562025 -161.119889) (xy 28.509409 -161.135419) (xy 28.45511 -161.143241) (xy 28.42768 -161.143696)
			(xy 28.400428 -161.143241) (xy 28.346478 -161.135481) (xy 28.294182 -161.120123) (xy 28.244604 -161.097479)
			(xy 28.198753 -161.068009) (xy 28.157563 -161.032314) (xy 28.121872 -160.991121) (xy 28.092406 -160.945268)
			(xy 28.069766 -160.895688) (xy 28.054412 -160.84339) (xy 28.046657 -160.78944) (xy 28.046172 -160.762188)
			(xy 28.047696 -160.72739) (xy 28.048492 -160.712374) (xy 28.042378 -160.682951) (xy 28.027959 -160.656584)
			(xy 28.006486 -160.635559) (xy 27.97982 -160.6217) (xy 27.965146 -160.618424) (xy 27.94033 -160.613351)
			(xy 27.892202 -160.597564) (xy 27.846588 -160.575544) (xy 27.804291 -160.54768) (xy 27.766054 -160.514462)
			(xy 27.748992 -160.495742) (xy 27.738999 -160.485052) (xy 27.714238 -160.469473) (xy 27.686077 -160.461554)
			(xy 27.656825 -160.461945) (xy 27.628885 -160.470613) (xy 27.604549 -160.486847) (xy 27.594814 -160.497774)
			(xy 27.576613 -160.51873) (xy 27.535206 -160.555693) (xy 27.48888 -160.586264) (xy 27.438613 -160.6098)
			(xy 27.385466 -160.625802) (xy 27.358086 -160.630362) (xy 27.344215 -160.632826) (xy 27.318551 -160.644429)
			(xy 27.297027 -160.662594) (xy 27.281276 -160.685943) (xy 27.272494 -160.712704) (xy 27.271346 -160.740845)
			(xy 27.277921 -160.768232) (xy 27.284426 -160.78073) (xy 27.296085 -160.80224) (xy 27.314413 -160.847605)
			(xy 27.326803 -160.894938) (xy 27.333054 -160.943464) (xy 27.333448 -160.967928) (xy 27.332962 -160.995179)
			(xy 27.325206 -161.049127) (xy 27.309851 -161.101422) (xy 27.287209 -161.150999) (xy 27.257743 -161.196849)
			(xy 27.222052 -161.23804) (xy 27.180861 -161.273731) (xy 27.135011 -161.303197) (xy 27.085434 -161.325839)
			(xy 27.033139 -161.341194) (xy 26.979191 -161.34895) (xy 26.924689 -161.34895) (xy 26.870741 -161.341194)
			(xy 26.818446 -161.325839) (xy 26.768869 -161.303197) (xy 26.723019 -161.273731) (xy 26.681828 -161.23804)
			(xy 26.646137 -161.196849) (xy 26.616671 -161.150999) (xy 26.594029 -161.101422) (xy 26.578674 -161.049127)
			(xy 26.570918 -160.995179) (xy 26.570432 -160.967928) (xy 26.309713 -160.967928) (xy 26.333137 -161.017895)
			(xy 26.349205 -161.071302) (xy 26.357325 -161.126478) (xy 26.357834 -161.154364) (xy 26.357325 -161.18225)
			(xy 26.349205 -161.237426) (xy 26.333137 -161.290833) (xy 26.309465 -161.34133) (xy 26.278692 -161.387843)
			(xy 26.241475 -161.42938) (xy 26.198607 -161.465055) (xy 26.151001 -161.494109) (xy 26.099672 -161.515921)
			(xy 26.045715 -161.530027) (xy 25.990278 -161.536127) (xy 25.934544 -161.53409) (xy 25.879701 -161.52396)
			(xy 25.826917 -161.505953) (xy 25.777317 -161.480452) (xy 25.731959 -161.448001) (xy 25.69181 -161.409292)
			(xy 25.657724 -161.365149) (xy 25.630428 -161.316514) (xy 25.610505 -161.264423) (xy 25.598379 -161.209986)
			(xy 25.594308 -161.154364) (xy 18.940526 -161.154364) (xy 18.940526 -162.067748) (xy 30.453582 -162.067748)
			(xy 30.457653 -162.012126) (xy 30.469779 -161.957689) (xy 30.489702 -161.905598) (xy 30.516998 -161.856963)
			(xy 30.551084 -161.81282) (xy 30.591233 -161.774111) (xy 30.636591 -161.74166) (xy 30.686191 -161.716159)
			(xy 30.738975 -161.698152) (xy 30.793818 -161.688022) (xy 30.849552 -161.685985) (xy 30.904989 -161.692085)
			(xy 30.958946 -161.706191) (xy 31.010275 -161.728003) (xy 31.057881 -161.757057) (xy 31.100749 -161.792732)
			(xy 31.137966 -161.834269) (xy 31.168739 -161.880782) (xy 31.192411 -161.931279) (xy 31.208479 -161.984686)
			(xy 31.216599 -162.039862) (xy 31.217108 -162.067748) (xy 31.216599 -162.095634) (xy 31.208479 -162.15081)
			(xy 31.192411 -162.204217) (xy 31.168739 -162.254714) (xy 31.137966 -162.301227) (xy 31.100749 -162.342764)
			(xy 31.057881 -162.378439) (xy 31.010275 -162.407493) (xy 30.958946 -162.429305) (xy 30.904989 -162.443411)
			(xy 30.849552 -162.449511) (xy 30.793818 -162.447474) (xy 30.738975 -162.437344) (xy 30.686191 -162.419337)
			(xy 30.636591 -162.393836) (xy 30.591233 -162.361385) (xy 30.551084 -162.322676) (xy 30.516998 -162.278533)
			(xy 30.489702 -162.229898) (xy 30.469779 -162.177807) (xy 30.457653 -162.12337) (xy 30.453582 -162.067748)
			(xy 18.940526 -162.067748) (xy 18.940526 -162.586162) (xy 33.079942 -162.586162) (xy 33.084013 -162.53054)
			(xy 33.096139 -162.476103) (xy 33.116062 -162.424012) (xy 33.143358 -162.375377) (xy 33.177444 -162.331234)
			(xy 33.217593 -162.292525) (xy 33.262951 -162.260074) (xy 33.312551 -162.234573) (xy 33.365335 -162.216566)
			(xy 33.420178 -162.206436) (xy 33.475912 -162.204399) (xy 33.531349 -162.210499) (xy 33.585306 -162.224605)
			(xy 33.636635 -162.246417) (xy 33.684241 -162.275471) (xy 33.727109 -162.311146) (xy 33.764326 -162.352683)
			(xy 33.795099 -162.399196) (xy 33.818771 -162.449693) (xy 33.834839 -162.5031) (xy 33.842959 -162.558276)
			(xy 33.843468 -162.586162) (xy 33.842959 -162.614048) (xy 33.834839 -162.669224) (xy 33.818771 -162.722631)
			(xy 33.795099 -162.773128) (xy 33.764326 -162.819641) (xy 33.727109 -162.861178) (xy 33.684241 -162.896853)
			(xy 33.636635 -162.925907) (xy 33.585306 -162.947719) (xy 33.531349 -162.961825) (xy 33.475912 -162.967925)
			(xy 33.420178 -162.965888) (xy 33.365335 -162.955758) (xy 33.312551 -162.937751) (xy 33.262951 -162.91225)
			(xy 33.217593 -162.879799) (xy 33.177444 -162.84109) (xy 33.143358 -162.796947) (xy 33.116062 -162.748312)
			(xy 33.096139 -162.696221) (xy 33.084013 -162.641784) (xy 33.079942 -162.586162) (xy 18.940526 -162.586162)
			(xy 18.940526 -163.032948) (xy 20.014182 -163.032948) (xy 20.018253 -162.977326) (xy 20.030379 -162.922889)
			(xy 20.050302 -162.870798) (xy 20.077598 -162.822163) (xy 20.111684 -162.77802) (xy 20.151833 -162.739311)
			(xy 20.197191 -162.70686) (xy 20.246791 -162.681359) (xy 20.299575 -162.663352) (xy 20.354418 -162.653222)
			(xy 20.410152 -162.651185) (xy 20.465589 -162.657285) (xy 20.519546 -162.671391) (xy 20.570875 -162.693203)
			(xy 20.618481 -162.722257) (xy 20.661349 -162.757932) (xy 20.698566 -162.799469) (xy 20.729339 -162.845982)
			(xy 20.753011 -162.896479) (xy 20.769079 -162.949886) (xy 20.777199 -163.005062) (xy 20.777708 -163.032948)
			(xy 20.777199 -163.060834) (xy 20.769079 -163.11601) (xy 20.753011 -163.169417) (xy 20.729339 -163.219914)
			(xy 20.698566 -163.266427) (xy 20.661349 -163.307964) (xy 20.618481 -163.343639) (xy 20.570875 -163.372693)
			(xy 20.525196 -163.392104) (xy 22.73884 -163.392104) (xy 22.742911 -163.336482) (xy 22.755037 -163.282045)
			(xy 22.77496 -163.229954) (xy 22.802256 -163.181319) (xy 22.836342 -163.137176) (xy 22.876491 -163.098467)
			(xy 22.921849 -163.066016) (xy 22.971449 -163.040515) (xy 23.024233 -163.022508) (xy 23.079076 -163.012378)
			(xy 23.13481 -163.010341) (xy 23.190247 -163.016441) (xy 23.244204 -163.030547) (xy 23.295533 -163.052359)
			(xy 23.343139 -163.081413) (xy 23.386007 -163.117088) (xy 23.423224 -163.158625) (xy 23.453997 -163.205138)
			(xy 23.477669 -163.255635) (xy 23.493737 -163.309042) (xy 23.501857 -163.364218) (xy 23.502366 -163.392104)
			(xy 23.501857 -163.41999) (xy 23.493737 -163.475166) (xy 23.477669 -163.528573) (xy 23.453997 -163.57907)
			(xy 23.428637 -163.617402) (xy 31.594042 -163.617402) (xy 31.598113 -163.56178) (xy 31.610239 -163.507343)
			(xy 31.630162 -163.455252) (xy 31.657458 -163.406617) (xy 31.691544 -163.362474) (xy 31.731693 -163.323765)
			(xy 31.777051 -163.291314) (xy 31.826651 -163.265813) (xy 31.879435 -163.247806) (xy 31.934278 -163.237676)
			(xy 31.990012 -163.235639) (xy 32.045449 -163.241739) (xy 32.099406 -163.255845) (xy 32.150735 -163.277657)
			(xy 32.198341 -163.306711) (xy 32.241209 -163.342386) (xy 32.278426 -163.383923) (xy 32.309199 -163.430436)
			(xy 32.332871 -163.480933) (xy 32.348939 -163.53434) (xy 32.357059 -163.589516) (xy 32.357568 -163.617402)
			(xy 32.357059 -163.645288) (xy 32.348939 -163.700464) (xy 32.332871 -163.753871) (xy 32.309199 -163.804368)
			(xy 32.278426 -163.850881) (xy 32.241209 -163.892418) (xy 32.198341 -163.928093) (xy 32.150735 -163.957147)
			(xy 32.099406 -163.978959) (xy 32.045449 -163.993065) (xy 31.990012 -163.999165) (xy 31.934278 -163.997128)
			(xy 31.879435 -163.986998) (xy 31.826651 -163.968991) (xy 31.777051 -163.94349) (xy 31.731693 -163.911039)
			(xy 31.691544 -163.87233) (xy 31.657458 -163.828187) (xy 31.630162 -163.779552) (xy 31.610239 -163.727461)
			(xy 31.598113 -163.673024) (xy 31.594042 -163.617402) (xy 23.428637 -163.617402) (xy 23.423224 -163.625583)
			(xy 23.386007 -163.66712) (xy 23.343139 -163.702795) (xy 23.295533 -163.731849) (xy 23.244204 -163.753661)
			(xy 23.190247 -163.767767) (xy 23.13481 -163.773867) (xy 23.079076 -163.77183) (xy 23.024233 -163.7617)
			(xy 22.971449 -163.743693) (xy 22.921849 -163.718192) (xy 22.876491 -163.685741) (xy 22.836342 -163.647032)
			(xy 22.802256 -163.602889) (xy 22.77496 -163.554254) (xy 22.755037 -163.502163) (xy 22.742911 -163.447726)
			(xy 22.73884 -163.392104) (xy 20.525196 -163.392104) (xy 20.519546 -163.394505) (xy 20.465589 -163.408611)
			(xy 20.410152 -163.414711) (xy 20.354418 -163.412674) (xy 20.299575 -163.402544) (xy 20.246791 -163.384537)
			(xy 20.197191 -163.359036) (xy 20.151833 -163.326585) (xy 20.111684 -163.287876) (xy 20.077598 -163.243733)
			(xy 20.050302 -163.195098) (xy 20.030379 -163.143007) (xy 20.018253 -163.08857) (xy 20.014182 -163.032948)
			(xy 18.940526 -163.032948) (xy 18.940526 -164.194744) (xy 20.752814 -164.194744) (xy 20.756885 -164.139122)
			(xy 20.769011 -164.084685) (xy 20.788934 -164.032594) (xy 20.81623 -163.983959) (xy 20.850316 -163.939816)
			(xy 20.890465 -163.901107) (xy 20.935823 -163.868656) (xy 20.985423 -163.843155) (xy 21.038207 -163.825148)
			(xy 21.09305 -163.815018) (xy 21.148784 -163.812981) (xy 21.204221 -163.819081) (xy 21.258178 -163.833187)
			(xy 21.309507 -163.854999) (xy 21.357113 -163.884053) (xy 21.399981 -163.919728) (xy 21.437198 -163.961265)
			(xy 21.467971 -164.007778) (xy 21.491643 -164.058275) (xy 21.507711 -164.111682) (xy 21.515831 -164.166858)
			(xy 21.51634 -164.194744) (xy 21.515831 -164.22263) (xy 21.507711 -164.277806) (xy 21.491643 -164.331213)
			(xy 21.467971 -164.38171) (xy 21.437198 -164.428223) (xy 21.399981 -164.46976) (xy 21.357113 -164.505435)
			(xy 21.309507 -164.534489) (xy 21.258178 -164.556301) (xy 21.204221 -164.570407) (xy 21.148784 -164.576507)
			(xy 21.09305 -164.57447) (xy 21.038207 -164.56434) (xy 20.985423 -164.546333) (xy 20.935823 -164.520832)
			(xy 20.890465 -164.488381) (xy 20.850316 -164.449672) (xy 20.81623 -164.405529) (xy 20.788934 -164.356894)
			(xy 20.769011 -164.304803) (xy 20.756885 -164.250366) (xy 20.752814 -164.194744) (xy 18.940526 -164.194744)
			(xy 18.940526 -164.994336) (xy 22.751794 -164.994336) (xy 22.755865 -164.938714) (xy 22.767991 -164.884277)
			(xy 22.787914 -164.832186) (xy 22.81521 -164.783551) (xy 22.849296 -164.739408) (xy 22.889445 -164.700699)
			(xy 22.934803 -164.668248) (xy 22.984403 -164.642747) (xy 23.037187 -164.62474) (xy 23.09203 -164.61461)
			(xy 23.147764 -164.612573) (xy 23.203201 -164.618673) (xy 23.257158 -164.632779) (xy 23.308487 -164.654591)
			(xy 23.356093 -164.683645) (xy 23.398961 -164.71932) (xy 23.436178 -164.760857) (xy 23.466951 -164.80737)
			(xy 23.490623 -164.857867) (xy 23.506691 -164.911274) (xy 23.514811 -164.96645) (xy 23.51532 -164.994336)
			(xy 23.514811 -165.022222) (xy 23.506691 -165.077398) (xy 23.490623 -165.130805) (xy 23.466951 -165.181302)
			(xy 23.436178 -165.227815) (xy 23.398961 -165.269352) (xy 23.356093 -165.305027) (xy 23.308487 -165.334081)
			(xy 23.257158 -165.355893) (xy 23.203201 -165.369999) (xy 23.147764 -165.376099) (xy 23.09203 -165.374062)
			(xy 23.037187 -165.363932) (xy 22.984403 -165.345925) (xy 22.934803 -165.320424) (xy 22.889445 -165.287973)
			(xy 22.849296 -165.249264) (xy 22.81521 -165.205121) (xy 22.787914 -165.156486) (xy 22.767991 -165.104395)
			(xy 22.755865 -165.049958) (xy 22.751794 -164.994336) (xy 18.940526 -164.994336) (xy 18.940526 -165.751256)
			(xy 20.741892 -165.751256) (xy 20.745963 -165.695634) (xy 20.758089 -165.641197) (xy 20.778012 -165.589106)
			(xy 20.805308 -165.540471) (xy 20.839394 -165.496328) (xy 20.879543 -165.457619) (xy 20.924901 -165.425168)
			(xy 20.974501 -165.399667) (xy 21.027285 -165.38166) (xy 21.082128 -165.37153) (xy 21.137862 -165.369493)
			(xy 21.193299 -165.375593) (xy 21.247256 -165.389699) (xy 21.298585 -165.411511) (xy 21.346191 -165.440565)
			(xy 21.389059 -165.47624) (xy 21.426276 -165.517777) (xy 21.457049 -165.56429) (xy 21.469681 -165.591236)
			(xy 30.677612 -165.591236) (xy 30.678089 -165.563983) (xy 30.685841 -165.510032) (xy 30.701194 -165.457733)
			(xy 30.723834 -165.408151) (xy 30.7533 -165.362297) (xy 30.788992 -165.321104) (xy 30.830184 -165.285409)
			(xy 30.876037 -165.255941) (xy 30.925618 -165.2333) (xy 30.977916 -165.217945) (xy 31.031867 -165.21019)
			(xy 31.05912 -165.209728) (xy 31.074876 -165.20987) (xy 31.106285 -165.21241) (xy 31.121858 -165.214808)
			(xy 31.136247 -165.216682) (xy 31.165042 -165.213223) (xy 31.191699 -165.2018) (xy 31.214065 -165.183337)
			(xy 31.230331 -165.159326) (xy 31.239182 -165.131707) (xy 31.239903 -165.102714) (xy 31.236666 -165.08857)
			(xy 31.230712 -165.064563) (xy 31.224341 -165.015512) (xy 31.223966 -164.99078) (xy 31.224477 -164.963529)
			(xy 31.232236 -164.909581) (xy 31.247594 -164.857286) (xy 31.270238 -164.80771) (xy 31.299707 -164.76186)
			(xy 31.335401 -164.720672) (xy 31.376594 -164.684982) (xy 31.422447 -164.655518) (xy 31.472026 -164.63288)
			(xy 31.524322 -164.617527) (xy 31.57827 -164.609774) (xy 31.632773 -164.609777) (xy 31.686721 -164.617537)
			(xy 31.739016 -164.632895) (xy 31.788592 -164.655539) (xy 31.834441 -164.685009) (xy 31.87563 -164.720703)
			(xy 31.911319 -164.761896) (xy 31.940783 -164.807748) (xy 31.963421 -164.857327) (xy 31.978773 -164.909624)
			(xy 31.986526 -164.963572) (xy 31.986523 -165.018075) (xy 31.978763 -165.072023) (xy 31.963404 -165.124318)
			(xy 31.94076 -165.173894) (xy 31.91129 -165.219743) (xy 31.875596 -165.260931) (xy 31.834403 -165.29662)
			(xy 31.78855 -165.326084) (xy 31.738971 -165.348722) (xy 31.686674 -165.364074) (xy 31.632726 -165.371827)
			(xy 31.605474 -165.372288) (xy 31.589718 -165.372146) (xy 31.558309 -165.369606) (xy 31.542736 -165.367208)
			(xy 31.528349 -165.365308) (xy 31.49955 -165.368769) (xy 31.472889 -165.380195) (xy 31.450522 -165.398663)
			(xy 31.434256 -165.422679) (xy 31.425406 -165.450303) (xy 31.424689 -165.4793) (xy 31.427928 -165.493446)
			(xy 31.433885 -165.517453) (xy 31.440254 -165.566504) (xy 31.440628 -165.591236) (xy 31.440072 -165.62106)
			(xy 31.430817 -165.679986) (xy 31.412508 -165.736754) (xy 31.385589 -165.789982) (xy 31.350717 -165.838374)
			(xy 31.330138 -165.859968) (xy 31.320921 -165.869896) (xy 31.307608 -165.893478) (xy 31.300954 -165.919729)
			(xy 31.301426 -165.946805) (xy 31.308991 -165.972808) (xy 31.323119 -165.995911) (xy 31.332678 -166.00551)
			(xy 31.351326 -166.023609) (xy 31.384039 -166.063986) (xy 31.410967 -166.108431) (xy 31.43161 -166.15612)
			(xy 31.445586 -166.206172) (xy 31.452637 -166.257657) (xy 31.453074 -166.28364) (xy 31.452588 -166.310891)
			(xy 31.444832 -166.364839) (xy 31.429477 -166.417134) (xy 31.406835 -166.466711) (xy 31.377369 -166.512561)
			(xy 31.341678 -166.553752) (xy 31.300487 -166.589443) (xy 31.254637 -166.618909) (xy 31.20506 -166.641551)
			(xy 31.152765 -166.656906) (xy 31.098817 -166.664662) (xy 31.044315 -166.664662) (xy 30.990367 -166.656906)
			(xy 30.938072 -166.641551) (xy 30.888495 -166.618909) (xy 30.842645 -166.589443) (xy 30.801454 -166.553752)
			(xy 30.765763 -166.512561) (xy 30.736297 -166.466711) (xy 30.713655 -166.417134) (xy 30.6983 -166.364839)
			(xy 30.690544 -166.310891) (xy 30.690058 -166.28364) (xy 30.690603 -166.253815) (xy 30.699861 -166.19489)
			(xy 30.718174 -166.138122) (xy 30.745094 -166.084894) (xy 30.779968 -166.036502) (xy 30.800548 -166.014908)
			(xy 30.809791 -166.005002) (xy 30.823104 -165.981413) (xy 30.829756 -165.955157) (xy 30.829279 -165.928075)
			(xy 30.821707 -165.902069) (xy 30.807572 -165.878964) (xy 30.798008 -165.869366) (xy 30.779346 -165.851282)
			(xy 30.746635 -165.810901) (xy 30.719709 -165.766453) (xy 30.699069 -165.71876) (xy 30.685095 -165.668707)
			(xy 30.678047 -165.61722) (xy 30.677612 -165.591236) (xy 21.469681 -165.591236) (xy 21.480721 -165.614787)
			(xy 21.496789 -165.668194) (xy 21.504909 -165.72337) (xy 21.505418 -165.751256) (xy 21.504909 -165.779142)
			(xy 21.496789 -165.834318) (xy 21.480721 -165.887725) (xy 21.457049 -165.938222) (xy 21.426276 -165.984735)
			(xy 21.389059 -166.026272) (xy 21.346191 -166.061947) (xy 21.298585 -166.091001) (xy 21.247256 -166.112813)
			(xy 21.193299 -166.126919) (xy 21.137862 -166.133019) (xy 21.082128 -166.130982) (xy 21.027285 -166.120852)
			(xy 20.974501 -166.102845) (xy 20.924901 -166.077344) (xy 20.879543 -166.044893) (xy 20.839394 -166.006184)
			(xy 20.805308 -165.962041) (xy 20.778012 -165.913406) (xy 20.758089 -165.861315) (xy 20.745963 -165.806878)
			(xy 20.741892 -165.751256) (xy 18.940526 -165.751256) (xy 18.940526 -166.25316) (xy 23.932132 -166.25316)
			(xy 23.936203 -166.197538) (xy 23.948329 -166.143101) (xy 23.968252 -166.09101) (xy 23.995548 -166.042375)
			(xy 24.029634 -165.998232) (xy 24.069783 -165.959523) (xy 24.115141 -165.927072) (xy 24.164741 -165.901571)
			(xy 24.217525 -165.883564) (xy 24.272368 -165.873434) (xy 24.328102 -165.871397) (xy 24.383539 -165.877497)
			(xy 24.437496 -165.891603) (xy 24.488825 -165.913415) (xy 24.536431 -165.942469) (xy 24.579299 -165.978144)
			(xy 24.616516 -166.019681) (xy 24.647289 -166.066194) (xy 24.670961 -166.116691) (xy 24.687029 -166.170098)
			(xy 24.695149 -166.225274) (xy 24.695658 -166.25316) (xy 24.695149 -166.281046) (xy 24.687029 -166.336222)
			(xy 24.670961 -166.389629) (xy 24.647289 -166.440126) (xy 24.616516 -166.486639) (xy 24.579299 -166.528176)
			(xy 24.536431 -166.563851) (xy 24.488825 -166.592905) (xy 24.437496 -166.614717) (xy 24.383539 -166.628823)
			(xy 24.328102 -166.634923) (xy 24.272368 -166.632886) (xy 24.217525 -166.622756) (xy 24.164741 -166.604749)
			(xy 24.115141 -166.579248) (xy 24.069783 -166.546797) (xy 24.029634 -166.508088) (xy 23.995548 -166.463945)
			(xy 23.968252 -166.41531) (xy 23.948329 -166.363219) (xy 23.936203 -166.308782) (xy 23.932132 -166.25316)
			(xy 18.940526 -166.25316) (xy 18.940526 -167.416046) (xy 20.000149 -167.416046) (xy 20.00015 -167.361539)
			(xy 20.007908 -167.307587) (xy 20.023266 -167.255288) (xy 20.04591 -167.205707) (xy 20.07538 -167.159853)
			(xy 20.111076 -167.118661) (xy 20.152271 -167.082967) (xy 20.198126 -167.0535) (xy 20.247708 -167.030858)
			(xy 20.300008 -167.015504) (xy 20.35396 -167.007748) (xy 20.381214 -167.007286) (xy 20.409833 -167.007814)
			(xy 20.46642 -167.016427) (xy 20.52109 -167.033384) (xy 20.547076 -167.045386) (xy 20.559384 -167.050937)
			(xy 20.585915 -167.055914) (xy 20.612823 -167.053761) (xy 20.638225 -167.044628) (xy 20.660345 -167.029155)
			(xy 20.677633 -167.008425) (xy 20.688882 -166.983886) (xy 20.693304 -166.957257) (xy 20.692364 -166.943786)
			(xy 20.690586 -166.906194) (xy 20.691062 -166.878942) (xy 20.698819 -166.824992) (xy 20.714176 -166.772695)
			(xy 20.736819 -166.723116) (xy 20.766287 -166.677264) (xy 20.801981 -166.636072) (xy 20.843174 -166.60038)
			(xy 20.889026 -166.570913) (xy 20.938606 -166.548272) (xy 20.990903 -166.532917) (xy 21.044854 -166.525161)
			(xy 21.099358 -166.525162) (xy 21.153308 -166.532919) (xy 21.205605 -166.548276) (xy 21.255184 -166.570919)
			(xy 21.301036 -166.600387) (xy 21.342228 -166.636081) (xy 21.37792 -166.677274) (xy 21.407387 -166.723126)
			(xy 21.430028 -166.772706) (xy 21.445383 -166.825003) (xy 21.453139 -166.878954) (xy 21.453138 -166.933458)
			(xy 21.445381 -166.987408) (xy 21.430024 -167.039705) (xy 21.407381 -167.089284) (xy 21.377913 -167.135136)
			(xy 21.342219 -167.176328) (xy 21.301026 -167.21202) (xy 21.255174 -167.241487) (xy 21.205594 -167.264128)
			(xy 21.153297 -167.279483) (xy 21.099346 -167.287239) (xy 21.072094 -167.287702) (xy 21.043475 -167.287173)
			(xy 20.986888 -167.27856) (xy 20.932218 -167.261604) (xy 20.906232 -167.249602) (xy 20.893916 -167.244072)
			(xy 20.867388 -167.239095) (xy 20.840484 -167.241247) (xy 20.815084 -167.250377) (xy 20.792967 -167.265846)
			(xy 20.775679 -167.286573) (xy 20.764429 -167.311108) (xy 20.760005 -167.337733) (xy 20.760944 -167.351202)
			(xy 20.762722 -167.388794) (xy 20.762251 -167.416048) (xy 20.754495 -167.47) (xy 20.739139 -167.522299)
			(xy 20.729234 -167.543988) (xy 23.966422 -167.543988) (xy 23.970493 -167.488366) (xy 23.982619 -167.433929)
			(xy 24.002542 -167.381838) (xy 24.029838 -167.333203) (xy 24.063924 -167.28906) (xy 24.104073 -167.250351)
			(xy 24.149431 -167.2179) (xy 24.199031 -167.192399) (xy 24.251815 -167.174392) (xy 24.306658 -167.164262)
			(xy 24.362392 -167.162225) (xy 24.417829 -167.168325) (xy 24.471786 -167.182431) (xy 24.523115 -167.204243)
			(xy 24.570721 -167.233297) (xy 24.613589 -167.268972) (xy 24.650806 -167.310509) (xy 24.681579 -167.357022)
			(xy 24.705251 -167.407519) (xy 24.721319 -167.460926) (xy 24.729439 -167.516102) (xy 24.729948 -167.543988)
			(xy 24.729439 -167.571874) (xy 24.721319 -167.62705) (xy 24.705251 -167.680457) (xy 24.681579 -167.730954)
			(xy 24.650806 -167.777467) (xy 24.613589 -167.819004) (xy 24.570721 -167.854679) (xy 24.523115 -167.883733)
			(xy 24.471786 -167.905545) (xy 24.417829 -167.919651) (xy 24.362392 -167.925751) (xy 24.306658 -167.923714)
			(xy 24.251815 -167.913584) (xy 24.199031 -167.895577) (xy 24.149431 -167.870076) (xy 24.104073 -167.837625)
			(xy 24.063924 -167.798916) (xy 24.029838 -167.754773) (xy 24.002542 -167.706138) (xy 23.982619 -167.654047)
			(xy 23.970493 -167.59961) (xy 23.966422 -167.543988) (xy 20.729234 -167.543988) (xy 20.716496 -167.571881)
			(xy 20.687028 -167.617736) (xy 20.651334 -167.65893) (xy 20.61014 -167.694625) (xy 20.564286 -167.724094)
			(xy 20.514704 -167.746737) (xy 20.462405 -167.762094) (xy 20.408453 -167.769851) (xy 20.353946 -167.769851)
			(xy 20.299993 -167.762093) (xy 20.247694 -167.746737) (xy 20.198113 -167.724093) (xy 20.152259 -167.694624)
			(xy 20.111065 -167.658929) (xy 20.075371 -167.617735) (xy 20.045903 -167.57188) (xy 20.023261 -167.522298)
			(xy 20.007905 -167.469999) (xy 20.000149 -167.416046) (xy 18.940526 -167.416046) (xy 18.940526 -168.126918)
			(xy 26.807412 -168.126918) (xy 26.811483 -168.071296) (xy 26.823609 -168.016859) (xy 26.843532 -167.964768)
			(xy 26.870828 -167.916133) (xy 26.904914 -167.87199) (xy 26.945063 -167.833281) (xy 26.990421 -167.80083)
			(xy 27.040021 -167.775329) (xy 27.092805 -167.757322) (xy 27.147648 -167.747192) (xy 27.203382 -167.745155)
			(xy 27.258819 -167.751255) (xy 27.312776 -167.765361) (xy 27.364105 -167.787173) (xy 27.411711 -167.816227)
			(xy 27.454579 -167.851902) (xy 27.491796 -167.893439) (xy 27.522569 -167.939952) (xy 27.545203 -167.988234)
			(xy 29.594808 -167.988234) (xy 29.598879 -167.932612) (xy 29.611005 -167.878175) (xy 29.630928 -167.826084)
			(xy 29.658224 -167.777449) (xy 29.69231 -167.733306) (xy 29.732459 -167.694597) (xy 29.777817 -167.662146)
			(xy 29.827417 -167.636645) (xy 29.880201 -167.618638) (xy 29.935044 -167.608508) (xy 29.990778 -167.606471)
			(xy 30.046215 -167.612571) (xy 30.100172 -167.626677) (xy 30.151501 -167.648489) (xy 30.199107 -167.677543)
			(xy 30.241975 -167.713218) (xy 30.279192 -167.754755) (xy 30.309965 -167.801268) (xy 30.333637 -167.851765)
			(xy 30.349705 -167.905172) (xy 30.357825 -167.960348) (xy 30.358334 -167.988234) (xy 30.357825 -168.01612)
			(xy 30.349705 -168.071296) (xy 30.333637 -168.124703) (xy 30.309965 -168.1752) (xy 30.279192 -168.221713)
			(xy 30.241975 -168.26325) (xy 30.199107 -168.298925) (xy 30.151501 -168.327979) (xy 30.100172 -168.349791)
			(xy 30.046215 -168.363897) (xy 29.990778 -168.369997) (xy 29.935044 -168.36796) (xy 29.880201 -168.35783)
			(xy 29.827417 -168.339823) (xy 29.777817 -168.314322) (xy 29.732459 -168.281871) (xy 29.69231 -168.243162)
			(xy 29.658224 -168.199019) (xy 29.630928 -168.150384) (xy 29.611005 -168.098293) (xy 29.598879 -168.043856)
			(xy 29.594808 -167.988234) (xy 27.545203 -167.988234) (xy 27.546241 -167.990449) (xy 27.562309 -168.043856)
			(xy 27.570429 -168.099032) (xy 27.570938 -168.126918) (xy 27.570429 -168.154804) (xy 27.562309 -168.20998)
			(xy 27.546241 -168.263387) (xy 27.522569 -168.313884) (xy 27.491796 -168.360397) (xy 27.454579 -168.401934)
			(xy 27.411711 -168.437609) (xy 27.364105 -168.466663) (xy 27.312776 -168.488475) (xy 27.258819 -168.502581)
			(xy 27.203382 -168.508681) (xy 27.147648 -168.506644) (xy 27.092805 -168.496514) (xy 27.040021 -168.478507)
			(xy 26.990421 -168.453006) (xy 26.945063 -168.420555) (xy 26.904914 -168.381846) (xy 26.870828 -168.337703)
			(xy 26.843532 -168.289068) (xy 26.823609 -168.236977) (xy 26.811483 -168.18254) (xy 26.807412 -168.126918)
			(xy 18.940526 -168.126918) (xy 18.940526 -168.15562) (xy 18.97761 -168.166034) (xy 19.003729 -168.173819)
			(xy 19.053413 -168.196221) (xy 19.099102 -168.225931) (xy 19.139732 -168.262255) (xy 19.174353 -168.304347)
			(xy 19.202156 -168.351221) (xy 19.222493 -168.401784) (xy 19.234888 -168.454856) (xy 19.239053 -168.509197)
			(xy 19.234889 -168.563538) (xy 19.222495 -168.616609) (xy 19.203486 -168.663874) (xy 19.969224 -168.663874)
			(xy 19.973295 -168.608252) (xy 19.985421 -168.553815) (xy 20.005344 -168.501724) (xy 20.03264 -168.453089)
			(xy 20.066726 -168.408946) (xy 20.106875 -168.370237) (xy 20.152233 -168.337786) (xy 20.201833 -168.312285)
			(xy 20.254617 -168.294278) (xy 20.30946 -168.284148) (xy 20.365194 -168.282111) (xy 20.420631 -168.288211)
			(xy 20.474588 -168.302317) (xy 20.525917 -168.324129) (xy 20.573523 -168.353183) (xy 20.616391 -168.388858)
			(xy 20.653608 -168.430395) (xy 20.684381 -168.476908) (xy 20.708053 -168.527405) (xy 20.724121 -168.580812)
			(xy 20.725168 -168.587928) (xy 24.769316 -168.587928) (xy 24.773387 -168.532306) (xy 24.785513 -168.477869)
			(xy 24.805436 -168.425778) (xy 24.832732 -168.377143) (xy 24.866818 -168.333) (xy 24.906967 -168.294291)
			(xy 24.952325 -168.26184) (xy 25.001925 -168.236339) (xy 25.054709 -168.218332) (xy 25.109552 -168.208202)
			(xy 25.165286 -168.206165) (xy 25.220723 -168.212265) (xy 25.27468 -168.226371) (xy 25.326009 -168.248183)
			(xy 25.373615 -168.277237) (xy 25.416483 -168.312912) (xy 25.4537 -168.354449) (xy 25.484473 -168.400962)
			(xy 25.508145 -168.451459) (xy 25.524213 -168.504866) (xy 25.532333 -168.560042) (xy 25.532842 -168.587928)
			(xy 25.532333 -168.615814) (xy 25.524213 -168.67099) (xy 25.508145 -168.724397) (xy 25.484473 -168.774894)
			(xy 25.4537 -168.821407) (xy 25.416483 -168.862944) (xy 25.373615 -168.898619) (xy 25.326009 -168.927673)
			(xy 25.27468 -168.949485) (xy 25.220723 -168.963591) (xy 25.165286 -168.969691) (xy 25.109552 -168.967654)
			(xy 25.054709 -168.957524) (xy 25.001925 -168.939517) (xy 24.952325 -168.914016) (xy 24.906967 -168.881565)
			(xy 24.866818 -168.842856) (xy 24.832732 -168.798713) (xy 24.805436 -168.750078) (xy 24.785513 -168.697987)
			(xy 24.773387 -168.64355) (xy 24.769316 -168.587928) (xy 20.725168 -168.587928) (xy 20.732241 -168.635988)
			(xy 20.73275 -168.663874) (xy 20.732241 -168.69176) (xy 20.724121 -168.746936) (xy 20.708053 -168.800343)
			(xy 20.684381 -168.85084) (xy 20.653608 -168.897353) (xy 20.616391 -168.93889) (xy 20.573523 -168.974565)
			(xy 20.525917 -169.003619) (xy 20.490399 -169.018712) (xy 20.763482 -169.018712) (xy 20.767553 -168.96309)
			(xy 20.779679 -168.908653) (xy 20.799602 -168.856562) (xy 20.826898 -168.807927) (xy 20.860984 -168.763784)
			(xy 20.901133 -168.725075) (xy 20.946491 -168.692624) (xy 20.996091 -168.667123) (xy 21.048875 -168.649116)
			(xy 21.103718 -168.638986) (xy 21.159452 -168.636949) (xy 21.214889 -168.643049) (xy 21.268846 -168.657155)
			(xy 21.320175 -168.678967) (xy 21.367781 -168.708021) (xy 21.410649 -168.743696) (xy 21.447866 -168.785233)
			(xy 21.478639 -168.831746) (xy 21.502311 -168.882243) (xy 21.518379 -168.93565) (xy 21.526499 -168.990826)
			(xy 21.527008 -169.018712) (xy 21.526499 -169.046598) (xy 21.51894 -169.09796) (xy 32.975802 -169.09796)
			(xy 32.979873 -169.042338) (xy 32.991999 -168.987901) (xy 33.011922 -168.93581) (xy 33.039218 -168.887175)
			(xy 33.073304 -168.843032) (xy 33.113453 -168.804323) (xy 33.158811 -168.771872) (xy 33.208411 -168.746371)
			(xy 33.261195 -168.728364) (xy 33.316038 -168.718234) (xy 33.371772 -168.716197) (xy 33.427209 -168.722297)
			(xy 33.481166 -168.736403) (xy 33.532495 -168.758215) (xy 33.580101 -168.787269) (xy 33.622969 -168.822944)
			(xy 33.660186 -168.864481) (xy 33.690959 -168.910994) (xy 33.714631 -168.961491) (xy 33.730699 -169.014898)
			(xy 33.738819 -169.070074) (xy 33.739328 -169.09796) (xy 33.738819 -169.125846) (xy 33.730699 -169.181022)
			(xy 33.714631 -169.234429) (xy 33.690959 -169.284926) (xy 33.660186 -169.331439) (xy 33.622969 -169.372976)
			(xy 33.580101 -169.408651) (xy 33.532495 -169.437705) (xy 33.481166 -169.459517) (xy 33.427209 -169.473623)
			(xy 33.371772 -169.479723) (xy 33.316038 -169.477686) (xy 33.261195 -169.467556) (xy 33.208411 -169.449549)
			(xy 33.158811 -169.424048) (xy 33.113453 -169.391597) (xy 33.073304 -169.352888) (xy 33.039218 -169.308745)
			(xy 33.011922 -169.26011) (xy 32.991999 -169.208019) (xy 32.979873 -169.153582) (xy 32.975802 -169.09796)
			(xy 21.51894 -169.09796) (xy 21.518379 -169.101774) (xy 21.502311 -169.155181) (xy 21.478639 -169.205678)
			(xy 21.447866 -169.252191) (xy 21.410649 -169.293728) (xy 21.367781 -169.329403) (xy 21.320175 -169.358457)
			(xy 21.268846 -169.380269) (xy 21.214889 -169.394375) (xy 21.159452 -169.400475) (xy 21.103718 -169.398438)
			(xy 21.048875 -169.388308) (xy 20.996091 -169.370301) (xy 20.946491 -169.3448) (xy 20.901133 -169.312349)
			(xy 20.860984 -169.27364) (xy 20.826898 -169.229497) (xy 20.799602 -169.180862) (xy 20.779679 -169.128771)
			(xy 20.767553 -169.074334) (xy 20.763482 -169.018712) (xy 20.490399 -169.018712) (xy 20.474588 -169.025431)
			(xy 20.420631 -169.039537) (xy 20.365194 -169.045637) (xy 20.30946 -169.0436) (xy 20.254617 -169.03347)
			(xy 20.201833 -169.015463) (xy 20.152233 -168.989962) (xy 20.106875 -168.957511) (xy 20.066726 -168.918802)
			(xy 20.03264 -168.874659) (xy 20.005344 -168.826024) (xy 19.985421 -168.773933) (xy 19.973295 -168.719496)
			(xy 19.969224 -168.663874) (xy 19.203486 -168.663874) (xy 19.202159 -168.667173) (xy 19.174356 -168.714048)
			(xy 19.139736 -168.75614) (xy 19.099107 -168.792465) (xy 19.053418 -168.822176) (xy 19.003736 -168.844579)
			(xy 18.97761 -168.852342) (xy 18.940526 -168.862756) (xy 18.940526 -169.240454) (xy 18.984976 -169.246042)
			(xy 19.012335 -169.24993) (xy 19.06562 -169.264572) (xy 19.116236 -169.286746) (xy 19.163125 -169.315989)
			(xy 19.205305 -169.351689) (xy 19.241895 -169.3931) (xy 19.27213 -169.439354) (xy 19.295378 -169.489486)
			(xy 19.311152 -169.542447) (xy 19.319122 -169.59713) (xy 19.319122 -169.65239) (xy 19.318744 -169.654982)
			(xy 19.972272 -169.654982) (xy 19.976343 -169.59936) (xy 19.988469 -169.544923) (xy 20.008392 -169.492832)
			(xy 20.035688 -169.444197) (xy 20.069774 -169.400054) (xy 20.109923 -169.361345) (xy 20.155281 -169.328894)
			(xy 20.204881 -169.303393) (xy 20.257665 -169.285386) (xy 20.312508 -169.275256) (xy 20.368242 -169.273219)
			(xy 20.423679 -169.279319) (xy 20.477636 -169.293425) (xy 20.528965 -169.315237) (xy 20.576571 -169.344291)
			(xy 20.619439 -169.379966) (xy 20.656656 -169.421503) (xy 20.687429 -169.468016) (xy 20.711101 -169.518513)
			(xy 20.727169 -169.57192) (xy 20.735289 -169.627096) (xy 20.735798 -169.654982) (xy 20.735289 -169.682868)
			(xy 20.727169 -169.738044) (xy 20.711101 -169.791451) (xy 20.687429 -169.841948) (xy 20.681898 -169.850308)
			(xy 21.073362 -169.850308) (xy 21.077433 -169.794686) (xy 21.089559 -169.740249) (xy 21.109482 -169.688158)
			(xy 21.136778 -169.639523) (xy 21.170864 -169.59538) (xy 21.211013 -169.556671) (xy 21.256371 -169.52422)
			(xy 21.305971 -169.498719) (xy 21.358755 -169.480712) (xy 21.413598 -169.470582) (xy 21.469332 -169.468545)
			(xy 21.524769 -169.474645) (xy 21.572365 -169.487088) (xy 25.88082 -169.487088) (xy 25.884891 -169.431466)
			(xy 25.897017 -169.377029) (xy 25.91694 -169.324938) (xy 25.944236 -169.276303) (xy 25.978322 -169.23216)
			(xy 26.018471 -169.193451) (xy 26.063829 -169.161) (xy 26.113429 -169.135499) (xy 26.166213 -169.117492)
			(xy 26.221056 -169.107362) (xy 26.27679 -169.105325) (xy 26.332227 -169.111425) (xy 26.386184 -169.125531)
			(xy 26.437513 -169.147343) (xy 26.485119 -169.176397) (xy 26.527987 -169.212072) (xy 26.565204 -169.253609)
			(xy 26.595977 -169.300122) (xy 26.619649 -169.350619) (xy 26.635717 -169.404026) (xy 26.643837 -169.459202)
			(xy 26.644346 -169.487088) (xy 26.643837 -169.514974) (xy 26.635717 -169.57015) (xy 26.619649 -169.623557)
			(xy 26.595977 -169.674054) (xy 26.565204 -169.720567) (xy 26.527987 -169.762104) (xy 26.485119 -169.797779)
			(xy 26.437513 -169.826833) (xy 26.386184 -169.848645) (xy 26.332227 -169.862751) (xy 26.27679 -169.868851)
			(xy 26.221056 -169.866814) (xy 26.166213 -169.856684) (xy 26.113429 -169.838677) (xy 26.063829 -169.813176)
			(xy 26.018471 -169.780725) (xy 25.978322 -169.742016) (xy 25.944236 -169.697873) (xy 25.91694 -169.649238)
			(xy 25.897017 -169.597147) (xy 25.884891 -169.54271) (xy 25.88082 -169.487088) (xy 21.572365 -169.487088)
			(xy 21.578726 -169.488751) (xy 21.630055 -169.510563) (xy 21.677661 -169.539617) (xy 21.720529 -169.575292)
			(xy 21.757746 -169.616829) (xy 21.788519 -169.663342) (xy 21.812191 -169.713839) (xy 21.828259 -169.767246)
			(xy 21.836379 -169.822422) (xy 21.836888 -169.850308) (xy 21.836379 -169.878194) (xy 21.828259 -169.93337)
			(xy 21.812191 -169.986777) (xy 21.788519 -170.037274) (xy 21.757746 -170.083787) (xy 21.720529 -170.125324)
			(xy 21.677661 -170.160999) (xy 21.630055 -170.190053) (xy 21.578726 -170.211865) (xy 21.524769 -170.225971)
			(xy 21.469332 -170.232071) (xy 21.413598 -170.230034) (xy 21.358755 -170.219904) (xy 21.305971 -170.201897)
			(xy 21.256371 -170.176396) (xy 21.211013 -170.143945) (xy 21.170864 -170.105236) (xy 21.136778 -170.061093)
			(xy 21.109482 -170.012458) (xy 21.089559 -169.960367) (xy 21.077433 -169.90593) (xy 21.073362 -169.850308)
			(xy 20.681898 -169.850308) (xy 20.656656 -169.888461) (xy 20.619439 -169.929998) (xy 20.576571 -169.965673)
			(xy 20.528965 -169.994727) (xy 20.477636 -170.016539) (xy 20.423679 -170.030645) (xy 20.368242 -170.036745)
			(xy 20.312508 -170.034708) (xy 20.257665 -170.024578) (xy 20.204881 -170.006571) (xy 20.155281 -169.98107)
			(xy 20.109923 -169.948619) (xy 20.069774 -169.90991) (xy 20.035688 -169.865767) (xy 20.008392 -169.817132)
			(xy 19.988469 -169.765041) (xy 19.976343 -169.710604) (xy 19.972272 -169.654982) (xy 19.318744 -169.654982)
			(xy 19.311152 -169.707072) (xy 19.295378 -169.760033) (xy 19.272131 -169.810165) (xy 19.241896 -169.85642)
			(xy 19.205306 -169.89783) (xy 19.163125 -169.93353) (xy 19.116237 -169.962773) (xy 19.065621 -169.984948)
			(xy 19.012336 -169.99959) (xy 18.984976 -170.00347) (xy 18.940526 -170.009058) (xy 18.940526 -170.67022)
			(xy 30.752032 -170.67022) (xy 30.756103 -170.614598) (xy 30.768229 -170.560161) (xy 30.788152 -170.50807)
			(xy 30.815448 -170.459435) (xy 30.849534 -170.415292) (xy 30.889683 -170.376583) (xy 30.935041 -170.344132)
			(xy 30.984641 -170.318631) (xy 31.037425 -170.300624) (xy 31.092268 -170.290494) (xy 31.148002 -170.288457)
			(xy 31.203439 -170.294557) (xy 31.257396 -170.308663) (xy 31.308725 -170.330475) (xy 31.356331 -170.359529)
			(xy 31.399199 -170.395204) (xy 31.436416 -170.436741) (xy 31.467189 -170.483254) (xy 31.490861 -170.533751)
			(xy 31.506929 -170.587158) (xy 31.515049 -170.642334) (xy 31.515558 -170.67022) (xy 31.515049 -170.698106)
			(xy 31.506929 -170.753282) (xy 31.490861 -170.806689) (xy 31.467189 -170.857186) (xy 31.436416 -170.903699)
			(xy 31.399199 -170.945236) (xy 31.356331 -170.980911) (xy 31.308725 -171.009965) (xy 31.257396 -171.031777)
			(xy 31.203439 -171.045883) (xy 31.148002 -171.051983) (xy 31.092268 -171.049946) (xy 31.037425 -171.039816)
			(xy 30.984641 -171.021809) (xy 30.935041 -170.996308) (xy 30.889683 -170.963857) (xy 30.849534 -170.925148)
			(xy 30.815448 -170.881005) (xy 30.788152 -170.83237) (xy 30.768229 -170.780279) (xy 30.756103 -170.725842)
			(xy 30.752032 -170.67022) (xy 18.940526 -170.67022) (xy 18.940526 -171.384468) (xy 18.94105 -171.399825)
			(xy 18.950175 -171.429153) (xy 18.967608 -171.45444) (xy 18.991773 -171.473399) (xy 19.020482 -171.484313)
			(xy 19.035776 -171.485814) (xy 19.056096 -171.465494) (xy 19.15414 -171.465494) (xy 19.15922 -171.465494)
			(xy 19.161506 -171.46524) (xy 32.071056 -171.46524) (xy 34.162492 -169.373804) (xy 34.162492 -164.878004)
			(xy 33.862264 -164.577776) (xy 33.84169 -164.556948) (xy 33.710626 -164.556948) (xy 33.69247 -164.576591)
			(xy 33.651607 -164.611105) (xy 33.606321 -164.639569) (xy 33.557501 -164.661424) (xy 33.506106 -164.676242)
			(xy 33.453144 -164.683732) (xy 33.4264 -164.684202) (xy 33.399149 -164.683716) (xy 33.345202 -164.67596)
			(xy 33.292908 -164.660605) (xy 33.243332 -164.637964) (xy 33.197482 -164.608498) (xy 33.156293 -164.572807)
			(xy 33.120602 -164.531618) (xy 33.091136 -164.485768) (xy 33.068495 -164.436192) (xy 33.05314 -164.383898)
			(xy 33.045384 -164.329951) (xy 33.045384 -164.275449) (xy 33.05314 -164.221502) (xy 33.068495 -164.169208)
			(xy 33.091136 -164.119632) (xy 33.120602 -164.073782) (xy 33.156293 -164.032593) (xy 33.197482 -163.996902)
			(xy 33.243332 -163.967436) (xy 33.292908 -163.944795) (xy 33.345202 -163.92944) (xy 33.399149 -163.921684)
			(xy 33.4264 -163.921186) (xy 33.453143 -163.921656) (xy 33.506099 -163.929164) (xy 33.557489 -163.943992)
			(xy 33.606305 -163.965848) (xy 33.651593 -163.994305) (xy 33.692464 -164.028805) (xy 33.710626 -164.04844)
			(xy 33.9471 -164.04844) (xy 34.05251 -164.04844) (xy 34.123122 -164.119052) (xy 34.123376 -164.119306)
			(xy 34.126932 -164.122862) (xy 34.596832 -164.592762) (xy 34.600388 -164.596318) (xy 34.600642 -164.596572)
			(xy 34.671254 -164.667184) (xy 34.671254 -164.765228) (xy 34.671254 -164.7698) (xy 34.671508 -164.772594)
			(xy 34.671508 -169.479214) (xy 34.671254 -169.482008) (xy 34.671254 -169.584624) (xy 34.600642 -169.655236)
			(xy 34.600388 -169.65549) (xy 34.596832 -169.659046) (xy 32.356298 -171.89958) (xy 32.352742 -171.903136)
			(xy 32.352488 -171.90339) (xy 32.281876 -171.974002) (xy 32.183832 -171.974002) (xy 32.17926 -171.974002)
			(xy 32.176466 -171.974256) (xy 19.266916 -171.974256) (xy 19.170904 -172.070268) (xy 18.940526 -172.300392)
			(xy 18.940526 -174.614586) (xy 18.762472 -174.79264) (xy 21.571964 -174.79264) (xy 21.576035 -174.737018)
			(xy 21.588161 -174.682581) (xy 21.608084 -174.63049) (xy 21.63538 -174.581855) (xy 21.669466 -174.537712)
			(xy 21.709615 -174.499003) (xy 21.754973 -174.466552) (xy 21.804573 -174.441051) (xy 21.857357 -174.423044)
			(xy 21.9122 -174.412914) (xy 21.967934 -174.410877) (xy 22.023371 -174.416977) (xy 22.077328 -174.431083)
			(xy 22.128657 -174.452895) (xy 22.176263 -174.481949) (xy 22.219131 -174.517624) (xy 22.256348 -174.559161)
			(xy 22.287121 -174.605674) (xy 22.310793 -174.656171) (xy 22.326861 -174.709578) (xy 22.334981 -174.764754)
			(xy 22.33549 -174.79264) (xy 22.334981 -174.820526) (xy 22.326861 -174.875702) (xy 22.314406 -174.9171)
			(xy 25.556462 -174.9171) (xy 25.560533 -174.861478) (xy 25.572659 -174.807041) (xy 25.592582 -174.75495)
			(xy 25.619878 -174.706315) (xy 25.653964 -174.662172) (xy 25.694113 -174.623463) (xy 25.739471 -174.591012)
			(xy 25.789071 -174.565511) (xy 25.841855 -174.547504) (xy 25.896698 -174.537374) (xy 25.952432 -174.535337)
			(xy 26.007869 -174.541437) (xy 26.061826 -174.555543) (xy 26.113155 -174.577355) (xy 26.160761 -174.606409)
			(xy 26.203629 -174.642084) (xy 26.240846 -174.683621) (xy 26.271619 -174.730134) (xy 26.295291 -174.780631)
			(xy 26.311359 -174.834038) (xy 26.319479 -174.889214) (xy 26.319988 -174.9171) (xy 26.319479 -174.944986)
			(xy 26.311359 -175.000162) (xy 26.295291 -175.053569) (xy 26.271619 -175.104066) (xy 26.240846 -175.150579)
			(xy 26.203629 -175.192116) (xy 26.160761 -175.227791) (xy 26.113155 -175.256845) (xy 26.061826 -175.278657)
			(xy 26.007869 -175.292763) (xy 25.952432 -175.298863) (xy 25.896698 -175.296826) (xy 25.841855 -175.286696)
			(xy 25.789071 -175.268689) (xy 25.739471 -175.243188) (xy 25.694113 -175.210737) (xy 25.653964 -175.172028)
			(xy 25.619878 -175.127885) (xy 25.592582 -175.07925) (xy 25.572659 -175.027159) (xy 25.560533 -174.972722)
			(xy 25.556462 -174.9171) (xy 22.314406 -174.9171) (xy 22.310793 -174.929109) (xy 22.287121 -174.979606)
			(xy 22.256348 -175.026119) (xy 22.219131 -175.067656) (xy 22.176263 -175.103331) (xy 22.128657 -175.132385)
			(xy 22.077328 -175.154197) (xy 22.023371 -175.168303) (xy 21.967934 -175.174403) (xy 21.9122 -175.172366)
			(xy 21.857357 -175.162236) (xy 21.804573 -175.144229) (xy 21.754973 -175.118728) (xy 21.709615 -175.086277)
			(xy 21.669466 -175.047568) (xy 21.63538 -175.003425) (xy 21.608084 -174.95479) (xy 21.588161 -174.902699)
			(xy 21.576035 -174.848262) (xy 21.571964 -174.79264) (xy 18.762472 -174.79264) (xy 18.344896 -175.210216)
			(xy 20.264372 -175.210216) (xy 20.268443 -175.154594) (xy 20.280569 -175.100157) (xy 20.300492 -175.048066)
			(xy 20.327788 -174.999431) (xy 20.361874 -174.955288) (xy 20.402023 -174.916579) (xy 20.447381 -174.884128)
			(xy 20.496981 -174.858627) (xy 20.549765 -174.84062) (xy 20.604608 -174.83049) (xy 20.660342 -174.828453)
			(xy 20.715779 -174.834553) (xy 20.769736 -174.848659) (xy 20.821065 -174.870471) (xy 20.868671 -174.899525)
			(xy 20.911539 -174.9352) (xy 20.948756 -174.976737) (xy 20.979529 -175.02325) (xy 21.003201 -175.073747)
			(xy 21.019269 -175.127154) (xy 21.027389 -175.18233) (xy 21.027898 -175.210216) (xy 21.027389 -175.238102)
			(xy 21.019269 -175.293278) (xy 21.003201 -175.346685) (xy 20.979529 -175.397182) (xy 20.948756 -175.443695)
			(xy 20.911539 -175.485232) (xy 20.868671 -175.520907) (xy 20.821065 -175.549961) (xy 20.769736 -175.571773)
			(xy 20.715779 -175.585879) (xy 20.660342 -175.591979) (xy 20.604608 -175.589942) (xy 20.549765 -175.579812)
			(xy 20.496981 -175.561805) (xy 20.447381 -175.536304) (xy 20.402023 -175.503853) (xy 20.361874 -175.465144)
			(xy 20.327788 -175.421001) (xy 20.300492 -175.372366) (xy 20.280569 -175.320275) (xy 20.268443 -175.265838)
			(xy 20.264372 -175.210216) (xy 18.344896 -175.210216) (xy 17.721072 -175.83404) (xy 23.37714 -175.83404)
			(xy 23.381229 -175.778158) (xy 23.393412 -175.723468) (xy 23.413428 -175.671134) (xy 23.440851 -175.622272)
			(xy 23.475096 -175.577924) (xy 23.515432 -175.539034) (xy 23.561002 -175.506432) (xy 23.610833 -175.480813)
			(xy 23.663863 -175.462721) (xy 23.718961 -175.452544) (xy 23.774955 -175.450498) (xy 23.83065 -175.456626)
			(xy 23.884859 -175.470798) (xy 23.936427 -175.492712) (xy 23.984255 -175.521901) (xy 24.027323 -175.557742)
			(xy 24.064713 -175.599472) (xy 24.095629 -175.646202) (xy 24.119412 -175.696935) (xy 24.135554 -175.750591)
			(xy 24.141855 -175.7934) (xy 25.541222 -175.7934) (xy 25.545293 -175.737778) (xy 25.557419 -175.683341)
			(xy 25.577342 -175.63125) (xy 25.604638 -175.582615) (xy 25.638724 -175.538472) (xy 25.678873 -175.499763)
			(xy 25.724231 -175.467312) (xy 25.773831 -175.441811) (xy 25.826615 -175.423804) (xy 25.881458 -175.413674)
			(xy 25.937192 -175.411637) (xy 25.992629 -175.417737) (xy 26.046586 -175.431843) (xy 26.097915 -175.453655)
			(xy 26.145521 -175.482709) (xy 26.156993 -175.492256) (xy 35.295733 -175.492256) (xy 35.295733 -175.437744)
			(xy 35.303491 -175.383786) (xy 35.31885 -175.331482) (xy 35.341497 -175.281896) (xy 35.370971 -175.236039)
			(xy 35.406671 -175.194842) (xy 35.447871 -175.159147) (xy 35.493731 -175.129678) (xy 35.54332 -175.107036)
			(xy 35.595625 -175.091683) (xy 35.649584 -175.08393) (xy 35.67684 -175.08347) (xy 35.70421 -175.083954)
			(xy 35.758389 -175.091765) (xy 35.810892 -175.107249) (xy 35.86064 -175.130087) (xy 35.906607 -175.159809)
			(xy 35.927538 -175.17745) (xy 35.938866 -175.186686) (xy 35.965423 -175.198862) (xy 35.99434 -175.203035)
			(xy 36.023257 -175.198862) (xy 36.049814 -175.186686) (xy 36.061142 -175.17745) (xy 36.082092 -175.159832)
			(xy 36.128059 -175.130116) (xy 36.177802 -175.107275) (xy 36.230299 -175.091779) (xy 36.284472 -175.083946)
			(xy 36.31184 -175.08347) (xy 36.339088 -175.084003) (xy 36.393028 -175.091764) (xy 36.445315 -175.107121)
			(xy 36.494884 -175.129763) (xy 36.540727 -175.159229) (xy 36.58191 -175.194918) (xy 36.617595 -175.236105)
			(xy 36.647056 -175.281951) (xy 36.669693 -175.331523) (xy 36.685045 -175.383811) (xy 36.6928 -175.437752)
			(xy 36.6928 -175.492248) (xy 36.685045 -175.546189) (xy 36.669693 -175.598477) (xy 36.647056 -175.648049)
			(xy 36.617595 -175.693895) (xy 36.58191 -175.735082) (xy 36.540727 -175.770771) (xy 36.494884 -175.800237)
			(xy 36.445315 -175.822879) (xy 36.393028 -175.838236) (xy 36.339088 -175.845997) (xy 36.31184 -175.846486)
			(xy 36.28447 -175.846) (xy 36.230292 -175.838187) (xy 36.177789 -175.822703) (xy 36.128042 -175.799866)
			(xy 36.082074 -175.770145) (xy 36.061142 -175.752506) (xy 36.049814 -175.74327) (xy 36.023257 -175.731094)
			(xy 35.99434 -175.726921) (xy 35.965423 -175.731094) (xy 35.938866 -175.74327) (xy 35.927538 -175.752506)
			(xy 35.906603 -175.770142) (xy 35.860631 -175.799854) (xy 35.810884 -175.82269) (xy 35.758384 -175.838182)
			(xy 35.704209 -175.846011) (xy 35.67684 -175.846486) (xy 35.649584 -175.84607) (xy 35.595625 -175.838317)
			(xy 35.54332 -175.822964) (xy 35.493731 -175.800322) (xy 35.447871 -175.770853) (xy 35.406671 -175.735158)
			(xy 35.370971 -175.693961) (xy 35.341497 -175.648104) (xy 35.31885 -175.598518) (xy 35.303491 -175.546214)
			(xy 35.295733 -175.492256) (xy 26.156993 -175.492256) (xy 26.188389 -175.518384) (xy 26.225606 -175.559921)
			(xy 26.256379 -175.606434) (xy 26.280051 -175.656931) (xy 26.296119 -175.710338) (xy 26.304239 -175.765514)
			(xy 26.304748 -175.7934) (xy 26.304239 -175.821286) (xy 26.296119 -175.876462) (xy 26.280051 -175.929869)
			(xy 26.256379 -175.980366) (xy 26.225606 -176.026879) (xy 26.188389 -176.068416) (xy 26.145521 -176.104091)
			(xy 26.097915 -176.133145) (xy 26.046586 -176.154957) (xy 25.992629 -176.169063) (xy 25.937192 -176.175163)
			(xy 25.881458 -176.173126) (xy 25.826615 -176.162996) (xy 25.773831 -176.144989) (xy 25.724231 -176.119488)
			(xy 25.678873 -176.087037) (xy 25.638724 -176.048328) (xy 25.604638 -176.004185) (xy 25.577342 -175.95555)
			(xy 25.557419 -175.903459) (xy 25.545293 -175.849022) (xy 25.541222 -175.7934) (xy 24.141855 -175.7934)
			(xy 24.143713 -175.806025) (xy 24.144224 -175.83404) (xy 24.143713 -175.862055) (xy 24.135554 -175.917489)
			(xy 24.119412 -175.971145) (xy 24.095629 -176.021878) (xy 24.064713 -176.068608) (xy 24.027323 -176.110338)
			(xy 23.984255 -176.146179) (xy 23.936427 -176.175368) (xy 23.923164 -176.181004) (xy 51.225448 -176.181004)
			(xy 51.229519 -176.125382) (xy 51.241645 -176.070945) (xy 51.261568 -176.018854) (xy 51.288864 -175.970219)
			(xy 51.32295 -175.926076) (xy 51.363099 -175.887367) (xy 51.408457 -175.854916) (xy 51.458057 -175.829415)
			(xy 51.510841 -175.811408) (xy 51.565684 -175.801278) (xy 51.621418 -175.799241) (xy 51.676855 -175.805341)
			(xy 51.730812 -175.819447) (xy 51.782141 -175.841259) (xy 51.829747 -175.870313) (xy 51.872615 -175.905988)
			(xy 51.909832 -175.947525) (xy 51.940605 -175.994038) (xy 51.964277 -176.044535) (xy 51.980345 -176.097942)
			(xy 51.988465 -176.153118) (xy 51.988974 -176.181004) (xy 51.988928 -176.183544) (xy 52.231542 -176.183544)
			(xy 52.235613 -176.127922) (xy 52.247739 -176.073485) (xy 52.267662 -176.021394) (xy 52.294958 -175.972759)
			(xy 52.329044 -175.928616) (xy 52.369193 -175.889907) (xy 52.414551 -175.857456) (xy 52.464151 -175.831955)
			(xy 52.516935 -175.813948) (xy 52.571778 -175.803818) (xy 52.627512 -175.801781) (xy 52.682949 -175.807881)
			(xy 52.736906 -175.821987) (xy 52.788235 -175.843799) (xy 52.835841 -175.872853) (xy 52.878709 -175.908528)
			(xy 52.915926 -175.950065) (xy 52.946699 -175.996578) (xy 52.970371 -176.047075) (xy 52.986439 -176.100482)
			(xy 52.994559 -176.155658) (xy 52.995068 -176.183544) (xy 52.994559 -176.21143) (xy 52.986439 -176.266606)
			(xy 52.970371 -176.320013) (xy 52.946699 -176.37051) (xy 52.915926 -176.417023) (xy 52.878709 -176.45856)
			(xy 52.835841 -176.494235) (xy 52.788235 -176.523289) (xy 52.736906 -176.545101) (xy 52.682949 -176.559207)
			(xy 52.627512 -176.565307) (xy 52.571778 -176.56327) (xy 52.516935 -176.55314) (xy 52.464151 -176.535133)
			(xy 52.414551 -176.509632) (xy 52.369193 -176.477181) (xy 52.329044 -176.438472) (xy 52.294958 -176.394329)
			(xy 52.267662 -176.345694) (xy 52.247739 -176.293603) (xy 52.235613 -176.239166) (xy 52.231542 -176.183544)
			(xy 51.988928 -176.183544) (xy 51.988465 -176.20889) (xy 51.980345 -176.264066) (xy 51.964277 -176.317473)
			(xy 51.940605 -176.36797) (xy 51.909832 -176.414483) (xy 51.872615 -176.45602) (xy 51.829747 -176.491695)
			(xy 51.782141 -176.520749) (xy 51.730812 -176.542561) (xy 51.676855 -176.556667) (xy 51.621418 -176.562767)
			(xy 51.565684 -176.56073) (xy 51.510841 -176.5506) (xy 51.458057 -176.532593) (xy 51.408457 -176.507092)
			(xy 51.363099 -176.474641) (xy 51.32295 -176.435932) (xy 51.288864 -176.391789) (xy 51.261568 -176.343154)
			(xy 51.241645 -176.291063) (xy 51.229519 -176.236626) (xy 51.225448 -176.181004) (xy 23.923164 -176.181004)
			(xy 23.884859 -176.197282) (xy 23.83065 -176.211454) (xy 23.774955 -176.217582) (xy 23.718961 -176.215536)
			(xy 23.663863 -176.205359) (xy 23.610833 -176.187267) (xy 23.561002 -176.161648) (xy 23.515432 -176.129046)
			(xy 23.475096 -176.090156) (xy 23.440851 -176.045808) (xy 23.413428 -175.996946) (xy 23.393412 -175.944612)
			(xy 23.381229 -175.889922) (xy 23.37714 -175.83404) (xy 17.721072 -175.83404) (xy 16.363696 -177.191416)
			(xy 20.962872 -177.191416) (xy 20.966943 -177.135794) (xy 20.979069 -177.081357) (xy 20.998992 -177.029266)
			(xy 21.026288 -176.980631) (xy 21.060374 -176.936488) (xy 21.100523 -176.897779) (xy 21.145881 -176.865328)
			(xy 21.195481 -176.839827) (xy 21.248265 -176.82182) (xy 21.303108 -176.81169) (xy 21.358842 -176.809653)
			(xy 21.414279 -176.815753) (xy 21.468236 -176.829859) (xy 21.519565 -176.851671) (xy 21.567171 -176.880725)
			(xy 21.610039 -176.9164) (xy 21.647256 -176.957937) (xy 21.678029 -177.00445) (xy 21.701701 -177.054947)
			(xy 21.716624 -177.104548) (xy 25.632662 -177.104548) (xy 25.636733 -177.048926) (xy 25.648859 -176.994489)
			(xy 25.668782 -176.942398) (xy 25.696078 -176.893763) (xy 25.730164 -176.84962) (xy 25.770313 -176.810911)
			(xy 25.815671 -176.77846) (xy 25.865271 -176.752959) (xy 25.918055 -176.734952) (xy 25.972898 -176.724822)
			(xy 26.028632 -176.722785) (xy 26.084069 -176.728885) (xy 26.138026 -176.742991) (xy 26.189355 -176.764803)
			(xy 26.236961 -176.793857) (xy 26.279829 -176.829532) (xy 26.317046 -176.871069) (xy 26.347819 -176.917582)
			(xy 26.353804 -176.930349) (xy 49.335704 -176.930349) (xy 49.335704 -176.875851) (xy 49.34346 -176.821908)
			(xy 49.358813 -176.769618) (xy 49.381452 -176.720045) (xy 49.410916 -176.674198) (xy 49.446604 -176.633011)
			(xy 49.48779 -176.597322) (xy 49.533636 -176.567857) (xy 49.583208 -176.545217) (xy 49.635498 -176.529862)
			(xy 49.689441 -176.522105) (xy 49.71669 -176.521618) (xy 49.74406 -176.522086) (xy 49.798239 -176.529902)
			(xy 49.850743 -176.545391) (xy 49.90049 -176.568232) (xy 49.946456 -176.597957) (xy 49.967388 -176.615598)
			(xy 49.978716 -176.624834) (xy 50.005273 -176.63701) (xy 50.03419 -176.641183) (xy 50.063107 -176.63701)
			(xy 50.089664 -176.624834) (xy 50.100992 -176.615598) (xy 50.121925 -176.597957) (xy 50.167893 -176.568233)
			(xy 50.217639 -176.545387) (xy 50.270141 -176.529891) (xy 50.324319 -176.522062) (xy 50.379061 -176.522062)
			(xy 50.433239 -176.529891) (xy 50.485741 -176.545387) (xy 50.535487 -176.568233) (xy 50.581455 -176.597957)
			(xy 50.602388 -176.615598) (xy 50.613716 -176.624834) (xy 50.640273 -176.63701) (xy 50.66919 -176.641183)
			(xy 50.698107 -176.63701) (xy 50.724664 -176.624834) (xy 50.735992 -176.615598) (xy 50.756916 -176.597949)
			(xy 50.802891 -176.568239) (xy 50.852641 -176.545405) (xy 50.905143 -176.529916) (xy 50.95932 -176.52209)
			(xy 50.98669 -176.521618) (xy 51.013944 -176.522065) (xy 51.067897 -176.529821) (xy 51.120196 -176.545177)
			(xy 51.169778 -176.56782) (xy 51.215633 -176.59729) (xy 51.256826 -176.632985) (xy 51.29252 -176.67418)
			(xy 51.321987 -176.720036) (xy 51.344629 -176.769619) (xy 51.359982 -176.821919) (xy 51.367736 -176.875872)
			(xy 51.368198 -176.903126) (xy 51.367748 -176.930497) (xy 51.359926 -176.984677) (xy 51.344433 -177.03718)
			(xy 51.321588 -177.086926) (xy 51.291861 -177.132893) (xy 51.274218 -177.153824) (xy 51.264955 -177.165132)
			(xy 51.252778 -177.191696) (xy 51.24861 -177.22062) (xy 51.252789 -177.249541) (xy 51.264976 -177.276101)
			(xy 51.274218 -177.287428) (xy 51.29184 -177.308374) (xy 51.321553 -177.354343) (xy 51.344392 -177.404087)
			(xy 51.359888 -177.456585) (xy 51.367721 -177.510758) (xy 51.368198 -177.538126) (xy 51.367746 -177.565378)
			(xy 51.359986 -177.619328) (xy 51.344627 -177.671624) (xy 51.321982 -177.721202) (xy 51.292512 -177.767053)
			(xy 51.256817 -177.808243) (xy 51.215624 -177.843934) (xy 51.16977 -177.873399) (xy 51.12019 -177.89604)
			(xy 51.067893 -177.911394) (xy 51.013942 -177.919149) (xy 50.98669 -177.919634) (xy 50.959319 -177.91919)
			(xy 50.905138 -177.911369) (xy 50.852634 -177.895876) (xy 50.802888 -177.873029) (xy 50.756922 -177.843298)
			(xy 50.735992 -177.825654) (xy 50.724664 -177.816418) (xy 50.698107 -177.804242) (xy 50.66919 -177.800069)
			(xy 50.640273 -177.804242) (xy 50.613716 -177.816418) (xy 50.602388 -177.825654) (xy 50.581428 -177.843258)
			(xy 50.535463 -177.872977) (xy 50.485723 -177.89582) (xy 50.433228 -177.911319) (xy 50.379057 -177.919156)
			(xy 50.35169 -177.919634) (xy 50.32444 -177.919132) (xy 50.270494 -177.911374) (xy 50.218201 -177.896019)
			(xy 50.168626 -177.873379) (xy 50.122776 -177.843914) (xy 50.081587 -177.808224) (xy 50.045896 -177.767036)
			(xy 50.016429 -177.721189) (xy 49.993786 -177.671614) (xy 49.978429 -177.619322) (xy 49.97067 -177.565376)
			(xy 49.970182 -177.538126) (xy 49.970663 -177.511891) (xy 49.977854 -177.459916) (xy 49.992105 -177.409419)
			(xy 50.013145 -177.361352) (xy 50.040578 -177.316625) (xy 50.073885 -177.276082) (xy 50.092864 -177.257964)
			(xy 50.100207 -177.250412) (xy 50.108638 -177.231137) (xy 50.108646 -177.210098) (xy 50.100228 -177.190817)
			(xy 50.092864 -177.183288) (xy 50.071528 -177.161952) (xy 50.063999 -177.15458) (xy 50.044714 -177.146149)
			(xy 50.023666 -177.146149) (xy 50.004381 -177.15458) (xy 49.996852 -177.161952) (xy 49.978741 -177.180941)
			(xy 49.938201 -177.214257) (xy 49.893474 -177.241698) (xy 49.845406 -177.262746) (xy 49.794905 -177.277002)
			(xy 49.742927 -177.284197) (xy 49.71669 -177.284634) (xy 49.689441 -177.284095) (xy 49.635498 -177.276338)
			(xy 49.583208 -177.260983) (xy 49.533636 -177.238343) (xy 49.48779 -177.208878) (xy 49.446604 -177.173189)
			(xy 49.410916 -177.132002) (xy 49.381452 -177.086155) (xy 49.358813 -177.036582) (xy 49.34346 -176.984292)
			(xy 49.335704 -176.930349) (xy 26.353804 -176.930349) (xy 26.371491 -176.968079) (xy 26.387559 -177.021486)
			(xy 26.395679 -177.076662) (xy 26.396188 -177.104548) (xy 26.395679 -177.132434) (xy 26.387559 -177.18761)
			(xy 26.371491 -177.241017) (xy 26.347819 -177.291514) (xy 26.317046 -177.338027) (xy 26.279829 -177.379564)
			(xy 26.236961 -177.415239) (xy 26.189355 -177.444293) (xy 26.138026 -177.466105) (xy 26.084069 -177.480211)
			(xy 26.028632 -177.486311) (xy 25.972898 -177.484274) (xy 25.918055 -177.474144) (xy 25.865271 -177.456137)
			(xy 25.815671 -177.430636) (xy 25.770313 -177.398185) (xy 25.730164 -177.359476) (xy 25.696078 -177.315333)
			(xy 25.668782 -177.266698) (xy 25.648859 -177.214607) (xy 25.636733 -177.16017) (xy 25.632662 -177.104548)
			(xy 21.716624 -177.104548) (xy 21.717769 -177.108354) (xy 21.725889 -177.16353) (xy 21.726398 -177.191416)
			(xy 21.725889 -177.219302) (xy 21.717769 -177.274478) (xy 21.701701 -177.327885) (xy 21.678029 -177.378382)
			(xy 21.647256 -177.424895) (xy 21.610039 -177.466432) (xy 21.567171 -177.502107) (xy 21.519565 -177.531161)
			(xy 21.468236 -177.552973) (xy 21.414279 -177.567079) (xy 21.358842 -177.573179) (xy 21.303108 -177.571142)
			(xy 21.248265 -177.561012) (xy 21.195481 -177.543005) (xy 21.145881 -177.517504) (xy 21.100523 -177.485053)
			(xy 21.060374 -177.446344) (xy 21.026288 -177.402201) (xy 20.998992 -177.353566) (xy 20.979069 -177.301475)
			(xy 20.966943 -177.247038) (xy 20.962872 -177.191416) (xy 16.363696 -177.191416) (xy 15.809468 -177.745644)
			(xy 24.330912 -177.745644) (xy 24.334983 -177.690022) (xy 24.347109 -177.635585) (xy 24.367032 -177.583494)
			(xy 24.394328 -177.534859) (xy 24.428414 -177.490716) (xy 24.468563 -177.452007) (xy 24.513921 -177.419556)
			(xy 24.563521 -177.394055) (xy 24.616305 -177.376048) (xy 24.671148 -177.365918) (xy 24.726882 -177.363881)
			(xy 24.782319 -177.369981) (xy 24.836276 -177.384087) (xy 24.887605 -177.405899) (xy 24.935211 -177.434953)
			(xy 24.978079 -177.470628) (xy 25.015296 -177.512165) (xy 25.023956 -177.525254) (xy 35.243449 -177.525254)
			(xy 35.243449 -177.470746) (xy 35.251207 -177.416793) (xy 35.266564 -177.364493) (xy 35.289208 -177.314911)
			(xy 35.318678 -177.269056) (xy 35.354374 -177.227863) (xy 35.395569 -177.192168) (xy 35.441425 -177.1627)
			(xy 35.491008 -177.140058) (xy 35.543308 -177.124704) (xy 35.597262 -177.116948) (xy 35.624516 -177.116486)
			(xy 35.651886 -177.116946) (xy 35.706066 -177.124766) (xy 35.758569 -177.140257) (xy 35.808315 -177.163099)
			(xy 35.854282 -177.192825) (xy 35.875214 -177.210466) (xy 35.886542 -177.219702) (xy 35.913099 -177.231878)
			(xy 35.942016 -177.236051) (xy 35.970933 -177.231878) (xy 35.99749 -177.219702) (xy 36.008818 -177.210466)
			(xy 36.029766 -177.192847) (xy 36.075735 -177.163133) (xy 36.125478 -177.140294) (xy 36.177975 -177.124798)
			(xy 36.232148 -177.116964) (xy 36.259516 -177.116486) (xy 36.286766 -177.116985) (xy 36.340711 -177.124743)
			(xy 36.393003 -177.140099) (xy 36.442578 -177.162741) (xy 36.488425 -177.192207) (xy 36.529613 -177.227898)
			(xy 36.565302 -177.269087) (xy 36.594767 -177.314936) (xy 36.617406 -177.364512) (xy 36.63276 -177.416804)
			(xy 36.640516 -177.47075) (xy 36.640516 -177.52525) (xy 36.63276 -177.579196) (xy 36.617406 -177.631488)
			(xy 36.594767 -177.681064) (xy 36.565302 -177.726913) (xy 36.529613 -177.768102) (xy 36.488425 -177.803793)
			(xy 36.442578 -177.833259) (xy 36.393003 -177.855901) (xy 36.340711 -177.871257) (xy 36.286766 -177.879015)
			(xy 36.259516 -177.879502) (xy 36.232146 -177.879026) (xy 36.177967 -177.871211) (xy 36.125464 -177.855724)
			(xy 36.075717 -177.832884) (xy 36.02975 -177.803162) (xy 36.008818 -177.785522) (xy 35.99749 -177.776286)
			(xy 35.970933 -177.76411) (xy 35.942016 -177.759937) (xy 35.913099 -177.76411) (xy 35.886542 -177.776286)
			(xy 35.875214 -177.785522) (xy 35.85429 -177.803171) (xy 35.808315 -177.832881) (xy 35.758565 -177.855715)
			(xy 35.706063 -177.871203) (xy 35.651886 -177.879029) (xy 35.624516 -177.879502) (xy 35.597262 -177.879052)
			(xy 35.543308 -177.871296) (xy 35.491008 -177.855942) (xy 35.441425 -177.8333) (xy 35.395569 -177.803832)
			(xy 35.354374 -177.768137) (xy 35.318678 -177.726944) (xy 35.289208 -177.681089) (xy 35.266564 -177.631507)
			(xy 35.251207 -177.579207) (xy 35.243449 -177.525254) (xy 25.023956 -177.525254) (xy 25.046069 -177.558678)
			(xy 25.069741 -177.609175) (xy 25.085809 -177.662582) (xy 25.093929 -177.717758) (xy 25.094438 -177.745644)
			(xy 25.093929 -177.77353) (xy 25.085809 -177.828706) (xy 25.069741 -177.882113) (xy 25.046069 -177.93261)
			(xy 25.015296 -177.979123) (xy 24.978079 -178.02066) (xy 24.935211 -178.056335) (xy 24.887605 -178.085389)
			(xy 24.836276 -178.107201) (xy 24.782319 -178.121307) (xy 24.726882 -178.127407) (xy 24.671148 -178.12537)
			(xy 24.616305 -178.11524) (xy 24.563521 -178.097233) (xy 24.513921 -178.071732) (xy 24.468563 -178.039281)
			(xy 24.428414 -178.000572) (xy 24.394328 -177.956429) (xy 24.367032 -177.907794) (xy 24.347109 -177.855703)
			(xy 24.334983 -177.801266) (xy 24.330912 -177.745644) (xy 15.809468 -177.745644) (xy 15.289784 -178.265328)
			(xy 19.450302 -178.265328) (xy 19.454373 -178.209706) (xy 19.466499 -178.155269) (xy 19.486422 -178.103178)
			(xy 19.513718 -178.054543) (xy 19.547804 -178.0104) (xy 19.587953 -177.971691) (xy 19.633311 -177.93924)
			(xy 19.682911 -177.913739) (xy 19.735695 -177.895732) (xy 19.790538 -177.885602) (xy 19.846272 -177.883565)
			(xy 19.901709 -177.889665) (xy 19.955666 -177.903771) (xy 20.006995 -177.925583) (xy 20.054601 -177.954637)
			(xy 20.097469 -177.990312) (xy 20.134686 -178.031849) (xy 20.165459 -178.078362) (xy 20.189131 -178.128859)
			(xy 20.205199 -178.182266) (xy 20.213319 -178.237442) (xy 20.213828 -178.265328) (xy 20.213319 -178.293214)
			(xy 20.205199 -178.34839) (xy 20.189131 -178.401797) (xy 20.165459 -178.452294) (xy 20.134686 -178.498807)
			(xy 20.097469 -178.540344) (xy 20.054601 -178.576019) (xy 20.006995 -178.605073) (xy 19.955666 -178.626885)
			(xy 19.901709 -178.640991) (xy 19.846272 -178.647091) (xy 19.790538 -178.645054) (xy 19.735695 -178.634924)
			(xy 19.682911 -178.616917) (xy 19.633311 -178.591416) (xy 19.587953 -178.558965) (xy 19.547804 -178.520256)
			(xy 19.513718 -178.476113) (xy 19.486422 -178.427478) (xy 19.466499 -178.375387) (xy 19.454373 -178.32095)
			(xy 19.450302 -178.265328) (xy 15.289784 -178.265328) (xy 14.731492 -178.82362) (xy 14.731492 -179.105814)
			(xy 20.700998 -179.105814) (xy 20.705069 -179.050192) (xy 20.717195 -178.995755) (xy 20.737118 -178.943664)
			(xy 20.764414 -178.895029) (xy 20.7985 -178.850886) (xy 20.838649 -178.812177) (xy 20.884007 -178.779726)
			(xy 20.933607 -178.754225) (xy 20.986391 -178.736218) (xy 21.041234 -178.726088) (xy 21.096968 -178.724051)
			(xy 21.152405 -178.730151) (xy 21.206362 -178.744257) (xy 21.257691 -178.766069) (xy 21.305297 -178.795123)
			(xy 21.348165 -178.830798) (xy 21.385382 -178.872335) (xy 21.416155 -178.918848) (xy 21.439827 -178.969345)
			(xy 21.455895 -179.022752) (xy 21.464015 -179.077928) (xy 21.464524 -179.105814) (xy 21.464015 -179.1337)
			(xy 21.455895 -179.188876) (xy 21.439827 -179.242283) (xy 21.416155 -179.29278) (xy 21.385382 -179.339293)
			(xy 21.348165 -179.38083) (xy 21.305297 -179.416505) (xy 21.257691 -179.445559) (xy 21.206362 -179.467371)
			(xy 21.152405 -179.481477) (xy 21.096968 -179.487577) (xy 21.041234 -179.48554) (xy 20.986391 -179.47541)
			(xy 20.933607 -179.457403) (xy 20.884007 -179.431902) (xy 20.838649 -179.399451) (xy 20.7985 -179.360742)
			(xy 20.764414 -179.316599) (xy 20.737118 -179.267964) (xy 20.717195 -179.215873) (xy 20.705069 -179.161436)
			(xy 20.700998 -179.105814) (xy 14.731492 -179.105814) (xy 14.731492 -179.563354) (xy 35.249545 -179.563354)
			(xy 35.249545 -179.508846) (xy 35.257302 -179.454892) (xy 35.272659 -179.402592) (xy 35.295303 -179.35301)
			(xy 35.324773 -179.307155) (xy 35.360469 -179.265961) (xy 35.401665 -179.230266) (xy 35.44752 -179.200798)
			(xy 35.497103 -179.178155) (xy 35.549404 -179.1628) (xy 35.603358 -179.155044) (xy 35.630612 -179.154582)
			(xy 35.657983 -179.155021) (xy 35.712164 -179.162842) (xy 35.764669 -179.178337) (xy 35.814415 -179.201185)
			(xy 35.86038 -179.230917) (xy 35.88131 -179.248562) (xy 35.892638 -179.257798) (xy 35.919195 -179.269974)
			(xy 35.948112 -179.274147) (xy 35.977029 -179.269974) (xy 36.003586 -179.257798) (xy 36.014914 -179.248562)
			(xy 36.035863 -179.230943) (xy 36.081831 -179.20123) (xy 36.131575 -179.17839) (xy 36.184072 -179.162894)
			(xy 36.238244 -179.155059) (xy 36.265612 -179.154582) (xy 36.292862 -179.155089) (xy 36.346807 -179.162847)
			(xy 36.399099 -179.178203) (xy 36.448673 -179.200844) (xy 36.494521 -179.23031) (xy 36.535708 -179.266)
			(xy 36.571398 -179.307189) (xy 36.600862 -179.353037) (xy 36.623502 -179.402612) (xy 36.638856 -179.454905)
			(xy 36.646612 -179.50885) (xy 36.646612 -179.56335) (xy 36.646611 -179.563354) (xy 40.532745 -179.563354)
			(xy 40.532745 -179.508846) (xy 40.540502 -179.454892) (xy 40.555859 -179.402592) (xy 40.578503 -179.35301)
			(xy 40.607973 -179.307155) (xy 40.643669 -179.265961) (xy 40.684865 -179.230266) (xy 40.73072 -179.200798)
			(xy 40.780303 -179.178155) (xy 40.832604 -179.1628) (xy 40.886558 -179.155044) (xy 40.913812 -179.154582)
			(xy 40.941183 -179.155021) (xy 40.995364 -179.162842) (xy 41.047869 -179.178337) (xy 41.097615 -179.201185)
			(xy 41.14358 -179.230917) (xy 41.16451 -179.248562) (xy 41.175838 -179.257798) (xy 41.202395 -179.269974)
			(xy 41.231312 -179.274147) (xy 41.260229 -179.269974) (xy 41.286786 -179.257798) (xy 41.298114 -179.248562)
			(xy 41.319063 -179.230943) (xy 41.365031 -179.20123) (xy 41.414775 -179.17839) (xy 41.467272 -179.162894)
			(xy 41.521444 -179.155059) (xy 41.548812 -179.154582) (xy 41.576062 -179.155089) (xy 41.630007 -179.162847)
			(xy 41.682299 -179.178203) (xy 41.731873 -179.200844) (xy 41.777721 -179.23031) (xy 41.818908 -179.266)
			(xy 41.854598 -179.307189) (xy 41.884062 -179.353037) (xy 41.906702 -179.402612) (xy 41.922056 -179.454905)
			(xy 41.929812 -179.50885) (xy 41.929812 -179.56335) (xy 41.922056 -179.617295) (xy 41.906702 -179.669588)
			(xy 41.884062 -179.719163) (xy 41.854598 -179.765011) (xy 41.818908 -179.8062) (xy 41.777721 -179.84189)
			(xy 41.731873 -179.871356) (xy 41.682299 -179.893997) (xy 41.630007 -179.909353) (xy 41.576062 -179.917111)
			(xy 41.548812 -179.917598) (xy 41.521442 -179.917125) (xy 41.467263 -179.909309) (xy 41.41476 -179.893822)
			(xy 41.365013 -179.870981) (xy 41.319046 -179.841258) (xy 41.298114 -179.823618) (xy 41.286786 -179.814382)
			(xy 41.260229 -179.802206) (xy 41.231312 -179.798033) (xy 41.202395 -179.802206) (xy 41.175838 -179.814382)
			(xy 41.16451 -179.823618) (xy 41.143587 -179.841269) (xy 41.097612 -179.870978) (xy 41.047862 -179.893812)
			(xy 40.995359 -179.9093) (xy 40.941182 -179.917125) (xy 40.913812 -179.917598) (xy 40.886558 -179.917156)
			(xy 40.832604 -179.9094) (xy 40.780303 -179.894045) (xy 40.73072 -179.871402) (xy 40.684865 -179.841934)
			(xy 40.643669 -179.806239) (xy 40.607973 -179.765045) (xy 40.578503 -179.71919) (xy 40.555859 -179.669608)
			(xy 40.540502 -179.617308) (xy 40.532745 -179.563354) (xy 36.646611 -179.563354) (xy 36.638856 -179.617295)
			(xy 36.623502 -179.669588) (xy 36.600862 -179.719163) (xy 36.571398 -179.765011) (xy 36.535708 -179.8062)
			(xy 36.494521 -179.84189) (xy 36.448673 -179.871356) (xy 36.399099 -179.893997) (xy 36.346807 -179.909353)
			(xy 36.292862 -179.917111) (xy 36.265612 -179.917598) (xy 36.238242 -179.917125) (xy 36.184063 -179.909309)
			(xy 36.13156 -179.893822) (xy 36.081813 -179.870981) (xy 36.035846 -179.841258) (xy 36.014914 -179.823618)
			(xy 36.003586 -179.814382) (xy 35.977029 -179.802206) (xy 35.948112 -179.798033) (xy 35.919195 -179.802206)
			(xy 35.892638 -179.814382) (xy 35.88131 -179.823618) (xy 35.860387 -179.841269) (xy 35.814412 -179.870978)
			(xy 35.764662 -179.893812) (xy 35.712159 -179.9093) (xy 35.657982 -179.917125) (xy 35.630612 -179.917598)
			(xy 35.603358 -179.917156) (xy 35.549404 -179.9094) (xy 35.497103 -179.894045) (xy 35.44752 -179.871402)
			(xy 35.401665 -179.841934) (xy 35.360469 -179.806239) (xy 35.324773 -179.765045) (xy 35.295303 -179.71919)
			(xy 35.272659 -179.669608) (xy 35.257302 -179.617308) (xy 35.249545 -179.563354) (xy 14.731492 -179.563354)
			(xy 14.731492 -181.954932) (xy 23.963628 -181.954932) (xy 23.967699 -181.89931) (xy 23.979825 -181.844873)
			(xy 23.999748 -181.792782) (xy 24.027044 -181.744147) (xy 24.06113 -181.700004) (xy 24.101279 -181.661295)
			(xy 24.146637 -181.628844) (xy 24.196237 -181.603343) (xy 24.249021 -181.585336) (xy 24.303864 -181.575206)
			(xy 24.359598 -181.573169) (xy 24.415035 -181.579269) (xy 24.468992 -181.593375) (xy 24.520321 -181.615187)
			(xy 24.567927 -181.644241) (xy 24.610795 -181.679916) (xy 24.648012 -181.721453) (xy 24.678785 -181.767966)
			(xy 24.702457 -181.818463) (xy 24.718525 -181.87187) (xy 24.726645 -181.927046) (xy 24.727154 -181.954932)
			(xy 24.726645 -181.982818) (xy 24.718525 -182.037994) (xy 24.702457 -182.091401) (xy 24.678785 -182.141898)
			(xy 24.648012 -182.188411) (xy 24.610795 -182.229948) (xy 24.567927 -182.265623) (xy 24.520321 -182.294677)
			(xy 24.468992 -182.316489) (xy 24.415035 -182.330595) (xy 24.359598 -182.336695) (xy 24.303864 -182.334658)
			(xy 24.249021 -182.324528) (xy 24.196237 -182.306521) (xy 24.146637 -182.28102) (xy 24.101279 -182.248569)
			(xy 24.06113 -182.20986) (xy 24.027044 -182.165717) (xy 23.999748 -182.117082) (xy 23.979825 -182.064991)
			(xy 23.967699 -182.010554) (xy 23.963628 -181.954932) (xy 14.731492 -181.954932) (xy 14.731492 -183.346598)
			(xy 14.81455 -183.429656) (xy 21.232112 -183.429656) (xy 21.236183 -183.374034) (xy 21.248309 -183.319597)
			(xy 21.268232 -183.267506) (xy 21.295528 -183.218871) (xy 21.329614 -183.174728) (xy 21.369763 -183.136019)
			(xy 21.415121 -183.103568) (xy 21.464721 -183.078067) (xy 21.517505 -183.06006) (xy 21.572348 -183.04993)
			(xy 21.628082 -183.047893) (xy 21.683519 -183.053993) (xy 21.737476 -183.068099) (xy 21.788805 -183.089911)
			(xy 21.836411 -183.118965) (xy 21.879279 -183.15464) (xy 21.916496 -183.196177) (xy 21.944931 -183.239156)
			(xy 22.886922 -183.239156) (xy 22.890993 -183.183534) (xy 22.903119 -183.129097) (xy 22.923042 -183.077006)
			(xy 22.950338 -183.028371) (xy 22.984424 -182.984228) (xy 23.024573 -182.945519) (xy 23.069931 -182.913068)
			(xy 23.119531 -182.887567) (xy 23.172315 -182.86956) (xy 23.227158 -182.85943) (xy 23.282892 -182.857393)
			(xy 23.338329 -182.863493) (xy 23.392286 -182.877599) (xy 23.443615 -182.899411) (xy 23.491221 -182.928465)
			(xy 23.534089 -182.96414) (xy 23.571306 -183.005677) (xy 23.602079 -183.05219) (xy 23.625751 -183.102687)
			(xy 23.641819 -183.156094) (xy 23.649939 -183.21127) (xy 23.650448 -183.239156) (xy 23.649939 -183.267042)
			(xy 23.641819 -183.322218) (xy 23.639824 -183.32885) (xy 35.261795 -183.32885) (xy 35.261795 -183.27435)
			(xy 35.269552 -183.220404) (xy 35.284906 -183.168112) (xy 35.307547 -183.118536) (xy 35.337012 -183.072688)
			(xy 35.372702 -183.031499) (xy 35.413891 -182.995809) (xy 35.45974 -182.966345) (xy 35.509315 -182.943705)
			(xy 35.561608 -182.928351) (xy 35.615554 -182.920595) (xy 35.642804 -182.920132) (xy 35.670175 -182.920588)
			(xy 35.724355 -182.928407) (xy 35.776858 -182.943898) (xy 35.826605 -182.966742) (xy 35.872571 -182.996469)
			(xy 35.893502 -183.014112) (xy 35.90483 -183.023348) (xy 35.931387 -183.035524) (xy 35.960304 -183.039697)
			(xy 35.989221 -183.035524) (xy 36.015778 -183.023348) (xy 36.027106 -183.014112) (xy 36.048027 -182.996459)
			(xy 36.094002 -182.966748) (xy 36.143753 -182.943915) (xy 36.196256 -182.928427) (xy 36.250434 -182.920604)
			(xy 36.277804 -182.920132) (xy 36.305058 -182.920538) (xy 36.359011 -182.928296) (xy 36.411311 -182.943653)
			(xy 36.460893 -182.966297) (xy 36.506747 -182.995766) (xy 36.547941 -183.031462) (xy 36.583636 -183.072656)
			(xy 36.613105 -183.118511) (xy 36.635748 -183.168093) (xy 36.651105 -183.220393) (xy 36.658862 -183.274346)
			(xy 36.658862 -183.32885) (xy 40.544995 -183.32885) (xy 40.544995 -183.27435) (xy 40.552752 -183.220404)
			(xy 40.568106 -183.168112) (xy 40.590747 -183.118536) (xy 40.620212 -183.072688) (xy 40.655902 -183.031499)
			(xy 40.697091 -182.995809) (xy 40.74294 -182.966345) (xy 40.792515 -182.943705) (xy 40.844808 -182.928351)
			(xy 40.898754 -182.920595) (xy 40.926004 -182.920132) (xy 40.953375 -182.920588) (xy 41.007555 -182.928407)
			(xy 41.060058 -182.943898) (xy 41.109805 -182.966742) (xy 41.155771 -182.996469) (xy 41.176702 -183.014112)
			(xy 41.18803 -183.023348) (xy 41.214587 -183.035524) (xy 41.243504 -183.039697) (xy 41.272421 -183.035524)
			(xy 41.298978 -183.023348) (xy 41.310306 -183.014112) (xy 41.331227 -182.996459) (xy 41.377202 -182.966748)
			(xy 41.426953 -182.943915) (xy 41.479456 -182.928427) (xy 41.533634 -182.920604) (xy 41.561004 -182.920132)
			(xy 41.588258 -182.920538) (xy 41.642211 -182.928296) (xy 41.694511 -182.943653) (xy 41.744093 -182.966297)
			(xy 41.789947 -182.995766) (xy 41.831141 -183.031462) (xy 41.866836 -183.072656) (xy 41.896305 -183.118511)
			(xy 41.918948 -183.168093) (xy 41.934305 -183.220393) (xy 41.942062 -183.274346) (xy 41.942062 -183.328854)
			(xy 41.934305 -183.382807) (xy 41.918948 -183.435107) (xy 41.896305 -183.484689) (xy 41.866836 -183.530544)
			(xy 41.831141 -183.571738) (xy 41.789947 -183.607434) (xy 41.744093 -183.636903) (xy 41.694511 -183.659547)
			(xy 41.642211 -183.674904) (xy 41.588258 -183.682662) (xy 41.561004 -183.683148) (xy 41.533633 -183.682692)
			(xy 41.479453 -183.674874) (xy 41.42695 -183.659383) (xy 41.377203 -183.636539) (xy 41.331237 -183.606811)
			(xy 41.310306 -183.589168) (xy 41.298978 -183.579932) (xy 41.272421 -183.567756) (xy 41.243504 -183.563583)
			(xy 41.214587 -183.567756) (xy 41.18803 -183.579932) (xy 41.176702 -183.589168) (xy 41.155776 -183.606815)
			(xy 41.109802 -183.636526) (xy 41.060053 -183.659361) (xy 41.007551 -183.674851) (xy 40.953374 -183.682676)
			(xy 40.926004 -183.683148) (xy 40.898754 -183.682605) (xy 40.844808 -183.674849) (xy 40.792515 -183.659495)
			(xy 40.74294 -183.636855) (xy 40.697091 -183.607391) (xy 40.655902 -183.571701) (xy 40.620212 -183.530512)
			(xy 40.590747 -183.484664) (xy 40.568106 -183.435088) (xy 40.552752 -183.382796) (xy 40.544995 -183.32885)
			(xy 36.658862 -183.32885) (xy 36.658862 -183.328854) (xy 36.651105 -183.382807) (xy 36.635748 -183.435107)
			(xy 36.613105 -183.484689) (xy 36.583636 -183.530544) (xy 36.547941 -183.571738) (xy 36.506747 -183.607434)
			(xy 36.460893 -183.636903) (xy 36.411311 -183.659547) (xy 36.359011 -183.674904) (xy 36.305058 -183.682662)
			(xy 36.277804 -183.683148) (xy 36.250433 -183.682692) (xy 36.196253 -183.674874) (xy 36.14375 -183.659383)
			(xy 36.094003 -183.636539) (xy 36.048037 -183.606811) (xy 36.027106 -183.589168) (xy 36.015778 -183.579932)
			(xy 35.989221 -183.567756) (xy 35.960304 -183.563583) (xy 35.931387 -183.567756) (xy 35.90483 -183.579932)
			(xy 35.893502 -183.589168) (xy 35.872576 -183.606815) (xy 35.826602 -183.636526) (xy 35.776853 -183.659361)
			(xy 35.724351 -183.674851) (xy 35.670174 -183.682676) (xy 35.642804 -183.683148) (xy 35.615554 -183.682605)
			(xy 35.561608 -183.674849) (xy 35.509315 -183.659495) (xy 35.45974 -183.636855) (xy 35.413891 -183.607391)
			(xy 35.372702 -183.571701) (xy 35.337012 -183.530512) (xy 35.307547 -183.484664) (xy 35.284906 -183.435088)
			(xy 35.269552 -183.382796) (xy 35.261795 -183.32885) (xy 23.639824 -183.32885) (xy 23.625751 -183.375625)
			(xy 23.602079 -183.426122) (xy 23.571306 -183.472635) (xy 23.534089 -183.514172) (xy 23.491221 -183.549847)
			(xy 23.443615 -183.578901) (xy 23.392286 -183.600713) (xy 23.338329 -183.614819) (xy 23.282892 -183.620919)
			(xy 23.227158 -183.618882) (xy 23.172315 -183.608752) (xy 23.119531 -183.590745) (xy 23.069931 -183.565244)
			(xy 23.024573 -183.532793) (xy 22.984424 -183.494084) (xy 22.950338 -183.449941) (xy 22.923042 -183.401306)
			(xy 22.903119 -183.349215) (xy 22.890993 -183.294778) (xy 22.886922 -183.239156) (xy 21.944931 -183.239156)
			(xy 21.947269 -183.24269) (xy 21.970941 -183.293187) (xy 21.987009 -183.346594) (xy 21.995129 -183.40177)
			(xy 21.995638 -183.429656) (xy 21.995129 -183.457542) (xy 21.987009 -183.512718) (xy 21.970941 -183.566125)
			(xy 21.947269 -183.616622) (xy 21.916496 -183.663135) (xy 21.879279 -183.704672) (xy 21.836411 -183.740347)
			(xy 21.788805 -183.769401) (xy 21.737476 -183.791213) (xy 21.683519 -183.805319) (xy 21.628082 -183.811419)
			(xy 21.572348 -183.809382) (xy 21.517505 -183.799252) (xy 21.464721 -183.781245) (xy 21.415121 -183.755744)
			(xy 21.369763 -183.723293) (xy 21.329614 -183.684584) (xy 21.295528 -183.640441) (xy 21.268232 -183.591806)
			(xy 21.248309 -183.539715) (xy 21.236183 -183.485278) (xy 21.232112 -183.429656) (xy 14.81455 -183.429656)
			(xy 15.831058 -184.446164) (xy 46.732444 -184.446164)
		)
		(stroke
			(width 0)
			(type solid)
		)
		(fill yes)
		(layer "In15.Cu")
		(net "GND")
	)
	(gr_poly
		(pts
			(xy 170.907456 -440.46648) (xy 170.922506 -440.465903) (xy 170.951282 -440.457065) (xy 170.976238 -440.440231)
			(xy 170.995211 -440.416859) (xy 171.006556 -440.388976) (xy 171.00929 -440.358998) (xy 171.003177 -440.329522)
			(xy 170.988745 -440.303104) (xy 170.978322 -440.292236) (xy 170.957079 -440.270567) (xy 170.921044 -440.221746)
			(xy 170.89319 -440.167838) (xy 170.874219 -440.110201) (xy 170.864608 -440.050287) (xy 170.864022 -440.019948)
			(xy 170.864508 -439.992697) (xy 170.872264 -439.938749) (xy 170.887619 -439.886454) (xy 170.910261 -439.836877)
			(xy 170.939727 -439.791027) (xy 170.975418 -439.749836) (xy 171.016609 -439.714145) (xy 171.062459 -439.684679)
			(xy 171.112036 -439.662037) (xy 171.164331 -439.646682) (xy 171.218279 -439.638926) (xy 171.272781 -439.638926)
			(xy 171.326729 -439.646682) (xy 171.379024 -439.662037) (xy 171.428601 -439.684679) (xy 171.474451 -439.714145)
			(xy 171.515642 -439.749836) (xy 171.551333 -439.791027) (xy 171.580799 -439.836877) (xy 171.603441 -439.886454)
			(xy 171.618796 -439.938749) (xy 171.626552 -439.992697) (xy 171.627038 -440.019948) (xy 171.626548 -440.047532)
			(xy 171.618598 -440.102124) (xy 171.60287 -440.155002) (xy 171.579692 -440.205065) (xy 171.549548 -440.251269)
			(xy 171.513065 -440.292651) (xy 171.471004 -440.328349) (xy 171.424241 -440.357618) (xy 171.3992 -440.369198)
			(xy 171.36872 -440.382406) (xy 171.36872 -440.46648) (xy 171.52366 -440.46648) (xy 172.13072 -439.85942)
			(xy 172.13072 -431.45202) (xy 172.335698 -431.247042) (xy 172.345316 -431.23681) (xy 172.359029 -431.212315)
			(xy 172.365547 -431.18501) (xy 172.364377 -431.156962) (xy 172.355606 -431.130296) (xy 172.3399 -431.107029)
			(xy 172.318447 -431.088923) (xy 172.292871 -431.07735) (xy 172.279056 -431.07483) (xy 172.252339 -431.070287)
			(xy 172.200453 -431.054639) (xy 172.151304 -431.031806) (xy 172.105882 -431.002246) (xy 172.0651 -430.966556)
			(xy 172.02978 -430.925453) (xy 172.000633 -430.879765) (xy 171.978245 -430.830411) (xy 171.963068 -430.778386)
			(xy 171.955406 -430.724737) (xy 171.954952 -430.69764) (xy 171.955435 -430.670386) (xy 171.963187 -430.616432)
			(xy 171.978538 -430.56413) (xy 172.001176 -430.514545) (xy 172.030641 -430.468687) (xy 172.066332 -430.427488)
			(xy 172.107523 -430.391789) (xy 172.153375 -430.362315) (xy 172.202955 -430.339666) (xy 172.255253 -430.324304)
			(xy 172.309206 -430.316541) (xy 172.33646 -430.316132) (xy 172.363553 -430.316611) (xy 172.417193 -430.324285)
			(xy 172.469208 -430.339471) (xy 172.518552 -430.361862) (xy 172.564231 -430.391009) (xy 172.605328 -430.426325)
			(xy 172.641015 -430.4671) (xy 172.670575 -430.512514) (xy 172.693412 -430.561653) (xy 172.709068 -430.613528)
			(xy 172.71365 -430.640236) (xy 172.716205 -430.654028) (xy 172.727815 -430.679551) (xy 172.745928 -430.700955)
			(xy 172.769178 -430.716627) (xy 172.795815 -430.725386) (xy 172.823829 -430.726572) (xy 172.85111 -430.720095)
			(xy 172.875602 -430.706444) (xy 172.885862 -430.696878) (xy 175.63084 -427.9519) (xy 183.7436 -427.9519)
			(xy 184.05856 -428.26686) (xy 191.606168 -428.26686) (xy 191.610239 -428.211238) (xy 191.622365 -428.156801)
			(xy 191.642288 -428.10471) (xy 191.669584 -428.056075) (xy 191.70367 -428.011932) (xy 191.743819 -427.973223)
			(xy 191.789177 -427.940772) (xy 191.838777 -427.915271) (xy 191.891561 -427.897264) (xy 191.946404 -427.887134)
			(xy 192.002138 -427.885097) (xy 192.057575 -427.891197) (xy 192.111532 -427.905303) (xy 192.162861 -427.927115)
			(xy 192.210467 -427.956169) (xy 192.253335 -427.991844) (xy 192.290552 -428.033381) (xy 192.321325 -428.079894)
			(xy 192.344997 -428.130391) (xy 192.361065 -428.183798) (xy 192.369185 -428.238974) (xy 192.369694 -428.26686)
			(xy 192.369185 -428.294746) (xy 192.361065 -428.349922) (xy 192.344997 -428.403329) (xy 192.321325 -428.453826)
			(xy 192.290552 -428.500339) (xy 192.253335 -428.541876) (xy 192.210467 -428.577551) (xy 192.162861 -428.606605)
			(xy 192.111532 -428.628417) (xy 192.057575 -428.642523) (xy 192.002138 -428.648623) (xy 191.946404 -428.646586)
			(xy 191.891561 -428.636456) (xy 191.838777 -428.618449) (xy 191.789177 -428.592948) (xy 191.743819 -428.560497)
			(xy 191.70367 -428.521788) (xy 191.669584 -428.477645) (xy 191.642288 -428.42901) (xy 191.622365 -428.376919)
			(xy 191.610239 -428.322482) (xy 191.606168 -428.26686) (xy 184.05856 -428.26686) (xy 186.409838 -430.618138)
			(xy 193.107562 -430.618138) (xy 193.111633 -430.562516) (xy 193.123759 -430.508079) (xy 193.143682 -430.455988)
			(xy 193.170978 -430.407353) (xy 193.205064 -430.36321) (xy 193.245213 -430.324501) (xy 193.290571 -430.29205)
			(xy 193.340171 -430.266549) (xy 193.392955 -430.248542) (xy 193.447798 -430.238412) (xy 193.503532 -430.236375)
			(xy 193.558969 -430.242475) (xy 193.612926 -430.256581) (xy 193.664255 -430.278393) (xy 193.711861 -430.307447)
			(xy 193.754729 -430.343122) (xy 193.791946 -430.384659) (xy 193.822719 -430.431172) (xy 193.846391 -430.481669)
			(xy 193.862459 -430.535076) (xy 193.870579 -430.590252) (xy 193.871088 -430.618138) (xy 193.870579 -430.646024)
			(xy 193.862459 -430.7012) (xy 193.846391 -430.754607) (xy 193.822719 -430.805104) (xy 193.791946 -430.851617)
			(xy 193.754729 -430.893154) (xy 193.711861 -430.928829) (xy 193.664255 -430.957883) (xy 193.612926 -430.979695)
			(xy 193.558969 -430.993801) (xy 193.503532 -430.999901) (xy 193.447798 -430.997864) (xy 193.392955 -430.987734)
			(xy 193.340171 -430.969727) (xy 193.290571 -430.944226) (xy 193.245213 -430.911775) (xy 193.205064 -430.873066)
			(xy 193.170978 -430.828923) (xy 193.143682 -430.780288) (xy 193.123759 -430.728197) (xy 193.111633 -430.67376)
			(xy 193.107562 -430.618138) (xy 186.409838 -430.618138) (xy 187.14466 -431.35296) (xy 187.14466 -434.3019)
			(xy 191.434464 -434.3019) (xy 191.438535 -434.246278) (xy 191.450661 -434.191841) (xy 191.470584 -434.13975)
			(xy 191.49788 -434.091115) (xy 191.531966 -434.046972) (xy 191.572115 -434.008263) (xy 191.617473 -433.975812)
			(xy 191.667073 -433.950311) (xy 191.719857 -433.932304) (xy 191.7747 -433.922174) (xy 191.830434 -433.920137)
			(xy 191.885871 -433.926237) (xy 191.939828 -433.940343) (xy 191.991157 -433.962155) (xy 192.038763 -433.991209)
			(xy 192.081631 -434.026884) (xy 192.118848 -434.068421) (xy 192.149621 -434.114934) (xy 192.173293 -434.165431)
			(xy 192.189361 -434.218838) (xy 192.197481 -434.274014) (xy 192.19799 -434.3019) (xy 192.197481 -434.329786)
			(xy 192.189361 -434.384962) (xy 192.173293 -434.438369) (xy 192.149621 -434.488866) (xy 192.118848 -434.535379)
			(xy 192.081631 -434.576916) (xy 192.038763 -434.612591) (xy 191.991157 -434.641645) (xy 191.939828 -434.663457)
			(xy 191.885871 -434.677563) (xy 191.830434 -434.683663) (xy 191.7747 -434.681626) (xy 191.719857 -434.671496)
			(xy 191.667073 -434.653489) (xy 191.617473 -434.627988) (xy 191.572115 -434.595537) (xy 191.531966 -434.556828)
			(xy 191.49788 -434.512685) (xy 191.470584 -434.46405) (xy 191.450661 -434.411959) (xy 191.438535 -434.357522)
			(xy 191.434464 -434.3019) (xy 187.14466 -434.3019) (xy 187.14466 -437.9087) (xy 187.81014 -438.57418)
			(xy 190.848232 -438.57418) (xy 190.852303 -438.518558) (xy 190.864429 -438.464121) (xy 190.884352 -438.41203)
			(xy 190.911648 -438.363395) (xy 190.945734 -438.319252) (xy 190.985883 -438.280543) (xy 191.031241 -438.248092)
			(xy 191.080841 -438.222591) (xy 191.133625 -438.204584) (xy 191.188468 -438.194454) (xy 191.244202 -438.192417)
			(xy 191.299639 -438.198517) (xy 191.353596 -438.212623) (xy 191.404925 -438.234435) (xy 191.452531 -438.263489)
			(xy 191.495399 -438.299164) (xy 191.532616 -438.340701) (xy 191.563389 -438.387214) (xy 191.587061 -438.437711)
			(xy 191.603129 -438.491118) (xy 191.611249 -438.546294) (xy 191.611758 -438.57418) (xy 191.611249 -438.602066)
			(xy 191.603129 -438.657242) (xy 191.587061 -438.710649) (xy 191.563389 -438.761146) (xy 191.532616 -438.807659)
			(xy 191.495399 -438.849196) (xy 191.452531 -438.884871) (xy 191.404925 -438.913925) (xy 191.353596 -438.935737)
			(xy 191.299639 -438.949843) (xy 191.244202 -438.955943) (xy 191.188468 -438.953906) (xy 191.133625 -438.943776)
			(xy 191.080841 -438.925769) (xy 191.031241 -438.900268) (xy 190.985883 -438.867817) (xy 190.945734 -438.829108)
			(xy 190.911648 -438.784965) (xy 190.884352 -438.73633) (xy 190.864429 -438.684239) (xy 190.852303 -438.629802)
			(xy 190.848232 -438.57418) (xy 187.81014 -438.57418) (xy 189.02934 -439.79338) (xy 193.0273 -439.79338)
			(xy 193.511424 -439.309256) (xy 193.511678 -439.288936) (xy 193.512761 -439.262528) (xy 193.52131 -439.21037)
			(xy 193.536974 -439.159891) (xy 193.559453 -439.112057) (xy 193.588319 -439.067782) (xy 193.623018 -439.027914)
			(xy 193.662887 -438.993215) (xy 193.707162 -438.96435) (xy 193.754997 -438.941871) (xy 193.805476 -438.926208)
			(xy 193.857634 -438.917661) (xy 193.884042 -438.916572) (xy 193.904362 -438.916318) (xy 195.05676 -437.76392)
			(xy 195.05676 -437.658002) (xy 195.05634 -437.647983) (xy 195.048669 -437.629473) (xy 195.034495 -437.61531)
			(xy 195.015979 -437.607652) (xy 195.00596 -437.607202) (xy 194.971924 -437.62041) (xy 194.950824 -437.638689)
			(xy 194.904285 -437.669517) (xy 194.853751 -437.693236) (xy 194.8003 -437.709339) (xy 194.745074 -437.717481)
			(xy 194.717162 -437.717946) (xy 194.68991 -437.717458) (xy 194.635961 -437.709696) (xy 194.583665 -437.694336)
			(xy 194.534088 -437.67169) (xy 194.488238 -437.64222) (xy 194.447048 -437.606525) (xy 194.411357 -437.565332)
			(xy 194.381891 -437.519479) (xy 194.359251 -437.469899) (xy 194.343896 -437.417602) (xy 194.33614 -437.363652)
			(xy 194.33614 -437.309148) (xy 194.343896 -437.255198) (xy 194.359251 -437.202901) (xy 194.381891 -437.153321)
			(xy 194.411357 -437.107468) (xy 194.447048 -437.066275) (xy 194.488238 -437.03058) (xy 194.534088 -437.00111)
			(xy 194.583665 -436.978464) (xy 194.635961 -436.963104) (xy 194.68991 -436.955342) (xy 194.717162 -436.95493)
			(xy 194.74174 -436.955311) (xy 194.790488 -436.961623) (xy 194.83802 -436.974148) (xy 194.883549 -436.992679)
			(xy 194.905122 -437.00446) (xy 194.918598 -437.011448) (xy 194.948225 -437.017987) (xy 194.978466 -437.015542)
			(xy 195.006658 -437.00433) (xy 195.030317 -436.985336) (xy 195.047359 -436.960235) (xy 195.056283 -436.931238)
			(xy 195.05676 -436.916068) (xy 195.05676 -429.464216) (xy 195.056319 -429.450214) (xy 195.048714 -429.423263)
			(xy 195.034072 -429.399393) (xy 195.013494 -429.380399) (xy 194.988529 -429.367712) (xy 194.961056 -429.362286)
			(xy 194.933142 -429.36453) (xy 194.919854 -429.368966) (xy 194.887948 -429.379974) (xy 194.821517 -429.391861)
			(xy 194.787774 -429.392588) (xy 194.78752 -429.392588) (xy 194.760268 -429.392126) (xy 194.706317 -429.384372)
			(xy 194.65402 -429.369018) (xy 194.60444 -429.346378) (xy 194.558587 -429.316912) (xy 194.517394 -429.28122)
			(xy 194.4817 -429.240029) (xy 194.452231 -429.194178) (xy 194.429589 -429.144599) (xy 194.414232 -429.092302)
			(xy 194.406475 -429.038352) (xy 194.406475 -428.983848) (xy 194.414232 -428.929898) (xy 194.429589 -428.877601)
			(xy 194.452231 -428.828022) (xy 194.4817 -428.782171) (xy 194.517394 -428.74098) (xy 194.558587 -428.705288)
			(xy 194.60444 -428.675822) (xy 194.65402 -428.653182) (xy 194.706317 -428.637828) (xy 194.760268 -428.630074)
			(xy 194.78752 -428.629572) (xy 194.787774 -428.629572) (xy 194.821519 -428.630288) (xy 194.887956 -428.642161)
			(xy 194.919854 -428.653194) (xy 194.93314 -428.65765) (xy 194.961064 -428.659892) (xy 194.988547 -428.654465)
			(xy 195.013522 -428.641777) (xy 195.034112 -428.622781) (xy 195.048769 -428.598908) (xy 195.05639 -428.571951)
			(xy 195.05676 -428.557944) (xy 195.05676 -426.04944) (xy 192.79362 -423.7863) (xy 191.12738 -423.7863)
			(xy 189.87008 -422.529) (xy 189.87008 -420.9669) (xy 180.971444 -412.068264) (xy 180.971444 -410.78912)
			(xy 180.979572 -410.780738) (xy 180.979572 -407.084784) (xy 180.952394 -407.07056) (xy 180.92945 -407.058201)
			(xy 180.886866 -407.028157) (xy 180.848771 -406.992594) (xy 180.815876 -406.952172) (xy 180.788792 -406.907647)
			(xy 180.768026 -406.859848) (xy 180.753964 -406.809666) (xy 180.746869 -406.758036) (xy 180.7464 -406.731978)
			(xy 180.746887 -406.704728) (xy 180.754646 -406.650783) (xy 180.770004 -406.598491) (xy 180.792646 -406.548917)
			(xy 180.822113 -406.50307) (xy 180.857805 -406.461883) (xy 180.898994 -406.426195) (xy 180.944844 -406.396732)
			(xy 180.99442 -406.374093) (xy 181.046712 -406.35874) (xy 181.100658 -406.350985) (xy 181.127908 -406.35047)
			(xy 181.156208 -406.350993) (xy 181.212184 -406.359373) (xy 181.266307 -406.375932) (xy 181.317388 -406.400308)
			(xy 181.364307 -406.431964) (xy 181.406033 -406.470206) (xy 181.44165 -406.514195) (xy 181.470375 -406.562963)
			(xy 181.491578 -406.615441) (xy 181.498748 -406.642824) (xy 181.502304 -406.656794) (xy 181.52237 -406.67686)
			(xy 181.539724 -406.694845) (xy 181.569124 -406.735257) (xy 181.591832 -406.779776) (xy 181.607286 -406.827302)
			(xy 181.615106 -406.876662) (xy 181.615588 -406.90165) (xy 181.615588 -408.593544) (xy 181.61606 -408.608175)
			(xy 181.624346 -408.63624) (xy 181.640253 -408.660801) (xy 181.662474 -408.679841) (xy 181.689184 -408.691794)
			(xy 181.718187 -408.69568) (xy 181.747101 -408.691178) (xy 181.77355 -408.678658) (xy 181.784752 -408.669236)
			(xy 181.805842 -408.651112) (xy 181.852282 -408.620529) (xy 181.902668 -408.597005) (xy 181.955932 -408.581038)
			(xy 182.010949 -408.572965) (xy 182.038752 -408.572462) (xy 182.066008 -408.572922) (xy 182.119966 -408.580673)
			(xy 182.172271 -408.596024) (xy 182.221859 -408.618664) (xy 182.267721 -408.64813) (xy 182.308921 -408.683823)
			(xy 182.344623 -408.725017) (xy 182.374099 -408.770872) (xy 182.396748 -408.820456) (xy 182.412111 -408.872758)
			(xy 182.419873 -408.926714) (xy 182.42026 -408.95397) (xy 182.41899 -408.984196) (xy 182.41833 -408.998473)
			(xy 182.424022 -409.02647) (xy 182.437237 -409.051799) (xy 182.456943 -409.072484) (xy 182.481602 -409.08691)
			(xy 182.509291 -409.093951) (xy 182.537846 -409.093057) (xy 182.551578 -409.089098) (xy 182.580079 -409.080459)
			(xy 182.638897 -409.071138) (xy 182.668672 -409.070556) (xy 182.695925 -409.07104) (xy 182.749878 -409.078793)
			(xy 182.802178 -409.094145) (xy 182.851761 -409.116784) (xy 182.897618 -409.146249) (xy 182.938814 -409.18194)
			(xy 182.974512 -409.223131) (xy 183.003985 -409.268982) (xy 183.026632 -409.318562) (xy 183.041993 -409.370859)
			(xy 183.049756 -409.424811) (xy 183.05018 -409.452064) (xy 183.05018 -409.452826) (xy 183.050033 -409.466656)
			(xy 183.047998 -409.494242) (xy 183.046116 -409.507944) (xy 183.044422 -409.522432) (xy 183.048422 -409.551314)
			(xy 183.060416 -409.57789) (xy 183.079428 -409.599997) (xy 183.10391 -409.615834) (xy 183.131868 -409.624112)
			(xy 183.146446 -409.62453) (xy 183.259984 -409.62453) (xy 183.449722 -409.435046) (xy 183.464351 -409.410743)
			(xy 183.49968 -409.366365) (xy 183.52008 -409.346654) (xy 183.52008 -408.42946) (xy 184.096152 -407.853134)
			(xy 184.096152 -407.017474) (xy 184.095898 -407.00706) (xy 184.096366 -406.982051) (xy 184.104198 -406.932648)
			(xy 184.119663 -406.88508) (xy 184.142379 -406.840517) (xy 184.171788 -406.800057) (xy 184.189116 -406.782016)
			(xy 184.20334 -406.767792) (xy 184.20334 -406.323546) (xy 184.181212 -406.306882) (xy 184.14155 -406.268212)
			(xy 184.107897 -406.224214) (xy 184.080959 -406.175812) (xy 184.061303 -406.124023) (xy 184.049343 -406.069937)
			(xy 184.045329 -406.014689) (xy 184.049346 -405.959442) (xy 184.061309 -405.905356) (xy 184.080968 -405.853569)
			(xy 184.107908 -405.805168) (xy 184.141564 -405.761172) (xy 184.181228 -405.722505) (xy 184.20334 -405.705818)
			(xy 184.20334 -404.57628) (xy 184.202834 -404.561391) (xy 184.194265 -404.532872) (xy 184.177833 -404.508038)
			(xy 184.154936 -404.489) (xy 184.127519 -404.477378) (xy 184.097915 -404.47416) (xy 184.083198 -404.476458)
			(xy 184.066081 -404.479428) (xy 184.031482 -404.482611) (xy 184.01411 -404.482808) (xy 183.986857 -404.482345)
			(xy 183.932905 -404.47459) (xy 183.880606 -404.459234) (xy 183.831024 -404.436592) (xy 183.78517 -404.407125)
			(xy 183.743976 -404.371431) (xy 183.708281 -404.330238) (xy 183.678812 -404.284385) (xy 183.656169 -404.234804)
			(xy 183.640813 -404.182505) (xy 183.633055 -404.128553) (xy 183.632602 -404.1013) (xy 183.63311 -404.08098)
			(xy 183.633391 -404.066772) (xy 183.627015 -404.039091) (xy 183.61325 -404.014243) (xy 183.593165 -403.994156)
			(xy 183.568318 -403.980389) (xy 183.540638 -403.974009) (xy 183.52643 -403.9743) (xy 183.50611 -403.974808)
			(xy 183.478857 -403.974345) (xy 183.424906 -403.96659) (xy 183.372607 -403.951235) (xy 183.323026 -403.928593)
			(xy 183.277172 -403.899126) (xy 183.235978 -403.863433) (xy 183.200284 -403.822241) (xy 183.170815 -403.776389)
			(xy 183.148171 -403.726809) (xy 183.132814 -403.674511) (xy 183.125056 -403.62056) (xy 183.125055 -403.566054)
			(xy 183.132811 -403.512102) (xy 183.148166 -403.459804) (xy 183.170808 -403.410223) (xy 183.200276 -403.364369)
			(xy 183.235969 -403.323176) (xy 183.277161 -403.287482) (xy 183.323014 -403.258013) (xy 183.372595 -403.23537)
			(xy 183.424893 -403.220013) (xy 183.478844 -403.212256) (xy 183.53335 -403.212255) (xy 183.587301 -403.220012)
			(xy 183.639599 -403.235367) (xy 183.68918 -403.25801) (xy 183.735033 -403.287478) (xy 183.776226 -403.323171)
			(xy 183.81192 -403.364364) (xy 183.841389 -403.410217) (xy 183.864031 -403.459798) (xy 183.879388 -403.512096)
			(xy 183.887145 -403.566047) (xy 183.887618 -403.5933) (xy 183.88711 -403.61362) (xy 183.886828 -403.627832)
			(xy 183.893204 -403.655522) (xy 183.906967 -403.680381) (xy 183.927051 -403.700481) (xy 183.951898 -403.714265)
			(xy 183.979582 -403.720664) (xy 183.99379 -403.7203) (xy 184.01411 -403.719792) (xy 184.03443 -403.7203)
			(xy 184.048637 -403.72058) (xy 184.076314 -403.714201) (xy 184.101158 -403.700436) (xy 184.121241 -403.680351)
			(xy 184.135005 -403.655505) (xy 184.141381 -403.627827) (xy 184.14111 -403.61362) (xy 184.140602 -403.5933)
			(xy 184.141101 -403.565555) (xy 184.149142 -403.510651) (xy 184.165055 -403.457492) (xy 184.188503 -403.407199)
			(xy 184.20334 -403.38375) (xy 184.20334 -402.72716) (xy 183.67248 -402.1963) (xy 183.641746 -402.207984)
			(xy 183.620058 -402.215875) (xy 183.575255 -402.226952) (xy 183.52944 -402.232529) (xy 183.506364 -402.232876)
			(xy 183.50611 -402.232876) (xy 183.478859 -402.232413) (xy 183.424911 -402.224658) (xy 183.372617 -402.209304)
			(xy 183.32304 -402.186664) (xy 183.277189 -402.157199) (xy 183.235999 -402.121508) (xy 183.200307 -402.080319)
			(xy 183.17084 -402.034469) (xy 183.148199 -401.984893) (xy 183.132844 -401.932598) (xy 183.125087 -401.878651)
			(xy 183.125087 -401.824149) (xy 183.132844 -401.770202) (xy 183.148199 -401.717907) (xy 183.17084 -401.668331)
			(xy 183.200307 -401.622481) (xy 183.235999 -401.581292) (xy 183.277189 -401.545601) (xy 183.32304 -401.516136)
			(xy 183.372617 -401.493496) (xy 183.424911 -401.478142) (xy 183.478859 -401.470387) (xy 183.50611 -401.46986)
			(xy 183.52643 -401.470368) (xy 183.54064 -401.470648) (xy 183.568325 -401.46427) (xy 183.593178 -401.450506)
			(xy 183.613273 -401.430422) (xy 183.627051 -401.405577) (xy 183.633444 -401.377895) (xy 183.63311 -401.363688)
			(xy 183.632602 -401.343368) (xy 183.633201 -401.312907) (xy 183.642894 -401.25276) (xy 183.662027 -401.194919)
			(xy 183.690114 -401.140857) (xy 183.707786 -401.116038) (xy 183.707786 -400.167094) (xy 183.683099 -400.153942)
			(xy 183.637526 -400.121509) (xy 183.597176 -400.082772) (xy 183.562912 -400.038559) (xy 183.535469 -399.989818)
			(xy 183.515435 -399.937594) (xy 183.50324 -399.883004) (xy 183.499143 -399.827219) (xy 183.503234 -399.771434)
			(xy 183.515424 -399.716843) (xy 183.535453 -399.664616) (xy 183.562891 -399.615873) (xy 183.59715 -399.571657)
			(xy 183.637497 -399.532915) (xy 183.683066 -399.500478) (xy 183.707786 -399.48739) (xy 183.707786 -398.069054)
			(xy 183.706262 -398.063212) (xy 183.701139 -398.04083) (xy 183.695666 -397.995239) (xy 183.69534 -397.97228)
			(xy 183.695669 -397.949321) (xy 183.701148 -397.903732) (xy 183.706262 -397.881348) (xy 183.707786 -397.875506)
			(xy 183.707786 -397.23568) (xy 182.491126 -396.01902) (xy 172.936662 -396.01902) (xy 172.921425 -396.019521)
			(xy 172.892303 -396.028496) (xy 172.867126 -396.045665) (xy 172.848137 -396.069498) (xy 172.837026 -396.097874)
			(xy 172.834783 -396.128265) (xy 172.841608 -396.157964) (xy 172.848778 -396.17142) (xy 172.860972 -396.193269)
			(xy 172.880162 -396.23948) (xy 172.893145 -396.287803) (xy 172.899698 -396.33741) (xy 172.900086 -396.362428)
			(xy 172.8996 -396.389679) (xy 172.891844 -396.443627) (xy 172.876489 -396.495922) (xy 172.853847 -396.545499)
			(xy 172.824381 -396.591349) (xy 172.78869 -396.63254) (xy 172.747499 -396.668231) (xy 172.701649 -396.697697)
			(xy 172.652072 -396.720339) (xy 172.599777 -396.735694) (xy 172.545829 -396.74345) (xy 172.491327 -396.74345)
			(xy 172.437379 -396.735694) (xy 172.385084 -396.720339) (xy 172.335507 -396.697697) (xy 172.289657 -396.668231)
			(xy 172.248466 -396.63254) (xy 172.212775 -396.591349) (xy 172.183309 -396.545499) (xy 172.160667 -396.495922)
			(xy 172.145312 -396.443627) (xy 172.137556 -396.389679) (xy 172.13707 -396.362428) (xy 172.137463 -396.337409)
			(xy 172.144007 -396.287802) (xy 172.156986 -396.239477) (xy 172.176178 -396.193266) (xy 172.188378 -396.17142)
			(xy 172.195502 -396.157955) (xy 172.202287 -396.128273) (xy 172.200024 -396.097911) (xy 172.188916 -396.069563)
			(xy 172.169947 -396.045747) (xy 172.144803 -396.028578) (xy 172.115717 -396.019579) (xy 172.100494 -396.01902)
			(xy 169.10812 -396.01902) (xy 168.97096 -396.15618) (xy 168.97096 -397.966692) (xy 172.05325 -397.966692)
			(xy 172.053763 -397.939241) (xy 172.06164 -397.884908) (xy 172.07723 -397.832267) (xy 172.100209 -397.782406)
			(xy 172.130104 -397.736358) (xy 172.166295 -397.695074) (xy 172.186854 -397.676878) (xy 172.197926 -397.666616)
			(xy 172.214148 -397.641181) (xy 172.222229 -397.612116) (xy 172.221464 -397.581958) (xy 172.211918 -397.553341)
			(xy 172.203618 -397.540734) (xy 172.187038 -397.516401) (xy 172.160743 -397.463721) (xy 172.142858 -397.407625)
			(xy 172.133807 -397.349447) (xy 172.13326 -397.320008) (xy 172.133746 -397.292757) (xy 172.141502 -397.238809)
			(xy 172.156857 -397.186514) (xy 172.179499 -397.136937) (xy 172.208965 -397.091087) (xy 172.244656 -397.049896)
			(xy 172.285847 -397.014205) (xy 172.331697 -396.984739) (xy 172.381274 -396.962097) (xy 172.433569 -396.946742)
			(xy 172.487517 -396.938986) (xy 172.542019 -396.938986) (xy 172.595967 -396.946742) (xy 172.648262 -396.962097)
			(xy 172.697839 -396.984739) (xy 172.743689 -397.014205) (xy 172.78488 -397.049896) (xy 172.820571 -397.091087)
			(xy 172.850037 -397.136937) (xy 172.872679 -397.186514) (xy 172.888034 -397.238809) (xy 172.89579 -397.292757)
			(xy 172.896276 -397.320008) (xy 172.895754 -397.347458) (xy 172.887877 -397.401791) (xy 172.872289 -397.454431)
			(xy 172.849311 -397.504292) (xy 172.819418 -397.550341) (xy 172.78323 -397.591625) (xy 172.762672 -397.609822)
			(xy 172.751597 -397.620079) (xy 172.735386 -397.645518) (xy 172.72731 -397.674583) (xy 172.728075 -397.704739)
			(xy 172.737613 -397.733357) (xy 172.745908 -397.745966) (xy 172.762479 -397.770305) (xy 172.788778 -397.822982)
			(xy 172.806666 -397.879076) (xy 172.815718 -397.937253) (xy 172.816266 -397.966692) (xy 172.81578 -397.993943)
			(xy 172.808024 -398.047891) (xy 172.80263 -398.06626) (xy 175.411382 -398.06626) (xy 175.415453 -398.010638)
			(xy 175.427579 -397.956201) (xy 175.447502 -397.90411) (xy 175.474798 -397.855475) (xy 175.508884 -397.811332)
			(xy 175.549033 -397.772623) (xy 175.594391 -397.740172) (xy 175.643991 -397.714671) (xy 175.696775 -397.696664)
			(xy 175.751618 -397.686534) (xy 175.807352 -397.684497) (xy 175.862789 -397.690597) (xy 175.916746 -397.704703)
			(xy 175.968075 -397.726515) (xy 176.015681 -397.755569) (xy 176.058549 -397.791244) (xy 176.095766 -397.832781)
			(xy 176.126539 -397.879294) (xy 176.150211 -397.929791) (xy 176.166279 -397.983198) (xy 176.168036 -397.99514)
			(xy 182.591962 -397.99514) (xy 182.596033 -397.939518) (xy 182.608159 -397.885081) (xy 182.628082 -397.83299)
			(xy 182.655378 -397.784355) (xy 182.689464 -397.740212) (xy 182.729613 -397.701503) (xy 182.774971 -397.669052)
			(xy 182.824571 -397.643551) (xy 182.877355 -397.625544) (xy 182.932198 -397.615414) (xy 182.987932 -397.613377)
			(xy 183.043369 -397.619477) (xy 183.097326 -397.633583) (xy 183.148655 -397.655395) (xy 183.196261 -397.684449)
			(xy 183.239129 -397.720124) (xy 183.276346 -397.761661) (xy 183.307119 -397.808174) (xy 183.330791 -397.858671)
			(xy 183.346859 -397.912078) (xy 183.354979 -397.967254) (xy 183.355488 -397.99514) (xy 183.354979 -398.023026)
			(xy 183.346859 -398.078202) (xy 183.330791 -398.131609) (xy 183.307119 -398.182106) (xy 183.276346 -398.228619)
			(xy 183.239129 -398.270156) (xy 183.196261 -398.305831) (xy 183.148655 -398.334885) (xy 183.097326 -398.356697)
			(xy 183.043369 -398.370803) (xy 182.987932 -398.376903) (xy 182.932198 -398.374866) (xy 182.877355 -398.364736)
			(xy 182.824571 -398.346729) (xy 182.774971 -398.321228) (xy 182.729613 -398.288777) (xy 182.689464 -398.250068)
			(xy 182.655378 -398.205925) (xy 182.628082 -398.15729) (xy 182.608159 -398.105199) (xy 182.596033 -398.050762)
			(xy 182.591962 -397.99514) (xy 176.168036 -397.99514) (xy 176.174399 -398.038374) (xy 176.174908 -398.06626)
			(xy 176.174399 -398.094146) (xy 176.166279 -398.149322) (xy 176.150211 -398.202729) (xy 176.126539 -398.253226)
			(xy 176.095766 -398.299739) (xy 176.058549 -398.341276) (xy 176.015681 -398.376951) (xy 175.968075 -398.406005)
			(xy 175.916746 -398.427817) (xy 175.862789 -398.441923) (xy 175.807352 -398.448023) (xy 175.751618 -398.445986)
			(xy 175.696775 -398.435856) (xy 175.643991 -398.417849) (xy 175.594391 -398.392348) (xy 175.549033 -398.359897)
			(xy 175.508884 -398.321188) (xy 175.474798 -398.277045) (xy 175.447502 -398.22841) (xy 175.427579 -398.176319)
			(xy 175.415453 -398.121882) (xy 175.411382 -398.06626) (xy 172.80263 -398.06626) (xy 172.792669 -398.100186)
			(xy 172.770027 -398.149763) (xy 172.740561 -398.195613) (xy 172.70487 -398.236804) (xy 172.663679 -398.272495)
			(xy 172.617829 -398.301961) (xy 172.568252 -398.324603) (xy 172.515957 -398.339958) (xy 172.462009 -398.347714)
			(xy 172.407507 -398.347714) (xy 172.353559 -398.339958) (xy 172.301264 -398.324603) (xy 172.251687 -398.301961)
			(xy 172.205837 -398.272495) (xy 172.164646 -398.236804) (xy 172.128955 -398.195613) (xy 172.099489 -398.149763)
			(xy 172.076847 -398.100186) (xy 172.061492 -398.047891) (xy 172.053736 -397.993943) (xy 172.05325 -397.966692)
			(xy 168.97096 -397.966692) (xy 168.97096 -399.77314) (xy 171.961302 -399.77314) (xy 171.961824 -399.745144)
			(xy 171.970009 -399.689754) (xy 171.986195 -399.636152) (xy 172.010034 -399.585489) (xy 172.041016 -399.53885)
			(xy 172.078477 -399.497235) (xy 172.099732 -399.479008) (xy 172.110476 -399.469551) (xy 172.12664 -399.445944)
			(xy 172.135625 -399.41878) (xy 172.136723 -399.39019) (xy 172.129851 -399.362417) (xy 172.115546 -399.337639)
			(xy 172.105574 -399.32737) (xy 172.087362 -399.309347) (xy 172.055489 -399.269229) (xy 172.029266 -399.225208)
			(xy 172.009166 -399.178077) (xy 171.995549 -399.12868) (xy 171.988659 -399.077907) (xy 171.988226 -399.052288)
			(xy 171.988712 -399.025037) (xy 171.996468 -398.971089) (xy 172.011823 -398.918794) (xy 172.034465 -398.869217)
			(xy 172.063931 -398.823367) (xy 172.099622 -398.782176) (xy 172.140813 -398.746485) (xy 172.186663 -398.717019)
			(xy 172.23624 -398.694377) (xy 172.288535 -398.679022) (xy 172.342483 -398.671266) (xy 172.396985 -398.671266)
			(xy 172.450933 -398.679022) (xy 172.503228 -398.694377) (xy 172.552805 -398.717019) (xy 172.598655 -398.746485)
			(xy 172.639846 -398.782176) (xy 172.675537 -398.823367) (xy 172.705003 -398.869217) (xy 172.727645 -398.918794)
			(xy 172.743 -398.971089) (xy 172.750756 -399.025037) (xy 172.751242 -399.052288) (xy 172.75076 -399.080286)
			(xy 172.742569 -399.135679) (xy 172.726377 -399.189282) (xy 172.71781 -399.207482) (xy 177.95443 -399.207482)
			(xy 177.958501 -399.15186) (xy 177.970627 -399.097423) (xy 177.99055 -399.045332) (xy 178.017846 -398.996697)
			(xy 178.051932 -398.952554) (xy 178.092081 -398.913845) (xy 178.137439 -398.881394) (xy 178.187039 -398.855893)
			(xy 178.239823 -398.837886) (xy 178.294666 -398.827756) (xy 178.3504 -398.825719) (xy 178.405837 -398.831819)
			(xy 178.459794 -398.845925) (xy 178.511123 -398.867737) (xy 178.558729 -398.896791) (xy 178.601597 -398.932466)
			(xy 178.624979 -398.958562) (xy 180.52237 -398.958562) (xy 180.526441 -398.90294) (xy 180.538567 -398.848503)
			(xy 180.55849 -398.796412) (xy 180.585786 -398.747777) (xy 180.619872 -398.703634) (xy 180.660021 -398.664925)
			(xy 180.705379 -398.632474) (xy 180.754979 -398.606973) (xy 180.807763 -398.588966) (xy 180.862606 -398.578836)
			(xy 180.91834 -398.576799) (xy 180.973777 -398.582899) (xy 181.027734 -398.597005) (xy 181.079063 -398.618817)
			(xy 181.126669 -398.647871) (xy 181.169537 -398.683546) (xy 181.206754 -398.725083) (xy 181.237527 -398.771596)
			(xy 181.25254 -398.803622) (xy 181.77459 -398.803622) (xy 181.778661 -398.748) (xy 181.790787 -398.693563)
			(xy 181.81071 -398.641472) (xy 181.838006 -398.592837) (xy 181.872092 -398.548694) (xy 181.912241 -398.509985)
			(xy 181.957599 -398.477534) (xy 182.007199 -398.452033) (xy 182.059983 -398.434026) (xy 182.114826 -398.423896)
			(xy 182.17056 -398.421859) (xy 182.225997 -398.427959) (xy 182.279954 -398.442065) (xy 182.331283 -398.463877)
			(xy 182.378889 -398.492931) (xy 182.421757 -398.528606) (xy 182.458974 -398.570143) (xy 182.489747 -398.616656)
			(xy 182.513419 -398.667153) (xy 182.529487 -398.72056) (xy 182.537607 -398.775736) (xy 182.538116 -398.803622)
			(xy 182.537607 -398.831508) (xy 182.529487 -398.886684) (xy 182.513419 -398.940091) (xy 182.489747 -398.990588)
			(xy 182.458974 -399.037101) (xy 182.421757 -399.078638) (xy 182.378889 -399.114313) (xy 182.331283 -399.143367)
			(xy 182.279954 -399.165179) (xy 182.225997 -399.179285) (xy 182.17056 -399.185385) (xy 182.114826 -399.183348)
			(xy 182.059983 -399.173218) (xy 182.007199 -399.155211) (xy 181.957599 -399.12971) (xy 181.912241 -399.097259)
			(xy 181.872092 -399.05855) (xy 181.838006 -399.014407) (xy 181.81071 -398.965772) (xy 181.790787 -398.913681)
			(xy 181.778661 -398.859244) (xy 181.77459 -398.803622) (xy 181.25254 -398.803622) (xy 181.261199 -398.822093)
			(xy 181.277267 -398.8755) (xy 181.285387 -398.930676) (xy 181.285896 -398.958562) (xy 181.285387 -398.986448)
			(xy 181.277267 -399.041624) (xy 181.261199 -399.095031) (xy 181.237527 -399.145528) (xy 181.206754 -399.192041)
			(xy 181.169537 -399.233578) (xy 181.126669 -399.269253) (xy 181.079063 -399.298307) (xy 181.027734 -399.320119)
			(xy 180.973777 -399.334225) (xy 180.91834 -399.340325) (xy 180.862606 -399.338288) (xy 180.807763 -399.328158)
			(xy 180.754979 -399.310151) (xy 180.705379 -399.28465) (xy 180.660021 -399.252199) (xy 180.619872 -399.21349)
			(xy 180.585786 -399.169347) (xy 180.55849 -399.120712) (xy 180.538567 -399.068621) (xy 180.526441 -399.014184)
			(xy 180.52237 -398.958562) (xy 178.624979 -398.958562) (xy 178.638814 -398.974003) (xy 178.669587 -399.020516)
			(xy 178.693259 -399.071013) (xy 178.709327 -399.12442) (xy 178.717447 -399.179596) (xy 178.717956 -399.207482)
			(xy 178.717447 -399.235368) (xy 178.709327 -399.290544) (xy 178.693259 -399.343951) (xy 178.669587 -399.394448)
			(xy 178.638814 -399.440961) (xy 178.601597 -399.482498) (xy 178.558729 -399.518173) (xy 178.511123 -399.547227)
			(xy 178.459794 -399.569039) (xy 178.405837 -399.583145) (xy 178.3504 -399.589245) (xy 178.294666 -399.587208)
			(xy 178.239823 -399.577078) (xy 178.187039 -399.559071) (xy 178.137439 -399.53357) (xy 178.092081 -399.501119)
			(xy 178.051932 -399.46241) (xy 178.017846 -399.418267) (xy 177.99055 -399.369632) (xy 177.970627 -399.317541)
			(xy 177.958501 -399.263104) (xy 177.95443 -399.207482) (xy 172.71781 -399.207482) (xy 172.70253 -399.239945)
			(xy 172.67154 -399.286583) (xy 172.634071 -399.328195) (xy 172.612812 -399.34642) (xy 172.602044 -399.355849)
			(xy 172.585888 -399.379466) (xy 172.576912 -399.406636) (xy 172.575819 -399.435229) (xy 172.582694 -399.463005)
			(xy 172.596998 -399.487787) (xy 172.60697 -399.498058) (xy 172.625137 -399.516124) (xy 172.657017 -399.556232)
			(xy 172.683246 -399.600243) (xy 172.703355 -399.647367) (xy 172.716981 -399.696756) (xy 172.723881 -399.747523)
			(xy 172.724318 -399.77314) (xy 172.723832 -399.800391) (xy 172.716076 -399.854339) (xy 172.700721 -399.906634)
			(xy 172.678079 -399.956211) (xy 172.648613 -400.002061) (xy 172.612922 -400.043252) (xy 172.571731 -400.078943)
			(xy 172.525881 -400.108409) (xy 172.476304 -400.131051) (xy 172.424009 -400.146406) (xy 172.370061 -400.154162)
			(xy 172.315559 -400.154162) (xy 172.261611 -400.146406) (xy 172.209316 -400.131051) (xy 172.159739 -400.108409)
			(xy 172.113889 -400.078943) (xy 172.072698 -400.043252) (xy 172.037007 -400.002061) (xy 172.007541 -399.956211)
			(xy 171.984899 -399.906634) (xy 171.969544 -399.854339) (xy 171.961788 -399.800391) (xy 171.961302 -399.77314)
			(xy 168.97096 -399.77314) (xy 168.97096 -400.223482) (xy 177.95443 -400.223482) (xy 177.958501 -400.16786)
			(xy 177.970627 -400.113423) (xy 177.99055 -400.061332) (xy 178.017846 -400.012697) (xy 178.051932 -399.968554)
			(xy 178.092081 -399.929845) (xy 178.137439 -399.897394) (xy 178.187039 -399.871893) (xy 178.239823 -399.853886)
			(xy 178.294666 -399.843756) (xy 178.3504 -399.841719) (xy 178.405837 -399.847819) (xy 178.459794 -399.861925)
			(xy 178.511123 -399.883737) (xy 178.558729 -399.912791) (xy 178.601597 -399.948466) (xy 178.638814 -399.990003)
			(xy 178.669587 -400.036516) (xy 178.693259 -400.087013) (xy 178.709327 -400.14042) (xy 178.717447 -400.195596)
			(xy 178.717956 -400.223482) (xy 178.717458 -400.250755) (xy 180.238837 -400.250755) (xy 180.238837 -400.196245)
			(xy 180.246594 -400.142291) (xy 180.261952 -400.08999) (xy 180.284596 -400.040407) (xy 180.314066 -399.994551)
			(xy 180.349762 -399.953357) (xy 180.390958 -399.917661) (xy 180.436814 -399.888192) (xy 180.486398 -399.865549)
			(xy 180.538699 -399.850193) (xy 180.592653 -399.842436) (xy 180.619908 -399.841974) (xy 180.645036 -399.842382)
			(xy 180.694858 -399.848982) (xy 180.743382 -399.862066) (xy 180.789768 -399.881407) (xy 180.833213 -399.906672)
			(xy 180.853334 -399.92173) (xy 180.864458 -399.929706) (xy 180.88974 -399.940152) (xy 180.916889 -399.943504)
			(xy 180.943953 -399.93952) (xy 180.968985 -399.928488) (xy 180.990185 -399.911201) (xy 181.006029 -399.888901)
			(xy 181.015377 -399.863193) (xy 181.01691 -399.849594) (xy 181.01967 -399.821296) (xy 181.03265 -399.76594)
			(xy 181.053702 -399.713124) (xy 181.082358 -399.664017) (xy 181.117986 -399.619706) (xy 181.159794 -399.581173)
			(xy 181.206858 -399.549271) (xy 181.258136 -399.524707) (xy 181.312491 -399.508025) (xy 181.368719 -399.499595)
			(xy 181.397148 -399.499074) (xy 181.425808 -399.499602) (xy 181.48248 -399.50819) (xy 181.537233 -399.52515)
			(xy 181.588836 -399.550102) (xy 181.636131 -399.582486) (xy 181.678056 -399.621573) (xy 181.713668 -399.666487)
			(xy 181.728364 -399.691098) (xy 181.736191 -399.703693) (xy 181.757705 -399.724083) (xy 181.784166 -399.73744)
			(xy 181.813347 -399.742642) (xy 181.842793 -399.73925) (xy 181.870027 -399.72755) (xy 181.892758 -399.708527)
			(xy 181.901338 -399.696432) (xy 181.916539 -399.67415) (xy 181.952215 -399.633696) (xy 181.993235 -399.598671)
			(xy 182.038779 -399.569774) (xy 182.087941 -399.547582) (xy 182.139738 -399.532538) (xy 182.193139 -399.52494)
			(xy 182.220108 -399.524474) (xy 182.247358 -399.524997) (xy 182.301302 -399.532754) (xy 182.353593 -399.548109)
			(xy 182.403167 -399.570749) (xy 182.449014 -399.600214) (xy 182.490201 -399.635904) (xy 182.52589 -399.677092)
			(xy 182.555354 -399.72294) (xy 182.577994 -399.772514) (xy 182.593348 -399.824806) (xy 182.601104 -399.87875)
			(xy 182.601104 -399.93325) (xy 182.593348 -399.987194) (xy 182.577994 -400.039486) (xy 182.555354 -400.08906)
			(xy 182.52589 -400.134908) (xy 182.490201 -400.176096) (xy 182.449014 -400.211786) (xy 182.403167 -400.241251)
			(xy 182.353593 -400.263891) (xy 182.301302 -400.279246) (xy 182.247358 -400.287003) (xy 182.220108 -400.28749)
			(xy 182.191449 -400.286936) (xy 182.134777 -400.278355) (xy 182.080024 -400.261401) (xy 182.02842 -400.236454)
			(xy 181.981124 -400.204074) (xy 181.939199 -400.164988) (xy 181.903587 -400.120076) (xy 181.888892 -400.095466)
			(xy 181.881126 -400.082826) (xy 181.859603 -400.062422) (xy 181.833129 -400.049057) (xy 181.803931 -400.043856)
			(xy 181.77447 -400.047258) (xy 181.747226 -400.058977) (xy 181.724494 -400.078025) (xy 181.715918 -400.090132)
			(xy 181.700734 -400.112426) (xy 181.665056 -400.152882) (xy 181.624034 -400.187907) (xy 181.578487 -400.216803)
			(xy 181.529322 -400.238993) (xy 181.477521 -400.254034) (xy 181.424118 -400.261627) (xy 181.397148 -400.26209)
			(xy 181.372019 -400.261693) (xy 181.322198 -400.255088) (xy 181.273674 -400.242001) (xy 181.227288 -400.222658)
			(xy 181.183843 -400.197392) (xy 181.163722 -400.182334) (xy 181.152662 -400.17426) (xy 181.127361 -400.163808)
			(xy 181.100193 -400.160458) (xy 181.073111 -400.16445) (xy 181.048064 -400.175498) (xy 181.026856 -400.192806)
			(xy 181.011012 -400.215129) (xy 181.001671 -400.240861) (xy 181.000146 -400.25447) (xy 180.997301 -400.282758)
			(xy 180.984328 -400.338108) (xy 180.963285 -400.39092) (xy 180.934638 -400.440025) (xy 180.89902 -400.484335)
			(xy 180.857222 -400.522868) (xy 180.810168 -400.554772) (xy 180.7589 -400.57934) (xy 180.704554 -400.596028)
			(xy 180.648333 -400.604465) (xy 180.619908 -400.60499) (xy 180.592653 -400.604564) (xy 180.538699 -400.596807)
			(xy 180.486398 -400.581451) (xy 180.436814 -400.558808) (xy 180.390958 -400.529339) (xy 180.349762 -400.493643)
			(xy 180.314066 -400.452449) (xy 180.284596 -400.406593) (xy 180.261952 -400.35701) (xy 180.246594 -400.304709)
			(xy 180.238837 -400.250755) (xy 178.717458 -400.250755) (xy 178.717447 -400.251368) (xy 178.709327 -400.306544)
			(xy 178.693259 -400.359951) (xy 178.669587 -400.410448) (xy 178.638814 -400.456961) (xy 178.601597 -400.498498)
			(xy 178.558729 -400.534173) (xy 178.511123 -400.563227) (xy 178.459794 -400.585039) (xy 178.405837 -400.599145)
			(xy 178.3504 -400.605245) (xy 178.294666 -400.603208) (xy 178.239823 -400.593078) (xy 178.187039 -400.575071)
			(xy 178.137439 -400.54957) (xy 178.092081 -400.517119) (xy 178.051932 -400.47841) (xy 178.017846 -400.434267)
			(xy 177.99055 -400.385632) (xy 177.970627 -400.333541) (xy 177.958501 -400.279104) (xy 177.95443 -400.223482)
			(xy 168.97096 -400.223482) (xy 168.97096 -401.15109) (xy 168.971505 -401.166172) (xy 168.980315 -401.195021)
			(xy 168.997169 -401.220038) (xy 169.020597 -401.239039) (xy 169.048554 -401.250366) (xy 169.0786 -401.253031)
			(xy 169.108114 -401.246802) (xy 169.121582 -401.23999) (xy 169.149961 -401.225072) (xy 169.210476 -401.20391)
			(xy 169.273678 -401.193172) (xy 169.305732 -401.192492) (xy 169.30624 -401.192492) (xy 169.333489 -401.192981)
			(xy 169.387433 -401.200742) (xy 169.439723 -401.2161) (xy 169.489295 -401.238744) (xy 169.53514 -401.268211)
			(xy 169.576326 -401.303903) (xy 169.612013 -401.345092) (xy 169.641476 -401.39094) (xy 169.664114 -401.440515)
			(xy 169.679467 -401.492806) (xy 169.687222 -401.546751) (xy 169.687222 -401.601249) (xy 169.679467 -401.655194)
			(xy 169.664114 -401.707485) (xy 169.641476 -401.75706) (xy 169.612013 -401.802908) (xy 169.576326 -401.844097)
			(xy 169.549764 -401.867116) (xy 171.985432 -401.867116) (xy 171.985843 -401.84127) (xy 171.992832 -401.790054)
			(xy 172.006671 -401.74025) (xy 172.027107 -401.69277) (xy 172.053765 -401.648483) (xy 172.086158 -401.6082)
			(xy 172.123692 -401.572659) (xy 172.144436 -401.557236) (xy 172.155338 -401.548828) (xy 172.172636 -401.527429)
			(xy 172.183584 -401.502185) (xy 172.187385 -401.474932) (xy 172.183762 -401.447655) (xy 172.172978 -401.42234)
			(xy 172.155819 -401.400829) (xy 172.144944 -401.39239) (xy 172.124401 -401.376959) (xy 172.087267 -401.341448)
			(xy 172.055235 -401.301274) (xy 172.028886 -401.257164) (xy 172.008696 -401.209916) (xy 171.99503 -401.160386)
			(xy 171.988136 -401.10947) (xy 171.987718 -401.08378) (xy 171.988204 -401.056529) (xy 171.99596 -401.002581)
			(xy 172.011315 -400.950286) (xy 172.033957 -400.900709) (xy 172.063423 -400.854859) (xy 172.099114 -400.813668)
			(xy 172.140305 -400.777977) (xy 172.186155 -400.748511) (xy 172.235732 -400.725869) (xy 172.288027 -400.710514)
			(xy 172.341975 -400.702758) (xy 172.396477 -400.702758) (xy 172.450425 -400.710514) (xy 172.50272 -400.725869)
			(xy 172.552297 -400.748511) (xy 172.574337 -400.762675) (xy 174.847103 -400.762675) (xy 174.854857 -400.708715)
			(xy 174.870211 -400.656408) (xy 174.892853 -400.606818) (xy 174.922323 -400.560955) (xy 174.95802 -400.519754)
			(xy 174.999217 -400.484052) (xy 175.045076 -400.454577) (xy 175.094663 -400.431928) (xy 175.146968 -400.416567)
			(xy 175.200927 -400.408806) (xy 175.255442 -400.408804) (xy 175.309402 -400.41656) (xy 175.361709 -400.431917)
			(xy 175.411297 -400.454562) (xy 175.457159 -400.484033) (xy 175.498359 -400.519732) (xy 175.534059 -400.560931)
			(xy 175.563532 -400.606791) (xy 175.586178 -400.656379) (xy 175.601537 -400.708685) (xy 175.609295 -400.762645)
			(xy 175.609758 -400.789902) (xy 175.609758 -400.79041) (xy 175.609341 -400.814852) (xy 175.603053 -400.863331)
			(xy 175.590633 -400.910611) (xy 175.581818 -400.933412) (xy 175.576988 -400.946287) (xy 175.57385 -400.973602)
			(xy 175.578109 -401.000764) (xy 175.589457 -401.025808) (xy 175.607071 -401.046918) (xy 175.629678 -401.062568)
			(xy 175.655638 -401.071622) (xy 175.683073 -401.073427) (xy 175.696626 -401.07108) (xy 175.715895 -401.067271)
			(xy 175.754964 -401.063205) (xy 175.774604 -401.062952) (xy 175.801857 -401.06346) (xy 175.855808 -401.071217)
			(xy 175.908107 -401.086574) (xy 175.957687 -401.109218) (xy 176.00354 -401.138687) (xy 176.044732 -401.174382)
			(xy 176.080425 -401.215576) (xy 176.095787 -401.239482) (xy 177.95443 -401.239482) (xy 177.958501 -401.18386)
			(xy 177.970627 -401.129423) (xy 177.99055 -401.077332) (xy 178.017846 -401.028697) (xy 178.051932 -400.984554)
			(xy 178.092081 -400.945845) (xy 178.137439 -400.913394) (xy 178.187039 -400.887893) (xy 178.239823 -400.869886)
			(xy 178.294666 -400.859756) (xy 178.3504 -400.857719) (xy 178.405837 -400.863819) (xy 178.459794 -400.877925)
			(xy 178.511123 -400.899737) (xy 178.558729 -400.928791) (xy 178.601597 -400.964466) (xy 178.638814 -401.006003)
			(xy 178.669587 -401.052516) (xy 178.693259 -401.103013) (xy 178.709327 -401.15642) (xy 178.717447 -401.211596)
			(xy 178.717956 -401.239482) (xy 180.73319 -401.239482) (xy 180.737261 -401.18386) (xy 180.749387 -401.129423)
			(xy 180.76931 -401.077332) (xy 180.796606 -401.028697) (xy 180.830692 -400.984554) (xy 180.870841 -400.945845)
			(xy 180.916199 -400.913394) (xy 180.965799 -400.887893) (xy 181.018583 -400.869886) (xy 181.073426 -400.859756)
			(xy 181.12916 -400.857719) (xy 181.184597 -400.863819) (xy 181.238554 -400.877925) (xy 181.289883 -400.899737)
			(xy 181.337489 -400.928791) (xy 181.380357 -400.964466) (xy 181.417574 -401.006003) (xy 181.448347 -401.052516)
			(xy 181.472019 -401.103013) (xy 181.488087 -401.15642) (xy 181.496207 -401.211596) (xy 181.496716 -401.239482)
			(xy 181.496207 -401.267368) (xy 181.488087 -401.322544) (xy 181.472019 -401.375951) (xy 181.448347 -401.426448)
			(xy 181.417574 -401.472961) (xy 181.380357 -401.514498) (xy 181.337489 -401.550173) (xy 181.289883 -401.579227)
			(xy 181.238554 -401.601039) (xy 181.184597 -401.615145) (xy 181.12916 -401.621245) (xy 181.073426 -401.619208)
			(xy 181.018583 -401.609078) (xy 180.965799 -401.591071) (xy 180.916199 -401.56557) (xy 180.870841 -401.533119)
			(xy 180.830692 -401.49441) (xy 180.796606 -401.450267) (xy 180.76931 -401.401632) (xy 180.749387 -401.349541)
			(xy 180.737261 -401.295104) (xy 180.73319 -401.239482) (xy 178.717956 -401.239482) (xy 178.717447 -401.267368)
			(xy 178.709327 -401.322544) (xy 178.693259 -401.375951) (xy 178.669587 -401.426448) (xy 178.638814 -401.472961)
			(xy 178.601597 -401.514498) (xy 178.558729 -401.550173) (xy 178.511123 -401.579227) (xy 178.459794 -401.601039)
			(xy 178.405837 -401.615145) (xy 178.3504 -401.621245) (xy 178.294666 -401.619208) (xy 178.239823 -401.609078)
			(xy 178.187039 -401.591071) (xy 178.137439 -401.56557) (xy 178.092081 -401.533119) (xy 178.051932 -401.49441)
			(xy 178.017846 -401.450267) (xy 177.99055 -401.401632) (xy 177.970627 -401.349541) (xy 177.958501 -401.295104)
			(xy 177.95443 -401.239482) (xy 176.095787 -401.239482) (xy 176.109892 -401.261431) (xy 176.132533 -401.311012)
			(xy 176.147887 -401.363311) (xy 176.155642 -401.417263) (xy 176.155639 -401.471769) (xy 176.14788 -401.52572)
			(xy 176.132521 -401.578018) (xy 176.109876 -401.627597) (xy 176.080405 -401.673449) (xy 176.044709 -401.71464)
			(xy 176.003514 -401.750332) (xy 175.957659 -401.779797) (xy 175.908076 -401.802437) (xy 175.855777 -401.817789)
			(xy 175.801825 -401.825543) (xy 175.747319 -401.825539) (xy 175.693368 -401.817777) (xy 175.641071 -401.802417)
			(xy 175.591492 -401.77977) (xy 175.545641 -401.750298) (xy 175.504451 -401.714601) (xy 175.468761 -401.673404)
			(xy 175.439297 -401.627548) (xy 175.416659 -401.577965) (xy 175.401308 -401.525665) (xy 175.393557 -401.471713)
			(xy 175.393096 -401.44446) (xy 175.393096 -401.443952) (xy 175.393505 -401.41951) (xy 175.399796 -401.371031)
			(xy 175.41222 -401.323751) (xy 175.421036 -401.30095) (xy 175.425733 -401.288031) (xy 175.428879 -401.260737)
			(xy 175.424633 -401.233593) (xy 175.413303 -401.208564) (xy 175.395709 -401.187461) (xy 175.373125 -401.171815)
			(xy 175.347187 -401.162756) (xy 175.319772 -401.160943) (xy 175.306228 -401.163282) (xy 175.286958 -401.167082)
			(xy 175.24789 -401.171155) (xy 175.22825 -401.17141) (xy 175.200993 -401.170999) (xy 175.147032 -401.163247)
			(xy 175.094724 -401.147895) (xy 175.045133 -401.125255) (xy 174.999269 -401.095787) (xy 174.958066 -401.060092)
			(xy 174.922362 -401.018897) (xy 174.892885 -400.97304) (xy 174.870234 -400.923454) (xy 174.85487 -400.871149)
			(xy 174.847107 -400.81719) (xy 174.847103 -400.762675) (xy 172.574337 -400.762675) (xy 172.598147 -400.777977)
			(xy 172.639338 -400.813668) (xy 172.675029 -400.854859) (xy 172.704495 -400.900709) (xy 172.727137 -400.950286)
			(xy 172.742492 -401.002581) (xy 172.750248 -401.056529) (xy 172.750734 -401.08378) (xy 172.750334 -401.109626)
			(xy 172.743345 -401.160844) (xy 172.729505 -401.210649) (xy 172.709067 -401.258129) (xy 172.682407 -401.302416)
			(xy 172.650012 -401.342698) (xy 172.612475 -401.378238) (xy 172.59173 -401.39366) (xy 172.580835 -401.402075)
			(xy 172.563543 -401.423474) (xy 172.552598 -401.448716) (xy 172.548798 -401.475966) (xy 172.552419 -401.503239)
			(xy 172.563198 -401.528553) (xy 172.58035 -401.550065) (xy 172.591222 -401.558506) (xy 172.611756 -401.57395)
			(xy 172.648892 -401.609457) (xy 172.680925 -401.649629) (xy 172.707276 -401.693737) (xy 172.727468 -401.740982)
			(xy 172.741135 -401.790511) (xy 172.74803 -401.841426) (xy 172.748448 -401.867116) (xy 172.747962 -401.894367)
			(xy 172.740206 -401.948315) (xy 172.724851 -402.00061) (xy 172.702209 -402.050187) (xy 172.672743 -402.096037)
			(xy 172.637052 -402.137228) (xy 172.595861 -402.172919) (xy 172.550011 -402.202385) (xy 172.500434 -402.225027)
			(xy 172.448139 -402.240382) (xy 172.394191 -402.248138) (xy 172.339689 -402.248138) (xy 172.285741 -402.240382)
			(xy 172.233446 -402.225027) (xy 172.183869 -402.202385) (xy 172.138019 -402.172919) (xy 172.096828 -402.137228)
			(xy 172.061137 -402.096037) (xy 172.031671 -402.050187) (xy 172.009029 -402.00061) (xy 171.993674 -401.948315)
			(xy 171.985918 -401.894367) (xy 171.985432 -401.867116) (xy 169.549764 -401.867116) (xy 169.53514 -401.879789)
			(xy 169.489295 -401.909256) (xy 169.439723 -401.9319) (xy 169.387433 -401.947258) (xy 169.333489 -401.955019)
			(xy 169.30624 -401.955508) (xy 169.305732 -401.955508) (xy 169.273678 -401.954831) (xy 169.210477 -401.944082)
			(xy 169.149958 -401.922932) (xy 169.121582 -401.90801) (xy 169.108116 -401.901219) (xy 169.078617 -401.895024)
			(xy 169.048594 -401.897707) (xy 169.020661 -401.909036) (xy 168.997251 -401.928023) (xy 168.9804 -401.953017)
			(xy 168.971578 -401.981839) (xy 168.97096 -401.99691) (xy 168.97096 -402.147532) (xy 168.971466 -402.162815)
			(xy 168.980488 -402.19202) (xy 168.997744 -402.217249) (xy 169.021691 -402.236244) (xy 169.050185 -402.247307)
			(xy 169.080677 -402.249445) (xy 169.110436 -402.242469) (xy 169.123868 -402.235162) (xy 169.14583 -402.222792)
			(xy 169.19232 -402.203312) (xy 169.240975 -402.190139) (xy 169.290943 -402.183505) (xy 169.316146 -402.183092)
			(xy 169.3164 -402.183092) (xy 169.343651 -402.183578) (xy 169.397599 -402.191334) (xy 169.449894 -402.206689)
			(xy 169.499471 -402.229331) (xy 169.540163 -402.255482) (xy 177.95443 -402.255482) (xy 177.958501 -402.19986)
			(xy 177.970627 -402.145423) (xy 177.99055 -402.093332) (xy 178.017846 -402.044697) (xy 178.051932 -402.000554)
			(xy 178.092081 -401.961845) (xy 178.137439 -401.929394) (xy 178.187039 -401.903893) (xy 178.239823 -401.885886)
			(xy 178.294666 -401.875756) (xy 178.3504 -401.873719) (xy 178.405837 -401.879819) (xy 178.459794 -401.893925)
			(xy 178.511123 -401.915737) (xy 178.558729 -401.944791) (xy 178.601597 -401.980466) (xy 178.638814 -402.022003)
			(xy 178.669587 -402.068516) (xy 178.693259 -402.119013) (xy 178.709327 -402.17242) (xy 178.717447 -402.227596)
			(xy 178.717956 -402.255482) (xy 178.717447 -402.283368) (xy 178.709327 -402.338544) (xy 178.693259 -402.391951)
			(xy 178.669587 -402.442448) (xy 178.638814 -402.488961) (xy 178.601597 -402.530498) (xy 178.578016 -402.550122)
			(xy 180.61381 -402.550122) (xy 180.617881 -402.4945) (xy 180.630007 -402.440063) (xy 180.64993 -402.387972)
			(xy 180.677226 -402.339337) (xy 180.711312 -402.295194) (xy 180.751461 -402.256485) (xy 180.796819 -402.224034)
			(xy 180.846419 -402.198533) (xy 180.899203 -402.180526) (xy 180.954046 -402.170396) (xy 181.00978 -402.168359)
			(xy 181.065217 -402.174459) (xy 181.119174 -402.188565) (xy 181.170503 -402.210377) (xy 181.218109 -402.239431)
			(xy 181.260977 -402.275106) (xy 181.298194 -402.316643) (xy 181.328967 -402.363156) (xy 181.352639 -402.413653)
			(xy 181.368707 -402.46706) (xy 181.373156 -402.49729) (xy 181.63743 -402.49729) (xy 181.641501 -402.441668)
			(xy 181.653627 -402.387231) (xy 181.67355 -402.33514) (xy 181.700846 -402.286505) (xy 181.734932 -402.242362)
			(xy 181.775081 -402.203653) (xy 181.820439 -402.171202) (xy 181.870039 -402.145701) (xy 181.922823 -402.127694)
			(xy 181.977666 -402.117564) (xy 182.0334 -402.115527) (xy 182.088837 -402.121627) (xy 182.142794 -402.135733)
			(xy 182.194123 -402.157545) (xy 182.241729 -402.186599) (xy 182.284597 -402.222274) (xy 182.321814 -402.263811)
			(xy 182.352587 -402.310324) (xy 182.376259 -402.360821) (xy 182.392327 -402.414228) (xy 182.400447 -402.469404)
			(xy 182.400956 -402.49729) (xy 182.400447 -402.525176) (xy 182.392327 -402.580352) (xy 182.376259 -402.633759)
			(xy 182.352587 -402.684256) (xy 182.321814 -402.730769) (xy 182.284597 -402.772306) (xy 182.241729 -402.807981)
			(xy 182.194123 -402.837035) (xy 182.142794 -402.858847) (xy 182.088837 -402.872953) (xy 182.0334 -402.879053)
			(xy 181.977666 -402.877016) (xy 181.922823 -402.866886) (xy 181.870039 -402.848879) (xy 181.820439 -402.823378)
			(xy 181.775081 -402.790927) (xy 181.734932 -402.752218) (xy 181.700846 -402.708075) (xy 181.67355 -402.65944)
			(xy 181.653627 -402.607349) (xy 181.641501 -402.552912) (xy 181.63743 -402.49729) (xy 181.373156 -402.49729)
			(xy 181.376827 -402.522236) (xy 181.377336 -402.550122) (xy 181.376827 -402.578008) (xy 181.368707 -402.633184)
			(xy 181.352639 -402.686591) (xy 181.328967 -402.737088) (xy 181.298194 -402.783601) (xy 181.260977 -402.825138)
			(xy 181.218109 -402.860813) (xy 181.170503 -402.889867) (xy 181.119174 -402.911679) (xy 181.065217 -402.925785)
			(xy 181.00978 -402.931885) (xy 180.954046 -402.929848) (xy 180.899203 -402.919718) (xy 180.846419 -402.901711)
			(xy 180.796819 -402.87621) (xy 180.751461 -402.843759) (xy 180.711312 -402.80505) (xy 180.677226 -402.760907)
			(xy 180.64993 -402.712272) (xy 180.630007 -402.660181) (xy 180.617881 -402.605744) (xy 180.61381 -402.550122)
			(xy 178.578016 -402.550122) (xy 178.558729 -402.566173) (xy 178.511123 -402.595227) (xy 178.459794 -402.617039)
			(xy 178.405837 -402.631145) (xy 178.3504 -402.637245) (xy 178.294666 -402.635208) (xy 178.239823 -402.625078)
			(xy 178.187039 -402.607071) (xy 178.137439 -402.58157) (xy 178.092081 -402.549119) (xy 178.051932 -402.51041)
			(xy 178.017846 -402.466267) (xy 177.99055 -402.417632) (xy 177.970627 -402.365541) (xy 177.958501 -402.311104)
			(xy 177.95443 -402.255482) (xy 169.540163 -402.255482) (xy 169.545321 -402.258797) (xy 169.586512 -402.294488)
			(xy 169.622203 -402.335679) (xy 169.651669 -402.381529) (xy 169.674311 -402.431106) (xy 169.689666 -402.483401)
			(xy 169.697422 -402.537349) (xy 169.697422 -402.591851) (xy 169.689666 -402.645799) (xy 169.674311 -402.698094)
			(xy 169.651669 -402.747671) (xy 169.622203 -402.793521) (xy 169.590569 -402.83003) (xy 172.025816 -402.83003)
			(xy 172.029887 -402.774408) (xy 172.042013 -402.719971) (xy 172.061936 -402.66788) (xy 172.089232 -402.619245)
			(xy 172.123318 -402.575102) (xy 172.163467 -402.536393) (xy 172.208825 -402.503942) (xy 172.258425 -402.478441)
			(xy 172.311209 -402.460434) (xy 172.366052 -402.450304) (xy 172.421786 -402.448267) (xy 172.477223 -402.454367)
			(xy 172.53118 -402.468473) (xy 172.582509 -402.490285) (xy 172.630115 -402.519339) (xy 172.672983 -402.555014)
			(xy 172.7102 -402.596551) (xy 172.740973 -402.643064) (xy 172.764645 -402.693561) (xy 172.780713 -402.746968)
			(xy 172.788833 -402.802144) (xy 172.789342 -402.83003) (xy 172.788833 -402.857916) (xy 172.780713 -402.913092)
			(xy 172.764645 -402.966499) (xy 172.740973 -403.016996) (xy 172.7102 -403.063509) (xy 172.672983 -403.105046)
			(xy 172.630115 -403.140721) (xy 172.582509 -403.169775) (xy 172.53118 -403.191587) (xy 172.477223 -403.205693)
			(xy 172.421786 -403.211793) (xy 172.366052 -403.209756) (xy 172.311209 -403.199626) (xy 172.258425 -403.181619)
			(xy 172.208825 -403.156118) (xy 172.163467 -403.123667) (xy 172.123318 -403.084958) (xy 172.089232 -403.040815)
			(xy 172.061936 -402.99218) (xy 172.042013 -402.940089) (xy 172.029887 -402.885652) (xy 172.025816 -402.83003)
			(xy 169.590569 -402.83003) (xy 169.586512 -402.834712) (xy 169.545321 -402.870403) (xy 169.499471 -402.899869)
			(xy 169.449894 -402.922511) (xy 169.397599 -402.937866) (xy 169.343651 -402.945622) (xy 169.3164 -402.946108)
			(xy 169.316146 -402.946108) (xy 169.290945 -402.945682) (xy 169.240986 -402.939015) (xy 169.192335 -402.925842)
			(xy 169.145837 -402.906392) (xy 169.123868 -402.894038) (xy 169.110429 -402.886774) (xy 169.080691 -402.879835)
			(xy 169.050231 -402.881992) (xy 169.021769 -402.893054) (xy 168.997845 -402.912031) (xy 168.980598 -402.93723)
			(xy 168.971566 -402.9664) (xy 168.97096 -402.981668) (xy 168.97096 -403.077934) (xy 168.971417 -403.091679)
			(xy 168.978766 -403.118167) (xy 168.99292 -403.141733) (xy 169.012853 -403.160663) (xy 169.037116 -403.173585)
			(xy 169.063948 -403.179558) (xy 169.091402 -403.178151) (xy 169.117483 -403.169465) (xy 169.129202 -403.162262)
			(xy 169.152897 -403.146956) (xy 169.203844 -403.122741) (xy 169.257803 -403.106298) (xy 169.313596 -403.097986)
			(xy 169.3418 -403.097492) (xy 169.369051 -403.097978) (xy 169.422999 -403.105734) (xy 169.475294 -403.121089)
			(xy 169.524871 -403.143731) (xy 169.570721 -403.173197) (xy 169.611912 -403.208888) (xy 169.647603 -403.250079)
			(xy 169.661358 -403.271482) (xy 177.95443 -403.271482) (xy 177.958501 -403.21586) (xy 177.970627 -403.161423)
			(xy 177.99055 -403.109332) (xy 178.017846 -403.060697) (xy 178.051932 -403.016554) (xy 178.092081 -402.977845)
			(xy 178.137439 -402.945394) (xy 178.187039 -402.919893) (xy 178.239823 -402.901886) (xy 178.294666 -402.891756)
			(xy 178.3504 -402.889719) (xy 178.405837 -402.895819) (xy 178.459794 -402.909925) (xy 178.511123 -402.931737)
			(xy 178.558729 -402.960791) (xy 178.601597 -402.996466) (xy 178.638814 -403.038003) (xy 178.669587 -403.084516)
			(xy 178.693259 -403.135013) (xy 178.709327 -403.18842) (xy 178.717447 -403.243596) (xy 178.717956 -403.271482)
			(xy 178.717447 -403.299368) (xy 178.709327 -403.354544) (xy 178.693259 -403.407951) (xy 178.669587 -403.458448)
			(xy 178.638814 -403.504961) (xy 178.601597 -403.546498) (xy 178.558729 -403.582173) (xy 178.511123 -403.611227)
			(xy 178.459794 -403.633039) (xy 178.405837 -403.647145) (xy 178.3504 -403.653245) (xy 178.294666 -403.651208)
			(xy 178.239823 -403.641078) (xy 178.187039 -403.623071) (xy 178.137439 -403.59757) (xy 178.092081 -403.565119)
			(xy 178.051932 -403.52641) (xy 178.017846 -403.482267) (xy 177.99055 -403.433632) (xy 177.970627 -403.381541)
			(xy 177.958501 -403.327104) (xy 177.95443 -403.271482) (xy 169.661358 -403.271482) (xy 169.677069 -403.295929)
			(xy 169.699711 -403.345506) (xy 169.715066 -403.397801) (xy 169.722822 -403.451749) (xy 169.723308 -403.479)
			(xy 169.722863 -403.505379) (xy 169.715599 -403.557634) (xy 169.70121 -403.608392) (xy 169.67997 -403.656685)
			(xy 169.652282 -403.701593) (xy 169.618676 -403.742262) (xy 169.57979 -403.777917) (xy 169.536365 -403.807878)
			(xy 169.512996 -403.820122) (xy 169.500641 -403.826826) (xy 169.47992 -403.845805) (xy 169.465165 -403.869718)
			(xy 169.457496 -403.89675) (xy 169.457496 -403.92485) (xy 169.465165 -403.951882) (xy 169.47992 -403.975795)
			(xy 169.500641 -403.994774) (xy 169.512996 -404.001478) (xy 169.536365 -404.013722) (xy 169.579791 -404.04368)
			(xy 169.618677 -404.079333) (xy 169.652282 -404.120002) (xy 169.679965 -404.164912) (xy 169.701199 -404.213207)
			(xy 169.71558 -404.263966) (xy 169.722832 -404.316222) (xy 169.723308 -404.3426) (xy 169.722822 -404.369851)
			(xy 169.715066 -404.423799) (xy 169.699711 -404.476094) (xy 169.677069 -404.525671) (xy 169.647603 -404.571521)
			(xy 169.611912 -404.612712) (xy 169.570721 -404.648403) (xy 169.524871 -404.677869) (xy 169.475294 -404.700511)
			(xy 169.422999 -404.715866) (xy 169.369051 -404.723622) (xy 169.3418 -404.724108) (xy 169.313596 -404.723599)
			(xy 169.257805 -404.71529) (xy 169.203846 -404.698851) (xy 169.152897 -404.674643) (xy 169.129202 -404.659338)
			(xy 169.117535 -404.652055) (xy 169.091444 -404.643386) (xy 169.063987 -404.641996) (xy 169.037154 -404.647984)
			(xy 169.012893 -404.660917) (xy 168.992964 -404.679856) (xy 168.978813 -404.703427) (xy 168.971466 -404.72992)
			(xy 168.97096 -404.743666) (xy 168.97096 -404.855934) (xy 168.971417 -404.869679) (xy 168.978766 -404.896167)
			(xy 168.99292 -404.919733) (xy 169.012853 -404.938663) (xy 169.037116 -404.951585) (xy 169.063948 -404.957558)
			(xy 169.091402 -404.956151) (xy 169.117483 -404.947465) (xy 169.129202 -404.940262) (xy 169.152897 -404.924956)
			(xy 169.203844 -404.900741) (xy 169.257803 -404.884298) (xy 169.313596 -404.875986) (xy 169.3418 -404.875492)
			(xy 169.369051 -404.875978) (xy 169.422999 -404.883734) (xy 169.475294 -404.899089) (xy 169.524871 -404.921731)
			(xy 169.570721 -404.951197) (xy 169.611912 -404.986888) (xy 169.647603 -405.028079) (xy 169.677069 -405.073929)
			(xy 169.699711 -405.123506) (xy 169.715066 -405.175801) (xy 169.722822 -405.229749) (xy 169.722822 -405.2316)
			(xy 172.059092 -405.2316) (xy 172.059092 -405.231346) (xy 172.059517 -405.20505) (xy 172.06677 -405.15296)
			(xy 172.081103 -405.102358) (xy 172.102244 -405.054202) (xy 172.129795 -405.009403) (xy 172.163233 -404.96881)
			(xy 172.182282 -404.950676) (xy 172.192304 -404.940865) (xy 172.207004 -404.916992) (xy 172.214643 -404.890018)
			(xy 172.214643 -404.861982) (xy 172.207004 -404.835008) (xy 172.192304 -404.811135) (xy 172.182282 -404.801324)
			(xy 172.16323 -404.783161) (xy 172.129746 -404.742549) (xy 172.10217 -404.697715) (xy 172.081026 -404.649512)
			(xy 172.066717 -404.598859) (xy 172.059514 -404.546718) (xy 172.059092 -404.5204) (xy 172.059501 -404.494083)
			(xy 172.066731 -404.441947) (xy 172.081052 -404.391298) (xy 172.102195 -404.343096) (xy 172.129758 -404.298255)
			(xy 172.163219 -404.257625) (xy 172.182282 -404.239476) (xy 172.192304 -404.229665) (xy 172.207004 -404.205792)
			(xy 172.214643 -404.178818) (xy 172.214643 -404.150782) (xy 172.207004 -404.123808) (xy 172.192304 -404.099935)
			(xy 172.182282 -404.090124) (xy 172.163225 -404.071996) (xy 172.12977 -404.031414) (xy 172.102211 -403.986617)
			(xy 172.081072 -403.938457) (xy 172.066755 -403.887848) (xy 172.05953 -403.835752) (xy 172.059092 -403.809454)
			(xy 172.059092 -403.8092) (xy 172.059578 -403.781949) (xy 172.067334 -403.728001) (xy 172.082689 -403.675706)
			(xy 172.105331 -403.626129) (xy 172.134797 -403.580279) (xy 172.170488 -403.539088) (xy 172.211679 -403.503397)
			(xy 172.257529 -403.473931) (xy 172.307106 -403.451289) (xy 172.359401 -403.435934) (xy 172.413349 -403.428178)
			(xy 172.467851 -403.428178) (xy 172.521799 -403.435934) (xy 172.574094 -403.451289) (xy 172.623671 -403.473931)
			(xy 172.669521 -403.503397) (xy 172.710712 -403.539088) (xy 172.746403 -403.580279) (xy 172.775869 -403.626129)
			(xy 172.798511 -403.675706) (xy 172.813866 -403.728001) (xy 172.821622 -403.781949) (xy 172.822108 -403.8092)
			(xy 172.822108 -403.809454) (xy 172.821683 -403.83575) (xy 172.81443 -403.88784) (xy 172.800097 -403.938442)
			(xy 172.778956 -403.986598) (xy 172.751405 -404.031397) (xy 172.717967 -404.07199) (xy 172.698918 -404.090124)
			(xy 172.688896 -404.099935) (xy 172.674196 -404.123808) (xy 172.666557 -404.150782) (xy 172.666557 -404.178818)
			(xy 172.674196 -404.205792) (xy 172.688896 -404.229665) (xy 172.698918 -404.239476) (xy 172.71797 -404.257639)
			(xy 172.742575 -404.287482) (xy 177.95443 -404.287482) (xy 177.958501 -404.23186) (xy 177.970627 -404.177423)
			(xy 177.99055 -404.125332) (xy 178.017846 -404.076697) (xy 178.051932 -404.032554) (xy 178.092081 -403.993845)
			(xy 178.137439 -403.961394) (xy 178.187039 -403.935893) (xy 178.239823 -403.917886) (xy 178.294666 -403.907756)
			(xy 178.3504 -403.905719) (xy 178.405837 -403.911819) (xy 178.459794 -403.925925) (xy 178.511123 -403.947737)
			(xy 178.558729 -403.976791) (xy 178.601597 -404.012466) (xy 178.638814 -404.054003) (xy 178.649499 -404.070153)
			(xy 180.301858 -404.070153) (xy 180.301858 -404.015647) (xy 180.309615 -403.961697) (xy 180.324971 -403.909399)
			(xy 180.347613 -403.859819) (xy 180.377081 -403.813967) (xy 180.412774 -403.772774) (xy 180.453967 -403.737081)
			(xy 180.499819 -403.707613) (xy 180.549399 -403.684971) (xy 180.601697 -403.669615) (xy 180.655647 -403.661858)
			(xy 180.6829 -403.661372) (xy 180.710305 -403.661837) (xy 180.76455 -403.669686) (xy 180.817112 -403.685222)
			(xy 180.866907 -403.708126) (xy 180.912909 -403.737924) (xy 180.933852 -403.755606) (xy 180.944742 -403.764409)
			(xy 180.970055 -403.776351) (xy 180.997658 -403.780979) (xy 181.025482 -403.777946) (xy 181.05144 -403.767481)
			(xy 181.073587 -403.750368) (xy 181.090263 -403.727889) (xy 181.09565 -403.714966) (xy 181.106349 -403.688164)
			(xy 181.134644 -403.63787) (xy 181.170192 -403.592411) (xy 181.212182 -403.552826) (xy 181.259654 -403.520017)
			(xy 181.311527 -403.494732) (xy 181.366617 -403.477549) (xy 181.423666 -403.46886) (xy 181.45252 -403.468332)
			(xy 181.479773 -403.468739) (xy 181.533724 -403.476499) (xy 181.586022 -403.491857) (xy 181.635602 -403.514502)
			(xy 181.681455 -403.543972) (xy 181.722647 -403.579667) (xy 181.75834 -403.620861) (xy 181.787808 -403.666715)
			(xy 181.81045 -403.716297) (xy 181.825805 -403.768595) (xy 181.833562 -403.822547) (xy 181.833562 -403.877053)
			(xy 181.825805 -403.931005) (xy 181.81045 -403.983303) (xy 181.787808 -404.032885) (xy 181.75834 -404.078739)
			(xy 181.722647 -404.119933) (xy 181.681455 -404.155628) (xy 181.635602 -404.185098) (xy 181.586022 -404.207743)
			(xy 181.533724 -404.223101) (xy 181.479773 -404.230861) (xy 181.45252 -404.231348) (xy 181.425116 -404.230867)
			(xy 181.370872 -404.223021) (xy 181.31831 -404.207488) (xy 181.268515 -404.184588) (xy 181.222512 -404.154794)
			(xy 181.201568 -404.137114) (xy 181.190755 -404.128208) (xy 181.16542 -404.116271) (xy 181.137796 -404.111652)
			(xy 181.109955 -404.114699) (xy 181.083985 -404.125184) (xy 181.061831 -404.142319) (xy 181.045155 -404.16482)
			(xy 181.03977 -404.177754) (xy 181.029065 -404.204553) (xy 181.000769 -404.254846) (xy 180.965221 -404.300303)
			(xy 180.923233 -404.339888) (xy 180.875761 -404.372698) (xy 180.823889 -404.397983) (xy 180.768801 -404.415167)
			(xy 180.711753 -404.423858) (xy 180.6829 -404.424388) (xy 180.655647 -404.423942) (xy 180.601697 -404.416185)
			(xy 180.549399 -404.400829) (xy 180.499819 -404.378187) (xy 180.453967 -404.348719) (xy 180.412774 -404.313026)
			(xy 180.377081 -404.271833) (xy 180.347613 -404.225981) (xy 180.324971 -404.176401) (xy 180.309615 -404.124103)
			(xy 180.301858 -404.070153) (xy 178.649499 -404.070153) (xy 178.669587 -404.100516) (xy 178.693259 -404.151013)
			(xy 178.709327 -404.20442) (xy 178.717447 -404.259596) (xy 178.717956 -404.287482) (xy 178.717447 -404.315368)
			(xy 178.709327 -404.370544) (xy 178.693259 -404.423951) (xy 178.669587 -404.474448) (xy 178.638814 -404.520961)
			(xy 178.601597 -404.562498) (xy 178.558729 -404.598173) (xy 178.511123 -404.627227) (xy 178.459794 -404.649039)
			(xy 178.405837 -404.663145) (xy 178.3504 -404.669245) (xy 178.294666 -404.667208) (xy 178.239823 -404.657078)
			(xy 178.187039 -404.639071) (xy 178.137439 -404.61357) (xy 178.092081 -404.581119) (xy 178.051932 -404.54241)
			(xy 178.017846 -404.498267) (xy 177.99055 -404.449632) (xy 177.970627 -404.397541) (xy 177.958501 -404.343104)
			(xy 177.95443 -404.287482) (xy 172.742575 -404.287482) (xy 172.751454 -404.298251) (xy 172.77903 -404.343085)
			(xy 172.800174 -404.391288) (xy 172.814483 -404.441941) (xy 172.821686 -404.494082) (xy 172.822108 -404.5204)
			(xy 172.821699 -404.546717) (xy 172.814469 -404.598853) (xy 172.800148 -404.649502) (xy 172.779005 -404.697704)
			(xy 172.751442 -404.742545) (xy 172.717981 -404.783175) (xy 172.698918 -404.801324) (xy 172.688896 -404.811135)
			(xy 172.674196 -404.835008) (xy 172.666557 -404.861982) (xy 172.666557 -404.890018) (xy 172.674196 -404.916992)
			(xy 172.688896 -404.940865) (xy 172.698918 -404.950676) (xy 172.717975 -404.968804) (xy 172.75143 -405.009386)
			(xy 172.778989 -405.054183) (xy 172.800128 -405.102343) (xy 172.814445 -405.152952) (xy 172.82167 -405.205048)
			(xy 172.822108 -405.231346) (xy 172.822108 -405.2316) (xy 172.821622 -405.258851) (xy 172.815205 -405.303482)
			(xy 177.95443 -405.303482) (xy 177.958501 -405.24786) (xy 177.970627 -405.193423) (xy 177.99055 -405.141332)
			(xy 178.017846 -405.092697) (xy 178.051932 -405.048554) (xy 178.092081 -405.009845) (xy 178.137439 -404.977394)
			(xy 178.187039 -404.951893) (xy 178.239823 -404.933886) (xy 178.294666 -404.923756) (xy 178.3504 -404.921719)
			(xy 178.405837 -404.927819) (xy 178.459794 -404.941925) (xy 178.511123 -404.963737) (xy 178.558729 -404.992791)
			(xy 178.601597 -405.028466) (xy 178.638814 -405.070003) (xy 178.669587 -405.116516) (xy 178.693259 -405.167013)
			(xy 178.709327 -405.22042) (xy 178.717447 -405.275596) (xy 178.717956 -405.303482) (xy 178.717447 -405.331368)
			(xy 178.709327 -405.386544) (xy 178.693259 -405.439951) (xy 178.679242 -405.469852) (xy 180.59603 -405.469852)
			(xy 180.600101 -405.41423) (xy 180.612227 -405.359793) (xy 180.63215 -405.307702) (xy 180.659446 -405.259067)
			(xy 180.693532 -405.214924) (xy 180.733681 -405.176215) (xy 180.779039 -405.143764) (xy 180.828639 -405.118263)
			(xy 180.881423 -405.100256) (xy 180.936266 -405.090126) (xy 180.992 -405.088089) (xy 181.047437 -405.094189)
			(xy 181.101394 -405.108295) (xy 181.152723 -405.130107) (xy 181.200329 -405.159161) (xy 181.243197 -405.194836)
			(xy 181.280414 -405.236373) (xy 181.311187 -405.282886) (xy 181.334859 -405.333383) (xy 181.350927 -405.38679)
			(xy 181.359047 -405.441966) (xy 181.359556 -405.469852) (xy 181.359047 -405.497738) (xy 181.350927 -405.552914)
			(xy 181.334859 -405.606321) (xy 181.311187 -405.656818) (xy 181.280414 -405.703331) (xy 181.243197 -405.744868)
			(xy 181.200329 -405.780543) (xy 181.152723 -405.809597) (xy 181.101394 -405.831409) (xy 181.047437 -405.845515)
			(xy 180.992 -405.851615) (xy 180.936266 -405.849578) (xy 180.881423 -405.839448) (xy 180.828639 -405.821441)
			(xy 180.779039 -405.79594) (xy 180.733681 -405.763489) (xy 180.693532 -405.72478) (xy 180.659446 -405.680637)
			(xy 180.63215 -405.632002) (xy 180.612227 -405.579911) (xy 180.600101 -405.525474) (xy 180.59603 -405.469852)
			(xy 178.679242 -405.469852) (xy 178.669587 -405.490448) (xy 178.638814 -405.536961) (xy 178.601597 -405.578498)
			(xy 178.558729 -405.614173) (xy 178.511123 -405.643227) (xy 178.459794 -405.665039) (xy 178.405837 -405.679145)
			(xy 178.3504 -405.685245) (xy 178.294666 -405.683208) (xy 178.239823 -405.673078) (xy 178.187039 -405.655071)
			(xy 178.137439 -405.62957) (xy 178.092081 -405.597119) (xy 178.051932 -405.55841) (xy 178.017846 -405.514267)
			(xy 177.99055 -405.465632) (xy 177.970627 -405.413541) (xy 177.958501 -405.359104) (xy 177.95443 -405.303482)
			(xy 172.815205 -405.303482) (xy 172.813866 -405.312799) (xy 172.798511 -405.365094) (xy 172.775869 -405.414671)
			(xy 172.746403 -405.460521) (xy 172.710712 -405.501712) (xy 172.669521 -405.537403) (xy 172.623671 -405.566869)
			(xy 172.574094 -405.589511) (xy 172.521799 -405.604866) (xy 172.467851 -405.612622) (xy 172.413349 -405.612622)
			(xy 172.359401 -405.604866) (xy 172.307106 -405.589511) (xy 172.257529 -405.566869) (xy 172.211679 -405.537403)
			(xy 172.170488 -405.501712) (xy 172.134797 -405.460521) (xy 172.105331 -405.414671) (xy 172.082689 -405.365094)
			(xy 172.067334 -405.312799) (xy 172.059578 -405.258851) (xy 172.059092 -405.2316) (xy 169.722822 -405.2316)
			(xy 169.722822 -405.284251) (xy 169.715066 -405.338199) (xy 169.699711 -405.390494) (xy 169.677069 -405.440071)
			(xy 169.647603 -405.485921) (xy 169.611912 -405.527112) (xy 169.570721 -405.562803) (xy 169.524871 -405.592269)
			(xy 169.475294 -405.614911) (xy 169.422999 -405.630266) (xy 169.369051 -405.638022) (xy 169.3418 -405.638508)
			(xy 169.313596 -405.637999) (xy 169.257805 -405.62969) (xy 169.203846 -405.613251) (xy 169.152897 -405.589043)
			(xy 169.129202 -405.573738) (xy 169.117535 -405.566455) (xy 169.091444 -405.557786) (xy 169.063987 -405.556396)
			(xy 169.037154 -405.562384) (xy 169.012893 -405.575317) (xy 168.992964 -405.594256) (xy 168.978813 -405.617827)
			(xy 168.971466 -405.64432) (xy 168.97096 -405.658066) (xy 168.97096 -406.713944) (xy 169.000424 -406.727406)
			(xy 169.022746 -406.738271) (xy 169.063832 -406.766132) (xy 169.09987 -406.800273) (xy 169.12991 -406.839795)
			(xy 169.152601 -406.8826) (xy 173.976296 -406.8826) (xy 173.980262 -406.798069) (xy 173.992127 -406.714282)
			(xy 174.011785 -406.631973) (xy 174.039065 -406.551867) (xy 174.073726 -406.474668) (xy 174.115464 -406.401053)
			(xy 174.163911 -406.33167) (xy 174.218643 -406.267129) (xy 174.279179 -406.207997) (xy 174.344985 -406.154793)
			(xy 174.415485 -406.107985) (xy 174.490057 -406.067984) (xy 174.568048 -406.035142) (xy 174.648772 -406.009748)
			(xy 174.731519 -405.992025) (xy 174.815561 -405.982127) (xy 174.900162 -405.980144) (xy 174.984576 -405.986091)
			(xy 175.068063 -405.999916) (xy 175.149888 -406.021499) (xy 175.229332 -406.050649) (xy 175.305698 -406.08711)
			(xy 175.373127 -406.127458) (xy 178.56022 -406.127458) (xy 178.564291 -406.071836) (xy 178.576417 -406.017399)
			(xy 178.59634 -405.965308) (xy 178.623636 -405.916673) (xy 178.657722 -405.87253) (xy 178.697871 -405.833821)
			(xy 178.743229 -405.80137) (xy 178.792829 -405.775869) (xy 178.845613 -405.757862) (xy 178.900456 -405.747732)
			(xy 178.95619 -405.745695) (xy 179.011627 -405.751795) (xy 179.065584 -405.765901) (xy 179.116913 -405.787713)
			(xy 179.164519 -405.816767) (xy 179.207387 -405.852442) (xy 179.244604 -405.893979) (xy 179.275377 -405.940492)
			(xy 179.299049 -405.990989) (xy 179.315117 -406.044396) (xy 179.323237 -406.099572) (xy 179.323746 -406.127458)
			(xy 179.323237 -406.155344) (xy 179.319704 -406.179349) (xy 181.425874 -406.179349) (xy 181.425874 -406.124851)
			(xy 181.433629 -406.070907) (xy 181.448982 -406.018616) (xy 181.471619 -405.969041) (xy 181.501081 -405.923193)
			(xy 181.536768 -405.882003) (xy 181.577953 -405.846311) (xy 181.623797 -405.816843) (xy 181.673369 -405.794199)
			(xy 181.725658 -405.77884) (xy 181.779601 -405.771077) (xy 181.80685 -405.770588) (xy 181.835046 -405.771058)
			(xy 181.890822 -405.779374) (xy 181.944769 -405.795802) (xy 181.995713 -405.819986) (xy 182.042546 -405.851399)
			(xy 182.08425 -405.889358) (xy 182.119917 -405.933038) (xy 182.148773 -405.981489) (xy 182.17019 -406.033656)
			(xy 182.177436 -406.06091) (xy 182.181212 -406.074447) (xy 182.195036 -406.098903) (xy 182.215011 -406.118655)
			(xy 182.23962 -406.132203) (xy 182.266993 -406.138518) (xy 182.29505 -406.137121) (xy 182.3085 -406.133046)
			(xy 182.338106 -406.123683) (xy 182.399375 -406.113607) (xy 182.43042 -406.11298) (xy 182.457708 -406.113458)
			(xy 182.511729 -406.121226) (xy 182.56409 -406.136614) (xy 182.613724 -406.159309) (xy 182.636922 -406.173686)
			(xy 182.649389 -406.18114) (xy 182.677243 -406.189344) (xy 182.706279 -406.189384) (xy 182.734154 -406.181257)
			(xy 182.758619 -406.165618) (xy 182.777699 -406.14373) (xy 182.784242 -406.13076) (xy 182.795994 -406.106252)
			(xy 182.825496 -406.060601) (xy 182.861179 -406.019601) (xy 182.902321 -405.984082) (xy 182.948089 -405.954762)
			(xy 182.997555 -405.932237) (xy 183.049718 -405.916961) (xy 183.103521 -405.909245) (xy 183.130698 -405.908764)
			(xy 183.157949 -405.909283) (xy 183.211896 -405.917039) (xy 183.26419 -405.932394) (xy 183.313767 -405.955035)
			(xy 183.359617 -405.984501) (xy 183.400807 -406.020192) (xy 183.436498 -406.061381) (xy 183.465964 -406.107231)
			(xy 183.488605 -406.156808) (xy 183.50396 -406.209102) (xy 183.511717 -406.263049) (xy 183.511717 -406.317551)
			(xy 183.50396 -406.371498) (xy 183.488605 -406.423792) (xy 183.465964 -406.473369) (xy 183.436498 -406.519219)
			(xy 183.400807 -406.560408) (xy 183.359617 -406.596099) (xy 183.313767 -406.625565) (xy 183.26419 -406.648206)
			(xy 183.211896 -406.663561) (xy 183.157949 -406.671317) (xy 183.130698 -406.67178) (xy 183.10341 -406.671299)
			(xy 183.049389 -406.663533) (xy 182.997028 -406.648146) (xy 182.947394 -406.625451) (xy 182.924196 -406.611074)
			(xy 182.911729 -406.603615) (xy 182.883875 -406.595401) (xy 182.854835 -406.595356) (xy 182.826956 -406.603484)
			(xy 182.80249 -406.619129) (xy 182.783415 -406.641026) (xy 182.776876 -406.654) (xy 182.765091 -406.678492)
			(xy 182.735596 -406.724143) (xy 182.699918 -406.765145) (xy 182.658781 -406.800667) (xy 182.613018 -406.829988)
			(xy 182.563555 -406.852517) (xy 182.511396 -406.867795) (xy 182.457596 -406.875513) (xy 182.43042 -406.875996)
			(xy 182.402225 -406.875475) (xy 182.346451 -406.867169) (xy 182.292505 -406.850749) (xy 182.241561 -406.826573)
			(xy 182.194727 -406.795167) (xy 182.153022 -406.757213) (xy 182.117353 -406.713538) (xy 182.088497 -406.665091)
			(xy 182.06708 -406.612926) (xy 182.059834 -406.585674) (xy 182.056103 -406.572122) (xy 182.04227 -406.547664)
			(xy 182.022285 -406.527912) (xy 181.997667 -406.514366) (xy 181.970286 -406.508055) (xy 181.942222 -406.509459)
			(xy 181.92877 -406.513538) (xy 181.899159 -406.522884) (xy 181.837894 -406.532971) (xy 181.80685 -406.533604)
			(xy 181.779601 -406.533123) (xy 181.725658 -406.52536) (xy 181.673369 -406.510001) (xy 181.623797 -406.487357)
			(xy 181.577953 -406.457889) (xy 181.536768 -406.422197) (xy 181.501081 -406.381007) (xy 181.471619 -406.335159)
			(xy 181.448982 -406.285584) (xy 181.433629 -406.233293) (xy 181.425874 -406.179349) (xy 179.319704 -406.179349)
			(xy 179.315117 -406.21052) (xy 179.299049 -406.263927) (xy 179.275377 -406.314424) (xy 179.244604 -406.360937)
			(xy 179.207387 -406.402474) (xy 179.164519 -406.438149) (xy 179.116913 -406.467203) (xy 179.065584 -406.489015)
			(xy 179.011627 -406.503121) (xy 178.95619 -406.509221) (xy 178.900456 -406.507184) (xy 178.845613 -406.497054)
			(xy 178.792829 -406.479047) (xy 178.743229 -406.453546) (xy 178.697871 -406.421095) (xy 178.657722 -406.382386)
			(xy 178.623636 -406.338243) (xy 178.59634 -406.289608) (xy 178.576417 -406.237517) (xy 178.564291 -406.18308)
			(xy 178.56022 -406.127458) (xy 175.373127 -406.127458) (xy 175.378314 -406.130562) (xy 175.446542 -406.180623)
			(xy 175.509782 -406.236853) (xy 175.567479 -406.298758) (xy 175.619126 -406.365794) (xy 175.664268 -406.437371)
			(xy 175.70251 -406.512861) (xy 175.733514 -406.5916) (xy 175.757009 -406.672897) (xy 175.772788 -406.756036)
			(xy 175.780712 -406.840288) (xy 175.781208 -406.8826) (xy 175.780712 -406.924912) (xy 175.772788 -407.009164)
			(xy 175.757009 -407.092303) (xy 175.733514 -407.1736) (xy 175.70251 -407.252339) (xy 175.664268 -407.327829)
			(xy 175.619126 -407.399406) (xy 175.567479 -407.466442) (xy 175.509782 -407.528347) (xy 175.470449 -407.56332)
			(xy 178.527962 -407.56332) (xy 178.532033 -407.507698) (xy 178.544159 -407.453261) (xy 178.564082 -407.40117)
			(xy 178.591378 -407.352535) (xy 178.625464 -407.308392) (xy 178.665613 -407.269683) (xy 178.710971 -407.237232)
			(xy 178.760571 -407.211731) (xy 178.813355 -407.193724) (xy 178.868198 -407.183594) (xy 178.923932 -407.181557)
			(xy 178.979369 -407.187657) (xy 179.033326 -407.201763) (xy 179.084655 -407.223575) (xy 179.132261 -407.252629)
			(xy 179.175129 -407.288304) (xy 179.212346 -407.329841) (xy 179.243119 -407.376354) (xy 179.266791 -407.426851)
			(xy 179.282859 -407.480258) (xy 179.290979 -407.535434) (xy 179.291488 -407.56332) (xy 179.290979 -407.591206)
			(xy 179.282859 -407.646382) (xy 179.266791 -407.699789) (xy 179.243119 -407.750286) (xy 179.212346 -407.796799)
			(xy 179.175129 -407.838336) (xy 179.132261 -407.874011) (xy 179.084655 -407.903065) (xy 179.033326 -407.924877)
			(xy 178.979369 -407.938983) (xy 178.923932 -407.945083) (xy 178.868198 -407.943046) (xy 178.813355 -407.932916)
			(xy 178.760571 -407.914909) (xy 178.710971 -407.889408) (xy 178.665613 -407.856957) (xy 178.625464 -407.818248)
			(xy 178.591378 -407.774105) (xy 178.564082 -407.72547) (xy 178.544159 -407.673379) (xy 178.532033 -407.618942)
			(xy 178.527962 -407.56332) (xy 175.470449 -407.56332) (xy 175.446542 -407.584577) (xy 175.378314 -407.634638)
			(xy 175.305698 -407.67809) (xy 175.229332 -407.714551) (xy 175.149888 -407.743701) (xy 175.068063 -407.765284)
			(xy 174.984576 -407.779109) (xy 174.900162 -407.785056) (xy 174.815561 -407.783073) (xy 174.731519 -407.773175)
			(xy 174.648772 -407.755452) (xy 174.568048 -407.730058) (xy 174.490057 -407.697216) (xy 174.415485 -407.657215)
			(xy 174.344985 -407.610407) (xy 174.279179 -407.557203) (xy 174.218643 -407.498071) (xy 174.163911 -407.43353)
			(xy 174.115464 -407.364147) (xy 174.073726 -407.290532) (xy 174.039065 -407.213333) (xy 174.011785 -407.133227)
			(xy 173.992127 -407.050918) (xy 173.980262 -406.967131) (xy 173.976296 -406.8826) (xy 169.152601 -406.8826)
			(xy 169.15316 -406.883655) (xy 169.169009 -406.930699) (xy 169.177038 -406.979687) (xy 169.177037 -407.029329)
			(xy 169.169005 -407.078317) (xy 169.153154 -407.12536) (xy 169.129901 -407.16922) (xy 169.099859 -407.208739)
			(xy 169.063819 -407.242878) (xy 169.022731 -407.270738) (xy 169.000424 -407.281634) (xy 168.97096 -407.295096)
			(xy 168.97096 -407.42616) (xy 172.152562 -407.42616) (xy 172.156633 -407.370538) (xy 172.168759 -407.316101)
			(xy 172.188682 -407.26401) (xy 172.215978 -407.215375) (xy 172.250064 -407.171232) (xy 172.290213 -407.132523)
			(xy 172.335571 -407.100072) (xy 172.385171 -407.074571) (xy 172.437955 -407.056564) (xy 172.492798 -407.046434)
			(xy 172.548532 -407.044397) (xy 172.603969 -407.050497) (xy 172.657926 -407.064603) (xy 172.709255 -407.086415)
			(xy 172.756861 -407.115469) (xy 172.799729 -407.151144) (xy 172.836946 -407.192681) (xy 172.867719 -407.239194)
			(xy 172.891391 -407.289691) (xy 172.907459 -407.343098) (xy 172.915579 -407.398274) (xy 172.916088 -407.42616)
			(xy 172.915579 -407.454046) (xy 172.907459 -407.509222) (xy 172.891391 -407.562629) (xy 172.867719 -407.613126)
			(xy 172.836946 -407.659639) (xy 172.799729 -407.701176) (xy 172.756861 -407.736851) (xy 172.709255 -407.765905)
			(xy 172.657926 -407.787717) (xy 172.603969 -407.801823) (xy 172.548532 -407.807923) (xy 172.492798 -407.805886)
			(xy 172.437955 -407.795756) (xy 172.385171 -407.777749) (xy 172.335571 -407.752248) (xy 172.290213 -407.719797)
			(xy 172.250064 -407.681088) (xy 172.215978 -407.636945) (xy 172.188682 -407.58831) (xy 172.168759 -407.536219)
			(xy 172.156633 -407.481782) (xy 172.152562 -407.42616) (xy 168.97096 -407.42616) (xy 168.97096 -409.4226)
			(xy 173.976296 -409.4226) (xy 173.980262 -409.338069) (xy 173.992127 -409.254282) (xy 174.011785 -409.171973)
			(xy 174.039065 -409.091867) (xy 174.073726 -409.014668) (xy 174.115464 -408.941053) (xy 174.163911 -408.87167)
			(xy 174.218643 -408.807129) (xy 174.279179 -408.747997) (xy 174.344985 -408.694793) (xy 174.415485 -408.647985)
			(xy 174.490057 -408.607984) (xy 174.568048 -408.575142) (xy 174.648772 -408.549748) (xy 174.731519 -408.532025)
			(xy 174.815561 -408.522127) (xy 174.900162 -408.520144) (xy 174.984576 -408.526091) (xy 175.068063 -408.539916)
			(xy 175.149888 -408.561499) (xy 175.229332 -408.590649) (xy 175.305698 -408.62711) (xy 175.378314 -408.670562)
			(xy 175.446542 -408.720623) (xy 175.509782 -408.776853) (xy 175.567479 -408.838758) (xy 175.619126 -408.905794)
			(xy 175.664268 -408.977371) (xy 175.70251 -409.052861) (xy 175.733514 -409.1316) (xy 175.757009 -409.212897)
			(xy 175.772788 -409.296036) (xy 175.780712 -409.380288) (xy 175.781208 -409.4226) (xy 175.780712 -409.464912)
			(xy 175.772788 -409.549164) (xy 175.757009 -409.632303) (xy 175.733514 -409.7136) (xy 175.70251 -409.792339)
			(xy 175.688828 -409.819348) (xy 179.66766 -409.819348) (xy 179.671731 -409.763726) (xy 179.683857 -409.709289)
			(xy 179.70378 -409.657198) (xy 179.731076 -409.608563) (xy 179.765162 -409.56442) (xy 179.805311 -409.525711)
			(xy 179.850669 -409.49326) (xy 179.900269 -409.467759) (xy 179.953053 -409.449752) (xy 180.007896 -409.439622)
			(xy 180.06363 -409.437585) (xy 180.119067 -409.443685) (xy 180.173024 -409.457791) (xy 180.224353 -409.479603)
			(xy 180.271959 -409.508657) (xy 180.314827 -409.544332) (xy 180.352044 -409.585869) (xy 180.382817 -409.632382)
			(xy 180.406489 -409.682879) (xy 180.422557 -409.736286) (xy 180.430677 -409.791462) (xy 180.431186 -409.819348)
			(xy 180.430677 -409.847234) (xy 180.422557 -409.90241) (xy 180.406489 -409.955817) (xy 180.382817 -410.006314)
			(xy 180.352044 -410.052827) (xy 180.314827 -410.094364) (xy 180.271959 -410.130039) (xy 180.224353 -410.159093)
			(xy 180.173024 -410.180905) (xy 180.119067 -410.195011) (xy 180.06363 -410.201111) (xy 180.007896 -410.199074)
			(xy 179.953053 -410.188944) (xy 179.900269 -410.170937) (xy 179.850669 -410.145436) (xy 179.805311 -410.112985)
			(xy 179.765162 -410.074276) (xy 179.731076 -410.030133) (xy 179.70378 -409.981498) (xy 179.683857 -409.929407)
			(xy 179.671731 -409.87497) (xy 179.66766 -409.819348) (xy 175.688828 -409.819348) (xy 175.664268 -409.867829)
			(xy 175.619126 -409.939406) (xy 175.567479 -410.006442) (xy 175.509782 -410.068347) (xy 175.446542 -410.124577)
			(xy 175.378314 -410.174638) (xy 175.305698 -410.21809) (xy 175.229332 -410.254551) (xy 175.149888 -410.283701)
			(xy 175.068063 -410.305284) (xy 174.984576 -410.319109) (xy 174.900162 -410.325056) (xy 174.815561 -410.323073)
			(xy 174.731519 -410.313175) (xy 174.648772 -410.295452) (xy 174.568048 -410.270058) (xy 174.490057 -410.237216)
			(xy 174.415485 -410.197215) (xy 174.344985 -410.150407) (xy 174.279179 -410.097203) (xy 174.218643 -410.038071)
			(xy 174.163911 -409.97353) (xy 174.115464 -409.904147) (xy 174.073726 -409.830532) (xy 174.039065 -409.753333)
			(xy 174.011785 -409.673227) (xy 173.992127 -409.590918) (xy 173.980262 -409.507131) (xy 173.976296 -409.4226)
			(xy 168.97096 -409.4226) (xy 168.97096 -409.739592) (xy 169.000424 -409.753054) (xy 169.02275 -409.763918)
			(xy 169.063845 -409.791781) (xy 169.099891 -409.825925) (xy 169.129938 -409.86545) (xy 169.153195 -409.909316)
			(xy 169.16905 -409.956366) (xy 169.177084 -410.005362) (xy 169.177086 -410.055011) (xy 169.169056 -410.104008)
			(xy 169.153206 -410.151059) (xy 169.129953 -410.194927) (xy 169.099909 -410.234455) (xy 169.063866 -410.268602)
			(xy 169.022774 -410.296468) (xy 169.000424 -410.307282) (xy 168.97096 -410.320744) (xy 168.97096 -410.881068)
			(xy 168.290748 -411.56128) (xy 171.248322 -411.56128) (xy 171.252393 -411.505658) (xy 171.264519 -411.451221)
			(xy 171.284442 -411.39913) (xy 171.311738 -411.350495) (xy 171.345824 -411.306352) (xy 171.385973 -411.267643)
			(xy 171.431331 -411.235192) (xy 171.480931 -411.209691) (xy 171.533715 -411.191684) (xy 171.588558 -411.181554)
			(xy 171.644292 -411.179517) (xy 171.699729 -411.185617) (xy 171.753686 -411.199723) (xy 171.805015 -411.221535)
			(xy 171.852621 -411.250589) (xy 171.895489 -411.286264) (xy 171.932706 -411.327801) (xy 171.963479 -411.374314)
			(xy 171.987151 -411.424811) (xy 172.003219 -411.478218) (xy 172.011339 -411.533394) (xy 172.011848 -411.56128)
			(xy 172.011339 -411.589166) (xy 172.003219 -411.644342) (xy 171.987151 -411.697749) (xy 171.963479 -411.748246)
			(xy 171.932706 -411.794759) (xy 171.895489 -411.836296) (xy 171.852621 -411.871971) (xy 171.805015 -411.901025)
			(xy 171.753686 -411.922837) (xy 171.699729 -411.936943) (xy 171.644292 -411.943043) (xy 171.588558 -411.941006)
			(xy 171.533715 -411.930876) (xy 171.480931 -411.912869) (xy 171.431331 -411.887368) (xy 171.385973 -411.854917)
			(xy 171.345824 -411.816208) (xy 171.311738 -411.772065) (xy 171.284442 -411.72343) (xy 171.264519 -411.671339)
			(xy 171.252393 -411.616902) (xy 171.248322 -411.56128) (xy 168.290748 -411.56128) (xy 167.922448 -411.92958)
			(xy 122.077226 -411.92958) (xy 120.102376 -409.95473) (xy 120.102376 -404.947882) (xy 120.101908 -404.933711)
			(xy 120.094111 -404.906462) (xy 120.079124 -404.882406) (xy 120.0581 -404.863397) (xy 120.032662 -404.8509)
			(xy 120.004767 -404.845879) (xy 119.990616 -404.84679) (xy 119.957342 -404.848568) (xy 119.931352 -404.848088)
			(xy 119.88001 -404.839962) (xy 119.830573 -404.823903) (xy 119.784257 -404.800307) (xy 119.742203 -404.769754)
			(xy 119.705447 -404.732999) (xy 119.674895 -404.690945) (xy 119.651298 -404.644629) (xy 119.635239 -404.595192)
			(xy 119.627112 -404.54385) (xy 119.626634 -404.51786) (xy 119.626634 -404.517606) (xy 119.627026 -404.494631)
			(xy 119.633398 -404.449126) (xy 119.639334 -404.426928) (xy 119.647462 -404.398226) (xy 118.484142 -403.234906)
			(xy 118.484142 -401.0406) (xy 118.253002 -401.0406) (xy 118.239036 -401.041038) (xy 118.212152 -401.048613)
			(xy 118.188329 -401.063194) (xy 118.169353 -401.08369) (xy 118.156647 -401.108564) (xy 118.151163 -401.135952)
			(xy 118.153312 -401.1638) (xy 118.162933 -401.190022) (xy 118.170706 -401.201636) (xy 118.18764 -401.22611)
			(xy 118.214505 -401.279213) (xy 118.232781 -401.335849) (xy 118.242025 -401.394638) (xy 118.242588 -401.424394)
			(xy 118.242588 -401.424648) (xy 118.242102 -401.451899) (xy 118.234346 -401.505847) (xy 118.218991 -401.558142)
			(xy 118.196349 -401.607719) (xy 118.166883 -401.653569) (xy 118.131192 -401.69476) (xy 118.090001 -401.730451)
			(xy 118.044151 -401.759917) (xy 117.994574 -401.782559) (xy 117.942279 -401.797914) (xy 117.888331 -401.80567)
			(xy 117.833829 -401.80567) (xy 117.779881 -401.797914) (xy 117.727586 -401.782559) (xy 117.678009 -401.759917)
			(xy 117.632159 -401.730451) (xy 117.590968 -401.69476) (xy 117.555277 -401.653569) (xy 117.525811 -401.607719)
			(xy 117.503169 -401.558142) (xy 117.487814 -401.505847) (xy 117.480058 -401.451899) (xy 117.479572 -401.424648)
			(xy 117.479572 -401.424394) (xy 117.48017 -401.394643) (xy 117.489453 -401.33587) (xy 117.507732 -401.279244)
			(xy 117.534565 -401.226136) (xy 117.551454 -401.201636) (xy 117.559271 -401.190058) (xy 117.568866 -401.163831)
			(xy 117.570995 -401.135986) (xy 117.565498 -401.108606) (xy 117.552788 -401.083741) (xy 117.533814 -401.063249)
			(xy 117.509998 -401.048667) (xy 117.483121 -401.041084) (xy 117.469158 -401.0406) (xy 116.39931 -401.0406)
			(xy 116.176298 -401.263612) (xy 116.187474 -401.293838) (xy 116.198273 -401.325456) (xy 116.209902 -401.391244)
			(xy 116.210588 -401.424648) (xy 116.210101 -401.451859) (xy 116.20236 -401.505728) (xy 116.187042 -401.557951)
			(xy 116.164458 -401.607466) (xy 116.135066 -401.65327) (xy 116.099463 -401.694431) (xy 116.058372 -401.730115)
			(xy 116.012627 -401.759597) (xy 115.988084 -401.771358) (xy 115.95862 -401.785074) (xy 115.95862 -403.128988)
			(xy 117.514622 -403.128988) (xy 117.518693 -403.073366) (xy 117.530819 -403.018929) (xy 117.550742 -402.966838)
			(xy 117.578038 -402.918203) (xy 117.612124 -402.87406) (xy 117.652273 -402.835351) (xy 117.697631 -402.8029)
			(xy 117.747231 -402.777399) (xy 117.800015 -402.759392) (xy 117.854858 -402.749262) (xy 117.910592 -402.747225)
			(xy 117.966029 -402.753325) (xy 118.019986 -402.767431) (xy 118.071315 -402.789243) (xy 118.118921 -402.818297)
			(xy 118.161789 -402.853972) (xy 118.199006 -402.895509) (xy 118.229779 -402.942022) (xy 118.253451 -402.992519)
			(xy 118.269519 -403.045926) (xy 118.277639 -403.101102) (xy 118.278148 -403.128988) (xy 118.277639 -403.156874)
			(xy 118.269519 -403.21205) (xy 118.253451 -403.265457) (xy 118.229779 -403.315954) (xy 118.199006 -403.362467)
			(xy 118.161789 -403.404004) (xy 118.118921 -403.439679) (xy 118.071315 -403.468733) (xy 118.019986 -403.490545)
			(xy 117.966029 -403.504651) (xy 117.910592 -403.510751) (xy 117.854858 -403.508714) (xy 117.800015 -403.498584)
			(xy 117.747231 -403.480577) (xy 117.697631 -403.455076) (xy 117.652273 -403.422625) (xy 117.612124 -403.383916)
			(xy 117.578038 -403.339773) (xy 117.550742 -403.291138) (xy 117.530819 -403.239047) (xy 117.518693 -403.18461)
			(xy 117.514622 -403.128988) (xy 115.95862 -403.128988) (xy 115.95862 -403.8346) (xy 116.508782 -403.8346)
			(xy 116.512853 -403.778978) (xy 116.524979 -403.724541) (xy 116.544902 -403.67245) (xy 116.572198 -403.623815)
			(xy 116.606284 -403.579672) (xy 116.646433 -403.540963) (xy 116.691791 -403.508512) (xy 116.741391 -403.483011)
			(xy 116.794175 -403.465004) (xy 116.849018 -403.454874) (xy 116.904752 -403.452837) (xy 116.960189 -403.458937)
			(xy 117.014146 -403.473043) (xy 117.065475 -403.494855) (xy 117.113081 -403.523909) (xy 117.155949 -403.559584)
			(xy 117.193166 -403.601121) (xy 117.223939 -403.647634) (xy 117.247611 -403.698131) (xy 117.263679 -403.751538)
			(xy 117.271799 -403.806714) (xy 117.272308 -403.8346) (xy 117.271799 -403.862486) (xy 117.263679 -403.917662)
			(xy 117.247611 -403.971069) (xy 117.223939 -404.021566) (xy 117.193166 -404.068079) (xy 117.155949 -404.109616)
			(xy 117.113081 -404.145291) (xy 117.065475 -404.174345) (xy 117.014146 -404.196157) (xy 116.960189 -404.210263)
			(xy 116.904752 -404.216363) (xy 116.849018 -404.214326) (xy 116.794175 -404.204196) (xy 116.741391 -404.186189)
			(xy 116.691791 -404.160688) (xy 116.646433 -404.128237) (xy 116.606284 -404.089528) (xy 116.572198 -404.045385)
			(xy 116.544902 -403.99675) (xy 116.524979 -403.944659) (xy 116.512853 -403.890222) (xy 116.508782 -403.8346)
			(xy 115.95862 -403.8346) (xy 115.95862 -406.743154) (xy 116.137944 -406.922732) (xy 116.157248 -406.924002)
			(xy 116.1848 -406.926184) (xy 116.238899 -406.937493) (xy 116.290799 -406.956493) (xy 116.339413 -406.982784)
			(xy 116.383724 -407.015817) (xy 116.422803 -407.054899) (xy 116.455832 -407.099212) (xy 116.482119 -407.147828)
			(xy 116.501115 -407.19973) (xy 116.51242 -407.253829) (xy 116.514626 -407.28138) (xy 116.515896 -407.300684)
			(xy 116.75618 -407.540968) (xy 116.75618 -408.314144) (xy 116.804186 -408.36469) (xy 116.83308 -408.366768)
			(xy 116.889794 -408.378559) (xy 116.944073 -408.39879) (xy 116.99467 -408.426996) (xy 117.04042 -408.462527)
			(xy 117.080271 -408.504567) (xy 117.113308 -408.55215) (xy 117.138771 -408.604181) (xy 117.156073 -408.659463)
			(xy 117.164819 -408.716726) (xy 117.165374 -408.74569) (xy 117.164833 -408.774695) (xy 117.156046 -408.832037)
			(xy 117.138675 -408.887385) (xy 117.113119 -408.939464) (xy 117.079969 -408.987069) (xy 117.039991 -409.029104)
			(xy 116.994105 -409.064598) (xy 116.969032 -409.079192) (xy 116.957465 -409.086055) (xy 116.938149 -409.10476)
			(xy 116.924395 -409.127864) (xy 116.917161 -409.15376) (xy 116.916949 -409.180647) (xy 116.923774 -409.206654)
			(xy 116.937161 -409.229972) (xy 116.946426 -409.23972) (xy 118.73103 -411.024324) (xy 118.73103 -411.131004)
			(xy 119.559322 -411.131004) (xy 119.563393 -411.075382) (xy 119.575519 -411.020945) (xy 119.595442 -410.968854)
			(xy 119.622738 -410.920219) (xy 119.656824 -410.876076) (xy 119.696973 -410.837367) (xy 119.742331 -410.804916)
			(xy 119.791931 -410.779415) (xy 119.844715 -410.761408) (xy 119.899558 -410.751278) (xy 119.955292 -410.749241)
			(xy 120.010729 -410.755341) (xy 120.064686 -410.769447) (xy 120.116015 -410.791259) (xy 120.163621 -410.820313)
			(xy 120.206489 -410.855988) (xy 120.243706 -410.897525) (xy 120.274479 -410.944038) (xy 120.298151 -410.994535)
			(xy 120.314219 -411.047942) (xy 120.322339 -411.103118) (xy 120.322848 -411.131004) (xy 120.322339 -411.15889)
			(xy 120.314219 -411.214066) (xy 120.298151 -411.267473) (xy 120.274479 -411.31797) (xy 120.243706 -411.364483)
			(xy 120.206489 -411.40602) (xy 120.163621 -411.441695) (xy 120.116015 -411.470749) (xy 120.064686 -411.492561)
			(xy 120.010729 -411.506667) (xy 119.955292 -411.512767) (xy 119.899558 -411.51073) (xy 119.844715 -411.5006)
			(xy 119.791931 -411.482593) (xy 119.742331 -411.457092) (xy 119.696973 -411.424641) (xy 119.656824 -411.385932)
			(xy 119.622738 -411.341789) (xy 119.595442 -411.293154) (xy 119.575519 -411.241063) (xy 119.563393 -411.186626)
			(xy 119.559322 -411.131004) (xy 118.73103 -411.131004) (xy 118.73103 -412.17469) (xy 119.559322 -412.17469)
			(xy 119.563393 -412.119068) (xy 119.575519 -412.064631) (xy 119.595442 -412.01254) (xy 119.622738 -411.963905)
			(xy 119.656824 -411.919762) (xy 119.696973 -411.881053) (xy 119.742331 -411.848602) (xy 119.791931 -411.823101)
			(xy 119.844715 -411.805094) (xy 119.899558 -411.794964) (xy 119.955292 -411.792927) (xy 120.010729 -411.799027)
			(xy 120.064686 -411.813133) (xy 120.116015 -411.834945) (xy 120.163621 -411.863999) (xy 120.206489 -411.899674)
			(xy 120.243706 -411.941211) (xy 120.257857 -411.9626) (xy 173.976296 -411.9626) (xy 173.980262 -411.878069)
			(xy 173.992127 -411.794282) (xy 174.011785 -411.711973) (xy 174.039065 -411.631867) (xy 174.073726 -411.554668)
			(xy 174.115464 -411.481053) (xy 174.163911 -411.41167) (xy 174.218643 -411.347129) (xy 174.279179 -411.287997)
			(xy 174.344985 -411.234793) (xy 174.415485 -411.187985) (xy 174.490057 -411.147984) (xy 174.568048 -411.115142)
			(xy 174.648772 -411.089748) (xy 174.731519 -411.072025) (xy 174.815561 -411.062127) (xy 174.900162 -411.060144)
			(xy 174.984576 -411.066091) (xy 175.068063 -411.079916) (xy 175.149888 -411.101499) (xy 175.229332 -411.130649)
			(xy 175.305698 -411.16711) (xy 175.378314 -411.210562) (xy 175.446542 -411.260623) (xy 175.509782 -411.316853)
			(xy 175.567479 -411.378758) (xy 175.619126 -411.445794) (xy 175.664268 -411.517371) (xy 175.683423 -411.555184)
			(xy 178.819556 -411.555184) (xy 178.82004 -411.526502) (xy 178.828644 -411.469788) (xy 178.84564 -411.415)
			(xy 178.870646 -411.363373) (xy 178.903097 -411.316071) (xy 178.942264 -411.27416) (xy 178.987262 -411.238583)
			(xy 179.03708 -411.210143) (xy 179.06365 -411.19933) (xy 179.077345 -411.193517) (xy 179.100896 -411.175363)
			(xy 179.118211 -411.15119) (xy 179.127821 -411.123051) (xy 179.12891 -411.093336) (xy 179.121383 -411.064569)
			(xy 179.105882 -411.039194) (xy 179.095146 -411.028896) (xy 179.075609 -411.01073) (xy 179.04128 -410.969896)
			(xy 179.012977 -410.924677) (xy 178.991252 -410.875954) (xy 178.97653 -410.824678) (xy 178.969098 -410.771851)
			(xy 178.968654 -410.745178) (xy 178.96914 -410.717927) (xy 178.976896 -410.663979) (xy 178.992251 -410.611684)
			(xy 179.014893 -410.562107) (xy 179.044359 -410.516257) (xy 179.08005 -410.475066) (xy 179.121241 -410.439375)
			(xy 179.167091 -410.409909) (xy 179.216668 -410.387267) (xy 179.268963 -410.371912) (xy 179.322911 -410.364156)
			(xy 179.377413 -410.364156) (xy 179.431361 -410.371912) (xy 179.483656 -410.387267) (xy 179.533233 -410.409909)
			(xy 179.579083 -410.439375) (xy 179.620274 -410.475066) (xy 179.655965 -410.516257) (xy 179.685431 -410.562107)
			(xy 179.708073 -410.611684) (xy 179.723428 -410.663979) (xy 179.731184 -410.717927) (xy 179.73167 -410.745178)
			(xy 179.731137 -410.773858) (xy 179.722539 -410.830569) (xy 179.70555 -410.885355) (xy 179.680551 -410.936981)
			(xy 179.648106 -410.984283) (xy 179.608947 -411.026195) (xy 179.563954 -411.061774) (xy 179.514144 -411.090217)
			(xy 179.487576 -411.101032) (xy 179.473839 -411.106759) (xy 179.450276 -411.124925) (xy 179.432954 -411.149115)
			(xy 179.423345 -411.177273) (xy 179.423033 -411.185868) (xy 179.732176 -411.185868) (xy 179.736247 -411.130246)
			(xy 179.748373 -411.075809) (xy 179.768296 -411.023718) (xy 179.795592 -410.975083) (xy 179.829678 -410.93094)
			(xy 179.869827 -410.892231) (xy 179.915185 -410.85978) (xy 179.964785 -410.834279) (xy 180.017569 -410.816272)
			(xy 180.072412 -410.806142) (xy 180.128146 -410.804105) (xy 180.183583 -410.810205) (xy 180.23754 -410.824311)
			(xy 180.288869 -410.846123) (xy 180.336475 -410.875177) (xy 180.379343 -410.910852) (xy 180.41656 -410.952389)
			(xy 180.447333 -410.998902) (xy 180.471005 -411.049399) (xy 180.487073 -411.102806) (xy 180.495193 -411.157982)
			(xy 180.495702 -411.185868) (xy 180.495193 -411.213754) (xy 180.487073 -411.26893) (xy 180.471005 -411.322337)
			(xy 180.447333 -411.372834) (xy 180.41656 -411.419347) (xy 180.379343 -411.460884) (xy 180.336475 -411.496559)
			(xy 180.288869 -411.525613) (xy 180.23754 -411.547425) (xy 180.183583 -411.561531) (xy 180.128146 -411.567631)
			(xy 180.072412 -411.565594) (xy 180.017569 -411.555464) (xy 179.964785 -411.537457) (xy 179.915185 -411.511956)
			(xy 179.869827 -411.479505) (xy 179.829678 -411.440796) (xy 179.795592 -411.396653) (xy 179.768296 -411.348018)
			(xy 179.748373 -411.295927) (xy 179.736247 -411.24149) (xy 179.732176 -411.185868) (xy 179.423033 -411.185868)
			(xy 179.422266 -411.207006) (xy 179.429809 -411.235786) (xy 179.445332 -411.261168) (xy 179.45608 -411.271466)
			(xy 179.475603 -411.289646) (xy 179.509933 -411.330477) (xy 179.538237 -411.375694) (xy 179.559964 -411.424414)
			(xy 179.574689 -411.475687) (xy 179.582125 -411.528511) (xy 179.582572 -411.555184) (xy 179.582086 -411.582435)
			(xy 179.57433 -411.636383) (xy 179.558975 -411.688678) (xy 179.536333 -411.738255) (xy 179.506867 -411.784105)
			(xy 179.471176 -411.825296) (xy 179.429985 -411.860987) (xy 179.384135 -411.890453) (xy 179.334558 -411.913095)
			(xy 179.282263 -411.92845) (xy 179.228315 -411.936206) (xy 179.173813 -411.936206) (xy 179.119865 -411.92845)
			(xy 179.06757 -411.913095) (xy 179.017993 -411.890453) (xy 178.972143 -411.860987) (xy 178.930952 -411.825296)
			(xy 178.895261 -411.784105) (xy 178.865795 -411.738255) (xy 178.843153 -411.688678) (xy 178.827798 -411.636383)
			(xy 178.820042 -411.582435) (xy 178.819556 -411.555184) (xy 175.683423 -411.555184) (xy 175.70251 -411.592861)
			(xy 175.733514 -411.6716) (xy 175.757009 -411.752897) (xy 175.772788 -411.836036) (xy 175.780712 -411.920288)
			(xy 175.781208 -411.9626) (xy 175.780712 -412.004912) (xy 175.772788 -412.089164) (xy 175.757009 -412.172303)
			(xy 175.733514 -412.2536) (xy 175.72658 -412.27121) (xy 179.660802 -412.27121) (xy 179.664873 -412.215588)
			(xy 179.676999 -412.161151) (xy 179.696922 -412.10906) (xy 179.724218 -412.060425) (xy 179.758304 -412.016282)
			(xy 179.798453 -411.977573) (xy 179.843811 -411.945122) (xy 179.893411 -411.919621) (xy 179.946195 -411.901614)
			(xy 180.001038 -411.891484) (xy 180.056772 -411.889447) (xy 180.112209 -411.895547) (xy 180.166166 -411.909653)
			(xy 180.217495 -411.931465) (xy 180.265101 -411.960519) (xy 180.307969 -411.996194) (xy 180.345186 -412.037731)
			(xy 180.375959 -412.084244) (xy 180.399631 -412.134741) (xy 180.415699 -412.188148) (xy 180.423819 -412.243324)
			(xy 180.424328 -412.27121) (xy 180.423819 -412.299096) (xy 180.415699 -412.354272) (xy 180.399631 -412.407679)
			(xy 180.375959 -412.458176) (xy 180.345186 -412.504689) (xy 180.307969 -412.546226) (xy 180.265101 -412.581901)
			(xy 180.217495 -412.610955) (xy 180.166166 -412.632767) (xy 180.112209 -412.646873) (xy 180.056772 -412.652973)
			(xy 180.001038 -412.650936) (xy 179.946195 -412.640806) (xy 179.893411 -412.622799) (xy 179.843811 -412.597298)
			(xy 179.798453 -412.564847) (xy 179.758304 -412.526138) (xy 179.724218 -412.481995) (xy 179.696922 -412.43336)
			(xy 179.676999 -412.381269) (xy 179.664873 -412.326832) (xy 179.660802 -412.27121) (xy 175.72658 -412.27121)
			(xy 175.70251 -412.332339) (xy 175.664268 -412.407829) (xy 175.619126 -412.479406) (xy 175.567479 -412.546442)
			(xy 175.509782 -412.608347) (xy 175.446542 -412.664577) (xy 175.378314 -412.714638) (xy 175.305698 -412.75809)
			(xy 175.229332 -412.794551) (xy 175.149888 -412.823701) (xy 175.068063 -412.845284) (xy 174.984576 -412.859109)
			(xy 174.900162 -412.865056) (xy 174.815561 -412.863073) (xy 174.731519 -412.853175) (xy 174.648772 -412.835452)
			(xy 174.568048 -412.810058) (xy 174.490057 -412.777216) (xy 174.415485 -412.737215) (xy 174.344985 -412.690407)
			(xy 174.279179 -412.637203) (xy 174.218643 -412.578071) (xy 174.163911 -412.51353) (xy 174.115464 -412.444147)
			(xy 174.073726 -412.370532) (xy 174.039065 -412.293333) (xy 174.011785 -412.213227) (xy 173.992127 -412.130918)
			(xy 173.980262 -412.047131) (xy 173.976296 -411.9626) (xy 120.257857 -411.9626) (xy 120.274479 -411.987724)
			(xy 120.298151 -412.038221) (xy 120.314219 -412.091628) (xy 120.322339 -412.146804) (xy 120.322848 -412.17469)
			(xy 120.322339 -412.202576) (xy 120.314219 -412.257752) (xy 120.298151 -412.311159) (xy 120.274479 -412.361656)
			(xy 120.243706 -412.408169) (xy 120.206489 -412.449706) (xy 120.163621 -412.485381) (xy 120.116015 -412.514435)
			(xy 120.064686 -412.536247) (xy 120.010729 -412.550353) (xy 119.955292 -412.556453) (xy 119.899558 -412.554416)
			(xy 119.844715 -412.544286) (xy 119.791931 -412.526279) (xy 119.742331 -412.500778) (xy 119.696973 -412.468327)
			(xy 119.656824 -412.429618) (xy 119.622738 -412.385475) (xy 119.595442 -412.33684) (xy 119.575519 -412.284749)
			(xy 119.563393 -412.230312) (xy 119.559322 -412.17469) (xy 118.73103 -412.17469) (xy 118.73103 -412.735268)
			(xy 122.846082 -412.735268) (xy 122.850153 -412.679646) (xy 122.862279 -412.625209) (xy 122.882202 -412.573118)
			(xy 122.909498 -412.524483) (xy 122.943584 -412.48034) (xy 122.983733 -412.441631) (xy 123.029091 -412.40918)
			(xy 123.078691 -412.383679) (xy 123.131475 -412.365672) (xy 123.186318 -412.355542) (xy 123.242052 -412.353505)
			(xy 123.297489 -412.359605) (xy 123.351446 -412.373711) (xy 123.402775 -412.395523) (xy 123.450381 -412.424577)
			(xy 123.493249 -412.460252) (xy 123.530466 -412.501789) (xy 123.561239 -412.548302) (xy 123.584911 -412.598799)
			(xy 123.600979 -412.652206) (xy 123.609099 -412.707382) (xy 123.609608 -412.735268) (xy 123.609099 -412.763154)
			(xy 123.600979 -412.81833) (xy 123.584911 -412.871737) (xy 123.561239 -412.922234) (xy 123.530466 -412.968747)
			(xy 123.493249 -413.010284) (xy 123.450381 -413.045959) (xy 123.402775 -413.075013) (xy 123.351446 -413.096825)
			(xy 123.297489 -413.110931) (xy 123.242052 -413.117031) (xy 123.186318 -413.114994) (xy 123.131475 -413.104864)
			(xy 123.078691 -413.086857) (xy 123.029091 -413.061356) (xy 122.983733 -413.028905) (xy 122.943584 -412.990196)
			(xy 122.909498 -412.946053) (xy 122.882202 -412.897418) (xy 122.862279 -412.845327) (xy 122.850153 -412.79089)
			(xy 122.846082 -412.735268) (xy 118.73103 -412.735268) (xy 118.73103 -412.862014) (xy 119.058944 -413.189928)
			(xy 119.561862 -413.189928) (xy 119.565933 -413.134306) (xy 119.578059 -413.079869) (xy 119.597982 -413.027778)
			(xy 119.625278 -412.979143) (xy 119.659364 -412.935) (xy 119.699513 -412.896291) (xy 119.744871 -412.86384)
			(xy 119.794471 -412.838339) (xy 119.847255 -412.820332) (xy 119.902098 -412.810202) (xy 119.957832 -412.808165)
			(xy 120.013269 -412.814265) (xy 120.067226 -412.828371) (xy 120.118555 -412.850183) (xy 120.166161 -412.879237)
			(xy 120.209029 -412.914912) (xy 120.246246 -412.956449) (xy 120.277019 -413.002962) (xy 120.300691 -413.053459)
			(xy 120.316759 -413.106866) (xy 120.324879 -413.162042) (xy 120.325388 -413.189928) (xy 120.324879 -413.217814)
			(xy 120.316759 -413.27299) (xy 120.300691 -413.326397) (xy 120.277019 -413.376894) (xy 120.246246 -413.423407)
			(xy 120.209029 -413.464944) (xy 120.166161 -413.500619) (xy 120.118555 -413.529673) (xy 120.067226 -413.551485)
			(xy 120.013269 -413.565591) (xy 119.957832 -413.571691) (xy 119.902098 -413.569654) (xy 119.847255 -413.559524)
			(xy 119.794471 -413.541517) (xy 119.744871 -413.516016) (xy 119.699513 -413.483565) (xy 119.659364 -413.444856)
			(xy 119.625278 -413.400713) (xy 119.597982 -413.352078) (xy 119.578059 -413.299987) (xy 119.565933 -413.24555)
			(xy 119.561862 -413.189928) (xy 119.058944 -413.189928) (xy 119.888369 -414.019353) (xy 180.103738 -414.019353)
			(xy 180.103738 -413.964847) (xy 180.111495 -413.910895) (xy 180.12685 -413.858597) (xy 180.149492 -413.809015)
			(xy 180.17896 -413.763161) (xy 180.214653 -413.721967) (xy 180.255845 -413.686272) (xy 180.301698 -413.656802)
			(xy 180.351278 -413.634157) (xy 180.403576 -413.618799) (xy 180.457527 -413.611039) (xy 180.48478 -413.610552)
			(xy 180.511681 -413.611049) (xy 180.564949 -413.618617) (xy 180.616625 -413.633592) (xy 180.665686 -413.655677)
			(xy 180.711159 -413.684433) (xy 180.752142 -413.719292) (xy 180.787822 -413.759561) (xy 180.803042 -413.781748)
			(xy 180.811585 -413.793738) (xy 180.834071 -413.812714) (xy 180.861034 -413.824491) (xy 180.890236 -413.828091)
			(xy 180.919252 -413.823216) (xy 180.945673 -413.81027) (xy 180.967307 -413.790328) (xy 180.975254 -413.777938)
			(xy 180.990123 -413.754008) (xy 181.02576 -413.710375) (xy 181.067429 -413.67246) (xy 181.114223 -413.641088)
			(xy 181.165123 -413.616942) (xy 181.219021 -413.600547) (xy 181.274746 -413.592261) (xy 181.302914 -413.591756)
			(xy 181.330162 -413.592315) (xy 181.384103 -413.600073) (xy 181.436391 -413.615427) (xy 181.485962 -413.638067)
			(xy 181.531806 -413.667531) (xy 181.572991 -413.703219) (xy 181.608677 -413.744405) (xy 181.63814 -413.79025)
			(xy 181.660777 -413.839822) (xy 181.67613 -413.892111) (xy 181.683886 -413.946052) (xy 181.683886 -414.000548)
			(xy 181.67613 -414.054489) (xy 181.660777 -414.106778) (xy 181.63814 -414.15635) (xy 181.608677 -414.202195)
			(xy 181.572991 -414.243381) (xy 181.531806 -414.279069) (xy 181.485962 -414.308533) (xy 181.436391 -414.331173)
			(xy 181.384103 -414.346527) (xy 181.330162 -414.354285) (xy 181.302914 -414.354772) (xy 181.276011 -414.354313)
			(xy 181.22274 -414.346743) (xy 181.171061 -414.331764) (xy 181.121999 -414.309674) (xy 181.076527 -414.28091)
			(xy 181.035546 -414.246044) (xy 180.999869 -414.205767) (xy 180.984652 -414.183576) (xy 180.976119 -414.171577)
			(xy 180.953632 -414.152597) (xy 180.926666 -414.140817) (xy 180.897461 -414.137216) (xy 180.868442 -414.142094)
			(xy 180.842018 -414.155044) (xy 180.820386 -414.174993) (xy 180.81244 -414.187386) (xy 180.797584 -414.211325)
			(xy 180.761944 -414.254956) (xy 180.720272 -414.29287) (xy 180.673476 -414.32424) (xy 180.622574 -414.348385)
			(xy 180.568674 -414.364778) (xy 180.512949 -414.373064) (xy 180.48478 -414.373568) (xy 180.457527 -414.373161)
			(xy 180.403576 -414.365401) (xy 180.351278 -414.350043) (xy 180.301698 -414.327398) (xy 180.255845 -414.297928)
			(xy 180.214653 -414.262233) (xy 180.17896 -414.221039) (xy 180.149492 -414.175185) (xy 180.12685 -414.125603)
			(xy 180.111495 -414.073305) (xy 180.103738 -414.019353) (xy 119.888369 -414.019353) (xy 120.300496 -414.43148)
			(xy 168.423842 -414.43148) (xy 168.427913 -414.375858) (xy 168.440039 -414.321421) (xy 168.459962 -414.26933)
			(xy 168.487258 -414.220695) (xy 168.521344 -414.176552) (xy 168.561493 -414.137843) (xy 168.606851 -414.105392)
			(xy 168.656451 -414.079891) (xy 168.709235 -414.061884) (xy 168.764078 -414.051754) (xy 168.819812 -414.049717)
			(xy 168.875249 -414.055817) (xy 168.929206 -414.069923) (xy 168.980535 -414.091735) (xy 169.028141 -414.120789)
			(xy 169.071009 -414.156464) (xy 169.108226 -414.198001) (xy 169.138999 -414.244514) (xy 169.162671 -414.295011)
			(xy 169.178739 -414.348418) (xy 169.186859 -414.403594) (xy 169.187368 -414.43148) (xy 169.186859 -414.459366)
			(xy 169.178739 -414.514542) (xy 169.162671 -414.567949) (xy 169.138999 -414.618446) (xy 169.108226 -414.664959)
			(xy 169.079143 -414.697418) (xy 176.68697 -414.697418) (xy 176.691041 -414.641796) (xy 176.703167 -414.587359)
			(xy 176.72309 -414.535268) (xy 176.750386 -414.486633) (xy 176.784472 -414.44249) (xy 176.824621 -414.403781)
			(xy 176.869979 -414.37133) (xy 176.919579 -414.345829) (xy 176.972363 -414.327822) (xy 177.027206 -414.317692)
			(xy 177.08294 -414.315655) (xy 177.138377 -414.321755) (xy 177.192334 -414.335861) (xy 177.243663 -414.357673)
			(xy 177.291269 -414.386727) (xy 177.334137 -414.422402) (xy 177.371354 -414.463939) (xy 177.402127 -414.510452)
			(xy 177.425799 -414.560949) (xy 177.441867 -414.614356) (xy 177.449987 -414.669532) (xy 177.450496 -414.697418)
			(xy 177.449987 -414.725304) (xy 177.441867 -414.78048) (xy 177.425799 -414.833887) (xy 177.402127 -414.884384)
			(xy 177.371354 -414.930897) (xy 177.334137 -414.972434) (xy 177.291269 -415.008109) (xy 177.243663 -415.037163)
			(xy 177.192334 -415.058975) (xy 177.138377 -415.073081) (xy 177.08294 -415.079181) (xy 177.027206 -415.077144)
			(xy 176.972363 -415.067014) (xy 176.919579 -415.049007) (xy 176.869979 -415.023506) (xy 176.824621 -414.991055)
			(xy 176.784472 -414.952346) (xy 176.750386 -414.908203) (xy 176.72309 -414.859568) (xy 176.703167 -414.807477)
			(xy 176.691041 -414.75304) (xy 176.68697 -414.697418) (xy 169.079143 -414.697418) (xy 169.071009 -414.706496)
			(xy 169.028141 -414.742171) (xy 168.980535 -414.771225) (xy 168.929206 -414.793037) (xy 168.875249 -414.807143)
			(xy 168.819812 -414.813243) (xy 168.764078 -414.811206) (xy 168.709235 -414.801076) (xy 168.656451 -414.783069)
			(xy 168.606851 -414.757568) (xy 168.561493 -414.725117) (xy 168.521344 -414.686408) (xy 168.487258 -414.642265)
			(xy 168.459962 -414.59363) (xy 168.440039 -414.541539) (xy 168.427913 -414.487102) (xy 168.423842 -414.43148)
			(xy 120.300496 -414.43148) (xy 121.119392 -415.250376) (xy 173.25035 -415.250376) (xy 173.254421 -415.194754)
			(xy 173.266547 -415.140317) (xy 173.28647 -415.088226) (xy 173.313766 -415.039591) (xy 173.347852 -414.995448)
			(xy 173.388001 -414.956739) (xy 173.433359 -414.924288) (xy 173.482959 -414.898787) (xy 173.535743 -414.88078)
			(xy 173.590586 -414.87065) (xy 173.64632 -414.868613) (xy 173.701757 -414.874713) (xy 173.755714 -414.888819)
			(xy 173.807043 -414.910631) (xy 173.854649 -414.939685) (xy 173.897517 -414.97536) (xy 173.934734 -415.016897)
			(xy 173.965507 -415.06341) (xy 173.989179 -415.113907) (xy 174.005247 -415.167314) (xy 174.013367 -415.22249)
			(xy 174.013876 -415.250376) (xy 174.013367 -415.278262) (xy 174.005247 -415.333438) (xy 173.989179 -415.386845)
			(xy 173.965507 -415.437342) (xy 173.934734 -415.483855) (xy 173.897517 -415.525392) (xy 173.854649 -415.561067)
			(xy 173.807043 -415.590121) (xy 173.755714 -415.611933) (xy 173.701757 -415.626039) (xy 173.64632 -415.632139)
			(xy 173.590586 -415.630102) (xy 173.535743 -415.619972) (xy 173.482959 -415.601965) (xy 173.433359 -415.576464)
			(xy 173.388001 -415.544013) (xy 173.347852 -415.505304) (xy 173.313766 -415.461161) (xy 173.28647 -415.412526)
			(xy 173.266547 -415.360435) (xy 173.254421 -415.305998) (xy 173.25035 -415.250376) (xy 121.119392 -415.250376)
			(xy 122.772424 -416.903408) (xy 123.402342 -416.903408) (xy 123.406413 -416.847786) (xy 123.418539 -416.793349)
			(xy 123.438462 -416.741258) (xy 123.465758 -416.692623) (xy 123.499844 -416.64848) (xy 123.539993 -416.609771)
			(xy 123.585351 -416.57732) (xy 123.634951 -416.551819) (xy 123.687735 -416.533812) (xy 123.742578 -416.523682)
			(xy 123.798312 -416.521645) (xy 123.853749 -416.527745) (xy 123.907706 -416.541851) (xy 123.927702 -416.550348)
			(xy 170.08043 -416.550348) (xy 170.084501 -416.494726) (xy 170.096627 -416.440289) (xy 170.11655 -416.388198)
			(xy 170.143846 -416.339563) (xy 170.177932 -416.29542) (xy 170.218081 -416.256711) (xy 170.263439 -416.22426)
			(xy 170.313039 -416.198759) (xy 170.365823 -416.180752) (xy 170.420666 -416.170622) (xy 170.4764 -416.168585)
			(xy 170.531837 -416.174685) (xy 170.585794 -416.188791) (xy 170.637123 -416.210603) (xy 170.684729 -416.239657)
			(xy 170.727597 -416.275332) (xy 170.764814 -416.316869) (xy 170.795587 -416.363382) (xy 170.819259 -416.413879)
			(xy 170.835327 -416.467286) (xy 170.843447 -416.522462) (xy 170.843956 -416.550348) (xy 170.843447 -416.578234)
			(xy 170.835327 -416.63341) (xy 170.819259 -416.686817) (xy 170.799288 -416.729418) (xy 173.917862 -416.729418)
			(xy 173.921933 -416.673796) (xy 173.934059 -416.619359) (xy 173.953982 -416.567268) (xy 173.981278 -416.518633)
			(xy 174.015364 -416.47449) (xy 174.055513 -416.435781) (xy 174.100871 -416.40333) (xy 174.150471 -416.377829)
			(xy 174.203255 -416.359822) (xy 174.258098 -416.349692) (xy 174.313832 -416.347655) (xy 174.369269 -416.353755)
			(xy 174.423226 -416.367861) (xy 174.474555 -416.389673) (xy 174.522161 -416.418727) (xy 174.565029 -416.454402)
			(xy 174.602246 -416.495939) (xy 174.606986 -416.503104) (xy 181.025544 -416.503104) (xy 181.029615 -416.447482)
			(xy 181.041741 -416.393045) (xy 181.061664 -416.340954) (xy 181.08896 -416.292319) (xy 181.123046 -416.248176)
			(xy 181.163195 -416.209467) (xy 181.208553 -416.177016) (xy 181.258153 -416.151515) (xy 181.310937 -416.133508)
			(xy 181.36578 -416.123378) (xy 181.421514 -416.121341) (xy 181.476951 -416.127441) (xy 181.530908 -416.141547)
			(xy 181.582237 -416.163359) (xy 181.629843 -416.192413) (xy 181.672711 -416.228088) (xy 181.709928 -416.269625)
			(xy 181.740701 -416.316138) (xy 181.764373 -416.366635) (xy 181.780441 -416.420042) (xy 181.788561 -416.475218)
			(xy 181.78907 -416.503104) (xy 181.788561 -416.53099) (xy 181.780441 -416.586166) (xy 181.764373 -416.639573)
			(xy 181.740701 -416.69007) (xy 181.709928 -416.736583) (xy 181.672711 -416.77812) (xy 181.629843 -416.813795)
			(xy 181.582237 -416.842849) (xy 181.530908 -416.864661) (xy 181.476951 -416.878767) (xy 181.421514 -416.884867)
			(xy 181.36578 -416.88283) (xy 181.310937 -416.8727) (xy 181.258153 -416.854693) (xy 181.208553 -416.829192)
			(xy 181.163195 -416.796741) (xy 181.123046 -416.758032) (xy 181.08896 -416.713889) (xy 181.061664 -416.665254)
			(xy 181.041741 -416.613163) (xy 181.029615 -416.558726) (xy 181.025544 -416.503104) (xy 174.606986 -416.503104)
			(xy 174.633019 -416.542452) (xy 174.656691 -416.592949) (xy 174.672759 -416.646356) (xy 174.680879 -416.701532)
			(xy 174.681388 -416.729418) (xy 174.680879 -416.757304) (xy 174.672759 -416.81248) (xy 174.656691 -416.865887)
			(xy 174.633019 -416.916384) (xy 174.602246 -416.962897) (xy 174.565029 -417.004434) (xy 174.522161 -417.040109)
			(xy 174.474555 -417.069163) (xy 174.423226 -417.090975) (xy 174.369269 -417.105081) (xy 174.313832 -417.111181)
			(xy 174.258098 -417.109144) (xy 174.203255 -417.099014) (xy 174.150471 -417.081007) (xy 174.100871 -417.055506)
			(xy 174.055513 -417.023055) (xy 174.015364 -416.984346) (xy 173.981278 -416.940203) (xy 173.953982 -416.891568)
			(xy 173.934059 -416.839477) (xy 173.921933 -416.78504) (xy 173.917862 -416.729418) (xy 170.799288 -416.729418)
			(xy 170.795587 -416.737314) (xy 170.764814 -416.783827) (xy 170.727597 -416.825364) (xy 170.684729 -416.861039)
			(xy 170.637123 -416.890093) (xy 170.585794 -416.911905) (xy 170.531837 -416.926011) (xy 170.4764 -416.932111)
			(xy 170.420666 -416.930074) (xy 170.365823 -416.919944) (xy 170.313039 -416.901937) (xy 170.263439 -416.876436)
			(xy 170.218081 -416.843985) (xy 170.177932 -416.805276) (xy 170.143846 -416.761133) (xy 170.11655 -416.712498)
			(xy 170.096627 -416.660407) (xy 170.084501 -416.60597) (xy 170.08043 -416.550348) (xy 123.927702 -416.550348)
			(xy 123.959035 -416.563663) (xy 124.006641 -416.592717) (xy 124.049509 -416.628392) (xy 124.086726 -416.669929)
			(xy 124.117499 -416.716442) (xy 124.141171 -416.766939) (xy 124.157239 -416.820346) (xy 124.165359 -416.875522)
			(xy 124.165868 -416.903408) (xy 124.165359 -416.931294) (xy 124.157239 -416.98647) (xy 124.141171 -417.039877)
			(xy 124.117499 -417.090374) (xy 124.086726 -417.136887) (xy 124.049509 -417.178424) (xy 124.006641 -417.214099)
			(xy 123.959035 -417.243153) (xy 123.907706 -417.264965) (xy 123.853749 -417.279071) (xy 123.798312 -417.285171)
			(xy 123.742578 -417.283134) (xy 123.687735 -417.273004) (xy 123.634951 -417.254997) (xy 123.585351 -417.229496)
			(xy 123.539993 -417.197045) (xy 123.499844 -417.158336) (xy 123.465758 -417.114193) (xy 123.438462 -417.065558)
			(xy 123.418539 -417.013467) (xy 123.406413 -416.95903) (xy 123.402342 -416.903408) (xy 122.772424 -416.903408)
			(xy 123.309634 -417.440618) (xy 163.124132 -417.440618) (xy 163.128203 -417.384996) (xy 163.140329 -417.330559)
			(xy 163.160252 -417.278468) (xy 163.187548 -417.229833) (xy 163.221634 -417.18569) (xy 163.261783 -417.146981)
			(xy 163.307141 -417.11453) (xy 163.356741 -417.089029) (xy 163.409525 -417.071022) (xy 163.464368 -417.060892)
			(xy 163.520102 -417.058855) (xy 163.575539 -417.064955) (xy 163.629496 -417.079061) (xy 163.680825 -417.100873)
			(xy 163.728431 -417.129927) (xy 163.771299 -417.165602) (xy 163.808516 -417.207139) (xy 163.839289 -417.253652)
			(xy 163.862961 -417.304149) (xy 163.879029 -417.357556) (xy 163.887149 -417.412732) (xy 163.887333 -417.422838)
			(xy 165.156132 -417.422838) (xy 165.160203 -417.367216) (xy 165.172329 -417.312779) (xy 165.192252 -417.260688)
			(xy 165.219548 -417.212053) (xy 165.253634 -417.16791) (xy 165.293783 -417.129201) (xy 165.339141 -417.09675)
			(xy 165.388741 -417.071249) (xy 165.441525 -417.053242) (xy 165.496368 -417.043112) (xy 165.552102 -417.041075)
			(xy 165.607539 -417.047175) (xy 165.661496 -417.061281) (xy 165.712825 -417.083093) (xy 165.760431 -417.112147)
			(xy 165.803299 -417.147822) (xy 165.840516 -417.189359) (xy 165.871289 -417.235872) (xy 165.894961 -417.286369)
			(xy 165.911029 -417.339776) (xy 165.919149 -417.394952) (xy 165.919658 -417.422838) (xy 165.919149 -417.450724)
			(xy 165.911029 -417.5059) (xy 165.894961 -417.559307) (xy 165.871289 -417.609804) (xy 165.840516 -417.656317)
			(xy 165.803299 -417.697854) (xy 165.760431 -417.733529) (xy 165.74095 -417.745418) (xy 176.70602 -417.745418)
			(xy 176.710091 -417.689796) (xy 176.722217 -417.635359) (xy 176.74214 -417.583268) (xy 176.769436 -417.534633)
			(xy 176.803522 -417.49049) (xy 176.843671 -417.451781) (xy 176.889029 -417.41933) (xy 176.938629 -417.393829)
			(xy 176.991413 -417.375822) (xy 177.046256 -417.365692) (xy 177.10199 -417.363655) (xy 177.157427 -417.369755)
			(xy 177.211384 -417.383861) (xy 177.262713 -417.405673) (xy 177.310319 -417.434727) (xy 177.353187 -417.470402)
			(xy 177.390404 -417.511939) (xy 177.421177 -417.558452) (xy 177.444849 -417.608949) (xy 177.460917 -417.662356)
			(xy 177.469037 -417.717532) (xy 177.469546 -417.745418) (xy 177.469037 -417.773304) (xy 177.460917 -417.82848)
			(xy 177.444849 -417.881887) (xy 177.421177 -417.932384) (xy 177.390404 -417.978897) (xy 177.353187 -418.020434)
			(xy 177.310319 -418.056109) (xy 177.262713 -418.085163) (xy 177.211384 -418.106975) (xy 177.157427 -418.121081)
			(xy 177.10199 -418.127181) (xy 177.046256 -418.125144) (xy 176.991413 -418.115014) (xy 176.938629 -418.097007)
			(xy 176.889029 -418.071506) (xy 176.843671 -418.039055) (xy 176.803522 -418.000346) (xy 176.769436 -417.956203)
			(xy 176.74214 -417.907568) (xy 176.722217 -417.855477) (xy 176.710091 -417.80104) (xy 176.70602 -417.745418)
			(xy 165.74095 -417.745418) (xy 165.712825 -417.762583) (xy 165.661496 -417.784395) (xy 165.607539 -417.798501)
			(xy 165.552102 -417.804601) (xy 165.496368 -417.802564) (xy 165.441525 -417.792434) (xy 165.388741 -417.774427)
			(xy 165.339141 -417.748926) (xy 165.293783 -417.716475) (xy 165.253634 -417.677766) (xy 165.219548 -417.633623)
			(xy 165.192252 -417.584988) (xy 165.172329 -417.532897) (xy 165.160203 -417.47846) (xy 165.156132 -417.422838)
			(xy 163.887333 -417.422838) (xy 163.887658 -417.440618) (xy 163.887149 -417.468504) (xy 163.879029 -417.52368)
			(xy 163.862961 -417.577087) (xy 163.839289 -417.627584) (xy 163.808516 -417.674097) (xy 163.771299 -417.715634)
			(xy 163.728431 -417.751309) (xy 163.680825 -417.780363) (xy 163.629496 -417.802175) (xy 163.575539 -417.816281)
			(xy 163.520102 -417.822381) (xy 163.464368 -417.820344) (xy 163.409525 -417.810214) (xy 163.356741 -417.792207)
			(xy 163.307141 -417.766706) (xy 163.261783 -417.734255) (xy 163.221634 -417.695546) (xy 163.187548 -417.651403)
			(xy 163.160252 -417.602768) (xy 163.140329 -417.550677) (xy 163.128203 -417.49624) (xy 163.124132 -417.440618)
			(xy 123.309634 -417.440618) (xy 124.628402 -418.759386) (xy 162.44646 -418.759386) (xy 162.450531 -418.703764)
			(xy 162.462657 -418.649327) (xy 162.48258 -418.597236) (xy 162.509876 -418.548601) (xy 162.543962 -418.504458)
			(xy 162.584111 -418.465749) (xy 162.629469 -418.433298) (xy 162.679069 -418.407797) (xy 162.731853 -418.38979)
			(xy 162.786696 -418.37966) (xy 162.84243 -418.377623) (xy 162.897867 -418.383723) (xy 162.951824 -418.397829)
			(xy 163.003153 -418.419641) (xy 163.050759 -418.448695) (xy 163.050818 -418.448744) (xy 166.06596 -418.448744)
			(xy 166.070031 -418.393122) (xy 166.082157 -418.338685) (xy 166.10208 -418.286594) (xy 166.129376 -418.237959)
			(xy 166.163462 -418.193816) (xy 166.203611 -418.155107) (xy 166.248969 -418.122656) (xy 166.298569 -418.097155)
			(xy 166.351353 -418.079148) (xy 166.406196 -418.069018) (xy 166.46193 -418.066981) (xy 166.517367 -418.073081)
			(xy 166.571324 -418.087187) (xy 166.622653 -418.108999) (xy 166.670259 -418.138053) (xy 166.713127 -418.173728)
			(xy 166.750344 -418.215265) (xy 166.781117 -418.261778) (xy 166.804789 -418.312275) (xy 166.820857 -418.365682)
			(xy 166.828977 -418.420858) (xy 166.829486 -418.448744) (xy 166.828977 -418.47663) (xy 166.828558 -418.479478)
			(xy 168.030904 -418.479478) (xy 168.034975 -418.423856) (xy 168.047101 -418.369419) (xy 168.067024 -418.317328)
			(xy 168.09432 -418.268693) (xy 168.128406 -418.22455) (xy 168.168555 -418.185841) (xy 168.213913 -418.15339)
			(xy 168.263513 -418.127889) (xy 168.316297 -418.109882) (xy 168.37114 -418.099752) (xy 168.426874 -418.097715)
			(xy 168.482311 -418.103815) (xy 168.536268 -418.117921) (xy 168.587597 -418.139733) (xy 168.629457 -418.16528)
			(xy 170.125642 -418.16528) (xy 170.129713 -418.109658) (xy 170.141839 -418.055221) (xy 170.161762 -418.00313)
			(xy 170.189058 -417.954495) (xy 170.223144 -417.910352) (xy 170.263293 -417.871643) (xy 170.308651 -417.839192)
			(xy 170.358251 -417.813691) (xy 170.411035 -417.795684) (xy 170.465878 -417.785554) (xy 170.521612 -417.783517)
			(xy 170.577049 -417.789617) (xy 170.631006 -417.803723) (xy 170.682335 -417.825535) (xy 170.729941 -417.854589)
			(xy 170.772809 -417.890264) (xy 170.810026 -417.931801) (xy 170.840799 -417.978314) (xy 170.864471 -418.028811)
			(xy 170.880539 -418.082218) (xy 170.888659 -418.137394) (xy 170.889168 -418.16528) (xy 170.888659 -418.193166)
			(xy 170.880539 -418.248342) (xy 170.871294 -418.279072) (xy 178.362608 -418.279072) (xy 178.366679 -418.22345)
			(xy 178.378805 -418.169013) (xy 178.398728 -418.116922) (xy 178.426024 -418.068287) (xy 178.46011 -418.024144)
			(xy 178.500259 -417.985435) (xy 178.545617 -417.952984) (xy 178.595217 -417.927483) (xy 178.648001 -417.909476)
			(xy 178.702844 -417.899346) (xy 178.758578 -417.897309) (xy 178.814015 -417.903409) (xy 178.867972 -417.917515)
			(xy 178.919301 -417.939327) (xy 178.966907 -417.968381) (xy 179.009775 -418.004056) (xy 179.046992 -418.045593)
			(xy 179.077765 -418.092106) (xy 179.101437 -418.142603) (xy 179.117505 -418.19601) (xy 179.125625 -418.251186)
			(xy 179.126106 -418.277548) (xy 179.703728 -418.277548) (xy 179.707799 -418.221926) (xy 179.719925 -418.167489)
			(xy 179.739848 -418.115398) (xy 179.767144 -418.066763) (xy 179.80123 -418.02262) (xy 179.841379 -417.983911)
			(xy 179.886737 -417.95146) (xy 179.936337 -417.925959) (xy 179.989121 -417.907952) (xy 180.043964 -417.897822)
			(xy 180.099698 -417.895785) (xy 180.155135 -417.901885) (xy 180.209092 -417.915991) (xy 180.260421 -417.937803)
			(xy 180.308027 -417.966857) (xy 180.350895 -418.002532) (xy 180.388112 -418.044069) (xy 180.418885 -418.090582)
			(xy 180.442557 -418.141079) (xy 180.458625 -418.194486) (xy 180.466745 -418.249662) (xy 180.467254 -418.277548)
			(xy 180.466745 -418.305434) (xy 180.458625 -418.36061) (xy 180.442557 -418.414017) (xy 180.418885 -418.464514)
			(xy 180.388112 -418.511027) (xy 180.350895 -418.552564) (xy 180.308027 -418.588239) (xy 180.260421 -418.617293)
			(xy 180.209092 -418.639105) (xy 180.155135 -418.653211) (xy 180.099698 -418.659311) (xy 180.043964 -418.657274)
			(xy 179.989121 -418.647144) (xy 179.936337 -418.629137) (xy 179.886737 -418.603636) (xy 179.841379 -418.571185)
			(xy 179.80123 -418.532476) (xy 179.767144 -418.488333) (xy 179.739848 -418.439698) (xy 179.719925 -418.387607)
			(xy 179.707799 -418.33317) (xy 179.703728 -418.277548) (xy 179.126106 -418.277548) (xy 179.126134 -418.279072)
			(xy 179.125625 -418.306958) (xy 179.117505 -418.362134) (xy 179.101437 -418.415541) (xy 179.077765 -418.466038)
			(xy 179.046992 -418.512551) (xy 179.009775 -418.554088) (xy 178.966907 -418.589763) (xy 178.919301 -418.618817)
			(xy 178.867972 -418.640629) (xy 178.814015 -418.654735) (xy 178.758578 -418.660835) (xy 178.702844 -418.658798)
			(xy 178.648001 -418.648668) (xy 178.595217 -418.630661) (xy 178.545617 -418.60516) (xy 178.500259 -418.572709)
			(xy 178.46011 -418.534) (xy 178.426024 -418.489857) (xy 178.398728 -418.441222) (xy 178.378805 -418.389131)
			(xy 178.366679 -418.334694) (xy 178.362608 -418.279072) (xy 170.871294 -418.279072) (xy 170.864471 -418.301749)
			(xy 170.840799 -418.352246) (xy 170.810026 -418.398759) (xy 170.772809 -418.440296) (xy 170.729941 -418.475971)
			(xy 170.682335 -418.505025) (xy 170.631006 -418.526837) (xy 170.577049 -418.540943) (xy 170.521612 -418.547043)
			(xy 170.465878 -418.545006) (xy 170.411035 -418.534876) (xy 170.358251 -418.516869) (xy 170.308651 -418.491368)
			(xy 170.263293 -418.458917) (xy 170.223144 -418.420208) (xy 170.189058 -418.376065) (xy 170.161762 -418.32743)
			(xy 170.141839 -418.275339) (xy 170.129713 -418.220902) (xy 170.125642 -418.16528) (xy 168.629457 -418.16528)
			(xy 168.635203 -418.168787) (xy 168.678071 -418.204462) (xy 168.715288 -418.245999) (xy 168.746061 -418.292512)
			(xy 168.769733 -418.343009) (xy 168.785801 -418.396416) (xy 168.793921 -418.451592) (xy 168.79443 -418.479478)
			(xy 168.793921 -418.507364) (xy 168.785801 -418.56254) (xy 168.769733 -418.615947) (xy 168.746061 -418.666444)
			(xy 168.715288 -418.712957) (xy 168.678071 -418.754494) (xy 168.635203 -418.790169) (xy 168.587597 -418.819223)
			(xy 168.536268 -418.841035) (xy 168.482311 -418.855141) (xy 168.426874 -418.861241) (xy 168.37114 -418.859204)
			(xy 168.316297 -418.849074) (xy 168.263513 -418.831067) (xy 168.213913 -418.805566) (xy 168.168555 -418.773115)
			(xy 168.128406 -418.734406) (xy 168.09432 -418.690263) (xy 168.067024 -418.641628) (xy 168.047101 -418.589537)
			(xy 168.034975 -418.5351) (xy 168.030904 -418.479478) (xy 166.828558 -418.479478) (xy 166.820857 -418.531806)
			(xy 166.804789 -418.585213) (xy 166.781117 -418.63571) (xy 166.750344 -418.682223) (xy 166.713127 -418.72376)
			(xy 166.670259 -418.759435) (xy 166.622653 -418.788489) (xy 166.571324 -418.810301) (xy 166.517367 -418.824407)
			(xy 166.46193 -418.830507) (xy 166.406196 -418.82847) (xy 166.351353 -418.81834) (xy 166.298569 -418.800333)
			(xy 166.248969 -418.774832) (xy 166.203611 -418.742381) (xy 166.163462 -418.703672) (xy 166.129376 -418.659529)
			(xy 166.10208 -418.610894) (xy 166.082157 -418.558803) (xy 166.070031 -418.504366) (xy 166.06596 -418.448744)
			(xy 163.050818 -418.448744) (xy 163.093627 -418.48437) (xy 163.130844 -418.525907) (xy 163.161617 -418.57242)
			(xy 163.185289 -418.622917) (xy 163.201357 -418.676324) (xy 163.209477 -418.7315) (xy 163.209986 -418.759386)
			(xy 163.209477 -418.787272) (xy 163.201357 -418.842448) (xy 163.185289 -418.895855) (xy 163.161617 -418.946352)
			(xy 163.130844 -418.992865) (xy 163.093627 -419.034402) (xy 163.050759 -419.070077) (xy 163.003153 -419.099131)
			(xy 162.967038 -419.114478) (xy 170.666662 -419.114478) (xy 170.670733 -419.058856) (xy 170.682859 -419.004419)
			(xy 170.702782 -418.952328) (xy 170.730078 -418.903693) (xy 170.764164 -418.85955) (xy 170.804313 -418.820841)
			(xy 170.849671 -418.78839) (xy 170.899271 -418.762889) (xy 170.952055 -418.744882) (xy 171.006898 -418.734752)
			(xy 171.062632 -418.732715) (xy 171.118069 -418.738815) (xy 171.172026 -418.752921) (xy 171.223355 -418.774733)
			(xy 171.270961 -418.803787) (xy 171.313829 -418.839462) (xy 171.351046 -418.880999) (xy 171.381819 -418.927512)
			(xy 171.405491 -418.978009) (xy 171.421559 -419.031416) (xy 171.423715 -419.046069) (xy 181.518607 -419.046069)
			(xy 181.52636 -418.992127) (xy 181.54171 -418.939838) (xy 181.564346 -418.890265) (xy 181.593806 -418.844418)
			(xy 181.62949 -418.80323) (xy 181.670672 -418.76754) (xy 181.716515 -418.738073) (xy 181.766084 -418.71543)
			(xy 181.818371 -418.700072) (xy 181.872312 -418.692311) (xy 181.89956 -418.691822) (xy 181.91429 -418.691967)
			(xy 181.94366 -418.694257) (xy 181.958234 -418.696394) (xy 181.971566 -418.698145) (xy 181.99829 -418.695215)
			(xy 182.023323 -418.685409) (xy 182.044926 -418.669407) (xy 182.061603 -418.64832) (xy 182.072195 -418.62361)
			(xy 182.075968 -418.596991) (xy 182.072661 -418.570311) (xy 182.067962 -418.55771) (xy 182.059122 -418.534917)
			(xy 182.046691 -418.487635) (xy 182.040411 -418.439152) (xy 182.040022 -418.414708) (xy 182.040022 -418.4142)
			(xy 182.040455 -418.386946) (xy 182.048213 -418.332992) (xy 182.063571 -418.280692) (xy 182.086215 -418.23111)
			(xy 182.115686 -418.185255) (xy 182.151383 -418.144062) (xy 182.192579 -418.108368) (xy 182.238436 -418.078901)
			(xy 182.28802 -418.05626) (xy 182.340322 -418.040907) (xy 182.394276 -418.033153) (xy 182.42153 -418.032692)
			(xy 182.448132 -418.033197) (xy 182.500823 -418.040569) (xy 182.551977 -418.055194) (xy 182.600601 -418.076787)
			(xy 182.645752 -418.10493) (xy 182.686553 -418.139076) (xy 182.722211 -418.178562) (xy 182.737506 -418.200332)
			(xy 182.74584 -418.211812) (xy 182.767584 -418.230016) (xy 182.793497 -418.241534) (xy 182.82158 -418.245474)
			(xy 182.849663 -418.241534) (xy 182.875576 -418.230016) (xy 182.89732 -418.211812) (xy 182.905654 -418.200332)
			(xy 182.920964 -418.178573) (xy 182.956628 -418.139094) (xy 182.997429 -418.10495) (xy 183.042576 -418.076803)
			(xy 183.091195 -418.055199) (xy 183.142343 -418.040556) (xy 183.195029 -418.033158) (xy 183.22163 -418.032692)
			(xy 183.24888 -418.03318) (xy 183.302824 -418.04094) (xy 183.355115 -418.056298) (xy 183.404689 -418.07894)
			(xy 183.450536 -418.108407) (xy 183.491722 -418.144099) (xy 183.527411 -418.185288) (xy 183.556874 -418.231137)
			(xy 183.579513 -418.280713) (xy 183.594867 -418.333005) (xy 183.602622 -418.38695) (xy 183.602622 -418.44145)
			(xy 183.594867 -418.495395) (xy 183.579513 -418.547687) (xy 183.556874 -418.597263) (xy 183.527411 -418.643112)
			(xy 183.491722 -418.684301) (xy 183.450536 -418.719993) (xy 183.404689 -418.74946) (xy 183.355115 -418.772102)
			(xy 183.311064 -418.78504) (xy 186.384182 -418.78504) (xy 186.388253 -418.729418) (xy 186.400379 -418.674981)
			(xy 186.420302 -418.62289) (xy 186.447598 -418.574255) (xy 186.481684 -418.530112) (xy 186.521833 -418.491403)
			(xy 186.567191 -418.458952) (xy 186.616791 -418.433451) (xy 186.669575 -418.415444) (xy 186.724418 -418.405314)
			(xy 186.780152 -418.403277) (xy 186.835589 -418.409377) (xy 186.889546 -418.423483) (xy 186.940875 -418.445295)
			(xy 186.988481 -418.474349) (xy 187.031349 -418.510024) (xy 187.068566 -418.551561) (xy 187.099339 -418.598074)
			(xy 187.123011 -418.648571) (xy 187.139079 -418.701978) (xy 187.147199 -418.757154) (xy 187.147708 -418.78504)
			(xy 187.147199 -418.812926) (xy 187.139079 -418.868102) (xy 187.123011 -418.921509) (xy 187.099339 -418.972006)
			(xy 187.068566 -419.018519) (xy 187.031349 -419.060056) (xy 186.988481 -419.095731) (xy 186.940875 -419.124785)
			(xy 186.889546 -419.146597) (xy 186.835589 -419.160703) (xy 186.780152 -419.166803) (xy 186.724418 -419.164766)
			(xy 186.669575 -419.154636) (xy 186.616791 -419.136629) (xy 186.567191 -419.111128) (xy 186.521833 -419.078677)
			(xy 186.481684 -419.039968) (xy 186.447598 -418.995825) (xy 186.420302 -418.94719) (xy 186.400379 -418.895099)
			(xy 186.388253 -418.840662) (xy 186.384182 -418.78504) (xy 183.311064 -418.78504) (xy 183.302824 -418.78746)
			(xy 183.24888 -418.79522) (xy 183.22163 -418.795708) (xy 183.195027 -418.795233) (xy 183.142335 -418.787855)
			(xy 183.09118 -418.773225) (xy 183.042555 -418.751627) (xy 182.997405 -418.72348) (xy 182.956605 -418.68933)
			(xy 182.920948 -418.64984) (xy 182.905654 -418.628068) (xy 182.89732 -418.616588) (xy 182.875576 -418.598384)
			(xy 182.849663 -418.586866) (xy 182.82158 -418.582926) (xy 182.793497 -418.586866) (xy 182.767584 -418.598384)
			(xy 182.74584 -418.616588) (xy 182.737506 -418.628068) (xy 182.722222 -418.649846) (xy 182.686553 -418.689325)
			(xy 182.645748 -418.723467) (xy 182.600596 -418.751612) (xy 182.551973 -418.773213) (xy 182.500822 -418.787852)
			(xy 182.448133 -418.795245) (xy 182.42153 -418.795708) (xy 182.4068 -418.795565) (xy 182.37743 -418.793273)
			(xy 182.362856 -418.791136) (xy 182.349519 -418.789471) (xy 182.32281 -418.792402) (xy 182.297792 -418.802202)
			(xy 182.276199 -418.818192) (xy 182.259527 -418.839263) (xy 182.248933 -418.863955) (xy 182.245149 -418.890557)
			(xy 182.24844 -418.917223) (xy 182.253128 -418.92982) (xy 182.261976 -418.95261) (xy 182.274404 -418.999893)
			(xy 182.280681 -419.048378) (xy 182.281068 -419.072822) (xy 182.281068 -419.07333) (xy 182.28059 -419.100578)
			(xy 182.27283 -419.154519) (xy 182.257473 -419.206806) (xy 182.234832 -419.256376) (xy 182.205366 -419.302219)
			(xy 182.169677 -419.343403) (xy 182.12849 -419.379088) (xy 182.082644 -419.408549) (xy 182.033072 -419.431186)
			(xy 181.980783 -419.446538) (xy 181.926841 -419.454292) (xy 181.872345 -419.454291) (xy 181.818404 -419.446535)
			(xy 181.766116 -419.431182) (xy 181.716544 -419.408543) (xy 181.670699 -419.37908) (xy 181.629513 -419.343394)
			(xy 181.593826 -419.302209) (xy 181.564362 -419.256364) (xy 181.541722 -419.206794) (xy 181.526367 -419.154506)
			(xy 181.518609 -419.100565) (xy 181.518607 -419.046069) (xy 171.423715 -419.046069) (xy 171.429679 -419.086592)
			(xy 171.430188 -419.114478) (xy 171.429679 -419.142364) (xy 171.421559 -419.19754) (xy 171.405491 -419.250947)
			(xy 171.381819 -419.301444) (xy 171.351046 -419.347957) (xy 171.313829 -419.389494) (xy 171.270961 -419.425169)
			(xy 171.223355 -419.454223) (xy 171.172026 -419.476035) (xy 171.118069 -419.490141) (xy 171.062632 -419.496241)
			(xy 171.006898 -419.494204) (xy 170.952055 -419.484074) (xy 170.899271 -419.466067) (xy 170.849671 -419.440566)
			(xy 170.804313 -419.408115) (xy 170.764164 -419.369406) (xy 170.730078 -419.325263) (xy 170.702782 -419.276628)
			(xy 170.682859 -419.224537) (xy 170.670733 -419.1701) (xy 170.666662 -419.114478) (xy 162.967038 -419.114478)
			(xy 162.951824 -419.120943) (xy 162.897867 -419.135049) (xy 162.84243 -419.141149) (xy 162.786696 -419.139112)
			(xy 162.731853 -419.128982) (xy 162.679069 -419.110975) (xy 162.629469 -419.085474) (xy 162.584111 -419.053023)
			(xy 162.543962 -419.014314) (xy 162.509876 -418.970171) (xy 162.48258 -418.921536) (xy 162.462657 -418.869445)
			(xy 162.450531 -418.815008) (xy 162.44646 -418.759386) (xy 124.628402 -418.759386) (xy 125.543564 -419.674548)
			(xy 174.656494 -419.674548) (xy 174.660565 -419.618926) (xy 174.672691 -419.564489) (xy 174.692614 -419.512398)
			(xy 174.71991 -419.463763) (xy 174.753996 -419.41962) (xy 174.794145 -419.380911) (xy 174.839503 -419.34846)
			(xy 174.889103 -419.322959) (xy 174.941887 -419.304952) (xy 174.99673 -419.294822) (xy 175.052464 -419.292785)
			(xy 175.107901 -419.298885) (xy 175.161858 -419.312991) (xy 175.213187 -419.334803) (xy 175.260793 -419.363857)
			(xy 175.303661 -419.399532) (xy 175.340878 -419.441069) (xy 175.371651 -419.487582) (xy 175.395323 -419.538079)
			(xy 175.411391 -419.591486) (xy 175.419511 -419.646662) (xy 175.42002 -419.674548) (xy 175.419511 -419.702434)
			(xy 175.417335 -419.71722) (xy 184.228232 -419.71722) (xy 184.228718 -419.689969) (xy 184.236474 -419.636021)
			(xy 184.251829 -419.583726) (xy 184.274471 -419.534149) (xy 184.303937 -419.488299) (xy 184.339628 -419.447108)
			(xy 184.380819 -419.411417) (xy 184.426669 -419.381951) (xy 184.476246 -419.359309) (xy 184.528541 -419.343954)
			(xy 184.582489 -419.336198) (xy 184.636991 -419.336198) (xy 184.690939 -419.343954) (xy 184.743234 -419.359309)
			(xy 184.792811 -419.381951) (xy 184.838661 -419.411417) (xy 184.879852 -419.447108) (xy 184.915543 -419.488299)
			(xy 184.945009 -419.534149) (xy 184.967651 -419.583726) (xy 184.983006 -419.636021) (xy 184.990762 -419.689969)
			(xy 184.991248 -419.71722) (xy 184.990769 -419.745231) (xy 184.982568 -419.800648) (xy 184.966346 -419.854269)
			(xy 184.942452 -419.90494) (xy 184.911401 -419.951568) (xy 184.87386 -419.99315) (xy 184.852564 -420.011352)
			(xy 184.841288 -420.021363) (xy 184.824656 -420.046497) (xy 184.816065 -420.075386) (xy 184.81626 -420.105524)
			(xy 184.825224 -420.134299) (xy 184.84218 -420.159216) (xy 184.85358 -420.169086) (xy 184.875449 -420.187285)
			(xy 184.914053 -420.229076) (xy 184.946017 -420.276141) (xy 184.970632 -420.327432) (xy 184.987351 -420.381813)
			(xy 184.995803 -420.438074) (xy 184.996328 -420.46652) (xy 184.995842 -420.493771) (xy 184.988086 -420.547719)
			(xy 184.979113 -420.57828) (xy 186.836302 -420.57828) (xy 186.840373 -420.522658) (xy 186.852499 -420.468221)
			(xy 186.872422 -420.41613) (xy 186.899718 -420.367495) (xy 186.933804 -420.323352) (xy 186.973953 -420.284643)
			(xy 187.019311 -420.252192) (xy 187.068911 -420.226691) (xy 187.121695 -420.208684) (xy 187.176538 -420.198554)
			(xy 187.232272 -420.196517) (xy 187.287709 -420.202617) (xy 187.341666 -420.216723) (xy 187.392995 -420.238535)
			(xy 187.440601 -420.267589) (xy 187.483469 -420.303264) (xy 187.520686 -420.344801) (xy 187.551459 -420.391314)
			(xy 187.575131 -420.441811) (xy 187.591199 -420.495218) (xy 187.594825 -420.51986) (xy 187.791342 -420.51986)
			(xy 187.795413 -420.464238) (xy 187.807539 -420.409801) (xy 187.827462 -420.35771) (xy 187.854758 -420.309075)
			(xy 187.888844 -420.264932) (xy 187.928993 -420.226223) (xy 187.974351 -420.193772) (xy 188.023951 -420.168271)
			(xy 188.076735 -420.150264) (xy 188.131578 -420.140134) (xy 188.187312 -420.138097) (xy 188.242749 -420.144197)
			(xy 188.296706 -420.158303) (xy 188.348035 -420.180115) (xy 188.395641 -420.209169) (xy 188.438509 -420.244844)
			(xy 188.475726 -420.286381) (xy 188.506499 -420.332894) (xy 188.530171 -420.383391) (xy 188.546239 -420.436798)
			(xy 188.554359 -420.491974) (xy 188.554868 -420.51986) (xy 188.554359 -420.547746) (xy 188.546239 -420.602922)
			(xy 188.530171 -420.656329) (xy 188.506499 -420.706826) (xy 188.475726 -420.753339) (xy 188.438509 -420.794876)
			(xy 188.395641 -420.830551) (xy 188.348035 -420.859605) (xy 188.296706 -420.881417) (xy 188.242749 -420.895523)
			(xy 188.187312 -420.901623) (xy 188.131578 -420.899586) (xy 188.076735 -420.889456) (xy 188.023951 -420.871449)
			(xy 187.974351 -420.845948) (xy 187.928993 -420.813497) (xy 187.888844 -420.774788) (xy 187.854758 -420.730645)
			(xy 187.827462 -420.68201) (xy 187.807539 -420.629919) (xy 187.795413 -420.575482) (xy 187.791342 -420.51986)
			(xy 187.594825 -420.51986) (xy 187.599319 -420.550394) (xy 187.599828 -420.57828) (xy 187.599319 -420.606166)
			(xy 187.591199 -420.661342) (xy 187.575131 -420.714749) (xy 187.551459 -420.765246) (xy 187.520686 -420.811759)
			(xy 187.483469 -420.853296) (xy 187.440601 -420.888971) (xy 187.392995 -420.918025) (xy 187.341666 -420.939837)
			(xy 187.287709 -420.953943) (xy 187.232272 -420.960043) (xy 187.176538 -420.958006) (xy 187.121695 -420.947876)
			(xy 187.068911 -420.929869) (xy 187.019311 -420.904368) (xy 186.973953 -420.871917) (xy 186.933804 -420.833208)
			(xy 186.899718 -420.789065) (xy 186.872422 -420.74043) (xy 186.852499 -420.688339) (xy 186.840373 -420.633902)
			(xy 186.836302 -420.57828) (xy 184.979113 -420.57828) (xy 184.972731 -420.600014) (xy 184.950089 -420.649591)
			(xy 184.920623 -420.695441) (xy 184.884932 -420.736632) (xy 184.843741 -420.772323) (xy 184.797891 -420.801789)
			(xy 184.748314 -420.824431) (xy 184.696019 -420.839786) (xy 184.642071 -420.847542) (xy 184.587569 -420.847542)
			(xy 184.533621 -420.839786) (xy 184.481326 -420.824431) (xy 184.431749 -420.801789) (xy 184.385899 -420.772323)
			(xy 184.344708 -420.736632) (xy 184.309017 -420.695441) (xy 184.279551 -420.649591) (xy 184.256909 -420.600014)
			(xy 184.241554 -420.547719) (xy 184.233798 -420.493771) (xy 184.233312 -420.46652) (xy 184.233834 -420.438511)
			(xy 184.242028 -420.383096) (xy 184.258242 -420.329476) (xy 184.282128 -420.278806) (xy 184.313172 -420.232177)
			(xy 184.350704 -420.190592) (xy 184.371996 -420.172388) (xy 184.383235 -420.162337) (xy 184.399876 -420.137216)
			(xy 184.408475 -420.108336) (xy 184.408287 -420.078204) (xy 184.399329 -420.049434) (xy 184.382378 -420.024522)
			(xy 184.37098 -420.014654) (xy 184.349122 -419.996443) (xy 184.31052 -419.954653) (xy 184.278555 -419.907591)
			(xy 184.253939 -419.856302) (xy 184.237217 -419.801924) (xy 184.22876 -419.745665) (xy 184.228232 -419.71722)
			(xy 175.417335 -419.71722) (xy 175.411391 -419.75761) (xy 175.395323 -419.811017) (xy 175.371651 -419.861514)
			(xy 175.340878 -419.908027) (xy 175.303661 -419.949564) (xy 175.260793 -419.985239) (xy 175.213187 -420.014293)
			(xy 175.161858 -420.036105) (xy 175.107901 -420.050211) (xy 175.052464 -420.056311) (xy 174.99673 -420.054274)
			(xy 174.941887 -420.044144) (xy 174.889103 -420.026137) (xy 174.839503 -420.000636) (xy 174.794145 -419.968185)
			(xy 174.753996 -419.929476) (xy 174.71991 -419.885333) (xy 174.692614 -419.836698) (xy 174.672691 -419.784607)
			(xy 174.660565 -419.73017) (xy 174.656494 -419.674548) (xy 125.543564 -419.674548) (xy 126.426976 -420.55796)
			(xy 183.166002 -420.55796) (xy 183.170073 -420.502338) (xy 183.182199 -420.447901) (xy 183.202122 -420.39581)
			(xy 183.229418 -420.347175) (xy 183.263504 -420.303032) (xy 183.303653 -420.264323) (xy 183.349011 -420.231872)
			(xy 183.398611 -420.206371) (xy 183.451395 -420.188364) (xy 183.506238 -420.178234) (xy 183.561972 -420.176197)
			(xy 183.617409 -420.182297) (xy 183.671366 -420.196403) (xy 183.722695 -420.218215) (xy 183.770301 -420.247269)
			(xy 183.813169 -420.282944) (xy 183.850386 -420.324481) (xy 183.881159 -420.370994) (xy 183.904831 -420.421491)
			(xy 183.920899 -420.474898) (xy 183.929019 -420.530074) (xy 183.929528 -420.55796) (xy 183.929019 -420.585846)
			(xy 183.920899 -420.641022) (xy 183.904831 -420.694429) (xy 183.881159 -420.744926) (xy 183.850386 -420.791439)
			(xy 183.813169 -420.832976) (xy 183.770301 -420.868651) (xy 183.722695 -420.897705) (xy 183.671366 -420.919517)
			(xy 183.617409 -420.933623) (xy 183.561972 -420.939723) (xy 183.506238 -420.937686) (xy 183.451395 -420.927556)
			(xy 183.398611 -420.909549) (xy 183.349011 -420.884048) (xy 183.303653 -420.851597) (xy 183.263504 -420.812888)
			(xy 183.229418 -420.768745) (xy 183.202122 -420.72011) (xy 183.182199 -420.668019) (xy 183.170073 -420.613582)
			(xy 183.166002 -420.55796) (xy 126.426976 -420.55796) (xy 126.931674 -421.062658) (xy 161.81832 -421.062658)
			(xy 162.003121 -421.247459) (xy 162.871004 -421.247459) (xy 162.87876 -421.193498) (xy 162.894118 -421.14119)
			(xy 162.916763 -421.0916) (xy 162.946236 -421.045738) (xy 162.981936 -421.004537) (xy 163.023136 -420.968837)
			(xy 163.068998 -420.939364) (xy 163.118588 -420.916718) (xy 163.170896 -420.901361) (xy 163.224857 -420.893604)
			(xy 163.279373 -420.893606) (xy 163.333334 -420.901367) (xy 163.385641 -420.916729) (xy 163.435229 -420.939379)
			(xy 163.481088 -420.968856) (xy 163.522286 -421.004559) (xy 163.557982 -421.045763) (xy 163.587452 -421.091627)
			(xy 163.610093 -421.141219) (xy 163.625446 -421.193528) (xy 163.633198 -421.24749) (xy 163.633315 -421.254428)
			(xy 164.267132 -421.254428) (xy 164.271203 -421.198806) (xy 164.283329 -421.144369) (xy 164.303252 -421.092278)
			(xy 164.330548 -421.043643) (xy 164.364634 -420.9995) (xy 164.404783 -420.960791) (xy 164.450141 -420.92834)
			(xy 164.499741 -420.902839) (xy 164.552525 -420.884832) (xy 164.607368 -420.874702) (xy 164.663102 -420.872665)
			(xy 164.718539 -420.878765) (xy 164.772496 -420.892871) (xy 164.823825 -420.914683) (xy 164.871431 -420.943737)
			(xy 164.914299 -420.979412) (xy 164.951516 -421.020949) (xy 164.960962 -421.035226) (xy 166.426132 -421.035226)
			(xy 166.430203 -420.979604) (xy 166.442329 -420.925167) (xy 166.462252 -420.873076) (xy 166.489548 -420.824441)
			(xy 166.523634 -420.780298) (xy 166.563783 -420.741589) (xy 166.609141 -420.709138) (xy 166.658741 -420.683637)
			(xy 166.711525 -420.66563) (xy 166.766368 -420.6555) (xy 166.822102 -420.653463) (xy 166.877539 -420.659563)
			(xy 166.931496 -420.673669) (xy 166.982825 -420.695481) (xy 167.030431 -420.724535) (xy 167.073299 -420.76021)
			(xy 167.110516 -420.801747) (xy 167.141289 -420.84826) (xy 167.164961 -420.898757) (xy 167.181029 -420.952164)
			(xy 167.184319 -420.97452) (xy 171.486574 -420.97452) (xy 171.490645 -420.918898) (xy 171.502771 -420.864461)
			(xy 171.522694 -420.81237) (xy 171.54999 -420.763735) (xy 171.584076 -420.719592) (xy 171.624225 -420.680883)
			(xy 171.669583 -420.648432) (xy 171.719183 -420.622931) (xy 171.771967 -420.604924) (xy 171.82681 -420.594794)
			(xy 171.882544 -420.592757) (xy 171.937981 -420.598857) (xy 171.991938 -420.612963) (xy 172.043267 -420.634775)
			(xy 172.090873 -420.663829) (xy 172.133741 -420.699504) (xy 172.170958 -420.741041) (xy 172.201731 -420.787554)
			(xy 172.225403 -420.838051) (xy 172.241471 -420.891458) (xy 172.249591 -420.946634) (xy 172.2501 -420.97452)
			(xy 172.249591 -421.002406) (xy 172.241471 -421.057582) (xy 172.225403 -421.110989) (xy 172.201731 -421.161486)
			(xy 172.170958 -421.207999) (xy 172.133741 -421.249536) (xy 172.090873 -421.285211) (xy 172.043267 -421.314265)
			(xy 171.991938 -421.336077) (xy 171.937981 -421.350183) (xy 171.931029 -421.350948) (xy 176.807112 -421.350948)
			(xy 176.811183 -421.295326) (xy 176.823309 -421.240889) (xy 176.843232 -421.188798) (xy 176.870528 -421.140163)
			(xy 176.904614 -421.09602) (xy 176.944763 -421.057311) (xy 176.990121 -421.02486) (xy 177.039721 -420.999359)
			(xy 177.092505 -420.981352) (xy 177.147348 -420.971222) (xy 177.203082 -420.969185) (xy 177.258519 -420.975285)
			(xy 177.312476 -420.989391) (xy 177.363805 -421.011203) (xy 177.411411 -421.040257) (xy 177.454279 -421.075932)
			(xy 177.491496 -421.117469) (xy 177.49506 -421.122856) (xy 178.543964 -421.122856) (xy 178.548035 -421.067234)
			(xy 178.560161 -421.012797) (xy 178.580084 -420.960706) (xy 178.60738 -420.912071) (xy 178.641466 -420.867928)
			(xy 178.681615 -420.829219) (xy 178.726973 -420.796768) (xy 178.776573 -420.771267) (xy 178.829357 -420.75326)
			(xy 178.8842 -420.74313) (xy 178.939934 -420.741093) (xy 178.995371 -420.747193) (xy 179.049328 -420.761299)
			(xy 179.100657 -420.783111) (xy 179.148263 -420.812165) (xy 179.191131 -420.84784) (xy 179.228348 -420.889377)
			(xy 179.259121 -420.93589) (xy 179.282793 -420.986387) (xy 179.298861 -421.039794) (xy 179.306981 -421.09497)
			(xy 179.30749 -421.122856) (xy 179.306981 -421.150742) (xy 179.298861 -421.205918) (xy 179.284037 -421.25519)
			(xy 179.876194 -421.25519) (xy 179.880265 -421.199568) (xy 179.892391 -421.145131) (xy 179.912314 -421.09304)
			(xy 179.93961 -421.044405) (xy 179.973696 -421.000262) (xy 180.013845 -420.961553) (xy 180.059203 -420.929102)
			(xy 180.108803 -420.903601) (xy 180.161587 -420.885594) (xy 180.21643 -420.875464) (xy 180.272164 -420.873427)
			(xy 180.327601 -420.879527) (xy 180.381558 -420.893633) (xy 180.432887 -420.915445) (xy 180.480493 -420.944499)
			(xy 180.523361 -420.980174) (xy 180.560578 -421.021711) (xy 180.591351 -421.068224) (xy 180.615023 -421.118721)
			(xy 180.631091 -421.172128) (xy 180.639211 -421.227304) (xy 180.63972 -421.25519) (xy 180.639211 -421.283076)
			(xy 180.631091 -421.338252) (xy 180.615023 -421.391659) (xy 180.591351 -421.442156) (xy 180.560578 -421.488669)
			(xy 180.523361 -421.530206) (xy 180.480493 -421.565881) (xy 180.432887 -421.594935) (xy 180.381558 -421.616747)
			(xy 180.327601 -421.630853) (xy 180.272164 -421.636953) (xy 180.21643 -421.634916) (xy 180.161587 -421.624786)
			(xy 180.108803 -421.606779) (xy 180.059203 -421.581278) (xy 180.013845 -421.548827) (xy 179.973696 -421.510118)
			(xy 179.93961 -421.465975) (xy 179.912314 -421.41734) (xy 179.892391 -421.365249) (xy 179.880265 -421.310812)
			(xy 179.876194 -421.25519) (xy 179.284037 -421.25519) (xy 179.282793 -421.259325) (xy 179.259121 -421.309822)
			(xy 179.228348 -421.356335) (xy 179.191131 -421.397872) (xy 179.148263 -421.433547) (xy 179.100657 -421.462601)
			(xy 179.049328 -421.484413) (xy 178.995371 -421.498519) (xy 178.939934 -421.504619) (xy 178.8842 -421.502582)
			(xy 178.829357 -421.492452) (xy 178.776573 -421.474445) (xy 178.726973 -421.448944) (xy 178.681615 -421.416493)
			(xy 178.641466 -421.377784) (xy 178.60738 -421.333641) (xy 178.580084 -421.285006) (xy 178.560161 -421.232915)
			(xy 178.548035 -421.178478) (xy 178.543964 -421.122856) (xy 177.49506 -421.122856) (xy 177.522269 -421.163982)
			(xy 177.545941 -421.214479) (xy 177.562009 -421.267886) (xy 177.570129 -421.323062) (xy 177.570638 -421.350948)
			(xy 177.570129 -421.378834) (xy 177.562009 -421.43401) (xy 177.545941 -421.487417) (xy 177.522269 -421.537914)
			(xy 177.491496 -421.584427) (xy 177.454279 -421.625964) (xy 177.411411 -421.661639) (xy 177.363805 -421.690693)
			(xy 177.312476 -421.712505) (xy 177.258519 -421.726611) (xy 177.203082 -421.732711) (xy 177.147348 -421.730674)
			(xy 177.092505 -421.720544) (xy 177.039721 -421.702537) (xy 176.990121 -421.677036) (xy 176.944763 -421.644585)
			(xy 176.904614 -421.605876) (xy 176.870528 -421.561733) (xy 176.843232 -421.513098) (xy 176.823309 -421.461007)
			(xy 176.811183 -421.40657) (xy 176.807112 -421.350948) (xy 171.931029 -421.350948) (xy 171.882544 -421.356283)
			(xy 171.82681 -421.354246) (xy 171.771967 -421.344116) (xy 171.719183 -421.326109) (xy 171.669583 -421.300608)
			(xy 171.624225 -421.268157) (xy 171.584076 -421.229448) (xy 171.54999 -421.185305) (xy 171.522694 -421.13667)
			(xy 171.502771 -421.084579) (xy 171.490645 -421.030142) (xy 171.486574 -420.97452) (xy 167.184319 -420.97452)
			(xy 167.189149 -421.00734) (xy 167.189658 -421.035226) (xy 167.189149 -421.063112) (xy 167.181029 -421.118288)
			(xy 167.164961 -421.171695) (xy 167.141289 -421.222192) (xy 167.110516 -421.268705) (xy 167.073299 -421.310242)
			(xy 167.030431 -421.345917) (xy 166.982825 -421.374971) (xy 166.931496 -421.396783) (xy 166.877539 -421.410889)
			(xy 166.822102 -421.416989) (xy 166.766368 -421.414952) (xy 166.711525 -421.404822) (xy 166.658741 -421.386815)
			(xy 166.609141 -421.361314) (xy 166.563783 -421.328863) (xy 166.523634 -421.290154) (xy 166.489548 -421.246011)
			(xy 166.462252 -421.197376) (xy 166.442329 -421.145285) (xy 166.430203 -421.090848) (xy 166.426132 -421.035226)
			(xy 164.960962 -421.035226) (xy 164.982289 -421.067462) (xy 165.005961 -421.117959) (xy 165.022029 -421.171366)
			(xy 165.030149 -421.226542) (xy 165.030658 -421.254428) (xy 165.030149 -421.282314) (xy 165.022029 -421.33749)
			(xy 165.005961 -421.390897) (xy 164.982289 -421.441394) (xy 164.951516 -421.487907) (xy 164.916061 -421.527478)
			(xy 168.049954 -421.527478) (xy 168.054025 -421.471856) (xy 168.066151 -421.417419) (xy 168.086074 -421.365328)
			(xy 168.11337 -421.316693) (xy 168.147456 -421.27255) (xy 168.187605 -421.233841) (xy 168.232963 -421.20139)
			(xy 168.282563 -421.175889) (xy 168.335347 -421.157882) (xy 168.39019 -421.147752) (xy 168.445924 -421.145715)
			(xy 168.501361 -421.151815) (xy 168.555318 -421.165921) (xy 168.606647 -421.187733) (xy 168.654253 -421.216787)
			(xy 168.697121 -421.252462) (xy 168.734338 -421.293999) (xy 168.765111 -421.340512) (xy 168.788783 -421.391009)
			(xy 168.804851 -421.444416) (xy 168.812971 -421.499592) (xy 168.81348 -421.527478) (xy 168.812971 -421.555364)
			(xy 168.804851 -421.61054) (xy 168.788783 -421.663947) (xy 168.765111 -421.714444) (xy 168.734338 -421.760957)
			(xy 168.697121 -421.802494) (xy 168.654253 -421.838169) (xy 168.606647 -421.867223) (xy 168.555318 -421.889035)
			(xy 168.501361 -421.903141) (xy 168.445924 -421.909241) (xy 168.39019 -421.907204) (xy 168.335347 -421.897074)
			(xy 168.282563 -421.879067) (xy 168.232963 -421.853566) (xy 168.187605 -421.821115) (xy 168.147456 -421.782406)
			(xy 168.11337 -421.738263) (xy 168.086074 -421.689628) (xy 168.066151 -421.637537) (xy 168.054025 -421.5831)
			(xy 168.049954 -421.527478) (xy 164.916061 -421.527478) (xy 164.914299 -421.529444) (xy 164.871431 -421.565119)
			(xy 164.823825 -421.594173) (xy 164.772496 -421.615985) (xy 164.718539 -421.630091) (xy 164.663102 -421.636191)
			(xy 164.607368 -421.634154) (xy 164.552525 -421.624024) (xy 164.499741 -421.606017) (xy 164.450141 -421.580516)
			(xy 164.404783 -421.548065) (xy 164.364634 -421.509356) (xy 164.330548 -421.465213) (xy 164.303252 -421.416578)
			(xy 164.283329 -421.364487) (xy 164.271203 -421.31005) (xy 164.267132 -421.254428) (xy 163.633315 -421.254428)
			(xy 163.633658 -421.274748) (xy 163.632642 -421.30091) (xy 163.632208 -421.315929) (xy 163.638916 -421.345195)
			(xy 163.653847 -421.371245) (xy 163.67571 -421.391825) (xy 163.702613 -421.405156) (xy 163.732231 -421.410085)
			(xy 163.762002 -421.406185) (xy 163.775898 -421.400478) (xy 163.800746 -421.389731) (xy 163.852717 -421.374574)
			(xy 163.90631 -421.366917) (xy 163.933378 -421.366442) (xy 163.960634 -421.366931) (xy 164.01459 -421.374686)
			(xy 164.066894 -421.390041) (xy 164.11648 -421.412684) (xy 164.162339 -421.442154) (xy 164.203536 -421.477849)
			(xy 164.239234 -421.519045) (xy 164.268706 -421.564903) (xy 164.291352 -421.614487) (xy 164.306709 -421.66679)
			(xy 164.314467 -421.720746) (xy 164.314467 -421.775258) (xy 164.306709 -421.829214) (xy 164.29135 -421.881516)
			(xy 164.268704 -421.931101) (xy 164.239232 -421.976958) (xy 164.203534 -422.018153) (xy 164.162335 -422.053849)
			(xy 164.116476 -422.083318) (xy 164.06689 -422.10596) (xy 164.014586 -422.121315) (xy 163.96063 -422.129069)
			(xy 163.906118 -422.129065) (xy 163.852163 -422.121303) (xy 163.799861 -422.105942) (xy 163.750278 -422.083293)
			(xy 163.704423 -422.053818) (xy 163.66323 -422.018117) (xy 163.627537 -421.976916) (xy 163.598071 -421.931055)
			(xy 163.575432 -421.881468) (xy 163.56008 -421.829163) (xy 163.552329 -421.775206) (xy 163.55187 -421.74795)
			(xy 163.552886 -421.721788) (xy 163.553423 -421.706767) (xy 163.546709 -421.677482) (xy 163.531764 -421.651419)
			(xy 163.509883 -421.630831) (xy 163.482958 -421.617502) (xy 163.453319 -421.612583) (xy 163.423531 -421.616501)
			(xy 163.40963 -421.62222) (xy 163.384778 -421.632958) (xy 163.332809 -421.648118) (xy 163.279218 -421.655779)
			(xy 163.25215 -421.656256) (xy 163.224892 -421.655798) (xy 163.17093 -421.648047) (xy 163.118621 -421.632694)
			(xy 163.069029 -421.610053) (xy 163.023164 -421.580584) (xy 162.981961 -421.544887) (xy 162.946257 -421.50369)
			(xy 162.91678 -421.45783) (xy 162.89413 -421.408242) (xy 162.878768 -421.355936) (xy 162.871006 -421.301975)
			(xy 162.871004 -421.247459) (xy 162.003121 -421.247459) (xy 162.6616 -421.905938) (xy 162.6616 -422.20769)
			(xy 169.466512 -422.20769) (xy 169.470583 -422.152068) (xy 169.482709 -422.097631) (xy 169.502632 -422.04554)
			(xy 169.529928 -421.996905) (xy 169.564014 -421.952762) (xy 169.604163 -421.914053) (xy 169.649521 -421.881602)
			(xy 169.699121 -421.856101) (xy 169.751905 -421.838094) (xy 169.806748 -421.827964) (xy 169.862482 -421.825927)
			(xy 169.917919 -421.832027) (xy 169.971876 -421.846133) (xy 170.023205 -421.867945) (xy 170.03177 -421.873172)
			(xy 177.534822 -421.873172) (xy 177.538893 -421.81755) (xy 177.551019 -421.763113) (xy 177.570942 -421.711022)
			(xy 177.598238 -421.662387) (xy 177.632324 -421.618244) (xy 177.672473 -421.579535) (xy 177.717831 -421.547084)
			(xy 177.767431 -421.521583) (xy 177.820215 -421.503576) (xy 177.875058 -421.493446) (xy 177.930792 -421.491409)
			(xy 177.986229 -421.497509) (xy 178.040186 -421.511615) (xy 178.091515 -421.533427) (xy 178.139121 -421.562481)
			(xy 178.181989 -421.598156) (xy 178.219206 -421.639693) (xy 178.249979 -421.686206) (xy 178.273651 -421.736703)
			(xy 178.289719 -421.79011) (xy 178.297839 -421.845286) (xy 178.298348 -421.873172) (xy 178.297839 -421.901058)
			(xy 178.289719 -421.956234) (xy 178.273651 -422.009641) (xy 178.249979 -422.060138) (xy 178.219206 -422.106651)
			(xy 178.181989 -422.148188) (xy 178.139121 -422.183863) (xy 178.091515 -422.212917) (xy 178.040186 -422.234729)
			(xy 177.986229 -422.248835) (xy 177.930792 -422.254935) (xy 177.875058 -422.252898) (xy 177.820215 -422.242768)
			(xy 177.767431 -422.224761) (xy 177.717831 -422.19926) (xy 177.672473 -422.166809) (xy 177.632324 -422.1281)
			(xy 177.598238 -422.083957) (xy 177.570942 -422.035322) (xy 177.551019 -421.983231) (xy 177.538893 -421.928794)
			(xy 177.534822 -421.873172) (xy 170.03177 -421.873172) (xy 170.070811 -421.896999) (xy 170.113679 -421.932674)
			(xy 170.150896 -421.974211) (xy 170.181669 -422.020724) (xy 170.205341 -422.071221) (xy 170.221409 -422.124628)
			(xy 170.229529 -422.179804) (xy 170.230038 -422.20769) (xy 170.229529 -422.235576) (xy 170.221409 -422.290752)
			(xy 170.205341 -422.344159) (xy 170.181669 -422.394656) (xy 170.180171 -422.39692) (xy 186.328302 -422.39692)
			(xy 186.332373 -422.341298) (xy 186.344499 -422.286861) (xy 186.364422 -422.23477) (xy 186.391718 -422.186135)
			(xy 186.425804 -422.141992) (xy 186.465953 -422.103283) (xy 186.511311 -422.070832) (xy 186.560911 -422.045331)
			(xy 186.613695 -422.027324) (xy 186.668538 -422.017194) (xy 186.724272 -422.015157) (xy 186.779709 -422.021257)
			(xy 186.833666 -422.035363) (xy 186.884995 -422.057175) (xy 186.932601 -422.086229) (xy 186.975469 -422.121904)
			(xy 187.012686 -422.163441) (xy 187.043459 -422.209954) (xy 187.067131 -422.260451) (xy 187.083199 -422.313858)
			(xy 187.091319 -422.369034) (xy 187.091828 -422.39692) (xy 187.091319 -422.424806) (xy 187.083199 -422.479982)
			(xy 187.067131 -422.533389) (xy 187.043459 -422.583886) (xy 187.012686 -422.630399) (xy 186.975469 -422.671936)
			(xy 186.932601 -422.707611) (xy 186.884995 -422.736665) (xy 186.833666 -422.758477) (xy 186.779709 -422.772583)
			(xy 186.724272 -422.778683) (xy 186.668538 -422.776646) (xy 186.613695 -422.766516) (xy 186.560911 -422.748509)
			(xy 186.511311 -422.723008) (xy 186.465953 -422.690557) (xy 186.425804 -422.651848) (xy 186.391718 -422.607705)
			(xy 186.364422 -422.55907) (xy 186.344499 -422.506979) (xy 186.332373 -422.452542) (xy 186.328302 -422.39692)
			(xy 170.180171 -422.39692) (xy 170.150896 -422.441169) (xy 170.113679 -422.482706) (xy 170.070811 -422.518381)
			(xy 170.023205 -422.547435) (xy 169.971876 -422.569247) (xy 169.917919 -422.583353) (xy 169.862482 -422.589453)
			(xy 169.806748 -422.587416) (xy 169.751905 -422.577286) (xy 169.699121 -422.559279) (xy 169.649521 -422.533778)
			(xy 169.604163 -422.501327) (xy 169.564014 -422.462618) (xy 169.529928 -422.418475) (xy 169.502632 -422.36984)
			(xy 169.482709 -422.317749) (xy 169.470583 -422.263312) (xy 169.466512 -422.20769) (xy 162.6616 -422.20769)
			(xy 162.6616 -422.874948) (xy 168.056812 -422.874948) (xy 168.060883 -422.819326) (xy 168.073009 -422.764889)
			(xy 168.092932 -422.712798) (xy 168.120228 -422.664163) (xy 168.154314 -422.62002) (xy 168.194463 -422.581311)
			(xy 168.239821 -422.54886) (xy 168.289421 -422.523359) (xy 168.342205 -422.505352) (xy 168.397048 -422.495222)
			(xy 168.452782 -422.493185) (xy 168.508219 -422.499285) (xy 168.562176 -422.513391) (xy 168.613505 -422.535203)
			(xy 168.661111 -422.564257) (xy 168.703979 -422.599932) (xy 168.741196 -422.641469) (xy 168.771969 -422.687982)
			(xy 168.795641 -422.738479) (xy 168.811709 -422.791886) (xy 168.819829 -422.847062) (xy 168.820236 -422.86936)
			(xy 188.797182 -422.86936) (xy 188.801253 -422.813738) (xy 188.813379 -422.759301) (xy 188.833302 -422.70721)
			(xy 188.860598 -422.658575) (xy 188.894684 -422.614432) (xy 188.934833 -422.575723) (xy 188.980191 -422.543272)
			(xy 189.029791 -422.517771) (xy 189.082575 -422.499764) (xy 189.137418 -422.489634) (xy 189.193152 -422.487597)
			(xy 189.248589 -422.493697) (xy 189.302546 -422.507803) (xy 189.353875 -422.529615) (xy 189.401481 -422.558669)
			(xy 189.444349 -422.594344) (xy 189.481566 -422.635881) (xy 189.512339 -422.682394) (xy 189.536011 -422.732891)
			(xy 189.552079 -422.786298) (xy 189.560199 -422.841474) (xy 189.560708 -422.86936) (xy 189.560199 -422.897246)
			(xy 189.552079 -422.952422) (xy 189.536011 -423.005829) (xy 189.512339 -423.056326) (xy 189.481566 -423.102839)
			(xy 189.444349 -423.144376) (xy 189.401481 -423.180051) (xy 189.353875 -423.209105) (xy 189.302546 -423.230917)
			(xy 189.248589 -423.245023) (xy 189.193152 -423.251123) (xy 189.137418 -423.249086) (xy 189.082575 -423.238956)
			(xy 189.029791 -423.220949) (xy 188.980191 -423.195448) (xy 188.934833 -423.162997) (xy 188.894684 -423.124288)
			(xy 188.860598 -423.080145) (xy 188.833302 -423.03151) (xy 188.813379 -422.979419) (xy 188.801253 -422.924982)
			(xy 188.797182 -422.86936) (xy 168.820236 -422.86936) (xy 168.820338 -422.874948) (xy 168.819829 -422.902834)
			(xy 168.811709 -422.95801) (xy 168.795641 -423.011417) (xy 168.771969 -423.061914) (xy 168.741196 -423.108427)
			(xy 168.703979 -423.149964) (xy 168.661111 -423.185639) (xy 168.613505 -423.214693) (xy 168.562176 -423.236505)
			(xy 168.508219 -423.250611) (xy 168.452782 -423.256711) (xy 168.397048 -423.254674) (xy 168.342205 -423.244544)
			(xy 168.289421 -423.226537) (xy 168.239821 -423.201036) (xy 168.194463 -423.168585) (xy 168.154314 -423.129876)
			(xy 168.120228 -423.085733) (xy 168.092932 -423.037098) (xy 168.073009 -422.985007) (xy 168.060883 -422.93057)
			(xy 168.056812 -422.874948) (xy 162.6616 -422.874948) (xy 162.6616 -425.143168) (xy 170.207432 -425.143168)
			(xy 170.207953 -425.115098) (xy 170.216184 -425.059565) (xy 170.232464 -425.005837) (xy 170.256441 -424.955075)
			(xy 170.287598 -424.908375) (xy 170.325261 -424.866744) (xy 170.346624 -424.848528) (xy 170.357817 -424.838661)
			(xy 170.37438 -424.813859) (xy 170.383078 -424.785331) (xy 170.383172 -424.755507) (xy 170.374654 -424.726925)
			(xy 170.358248 -424.702018) (xy 170.347132 -424.692064) (xy 170.326079 -424.673809) (xy 170.288943 -424.632267)
			(xy 170.258239 -424.585769) (xy 170.23462 -424.535301) (xy 170.218587 -424.481937) (xy 170.210481 -424.426808)
			(xy 170.209972 -424.398948) (xy 170.210447 -424.370789) (xy 170.218754 -424.315086) (xy 170.235165 -424.261211)
			(xy 170.259323 -424.210337) (xy 170.290701 -424.16357) (xy 170.309286 -424.142408) (xy 170.319087 -424.130962)
			(xy 170.332026 -424.10376) (xy 170.336461 -424.073967) (xy 170.332007 -424.044176) (xy 170.31905 -424.016983)
			(xy 170.309286 -424.005502) (xy 170.290688 -423.984356) (xy 170.259341 -423.937572) (xy 170.235205 -423.886691)
			(xy 170.218804 -423.832818) (xy 170.210494 -423.777119) (xy 170.209972 -423.748962) (xy 170.210458 -423.721711)
			(xy 170.218214 -423.667763) (xy 170.233569 -423.615468) (xy 170.256211 -423.565891) (xy 170.285677 -423.520041)
			(xy 170.321368 -423.47885) (xy 170.362559 -423.443159) (xy 170.408409 -423.413693) (xy 170.457986 -423.391051)
			(xy 170.510281 -423.375696) (xy 170.564229 -423.36794) (xy 170.618731 -423.36794) (xy 170.672679 -423.375696)
			(xy 170.697377 -423.382948) (xy 176.807112 -423.382948) (xy 176.811183 -423.327326) (xy 176.823309 -423.272889)
			(xy 176.843232 -423.220798) (xy 176.870528 -423.172163) (xy 176.904614 -423.12802) (xy 176.944763 -423.089311)
			(xy 176.990121 -423.05686) (xy 177.039721 -423.031359) (xy 177.092505 -423.013352) (xy 177.147348 -423.003222)
			(xy 177.203082 -423.001185) (xy 177.258519 -423.007285) (xy 177.312476 -423.021391) (xy 177.363805 -423.043203)
			(xy 177.411411 -423.072257) (xy 177.454279 -423.107932) (xy 177.491496 -423.149469) (xy 177.522269 -423.195982)
			(xy 177.545941 -423.246479) (xy 177.562009 -423.299886) (xy 177.570129 -423.355062) (xy 177.570638 -423.382948)
			(xy 177.570129 -423.410834) (xy 177.562009 -423.46601) (xy 177.545941 -423.519417) (xy 177.522269 -423.569914)
			(xy 177.491496 -423.616427) (xy 177.454279 -423.657964) (xy 177.411411 -423.693639) (xy 177.363805 -423.722693)
			(xy 177.312476 -423.744505) (xy 177.258519 -423.758611) (xy 177.203082 -423.764711) (xy 177.147348 -423.762674)
			(xy 177.092505 -423.752544) (xy 177.039721 -423.734537) (xy 176.990121 -423.709036) (xy 176.944763 -423.676585)
			(xy 176.904614 -423.637876) (xy 176.870528 -423.593733) (xy 176.843232 -423.545098) (xy 176.823309 -423.493007)
			(xy 176.811183 -423.43857) (xy 176.807112 -423.382948) (xy 170.697377 -423.382948) (xy 170.724974 -423.391051)
			(xy 170.774551 -423.413693) (xy 170.820401 -423.443159) (xy 170.861592 -423.47885) (xy 170.897283 -423.520041)
			(xy 170.926749 -423.565891) (xy 170.949391 -423.615468) (xy 170.964746 -423.667763) (xy 170.972502 -423.721711)
			(xy 170.972988 -423.748962) (xy 170.972443 -423.777118) (xy 170.964151 -423.832817) (xy 170.947755 -423.886691)
			(xy 170.923614 -423.937566) (xy 170.892251 -423.984338) (xy 170.873674 -424.005502) (xy 170.864013 -424.017039)
			(xy 170.851146 -424.04422) (xy 170.846723 -424.073966) (xy 170.851126 -424.103715) (xy 170.863975 -424.130905)
			(xy 170.873674 -424.142408) (xy 170.892223 -424.163596) (xy 170.921952 -424.20794) (xy 171.814742 -424.20794)
			(xy 171.818813 -424.152318) (xy 171.830939 -424.097881) (xy 171.850862 -424.04579) (xy 171.878158 -423.997155)
			(xy 171.912244 -423.953012) (xy 171.952393 -423.914303) (xy 171.997751 -423.881852) (xy 172.047351 -423.856351)
			(xy 172.100135 -423.838344) (xy 172.154978 -423.828214) (xy 172.210712 -423.826177) (xy 172.266149 -423.832277)
			(xy 172.320106 -423.846383) (xy 172.371435 -423.868195) (xy 172.419041 -423.897249) (xy 172.461909 -423.932924)
			(xy 172.499126 -423.974461) (xy 172.529899 -424.020974) (xy 172.553571 -424.071471) (xy 172.569639 -424.124878)
			(xy 172.577759 -424.180054) (xy 172.578268 -424.20794) (xy 172.577759 -424.235826) (xy 172.569639 -424.291002)
			(xy 172.553571 -424.344409) (xy 172.529899 -424.394906) (xy 172.527225 -424.398948) (xy 175.537112 -424.398948)
			(xy 175.541183 -424.343326) (xy 175.553309 -424.288889) (xy 175.573232 -424.236798) (xy 175.600528 -424.188163)
			(xy 175.634614 -424.14402) (xy 175.674763 -424.105311) (xy 175.720121 -424.07286) (xy 175.769721 -424.047359)
			(xy 175.822505 -424.029352) (xy 175.877348 -424.019222) (xy 175.933082 -424.017185) (xy 175.988519 -424.023285)
			(xy 176.042476 -424.037391) (xy 176.049322 -424.0403) (xy 185.725052 -424.0403) (xy 185.729123 -423.984678)
			(xy 185.741249 -423.930241) (xy 185.761172 -423.87815) (xy 185.788468 -423.829515) (xy 185.822554 -423.785372)
			(xy 185.862703 -423.746663) (xy 185.908061 -423.714212) (xy 185.957661 -423.688711) (xy 186.010445 -423.670704)
			(xy 186.065288 -423.660574) (xy 186.121022 -423.658537) (xy 186.176459 -423.664637) (xy 186.230416 -423.678743)
			(xy 186.281745 -423.700555) (xy 186.329351 -423.729609) (xy 186.372219 -423.765284) (xy 186.409436 -423.806821)
			(xy 186.440209 -423.853334) (xy 186.463881 -423.903831) (xy 186.479949 -423.957238) (xy 186.488069 -424.012414)
			(xy 186.488578 -424.0403) (xy 186.488069 -424.068186) (xy 186.479949 -424.123362) (xy 186.463881 -424.176769)
			(xy 186.440209 -424.227266) (xy 186.409436 -424.273779) (xy 186.372219 -424.315316) (xy 186.329351 -424.350991)
			(xy 186.281745 -424.380045) (xy 186.230416 -424.401857) (xy 186.176459 -424.415963) (xy 186.121022 -424.422063)
			(xy 186.065288 -424.420026) (xy 186.010445 -424.409896) (xy 185.957661 -424.391889) (xy 185.908061 -424.366388)
			(xy 185.862703 -424.333937) (xy 185.822554 -424.295228) (xy 185.788468 -424.251085) (xy 185.761172 -424.20245)
			(xy 185.741249 -424.150359) (xy 185.729123 -424.095922) (xy 185.725052 -424.0403) (xy 176.049322 -424.0403)
			(xy 176.093805 -424.059203) (xy 176.141411 -424.088257) (xy 176.184279 -424.123932) (xy 176.221496 -424.165469)
			(xy 176.252269 -424.211982) (xy 176.275941 -424.262479) (xy 176.292009 -424.315886) (xy 176.300129 -424.371062)
			(xy 176.300638 -424.398948) (xy 176.300129 -424.426834) (xy 176.292009 -424.48201) (xy 176.275941 -424.535417)
			(xy 176.252269 -424.585914) (xy 176.221496 -424.632427) (xy 176.184279 -424.673964) (xy 176.141411 -424.709639)
			(xy 176.093805 -424.738693) (xy 176.042476 -424.760505) (xy 175.988519 -424.774611) (xy 175.933082 -424.780711)
			(xy 175.877348 -424.778674) (xy 175.822505 -424.768544) (xy 175.769721 -424.750537) (xy 175.720121 -424.725036)
			(xy 175.674763 -424.692585) (xy 175.634614 -424.653876) (xy 175.600528 -424.609733) (xy 175.573232 -424.561098)
			(xy 175.553309 -424.509007) (xy 175.541183 -424.45457) (xy 175.537112 -424.398948) (xy 172.527225 -424.398948)
			(xy 172.499126 -424.441419) (xy 172.461909 -424.482956) (xy 172.419041 -424.518631) (xy 172.371435 -424.547685)
			(xy 172.320106 -424.569497) (xy 172.266149 -424.583603) (xy 172.210712 -424.589703) (xy 172.154978 -424.587666)
			(xy 172.100135 -424.577536) (xy 172.047351 -424.559529) (xy 171.997751 -424.534028) (xy 171.952393 -424.501577)
			(xy 171.912244 -424.462868) (xy 171.878158 -424.418725) (xy 171.850862 -424.37009) (xy 171.830939 -424.317999)
			(xy 171.818813 -424.263562) (xy 171.814742 -424.20794) (xy 170.921952 -424.20794) (xy 170.923579 -424.210367)
			(xy 170.947725 -424.261237) (xy 170.964137 -424.315102) (xy 170.972459 -424.370794) (xy 170.972988 -424.398948)
			(xy 170.972471 -424.427018) (xy 170.964238 -424.482551) (xy 170.947957 -424.536278) (xy 170.923979 -424.58704)
			(xy 170.892822 -424.633741) (xy 170.855158 -424.675372) (xy 170.833796 -424.693588) (xy 170.822586 -424.703437)
			(xy 170.80602 -424.728244) (xy 170.797321 -424.756776) (xy 170.79723 -424.786606) (xy 170.805754 -424.815191)
			(xy 170.822168 -424.840099) (xy 170.833288 -424.850052) (xy 170.854333 -424.868317) (xy 170.891473 -424.909854)
			(xy 170.92218 -424.95635) (xy 170.945801 -425.006816) (xy 170.946016 -425.007532) (xy 178.04333 -425.007532)
			(xy 178.047401 -424.95191) (xy 178.059527 -424.897473) (xy 178.07945 -424.845382) (xy 178.106746 -424.796747)
			(xy 178.140832 -424.752604) (xy 178.180981 -424.713895) (xy 178.226339 -424.681444) (xy 178.275939 -424.655943)
			(xy 178.328723 -424.637936) (xy 178.383566 -424.627806) (xy 178.4393 -424.625769) (xy 178.494737 -424.631869)
			(xy 178.548694 -424.645975) (xy 178.600023 -424.667787) (xy 178.647629 -424.696841) (xy 178.690497 -424.732516)
			(xy 178.727714 -424.774053) (xy 178.758487 -424.820566) (xy 178.782159 -424.871063) (xy 178.798227 -424.92447)
			(xy 178.806347 -424.979646) (xy 178.806856 -425.007532) (xy 178.806347 -425.035418) (xy 178.798227 -425.090594)
			(xy 178.782159 -425.144001) (xy 178.781597 -425.1452) (xy 182.182514 -425.1452) (xy 182.186585 -425.089578)
			(xy 182.198711 -425.035141) (xy 182.218634 -424.98305) (xy 182.24593 -424.934415) (xy 182.280016 -424.890272)
			(xy 182.320165 -424.851563) (xy 182.365523 -424.819112) (xy 182.415123 -424.793611) (xy 182.467907 -424.775604)
			(xy 182.52275 -424.765474) (xy 182.578484 -424.763437) (xy 182.633921 -424.769537) (xy 182.687878 -424.783643)
			(xy 182.739207 -424.805455) (xy 182.786813 -424.834509) (xy 182.829681 -424.870184) (xy 182.866898 -424.911721)
			(xy 182.897671 -424.958234) (xy 182.921343 -425.008731) (xy 182.937411 -425.062138) (xy 182.945531 -425.117314)
			(xy 182.94604 -425.1452) (xy 182.945531 -425.173086) (xy 182.937411 -425.228262) (xy 182.923275 -425.275248)
			(xy 190.529462 -425.275248) (xy 190.533533 -425.219626) (xy 190.545659 -425.165189) (xy 190.565582 -425.113098)
			(xy 190.592878 -425.064463) (xy 190.626964 -425.02032) (xy 190.667113 -424.981611) (xy 190.712471 -424.94916)
			(xy 190.762071 -424.923659) (xy 190.814855 -424.905652) (xy 190.869698 -424.895522) (xy 190.925432 -424.893485)
			(xy 190.980869 -424.899585) (xy 191.034826 -424.913691) (xy 191.086155 -424.935503) (xy 191.133761 -424.964557)
			(xy 191.176629 -425.000232) (xy 191.213846 -425.041769) (xy 191.244619 -425.088282) (xy 191.268291 -425.138779)
			(xy 191.284359 -425.192186) (xy 191.292479 -425.247362) (xy 191.292988 -425.275248) (xy 191.292479 -425.303134)
			(xy 191.284359 -425.35831) (xy 191.270299 -425.405042) (xy 192.360802 -425.405042) (xy 192.364873 -425.34942)
			(xy 192.376999 -425.294983) (xy 192.396922 -425.242892) (xy 192.424218 -425.194257) (xy 192.458304 -425.150114)
			(xy 192.498453 -425.111405) (xy 192.543811 -425.078954) (xy 192.593411 -425.053453) (xy 192.646195 -425.035446)
			(xy 192.701038 -425.025316) (xy 192.756772 -425.023279) (xy 192.812209 -425.029379) (xy 192.866166 -425.043485)
			(xy 192.917495 -425.065297) (xy 192.965101 -425.094351) (xy 193.007969 -425.130026) (xy 193.045186 -425.171563)
			(xy 193.075959 -425.218076) (xy 193.099631 -425.268573) (xy 193.115699 -425.32198) (xy 193.123819 -425.377156)
			(xy 193.124328 -425.405042) (xy 193.123819 -425.432928) (xy 193.115699 -425.488104) (xy 193.099631 -425.541511)
			(xy 193.075959 -425.592008) (xy 193.045186 -425.638521) (xy 193.007969 -425.680058) (xy 192.965101 -425.715733)
			(xy 192.917495 -425.744787) (xy 192.866166 -425.766599) (xy 192.812209 -425.780705) (xy 192.756772 -425.786805)
			(xy 192.701038 -425.784768) (xy 192.646195 -425.774638) (xy 192.593411 -425.756631) (xy 192.543811 -425.73113)
			(xy 192.498453 -425.698679) (xy 192.458304 -425.65997) (xy 192.424218 -425.615827) (xy 192.396922 -425.567192)
			(xy 192.376999 -425.515101) (xy 192.364873 -425.460664) (xy 192.360802 -425.405042) (xy 191.270299 -425.405042)
			(xy 191.268291 -425.411717) (xy 191.244619 -425.462214) (xy 191.213846 -425.508727) (xy 191.176629 -425.550264)
			(xy 191.133761 -425.585939) (xy 191.086155 -425.614993) (xy 191.034826 -425.636805) (xy 190.980869 -425.650911)
			(xy 190.925432 -425.657011) (xy 190.869698 -425.654974) (xy 190.814855 -425.644844) (xy 190.762071 -425.626837)
			(xy 190.712471 -425.601336) (xy 190.667113 -425.568885) (xy 190.626964 -425.530176) (xy 190.592878 -425.486033)
			(xy 190.565582 -425.437398) (xy 190.545659 -425.385307) (xy 190.533533 -425.33087) (xy 190.529462 -425.275248)
			(xy 182.923275 -425.275248) (xy 182.921343 -425.281669) (xy 182.897671 -425.332166) (xy 182.866898 -425.378679)
			(xy 182.829681 -425.420216) (xy 182.786813 -425.455891) (xy 182.739207 -425.484945) (xy 182.687878 -425.506757)
			(xy 182.633921 -425.520863) (xy 182.578484 -425.526963) (xy 182.52275 -425.524926) (xy 182.467907 -425.514796)
			(xy 182.415123 -425.496789) (xy 182.365523 -425.471288) (xy 182.320165 -425.438837) (xy 182.280016 -425.400128)
			(xy 182.24593 -425.355985) (xy 182.218634 -425.30735) (xy 182.198711 -425.255259) (xy 182.186585 -425.200822)
			(xy 182.182514 -425.1452) (xy 178.781597 -425.1452) (xy 178.758487 -425.194498) (xy 178.727714 -425.241011)
			(xy 178.690497 -425.282548) (xy 178.647629 -425.318223) (xy 178.600023 -425.347277) (xy 178.548694 -425.369089)
			(xy 178.494737 -425.383195) (xy 178.4393 -425.389295) (xy 178.383566 -425.387258) (xy 178.328723 -425.377128)
			(xy 178.275939 -425.359121) (xy 178.226339 -425.33362) (xy 178.180981 -425.301169) (xy 178.140832 -425.26246)
			(xy 178.106746 -425.218317) (xy 178.07945 -425.169682) (xy 178.059527 -425.117591) (xy 178.047401 -425.063154)
			(xy 178.04333 -425.007532) (xy 170.946016 -425.007532) (xy 170.961834 -425.06018) (xy 170.96994 -425.115308)
			(xy 170.970448 -425.143168) (xy 170.969962 -425.170419) (xy 170.962206 -425.224367) (xy 170.946851 -425.276662)
			(xy 170.924209 -425.326239) (xy 170.894743 -425.372089) (xy 170.859052 -425.41328) (xy 170.817861 -425.448971)
			(xy 170.772011 -425.478437) (xy 170.722434 -425.501079) (xy 170.670139 -425.516434) (xy 170.616191 -425.52419)
			(xy 170.561689 -425.52419) (xy 170.507741 -425.516434) (xy 170.455446 -425.501079) (xy 170.405869 -425.478437)
			(xy 170.360019 -425.448971) (xy 170.318828 -425.41328) (xy 170.283137 -425.372089) (xy 170.253671 -425.326239)
			(xy 170.231029 -425.276662) (xy 170.215674 -425.224367) (xy 170.207918 -425.170419) (xy 170.207432 -425.143168)
			(xy 162.6616 -425.143168) (xy 162.6616 -425.922948) (xy 168.056812 -425.922948) (xy 168.060883 -425.867326)
			(xy 168.073009 -425.812889) (xy 168.092932 -425.760798) (xy 168.120228 -425.712163) (xy 168.154314 -425.66802)
			(xy 168.194463 -425.629311) (xy 168.239821 -425.59686) (xy 168.289421 -425.571359) (xy 168.342205 -425.553352)
			(xy 168.397048 -425.543222) (xy 168.452782 -425.541185) (xy 168.508219 -425.547285) (xy 168.562176 -425.561391)
			(xy 168.613505 -425.583203) (xy 168.661111 -425.612257) (xy 168.703979 -425.647932) (xy 168.741196 -425.689469)
			(xy 168.771969 -425.735982) (xy 168.795641 -425.786479) (xy 168.811709 -425.839886) (xy 168.819829 -425.895062)
			(xy 168.820338 -425.922948) (xy 168.819829 -425.950834) (xy 168.818737 -425.958254) (xy 178.626768 -425.958254)
			(xy 178.630839 -425.902632) (xy 178.642965 -425.848195) (xy 178.662888 -425.796104) (xy 178.690184 -425.747469)
			(xy 178.72427 -425.703326) (xy 178.764419 -425.664617) (xy 178.809777 -425.632166) (xy 178.859377 -425.606665)
			(xy 178.912161 -425.588658) (xy 178.967004 -425.578528) (xy 179.022738 -425.576491) (xy 179.078175 -425.582591)
			(xy 179.132132 -425.596697) (xy 179.183461 -425.618509) (xy 179.231067 -425.647563) (xy 179.273935 -425.683238)
			(xy 179.311152 -425.724775) (xy 179.341925 -425.771288) (xy 179.365597 -425.821785) (xy 179.368369 -425.831)
			(xy 183.640982 -425.831) (xy 183.645053 -425.775378) (xy 183.657179 -425.720941) (xy 183.677102 -425.66885)
			(xy 183.704398 -425.620215) (xy 183.738484 -425.576072) (xy 183.778633 -425.537363) (xy 183.823991 -425.504912)
			(xy 183.873591 -425.479411) (xy 183.926375 -425.461404) (xy 183.981218 -425.451274) (xy 184.036952 -425.449237)
			(xy 184.092389 -425.455337) (xy 184.146346 -425.469443) (xy 184.197675 -425.491255) (xy 184.245281 -425.520309)
			(xy 184.288149 -425.555984) (xy 184.325366 -425.597521) (xy 184.356139 -425.644034) (xy 184.379811 -425.694531)
			(xy 184.395879 -425.747938) (xy 184.403999 -425.803114) (xy 184.404508 -425.831) (xy 184.403999 -425.858886)
			(xy 184.395879 -425.914062) (xy 184.379811 -425.967469) (xy 184.356139 -426.017966) (xy 184.325366 -426.064479)
			(xy 184.288149 -426.106016) (xy 184.245281 -426.141691) (xy 184.197675 -426.170745) (xy 184.146346 -426.192557)
			(xy 184.092389 -426.206663) (xy 184.036952 -426.212763) (xy 183.981218 -426.210726) (xy 183.926375 -426.200596)
			(xy 183.873591 -426.182589) (xy 183.823991 -426.157088) (xy 183.778633 -426.124637) (xy 183.738484 -426.085928)
			(xy 183.704398 -426.041785) (xy 183.677102 -425.99315) (xy 183.657179 -425.941059) (xy 183.645053 -425.886622)
			(xy 183.640982 -425.831) (xy 179.368369 -425.831) (xy 179.381665 -425.875192) (xy 179.389785 -425.930368)
			(xy 179.390294 -425.958254) (xy 179.389785 -425.98614) (xy 179.381665 -426.041316) (xy 179.365597 -426.094723)
			(xy 179.341925 -426.14522) (xy 179.311152 -426.191733) (xy 179.273935 -426.23327) (xy 179.231067 -426.268945)
			(xy 179.183461 -426.297999) (xy 179.169462 -426.303948) (xy 188.252352 -426.303948) (xy 188.256423 -426.248326)
			(xy 188.268549 -426.193889) (xy 188.288472 -426.141798) (xy 188.315768 -426.093163) (xy 188.349854 -426.04902)
			(xy 188.390003 -426.010311) (xy 188.435361 -425.97786) (xy 188.484961 -425.952359) (xy 188.537745 -425.934352)
			(xy 188.592588 -425.924222) (xy 188.648322 -425.922185) (xy 188.703759 -425.928285) (xy 188.757716 -425.942391)
			(xy 188.809045 -425.964203) (xy 188.856651 -425.993257) (xy 188.899519 -426.028932) (xy 188.936736 -426.070469)
			(xy 188.967509 -426.116982) (xy 188.991181 -426.167479) (xy 189.007249 -426.220886) (xy 189.015369 -426.276062)
			(xy 189.015878 -426.303948) (xy 189.015369 -426.331834) (xy 189.007249 -426.38701) (xy 188.991181 -426.440417)
			(xy 188.967509 -426.490914) (xy 188.936736 -426.537427) (xy 188.899519 -426.578964) (xy 188.856651 -426.614639)
			(xy 188.809045 -426.643693) (xy 188.757716 -426.665505) (xy 188.703759 -426.679611) (xy 188.648322 -426.685711)
			(xy 188.592588 -426.683674) (xy 188.537745 -426.673544) (xy 188.484961 -426.655537) (xy 188.435361 -426.630036)
			(xy 188.390003 -426.597585) (xy 188.349854 -426.558876) (xy 188.315768 -426.514733) (xy 188.288472 -426.466098)
			(xy 188.268549 -426.414007) (xy 188.256423 -426.35957) (xy 188.252352 -426.303948) (xy 179.169462 -426.303948)
			(xy 179.132132 -426.319811) (xy 179.078175 -426.333917) (xy 179.022738 -426.340017) (xy 178.967004 -426.33798)
			(xy 178.912161 -426.32785) (xy 178.859377 -426.309843) (xy 178.809777 -426.284342) (xy 178.764419 -426.251891)
			(xy 178.72427 -426.213182) (xy 178.690184 -426.169039) (xy 178.662888 -426.120404) (xy 178.642965 -426.068313)
			(xy 178.630839 -426.013876) (xy 178.626768 -425.958254) (xy 168.818737 -425.958254) (xy 168.811709 -426.00601)
			(xy 168.795641 -426.059417) (xy 168.771969 -426.109914) (xy 168.741196 -426.156427) (xy 168.703979 -426.197964)
			(xy 168.661111 -426.233639) (xy 168.613505 -426.262693) (xy 168.562176 -426.284505) (xy 168.508219 -426.298611)
			(xy 168.452782 -426.304711) (xy 168.397048 -426.302674) (xy 168.342205 -426.292544) (xy 168.289421 -426.274537)
			(xy 168.239821 -426.249036) (xy 168.194463 -426.216585) (xy 168.154314 -426.177876) (xy 168.120228 -426.133733)
			(xy 168.092932 -426.085098) (xy 168.073009 -426.033007) (xy 168.060883 -425.97857) (xy 168.056812 -425.922948)
			(xy 162.6616 -425.922948) (xy 162.6616 -426.92574) (xy 176.851562 -426.92574) (xy 176.855633 -426.870118)
			(xy 176.867759 -426.815681) (xy 176.887682 -426.76359) (xy 176.914978 -426.714955) (xy 176.949064 -426.670812)
			(xy 176.989213 -426.632103) (xy 177.034571 -426.599652) (xy 177.084171 -426.574151) (xy 177.136955 -426.556144)
			(xy 177.191798 -426.546014) (xy 177.247532 -426.543977) (xy 177.302969 -426.550077) (xy 177.356926 -426.564183)
			(xy 177.408255 -426.585995) (xy 177.455861 -426.615049) (xy 177.498729 -426.650724) (xy 177.535946 -426.692261)
			(xy 177.566719 -426.738774) (xy 177.590391 -426.789271) (xy 177.606459 -426.842678) (xy 177.614579 -426.897854)
			(xy 177.615088 -426.92574) (xy 177.614579 -426.953626) (xy 177.606459 -427.008802) (xy 177.590391 -427.062209)
			(xy 177.566719 -427.112706) (xy 177.535946 -427.159219) (xy 177.498729 -427.200756) (xy 177.455861 -427.236431)
			(xy 177.408255 -427.265485) (xy 177.356926 -427.287297) (xy 177.302969 -427.301403) (xy 177.247532 -427.307503)
			(xy 177.191798 -427.305466) (xy 177.136955 -427.295336) (xy 177.084171 -427.277329) (xy 177.034571 -427.251828)
			(xy 176.989213 -427.219377) (xy 176.949064 -427.180668) (xy 176.914978 -427.136525) (xy 176.887682 -427.08789)
			(xy 176.867759 -427.035799) (xy 176.855633 -426.981362) (xy 176.851562 -426.92574) (xy 162.6616 -426.92574)
			(xy 162.6616 -427.319948) (xy 188.252352 -427.319948) (xy 188.256423 -427.264326) (xy 188.268549 -427.209889)
			(xy 188.288472 -427.157798) (xy 188.315768 -427.109163) (xy 188.349854 -427.06502) (xy 188.390003 -427.026311)
			(xy 188.435361 -426.99386) (xy 188.484961 -426.968359) (xy 188.537745 -426.950352) (xy 188.592588 -426.940222)
			(xy 188.648322 -426.938185) (xy 188.703759 -426.944285) (xy 188.757716 -426.958391) (xy 188.809045 -426.980203)
			(xy 188.856651 -427.009257) (xy 188.899519 -427.044932) (xy 188.936736 -427.086469) (xy 188.967509 -427.132982)
			(xy 188.991181 -427.183479) (xy 189.007249 -427.236886) (xy 189.015369 -427.292062) (xy 189.015878 -427.319948)
			(xy 189.015369 -427.347834) (xy 189.007249 -427.40301) (xy 188.991181 -427.456417) (xy 188.967509 -427.506914)
			(xy 188.936736 -427.553427) (xy 188.899519 -427.594964) (xy 188.856651 -427.630639) (xy 188.809045 -427.659693)
			(xy 188.757716 -427.681505) (xy 188.703759 -427.695611) (xy 188.648322 -427.701711) (xy 188.592588 -427.699674)
			(xy 188.537745 -427.689544) (xy 188.484961 -427.671537) (xy 188.435361 -427.646036) (xy 188.390003 -427.613585)
			(xy 188.349854 -427.574876) (xy 188.315768 -427.530733) (xy 188.288472 -427.482098) (xy 188.268549 -427.430007)
			(xy 188.256423 -427.37557) (xy 188.252352 -427.319948) (xy 162.6616 -427.319948) (xy 162.6616 -428.110396)
			(xy 162.662081 -428.124068) (xy 162.669411 -428.150414) (xy 162.683466 -428.173873) (xy 162.703239 -428.192763)
			(xy 162.727315 -428.205732) (xy 162.753968 -428.211851) (xy 162.78129 -428.210682) (xy 162.794442 -428.206916)
			(xy 162.823005 -428.198267) (xy 162.881951 -428.188955) (xy 162.91179 -428.188374) (xy 162.912044 -428.188374)
			(xy 162.939294 -428.188863) (xy 162.99324 -428.196625) (xy 163.045532 -428.211984) (xy 163.095106 -428.234629)
			(xy 163.140953 -428.264098) (xy 163.18214 -428.299791) (xy 163.194321 -428.31385) (xy 165.40683 -428.31385)
			(xy 165.410901 -428.258228) (xy 165.423027 -428.203791) (xy 165.44295 -428.1517) (xy 165.470246 -428.103065)
			(xy 165.504332 -428.058922) (xy 165.544481 -428.020213) (xy 165.589839 -427.987762) (xy 165.639439 -427.962261)
			(xy 165.692223 -427.944254) (xy 165.747066 -427.934124) (xy 165.8028 -427.932087) (xy 165.858237 -427.938187)
			(xy 165.912194 -427.952293) (xy 165.963523 -427.974105) (xy 166.011129 -428.003159) (xy 166.053997 -428.038834)
			(xy 166.091214 -428.080371) (xy 166.121987 -428.126884) (xy 166.145659 -428.177381) (xy 166.161727 -428.230788)
			(xy 166.169847 -428.285964) (xy 166.170356 -428.31385) (xy 166.169847 -428.341736) (xy 166.161727 -428.396912)
			(xy 166.145659 -428.450319) (xy 166.121987 -428.500816) (xy 166.091214 -428.547329) (xy 166.053997 -428.588866)
			(xy 166.011129 -428.624541) (xy 165.963523 -428.653595) (xy 165.912194 -428.675407) (xy 165.858237 -428.689513)
			(xy 165.8028 -428.695613) (xy 165.747066 -428.693576) (xy 165.692223 -428.683446) (xy 165.639439 -428.665439)
			(xy 165.589839 -428.639938) (xy 165.544481 -428.607487) (xy 165.504332 -428.568778) (xy 165.470246 -428.524635)
			(xy 165.44295 -428.476) (xy 165.423027 -428.423909) (xy 165.410901 -428.369472) (xy 165.40683 -428.31385)
			(xy 163.194321 -428.31385) (xy 163.217828 -428.340982) (xy 163.247292 -428.386833) (xy 163.269931 -428.436409)
			(xy 163.285285 -428.488703) (xy 163.29304 -428.542649) (xy 163.29304 -428.597151) (xy 163.285285 -428.651097)
			(xy 163.269931 -428.703391) (xy 163.247292 -428.752967) (xy 163.217828 -428.798818) (xy 163.18214 -428.840009)
			(xy 163.140953 -428.875702) (xy 163.095106 -428.905171) (xy 163.045532 -428.927816) (xy 162.99324 -428.943175)
			(xy 162.939294 -428.950937) (xy 162.912044 -428.95139) (xy 162.91179 -428.95139) (xy 162.881954 -428.950788)
			(xy 162.823013 -428.941467) (xy 162.794442 -428.932848) (xy 162.78129 -428.929063) (xy 162.753959 -428.927866)
			(xy 162.727292 -428.933972) (xy 162.703205 -428.946944) (xy 162.68343 -428.965847) (xy 162.669387 -428.989325)
			(xy 162.662085 -429.01569) (xy 162.6616 -429.029368) (xy 162.6616 -429.146208) (xy 162.662204 -429.16177)
			(xy 162.671652 -429.19143) (xy 162.68958 -429.216877) (xy 162.714329 -429.235757) (xy 162.743609 -429.246322)
			(xy 162.759136 -429.247554) (xy 162.78693 -429.249155) (xy 162.841649 -429.25941) (xy 162.894296 -429.277509)
			(xy 162.943754 -429.303066) (xy 162.988973 -429.33554) (xy 163.028993 -429.374241) (xy 163.062963 -429.418346)
			(xy 163.090163 -429.466921) (xy 163.110015 -429.518932) (xy 163.119196 -429.560228) (xy 163.632132 -429.560228)
			(xy 163.636203 -429.504606) (xy 163.648329 -429.450169) (xy 163.668252 -429.398078) (xy 163.695548 -429.349443)
			(xy 163.729634 -429.3053) (xy 163.769783 -429.266591) (xy 163.815141 -429.23414) (xy 163.864741 -429.208639)
			(xy 163.917525 -429.190632) (xy 163.972368 -429.180502) (xy 164.028102 -429.178465) (xy 164.083539 -429.184565)
			(xy 164.137496 -429.198671) (xy 164.188825 -429.220483) (xy 164.236431 -429.249537) (xy 164.279299 -429.285212)
			(xy 164.316516 -429.326749) (xy 164.347289 -429.373262) (xy 164.370961 -429.423759) (xy 164.37381 -429.433228)
			(xy 164.902132 -429.433228) (xy 164.906203 -429.377606) (xy 164.918329 -429.323169) (xy 164.938252 -429.271078)
			(xy 164.965548 -429.222443) (xy 164.999634 -429.1783) (xy 165.039783 -429.139591) (xy 165.085141 -429.10714)
			(xy 165.134741 -429.081639) (xy 165.187525 -429.063632) (xy 165.242368 -429.053502) (xy 165.298102 -429.051465)
			(xy 165.353539 -429.057565) (xy 165.407496 -429.071671) (xy 165.458825 -429.093483) (xy 165.506431 -429.122537)
			(xy 165.549299 -429.158212) (xy 165.586516 -429.199749) (xy 165.617289 -429.246262) (xy 165.640961 -429.296759)
			(xy 165.657029 -429.350166) (xy 165.665149 -429.405342) (xy 165.665658 -429.433228) (xy 165.665149 -429.461114)
			(xy 165.657029 -429.51629) (xy 165.640961 -429.569697) (xy 165.617289 -429.620194) (xy 165.586516 -429.666707)
			(xy 165.549299 -429.708244) (xy 165.506431 -429.743919) (xy 165.458825 -429.772973) (xy 165.407496 -429.794785)
			(xy 165.353539 -429.808891) (xy 165.298102 -429.814991) (xy 165.242368 -429.812954) (xy 165.187525 -429.802824)
			(xy 165.134741 -429.784817) (xy 165.085141 -429.759316) (xy 165.039783 -429.726865) (xy 164.999634 -429.688156)
			(xy 164.965548 -429.644013) (xy 164.938252 -429.595378) (xy 164.918329 -429.543287) (xy 164.906203 -429.48885)
			(xy 164.902132 -429.433228) (xy 164.37381 -429.433228) (xy 164.387029 -429.477166) (xy 164.395149 -429.532342)
			(xy 164.395658 -429.560228) (xy 164.395149 -429.588114) (xy 164.387029 -429.64329) (xy 164.370961 -429.696697)
			(xy 164.347289 -429.747194) (xy 164.316516 -429.793707) (xy 164.279299 -429.835244) (xy 164.236431 -429.870919)
			(xy 164.188825 -429.899973) (xy 164.137496 -429.921785) (xy 164.083539 -429.935891) (xy 164.028102 -429.941991)
			(xy 163.972368 -429.939954) (xy 163.917525 -429.929824) (xy 163.864741 -429.911817) (xy 163.815141 -429.886316)
			(xy 163.769783 -429.853865) (xy 163.729634 -429.815156) (xy 163.695548 -429.771013) (xy 163.668252 -429.722378)
			(xy 163.648329 -429.670287) (xy 163.636203 -429.61585) (xy 163.632132 -429.560228) (xy 163.119196 -429.560228)
			(xy 163.122097 -429.573277) (xy 163.126153 -429.6288) (xy 163.122097 -429.684324) (xy 163.110014 -429.738668)
			(xy 163.090163 -429.79068) (xy 163.062963 -429.839254) (xy 163.028992 -429.88336) (xy 162.988973 -429.92206)
			(xy 162.943754 -429.954534) (xy 162.894296 -429.980091) (xy 162.841648 -429.99819) (xy 162.78693 -430.008445)
			(xy 162.759136 -430.010062) (xy 162.743594 -430.011232) (xy 162.714279 -430.021774) (xy 162.689506 -430.040661)
			(xy 162.671577 -430.066137) (xy 162.662161 -430.095832) (xy 162.6616 -430.111408) (xy 162.6616 -431.460148)
			(xy 165.586662 -431.460148) (xy 165.590733 -431.404526) (xy 165.602859 -431.350089) (xy 165.622782 -431.297998)
			(xy 165.650078 -431.249363) (xy 165.684164 -431.20522) (xy 165.724313 -431.166511) (xy 165.769671 -431.13406)
			(xy 165.819271 -431.108559) (xy 165.872055 -431.090552) (xy 165.926898 -431.080422) (xy 165.982632 -431.078385)
			(xy 166.038069 -431.084485) (xy 166.092026 -431.098591) (xy 166.143355 -431.120403) (xy 166.190961 -431.149457)
			(xy 166.233829 -431.185132) (xy 166.271046 -431.226669) (xy 166.301819 -431.273182) (xy 166.325491 -431.323679)
			(xy 166.341559 -431.377086) (xy 166.349679 -431.432262) (xy 166.350188 -431.460148) (xy 166.349887 -431.476658)
			(xy 166.489124 -431.476658) (xy 166.493195 -431.421036) (xy 166.505321 -431.366599) (xy 166.525244 -431.314508)
			(xy 166.55254 -431.265873) (xy 166.586626 -431.22173) (xy 166.626775 -431.183021) (xy 166.672133 -431.15057)
			(xy 166.721733 -431.125069) (xy 166.774517 -431.107062) (xy 166.82936 -431.096932) (xy 166.885094 -431.094895)
			(xy 166.940531 -431.100995) (xy 166.994488 -431.115101) (xy 167.045817 -431.136913) (xy 167.093423 -431.165967)
			(xy 167.136291 -431.201642) (xy 167.173508 -431.243179) (xy 167.204281 -431.289692) (xy 167.227953 -431.340189)
			(xy 167.244021 -431.393596) (xy 167.252141 -431.448772) (xy 167.25265 -431.476658) (xy 167.252141 -431.504544)
			(xy 167.244021 -431.55972) (xy 167.227953 -431.613127) (xy 167.204281 -431.663624) (xy 167.173508 -431.710137)
			(xy 167.136291 -431.751674) (xy 167.093423 -431.787349) (xy 167.045817 -431.816403) (xy 166.994488 -431.838215)
			(xy 166.940531 -431.852321) (xy 166.885094 -431.858421) (xy 166.82936 -431.856384) (xy 166.774517 -431.846254)
			(xy 166.721733 -431.828247) (xy 166.672133 -431.802746) (xy 166.626775 -431.770295) (xy 166.586626 -431.731586)
			(xy 166.55254 -431.687443) (xy 166.525244 -431.638808) (xy 166.505321 -431.586717) (xy 166.493195 -431.53228)
			(xy 166.489124 -431.476658) (xy 166.349887 -431.476658) (xy 166.349679 -431.488034) (xy 166.341559 -431.54321)
			(xy 166.325491 -431.596617) (xy 166.301819 -431.647114) (xy 166.271046 -431.693627) (xy 166.233829 -431.735164)
			(xy 166.190961 -431.770839) (xy 166.143355 -431.799893) (xy 166.092026 -431.821705) (xy 166.038069 -431.835811)
			(xy 165.982632 -431.841911) (xy 165.926898 -431.839874) (xy 165.872055 -431.829744) (xy 165.819271 -431.811737)
			(xy 165.769671 -431.786236) (xy 165.724313 -431.753785) (xy 165.684164 -431.715076) (xy 165.650078 -431.670933)
			(xy 165.622782 -431.622298) (xy 165.602859 -431.570207) (xy 165.590733 -431.51577) (xy 165.586662 -431.460148)
			(xy 162.6616 -431.460148) (xy 162.6616 -433.628292) (xy 162.662079 -433.641954) (xy 162.669398 -433.668283)
			(xy 162.683433 -433.691731) (xy 162.703181 -433.71062) (xy 162.727229 -433.7236) (xy 162.753857 -433.729741)
			(xy 162.781161 -433.728605) (xy 162.807187 -433.720273) (xy 162.830074 -433.705341) (xy 162.8394 -433.695348)
			(xy 162.857586 -433.675483) (xy 162.898583 -433.640556) (xy 162.944082 -433.61174) (xy 162.99318 -433.589606)
			(xy 163.044903 -433.574594) (xy 163.098222 -433.567002) (xy 163.12515 -433.56657) (xy 163.152407 -433.567029)
			(xy 163.206366 -433.574781) (xy 163.258673 -433.590134) (xy 163.308263 -433.612775) (xy 163.354125 -433.642243)
			(xy 163.395326 -433.677939) (xy 163.431027 -433.719135) (xy 163.460501 -433.764993) (xy 163.483149 -433.81458)
			(xy 163.498508 -433.866885) (xy 163.506267 -433.920843) (xy 163.506267 -433.923948) (xy 170.863512 -433.923948)
			(xy 170.867583 -433.868326) (xy 170.879709 -433.813889) (xy 170.899632 -433.761798) (xy 170.926928 -433.713163)
			(xy 170.961014 -433.66902) (xy 171.001163 -433.630311) (xy 171.046521 -433.59786) (xy 171.096121 -433.572359)
			(xy 171.148905 -433.554352) (xy 171.203748 -433.544222) (xy 171.259482 -433.542185) (xy 171.314919 -433.548285)
			(xy 171.368876 -433.562391) (xy 171.420205 -433.584203) (xy 171.467811 -433.613257) (xy 171.510679 -433.648932)
			(xy 171.547896 -433.690469) (xy 171.578669 -433.736982) (xy 171.602341 -433.787479) (xy 171.618409 -433.840886)
			(xy 171.626529 -433.896062) (xy 171.627038 -433.923948) (xy 171.626529 -433.951834) (xy 171.618409 -434.00701)
			(xy 171.602341 -434.060417) (xy 171.578669 -434.110914) (xy 171.547896 -434.157427) (xy 171.510679 -434.198964)
			(xy 171.467811 -434.234639) (xy 171.420205 -434.263693) (xy 171.368876 -434.285505) (xy 171.314919 -434.299611)
			(xy 171.259482 -434.305711) (xy 171.203748 -434.303674) (xy 171.148905 -434.293544) (xy 171.096121 -434.275537)
			(xy 171.046521 -434.250036) (xy 171.001163 -434.217585) (xy 170.961014 -434.178876) (xy 170.926928 -434.134733)
			(xy 170.899632 -434.086098) (xy 170.879709 -434.034007) (xy 170.867583 -433.97957) (xy 170.863512 -433.923948)
			(xy 163.506267 -433.923948) (xy 163.506267 -433.975357) (xy 163.498508 -434.029315) (xy 163.483149 -434.08162)
			(xy 163.460501 -434.131207) (xy 163.431027 -434.177065) (xy 163.395326 -434.218261) (xy 163.354125 -434.253957)
			(xy 163.308263 -434.283425) (xy 163.258673 -434.306066) (xy 163.206366 -434.321419) (xy 163.152407 -434.329171)
			(xy 163.12515 -434.329586) (xy 163.098221 -434.329126) (xy 163.044897 -434.321556) (xy 162.993169 -434.306559)
			(xy 162.944065 -434.284434) (xy 162.898562 -434.255621) (xy 162.857565 -434.220692) (xy 162.8394 -434.200808)
			(xy 162.830023 -434.190855) (xy 162.807143 -434.175899) (xy 162.781116 -434.167546) (xy 162.753806 -434.166395)
			(xy 162.727168 -434.172529) (xy 162.703111 -434.185508) (xy 162.683358 -434.204402) (xy 162.669324 -434.227859)
			(xy 162.662013 -434.254198) (xy 162.6616 -434.267864) (xy 162.6616 -434.75148) (xy 162.511994 -434.901086)
			(xy 162.502537 -434.911168) (xy 162.488923 -434.935213) (xy 162.482259 -434.962029) (xy 162.483035 -434.98965)
			(xy 162.491194 -435.01605) (xy 162.506137 -435.039292) (xy 162.526769 -435.057672) (xy 162.551576 -435.069843)
			(xy 162.56508 -435.07279) (xy 162.591019 -435.078077) (xy 162.641224 -435.094865) (xy 162.688625 -435.118433)
			(xy 162.732311 -435.148329) (xy 162.771444 -435.183979) (xy 162.805272 -435.224698) (xy 162.833144 -435.269703)
			(xy 162.854525 -435.31813) (xy 162.869005 -435.369048) (xy 162.876304 -435.421479) (xy 162.876738 -435.447948)
			(xy 162.876249 -435.475198) (xy 162.868487 -435.529142) (xy 162.853128 -435.581433) (xy 162.830485 -435.631006)
			(xy 162.801018 -435.676852) (xy 162.765326 -435.718039) (xy 162.724138 -435.753728) (xy 162.67829 -435.783193)
			(xy 162.628716 -435.805834) (xy 162.576424 -435.821191) (xy 162.52248 -435.82895) (xy 162.49523 -435.829456)
			(xy 162.468765 -435.829) (xy 162.416343 -435.821678) (xy 162.365435 -435.807184) (xy 162.317018 -435.785796)
			(xy 162.272019 -435.757925) (xy 162.231303 -435.724104) (xy 162.195649 -435.684983) (xy 162.165742 -435.641311)
			(xy 162.142155 -435.593926) (xy 162.12534 -435.543737) (xy 162.120072 -435.517798) (xy 162.117097 -435.504297)
			(xy 162.104945 -435.479476) (xy 162.086575 -435.458831) (xy 162.063334 -435.443878) (xy 162.036932 -435.435716)
			(xy 162.009307 -435.434944) (xy 161.98249 -435.44162) (xy 161.958452 -435.455253) (xy 161.948368 -435.464712)
			(xy 161.73958 -435.6735) (xy 161.73958 -437.621934) (xy 164.266372 -437.621934) (xy 164.266857 -437.593965)
			(xy 164.275009 -437.538626) (xy 164.291159 -437.485071) (xy 164.314959 -437.43445) (xy 164.3459 -437.387849)
			(xy 164.383316 -437.346268) (xy 164.404548 -437.328056) (xy 164.415368 -437.318406) (xy 164.431603 -437.294404)
			(xy 164.440439 -437.266807) (xy 164.441162 -437.23784) (xy 164.433716 -437.209836) (xy 164.4187 -437.185053)
			(xy 164.408358 -437.174894) (xy 164.389154 -437.156747) (xy 164.355435 -437.116068) (xy 164.327652 -437.071127)
			(xy 164.306335 -437.022781) (xy 164.291893 -436.971957) (xy 164.284601 -436.919626) (xy 164.284152 -436.893208)
			(xy 164.284559 -436.867334) (xy 164.291542 -436.816059) (xy 164.305394 -436.7662) (xy 164.325861 -436.718671)
			(xy 164.352567 -436.674347) (xy 164.385021 -436.634041) (xy 164.422628 -436.598493) (xy 164.44341 -436.583074)
			(xy 164.454656 -436.574524) (xy 164.47221 -436.552398) (xy 164.483032 -436.52631) (xy 164.486295 -436.498255)
			(xy 164.481748 -436.470379) (xy 164.469739 -436.444816) (xy 164.451188 -436.423519) (xy 164.4396 -436.415434)
			(xy 164.417181 -436.400223) (xy 164.376443 -436.364512) (xy 164.341162 -436.3234) (xy 164.312046 -436.277715)
			(xy 164.28968 -436.228373) (xy 164.274513 -436.176365) (xy 164.266849 -436.122735) (xy 164.266372 -436.095648)
			(xy 164.266858 -436.068397) (xy 164.274614 -436.014449) (xy 164.289969 -435.962154) (xy 164.312611 -435.912577)
			(xy 164.342077 -435.866727) (xy 164.377768 -435.825536) (xy 164.418959 -435.789845) (xy 164.464809 -435.760379)
			(xy 164.514386 -435.737737) (xy 164.566681 -435.722382) (xy 164.620629 -435.714626) (xy 164.675131 -435.714626)
			(xy 164.729079 -435.722382) (xy 164.781374 -435.737737) (xy 164.830951 -435.760379) (xy 164.876801 -435.789845)
			(xy 164.917992 -435.825536) (xy 164.953683 -435.866727) (xy 164.983149 -435.912577) (xy 164.989036 -435.925468)
			(xy 171.098462 -435.925468) (xy 171.102533 -435.869846) (xy 171.114659 -435.815409) (xy 171.134582 -435.763318)
			(xy 171.161878 -435.714683) (xy 171.195964 -435.67054) (xy 171.236113 -435.631831) (xy 171.281471 -435.59938)
			(xy 171.331071 -435.573879) (xy 171.383855 -435.555872) (xy 171.438698 -435.545742) (xy 171.494432 -435.543705)
			(xy 171.549869 -435.549805) (xy 171.603826 -435.563911) (xy 171.655155 -435.585723) (xy 171.702761 -435.614777)
			(xy 171.745629 -435.650452) (xy 171.782846 -435.691989) (xy 171.813619 -435.738502) (xy 171.837291 -435.788999)
			(xy 171.853359 -435.842406) (xy 171.861479 -435.897582) (xy 171.861988 -435.925468) (xy 171.861479 -435.953354)
			(xy 171.853359 -436.00853) (xy 171.837291 -436.061937) (xy 171.813619 -436.112434) (xy 171.782846 -436.158947)
			(xy 171.745629 -436.200484) (xy 171.702761 -436.236159) (xy 171.655155 -436.265213) (xy 171.603826 -436.287025)
			(xy 171.549869 -436.301131) (xy 171.494432 -436.307231) (xy 171.438698 -436.305194) (xy 171.383855 -436.295064)
			(xy 171.331071 -436.277057) (xy 171.281471 -436.251556) (xy 171.236113 -436.219105) (xy 171.195964 -436.180396)
			(xy 171.161878 -436.136253) (xy 171.134582 -436.087618) (xy 171.114659 -436.035527) (xy 171.102533 -435.98109)
			(xy 171.098462 -435.925468) (xy 164.989036 -435.925468) (xy 165.005791 -435.962154) (xy 165.021146 -436.014449)
			(xy 165.028902 -436.068397) (xy 165.029388 -436.095648) (xy 165.028932 -436.12152) (xy 165.021956 -436.172792)
			(xy 165.008111 -436.22265) (xy 164.987651 -436.270178) (xy 164.960953 -436.314503) (xy 164.928507 -436.35481)
			(xy 164.890908 -436.390361) (xy 164.87013 -436.405782) (xy 164.858935 -436.41439) (xy 164.841392 -436.436506)
			(xy 164.830574 -436.46258) (xy 164.827309 -436.490619) (xy 164.831844 -436.518481) (xy 164.843835 -436.544037)
			(xy 164.862364 -436.565334) (xy 164.87394 -436.573422) (xy 164.896371 -436.588616) (xy 164.899031 -436.590948)
			(xy 169.574462 -436.590948) (xy 169.578533 -436.535326) (xy 169.590659 -436.480889) (xy 169.610582 -436.428798)
			(xy 169.637878 -436.380163) (xy 169.671964 -436.33602) (xy 169.712113 -436.297311) (xy 169.757471 -436.26486)
			(xy 169.807071 -436.239359) (xy 169.859855 -436.221352) (xy 169.914698 -436.211222) (xy 169.970432 -436.209185)
			(xy 170.025869 -436.215285) (xy 170.079826 -436.229391) (xy 170.131155 -436.251203) (xy 170.178761 -436.280257)
			(xy 170.221629 -436.315932) (xy 170.258846 -436.357469) (xy 170.289619 -436.403982) (xy 170.313291 -436.454479)
			(xy 170.329359 -436.507886) (xy 170.337479 -436.563062) (xy 170.337988 -436.590948) (xy 170.337479 -436.618834)
			(xy 170.329359 -436.67401) (xy 170.313291 -436.727417) (xy 170.289619 -436.777914) (xy 170.258846 -436.824427)
			(xy 170.221629 -436.865964) (xy 170.178761 -436.901639) (xy 170.131155 -436.930693) (xy 170.079826 -436.952505)
			(xy 170.025869 -436.966611) (xy 169.970432 -436.972711) (xy 169.914698 -436.970674) (xy 169.859855 -436.960544)
			(xy 169.807071 -436.942537) (xy 169.757471 -436.917036) (xy 169.712113 -436.884585) (xy 169.671964 -436.845876)
			(xy 169.637878 -436.801733) (xy 169.610582 -436.753098) (xy 169.590659 -436.701007) (xy 169.578533 -436.64657)
			(xy 169.574462 -436.590948) (xy 164.899031 -436.590948) (xy 164.937111 -436.624328) (xy 164.972394 -436.665441)
			(xy 165.001509 -436.711129) (xy 165.023874 -436.760475) (xy 165.039037 -436.812487) (xy 165.046695 -436.86612)
			(xy 165.047168 -436.893208) (xy 165.046698 -436.921177) (xy 165.038541 -436.976517) (xy 165.022387 -437.030071)
			(xy 164.998584 -437.080692) (xy 164.967641 -437.127292) (xy 164.930224 -437.168873) (xy 164.908992 -437.187086)
			(xy 164.898128 -437.196692) (xy 164.881888 -437.220704) (xy 164.873054 -437.248313) (xy 164.872337 -437.277293)
			(xy 164.875574 -437.289448) (xy 170.374562 -437.289448) (xy 170.378633 -437.233826) (xy 170.390759 -437.179389)
			(xy 170.410682 -437.127298) (xy 170.437978 -437.078663) (xy 170.472064 -437.03452) (xy 170.512213 -436.995811)
			(xy 170.557571 -436.96336) (xy 170.607171 -436.937859) (xy 170.659955 -436.919852) (xy 170.714798 -436.909722)
			(xy 170.770532 -436.907685) (xy 170.825969 -436.913785) (xy 170.879926 -436.927891) (xy 170.931255 -436.949703)
			(xy 170.978861 -436.978757) (xy 171.021729 -437.014432) (xy 171.058946 -437.055969) (xy 171.089719 -437.102482)
			(xy 171.113391 -437.152979) (xy 171.129459 -437.206386) (xy 171.137579 -437.261562) (xy 171.138088 -437.289448)
			(xy 171.137579 -437.317334) (xy 171.129459 -437.37251) (xy 171.113391 -437.425917) (xy 171.089719 -437.476414)
			(xy 171.058946 -437.522927) (xy 171.021729 -437.564464) (xy 170.978861 -437.600139) (xy 170.931255 -437.629193)
			(xy 170.879926 -437.651005) (xy 170.825969 -437.665111) (xy 170.770532 -437.671211) (xy 170.714798 -437.669174)
			(xy 170.659955 -437.659044) (xy 170.607171 -437.641037) (xy 170.557571 -437.615536) (xy 170.512213 -437.583085)
			(xy 170.472064 -437.544376) (xy 170.437978 -437.500233) (xy 170.410682 -437.451598) (xy 170.390759 -437.399507)
			(xy 170.378633 -437.34507) (xy 170.374562 -437.289448) (xy 164.875574 -437.289448) (xy 164.879797 -437.305305)
			(xy 164.89483 -437.33009) (xy 164.905182 -437.340248) (xy 164.924395 -437.358386) (xy 164.958115 -437.399065)
			(xy 164.985899 -437.444008) (xy 165.007215 -437.492356) (xy 165.021654 -437.543182) (xy 165.028942 -437.595515)
			(xy 165.029388 -437.621934) (xy 165.028902 -437.649185) (xy 165.021146 -437.703133) (xy 165.005791 -437.755428)
			(xy 164.983149 -437.805005) (xy 164.953683 -437.850855) (xy 164.917992 -437.892046) (xy 164.876801 -437.927737)
			(xy 164.830951 -437.957203) (xy 164.781374 -437.979845) (xy 164.729079 -437.9952) (xy 164.675131 -438.002956)
			(xy 164.620629 -438.002956) (xy 164.566681 -437.9952) (xy 164.514386 -437.979845) (xy 164.464809 -437.957203)
			(xy 164.418959 -437.927737) (xy 164.377768 -437.892046) (xy 164.342077 -437.850855) (xy 164.312611 -437.805005)
			(xy 164.289969 -437.755428) (xy 164.274614 -437.703133) (xy 164.266858 -437.649185) (xy 164.266372 -437.621934)
			(xy 161.73958 -437.621934) (xy 161.73958 -438.495948) (xy 162.113212 -438.495948) (xy 162.117283 -438.440326)
			(xy 162.129409 -438.385889) (xy 162.149332 -438.333798) (xy 162.176628 -438.285163) (xy 162.210714 -438.24102)
			(xy 162.250863 -438.202311) (xy 162.296221 -438.16986) (xy 162.345821 -438.144359) (xy 162.398605 -438.126352)
			(xy 162.453448 -438.116222) (xy 162.509182 -438.114185) (xy 162.564619 -438.120285) (xy 162.618576 -438.134391)
			(xy 162.669905 -438.156203) (xy 162.717511 -438.185257) (xy 162.760379 -438.220932) (xy 162.797596 -438.262469)
			(xy 162.828369 -438.308982) (xy 162.852041 -438.359479) (xy 162.868109 -438.412886) (xy 162.876229 -438.468062)
			(xy 162.876738 -438.495948) (xy 162.876229 -438.523834) (xy 162.868109 -438.57901) (xy 162.852041 -438.632417)
			(xy 162.828369 -438.682914) (xy 162.797596 -438.729427) (xy 162.760379 -438.770964) (xy 162.717511 -438.806639)
			(xy 162.669905 -438.835693) (xy 162.618576 -438.857505) (xy 162.564619 -438.871611) (xy 162.509182 -438.877711)
			(xy 162.453448 -438.875674) (xy 162.398605 -438.865544) (xy 162.345821 -438.847537) (xy 162.296221 -438.822036)
			(xy 162.250863 -438.789585) (xy 162.210714 -438.750876) (xy 162.176628 -438.706733) (xy 162.149332 -438.658098)
			(xy 162.129409 -438.606007) (xy 162.117283 -438.55157) (xy 162.113212 -438.495948) (xy 161.73958 -438.495948)
			(xy 161.73958 -439.6613) (xy 162.54476 -440.46648)
		)
		(stroke
			(width 0)
			(type solid)
		)
		(fill yes)
		(layer "In15.Cu")
		(net "P3V3_AUX")
	)
	(gr_poly
		(pts
			(xy 447.118994 -375.334276) (xy 447.069972 -375.285) (xy 447.051176 -375.283476) (xy 447.023505 -375.280762)
			(xy 446.969349 -375.268174) (xy 446.917664 -375.247682) (xy 446.869597 -375.21974) (xy 446.826212 -375.184968)
			(xy 446.788475 -375.144138) (xy 446.75722 -375.098155) (xy 446.733143 -375.04804) (xy 446.716776 -374.994904)
			(xy 446.708484 -374.939927) (xy 446.708022 -374.912128) (xy 446.708472 -374.88551) (xy 446.716045 -374.832815)
			(xy 446.731042 -374.781735) (xy 446.753156 -374.733309) (xy 446.781937 -374.688524) (xy 446.816799 -374.648291)
			(xy 446.857033 -374.61343) (xy 446.90182 -374.58465) (xy 446.950246 -374.562537) (xy 447.001327 -374.547543)
			(xy 447.054022 -374.539971) (xy 447.08064 -374.53951) (xy 447.108753 -374.540018) (xy 447.164342 -374.548457)
			(xy 447.218031 -374.565153) (xy 447.268603 -374.589727) (xy 447.314908 -374.62162) (xy 447.355895 -374.660109)
			(xy 447.390634 -374.704319) (xy 447.418335 -374.753247) (xy 447.438371 -374.805782) (xy 447.450285 -374.860731)
			(xy 447.452496 -374.88876) (xy 447.453929 -374.903211) (xy 447.463839 -374.930492) (xy 447.481017 -374.953888)
			(xy 447.504077 -374.971514) (xy 447.531162 -374.981949) (xy 447.560088 -374.984351) (xy 447.574416 -374.981978)
			(xy 447.596767 -374.977605) (xy 447.642068 -374.972894) (xy 447.66484 -374.97258) (xy 451.10527 -374.97258)
			(xy 451.397878 -374.680226) (xy 451.397878 -350.787462) (xy 443.904878 -343.294462) (xy 443.904878 -333.246222)
			(xy 443.904448 -333.232618) (xy 443.897264 -333.206375) (xy 443.883402 -333.182963) (xy 443.863847 -333.164045)
			(xy 443.839988 -333.150967) (xy 443.813521 -333.144658) (xy 443.786328 -333.145566) (xy 443.760341 -333.153627)
			(xy 443.748668 -333.160624) (xy 443.72711 -333.173847) (xy 443.681053 -333.194734) (xy 443.632503 -333.208894)
			(xy 443.582438 -333.216043) (xy 443.557152 -333.216504) (xy 443.530505 -333.216003) (xy 443.477808 -333.208054)
			(xy 443.426884 -333.192339) (xy 443.37887 -333.169212) (xy 443.33484 -333.139187) (xy 443.295776 -333.102935)
			(xy 443.26255 -333.061267) (xy 443.235905 -333.015112) (xy 443.216437 -332.965502) (xy 443.204579 -332.913544)
			(xy 443.200596 -332.8604) (xy 443.204579 -332.807256) (xy 443.216437 -332.755298) (xy 443.235905 -332.705688)
			(xy 443.26255 -332.659533) (xy 443.295776 -332.617865) (xy 443.33484 -332.581613) (xy 443.37887 -332.551588)
			(xy 443.426884 -332.528461) (xy 443.477808 -332.512746) (xy 443.530505 -332.504797) (xy 443.557152 -332.504288)
			(xy 443.582438 -332.504734) (xy 443.6325 -332.511896) (xy 443.681045 -332.526068) (xy 443.727097 -332.546966)
			(xy 443.748668 -332.560168) (xy 443.760366 -332.567115) (xy 443.786346 -332.575165) (xy 443.813529 -332.576069)
			(xy 443.839986 -332.569763) (xy 443.863838 -332.556695) (xy 443.883394 -332.537792) (xy 443.897264 -332.514396)
			(xy 443.904464 -332.488169) (xy 443.904878 -332.47457) (xy 443.904878 -327.366884) (xy 443.864746 -327.358502)
			(xy 443.836659 -327.351946) (xy 443.782724 -327.331514) (xy 443.73248 -327.303194) (xy 443.687075 -327.267631)
			(xy 443.647542 -327.225636) (xy 443.614784 -327.178167) (xy 443.589547 -327.126306) (xy 443.572408 -327.071236)
			(xy 443.563756 -327.014214) (xy 443.563248 -326.985376) (xy 443.563735 -326.958125) (xy 443.571494 -326.904177)
			(xy 443.586851 -326.851883) (xy 443.609493 -326.802306) (xy 443.638959 -326.756455) (xy 443.67465 -326.715264)
			(xy 443.715839 -326.679571) (xy 443.761688 -326.650103) (xy 443.811264 -326.627458) (xy 443.863558 -326.612099)
			(xy 443.917505 -326.604337) (xy 443.944756 -326.603868) (xy 443.971297 -326.604322) (xy 444.023866 -326.61167)
			(xy 444.074911 -326.626231) (xy 444.123447 -326.647723) (xy 444.168536 -326.675733) (xy 444.20931 -326.70972)
			(xy 444.227458 -326.72909) (xy 444.237024 -326.738948) (xy 444.260238 -326.753614) (xy 444.286519 -326.761567)
			(xy 444.31397 -326.762233) (xy 444.340606 -326.755564) (xy 444.364503 -326.742041) (xy 444.374524 -326.732646)
			(xy 445.256158 -325.851012) (xy 446.791588 -325.851012) (xy 446.853056 -325.91248) (xy 465.586318 -325.91248)
			(xy 467.394544 -324.104254) (xy 467.55177 -323.947028) (xy 467.55177 -170.476418) (xy 467.55143 -170.466882)
			(xy 467.544561 -170.449096) (xy 467.531657 -170.435059) (xy 467.51451 -170.426721) (xy 467.505034 -170.425618)
			(xy 467.476722 -170.422815) (xy 467.421318 -170.409888) (xy 467.368448 -170.388876) (xy 467.319284 -170.360248)
			(xy 467.274916 -170.324636) (xy 467.236328 -170.282831) (xy 467.204375 -170.235759) (xy 467.179766 -170.184465)
			(xy 467.163047 -170.130085) (xy 467.154587 -170.073826) (xy 467.154006 -170.04538) (xy 467.154477 -170.018365)
			(xy 467.162103 -169.964875) (xy 467.1772 -169.912996) (xy 467.199466 -169.863766) (xy 467.228456 -169.81817)
			(xy 467.263588 -169.777121) (xy 467.304161 -169.74144) (xy 467.349363 -169.71184) (xy 467.398289 -169.688914)
			(xy 467.424008 -169.680636) (xy 467.4382 -169.675761) (xy 467.463117 -169.659065) (xy 467.482101 -169.635844)
			(xy 467.493509 -169.608105) (xy 467.496356 -169.578247) (xy 467.490395 -169.548851) (xy 467.476141 -169.522461)
			(xy 467.465918 -169.511472) (xy 467.253066 -169.29862) (xy 467.116922 -169.16273) (xy 467.113366 -169.15892)
			(xy 467.113112 -169.158666) (xy 464.787996 -166.83355) (xy 457.233274 -166.83355) (xy 456.408536 -166.008812)
			(xy 456.408536 -162.006534) (xy 456.37788 -161.901795) (xy 456.324207 -161.690235) (xy 456.279334 -161.476634)
			(xy 456.243338 -161.26136) (xy 456.216281 -161.04478) (xy 456.19821 -160.827267) (xy 456.189155 -160.609191)
			(xy 456.188572 -160.50006) (xy 456.189134 -160.390928) (xy 456.198178 -160.172851) (xy 456.216243 -159.955336)
			(xy 456.243299 -159.738755) (xy 456.279299 -159.52348) (xy 456.324183 -159.309881) (xy 456.377872 -159.098323)
			(xy 456.408536 -158.993586) (xy 456.408536 -123.373642) (xy 459.967584 -119.814594) (xy 459.982321 -119.792437)
			(xy 460.016965 -119.752045) (xy 460.056881 -119.716855) (xy 460.078836 -119.701818) (xy 460.083154 -119.699024)
			(xy 465.094828 -114.68735) (xy 465.094828 -103.576882) (xy 465.094359 -103.562346) (xy 465.086161 -103.534454)
			(xy 465.070434 -103.510004) (xy 465.048454 -103.490977) (xy 465.022002 -103.478916) (xy 464.993223 -103.474799)
			(xy 464.964451 -103.478959) (xy 464.938017 -103.49106) (xy 464.92668 -103.500174) (xy 464.905752 -103.517763)
			(xy 464.859813 -103.547394) (xy 464.810115 -103.570166) (xy 464.757676 -103.585614) (xy 464.703569 -103.59342)
			(xy 464.676236 -103.5939) (xy 464.648982 -103.593439) (xy 464.595028 -103.585686) (xy 464.542727 -103.570334)
			(xy 464.493144 -103.547694) (xy 464.447287 -103.518228) (xy 464.406091 -103.482535) (xy 464.370394 -103.441342)
			(xy 464.340923 -103.395488) (xy 464.318279 -103.345906) (xy 464.302921 -103.293607) (xy 464.295163 -103.239654)
			(xy 464.295163 -103.185146) (xy 464.302921 -103.131193) (xy 464.318279 -103.078894) (xy 464.340923 -103.029312)
			(xy 464.370394 -102.983458) (xy 464.406091 -102.942265) (xy 464.447287 -102.906572) (xy 464.493144 -102.877106)
			(xy 464.542727 -102.854466) (xy 464.595028 -102.839114) (xy 464.648982 -102.831361) (xy 464.676236 -102.830884)
			(xy 464.703571 -102.831349) (xy 464.757683 -102.839146) (xy 464.810128 -102.854588) (xy 464.85983 -102.877361)
			(xy 464.905771 -102.906996) (xy 464.92668 -102.92461) (xy 464.937966 -102.93378) (xy 464.964403 -102.945863)
			(xy 464.993173 -102.950008) (xy 465.021946 -102.945879) (xy 465.048389 -102.933809) (xy 465.07036 -102.914777)
			(xy 465.086077 -102.890325) (xy 465.094268 -102.862436) (xy 465.094828 -102.847902) (xy 465.094828 -92.686886)
			(xy 465.094386 -92.672898) (xy 465.086792 -92.645971) (xy 465.072178 -92.622115) (xy 465.05164 -92.603118)
			(xy 465.026718 -92.590405) (xy 464.999282 -92.584931) (xy 464.97139 -92.587105) (xy 464.945134 -92.596765)
			(xy 464.922483 -92.613186) (xy 464.913472 -92.623894) (xy 464.895291 -92.646133) (xy 464.85338 -92.685414)
			(xy 464.80605 -92.717961) (xy 464.754372 -92.74304) (xy 464.699517 -92.760081) (xy 464.642727 -92.7687)
			(xy 464.614006 -92.769182) (xy 464.586755 -92.768719) (xy 464.532807 -92.760963) (xy 464.480512 -92.745609)
			(xy 464.430934 -92.722968) (xy 464.385084 -92.693502) (xy 464.343893 -92.657811) (xy 464.308201 -92.616621)
			(xy 464.278735 -92.570771) (xy 464.256093 -92.521194) (xy 464.240738 -92.468899) (xy 464.232981 -92.414951)
			(xy 464.232981 -92.360449) (xy 464.240738 -92.306501) (xy 464.256093 -92.254206) (xy 464.278735 -92.204629)
			(xy 464.308201 -92.158779) (xy 464.343893 -92.117589) (xy 464.385084 -92.081898) (xy 464.430934 -92.052432)
			(xy 464.480512 -92.029791) (xy 464.532807 -92.014437) (xy 464.586755 -92.006681) (xy 464.614006 -92.006166)
			(xy 464.642725 -92.006687) (xy 464.699514 -92.015302) (xy 464.754368 -92.032337) (xy 464.806046 -92.057406)
			(xy 464.853381 -92.089942) (xy 464.8953 -92.129209) (xy 464.913472 -92.151454) (xy 464.922486 -92.162159)
			(xy 464.945131 -92.178586) (xy 464.971384 -92.188251) (xy 464.999275 -92.190428) (xy 465.02671 -92.184954)
			(xy 465.051629 -92.172239) (xy 465.072163 -92.153239) (xy 465.086769 -92.129379) (xy 465.094351 -92.10245)
			(xy 465.094828 -92.088462) (xy 465.094828 -82.185256) (xy 464.58886 -81.679288) (xy 444.616586 -81.679288)
			(xy 441.81649 -78.879192) (xy 441.81649 -61.067442) (xy 439.7248 -58.975752) (xy 439.7248 -53.51399)
			(xy 438.8104 -52.59959) (xy 431.861722 -52.59959) (xy 431.15484 -53.306472) (xy 431.152046 -53.322728)
			(xy 431.14702 -53.349968) (xy 431.143601 -53.36032) (xy 433.236368 -53.36032) (xy 433.240439 -53.304698)
			(xy 433.252565 -53.250261) (xy 433.272488 -53.19817) (xy 433.299784 -53.149535) (xy 433.33387 -53.105392)
			(xy 433.374019 -53.066683) (xy 433.419377 -53.034232) (xy 433.468977 -53.008731) (xy 433.521761 -52.990724)
			(xy 433.576604 -52.980594) (xy 433.632338 -52.978557) (xy 433.687775 -52.984657) (xy 433.741732 -52.998763)
			(xy 433.793061 -53.020575) (xy 433.840667 -53.049629) (xy 433.883535 -53.085304) (xy 433.920752 -53.126841)
			(xy 433.951525 -53.173354) (xy 433.975197 -53.223851) (xy 433.991265 -53.277258) (xy 433.999385 -53.332434)
			(xy 433.999894 -53.36032) (xy 433.999385 -53.388206) (xy 433.991265 -53.443382) (xy 433.975197 -53.496789)
			(xy 433.951525 -53.547286) (xy 433.920752 -53.593799) (xy 433.883535 -53.635336) (xy 433.840667 -53.671011)
			(xy 433.793061 -53.700065) (xy 433.741732 -53.721877) (xy 433.687775 -53.735983) (xy 433.632338 -53.742083)
			(xy 433.576604 -53.740046) (xy 433.521761 -53.729916) (xy 433.468977 -53.711909) (xy 433.419377 -53.686408)
			(xy 433.374019 -53.653957) (xy 433.33387 -53.615248) (xy 433.299784 -53.571105) (xy 433.272488 -53.52247)
			(xy 433.252565 -53.470379) (xy 433.240439 -53.415942) (xy 433.236368 -53.36032) (xy 431.143601 -53.36032)
			(xy 431.129651 -53.402563) (xy 431.104346 -53.451834) (xy 431.071715 -53.496591) (xy 431.032545 -53.535753)
			(xy 430.987783 -53.568377) (xy 430.938508 -53.593674) (xy 430.88591 -53.611034) (xy 430.858676 -53.616098)
			(xy 430.84242 -53.618892) (xy 430.48936 -53.971952) (xy 430.486058 -53.985668) (xy 430.478903 -54.012321)
			(xy 430.457497 -54.063185) (xy 430.428503 -54.110138) (xy 430.392613 -54.152058) (xy 430.350687 -54.18794)
			(xy 430.303729 -54.216926) (xy 430.252861 -54.238323) (xy 430.226216 -54.24551) (xy 430.2125 -54.248812)
			(xy 429.65624 -54.805072) (xy 429.65624 -59.226196) (xy 429.89119 -59.226196) (xy 429.891671 -59.197277)
			(xy 429.900403 -59.140103) (xy 429.917666 -59.084902) (xy 429.943065 -59.032939) (xy 429.976016 -58.985407)
			(xy 430.015766 -58.943393) (xy 430.038256 -58.925206) (xy 430.050068 -58.915315) (xy 430.067591 -58.889991)
			(xy 430.076769 -58.860595) (xy 430.076768 -58.8298) (xy 430.067589 -58.800405) (xy 430.050065 -58.775082)
			(xy 430.038256 -58.765186) (xy 430.015757 -58.747014) (xy 429.976024 -58.704989) (xy 429.943089 -58.65745)
			(xy 429.917703 -58.605485) (xy 429.90045 -58.550285) (xy 429.891724 -58.493113) (xy 429.89119 -58.464196)
			(xy 429.891676 -58.436945) (xy 429.899432 -58.382997) (xy 429.914787 -58.330702) (xy 429.937429 -58.281125)
			(xy 429.966895 -58.235275) (xy 430.002586 -58.194084) (xy 430.043777 -58.158393) (xy 430.089627 -58.128927)
			(xy 430.139204 -58.106285) (xy 430.191499 -58.09093) (xy 430.245447 -58.083174) (xy 430.299949 -58.083174)
			(xy 430.353897 -58.09093) (xy 430.406192 -58.106285) (xy 430.455769 -58.128927) (xy 430.501619 -58.158393)
			(xy 430.54281 -58.194084) (xy 430.578501 -58.235275) (xy 430.607967 -58.281125) (xy 430.630609 -58.330702)
			(xy 430.645964 -58.382997) (xy 430.65372 -58.436945) (xy 430.654206 -58.464196) (xy 430.653721 -58.493115)
			(xy 430.64499 -58.550289) (xy 430.627728 -58.60549) (xy 430.60233 -58.657452) (xy 430.569379 -58.704985)
			(xy 430.52963 -58.746999) (xy 430.50714 -58.765186) (xy 430.495336 -58.775086) (xy 430.477814 -58.800408)
			(xy 430.468635 -58.829801) (xy 430.468635 -58.860594) (xy 430.477812 -58.889988) (xy 430.495333 -58.91531)
			(xy 430.50714 -58.925206) (xy 430.529635 -58.943384) (xy 430.556876 -58.972196) (xy 432.30368 -58.972196)
			(xy 432.307751 -58.916574) (xy 432.319877 -58.862137) (xy 432.3398 -58.810046) (xy 432.367096 -58.761411)
			(xy 432.401182 -58.717268) (xy 432.441331 -58.678559) (xy 432.486689 -58.646108) (xy 432.536289 -58.620607)
			(xy 432.589073 -58.6026) (xy 432.643916 -58.59247) (xy 432.69965 -58.590433) (xy 432.755087 -58.596533)
			(xy 432.809044 -58.610639) (xy 432.860373 -58.632451) (xy 432.907979 -58.661505) (xy 432.950847 -58.69718)
			(xy 432.988064 -58.738717) (xy 433.018837 -58.78523) (xy 433.042509 -58.835727) (xy 433.058577 -58.889134)
			(xy 433.066697 -58.94431) (xy 433.067206 -58.972196) (xy 433.066697 -59.000082) (xy 433.058577 -59.055258)
			(xy 433.042509 -59.108665) (xy 433.018837 -59.159162) (xy 432.988064 -59.205675) (xy 432.950847 -59.247212)
			(xy 432.907979 -59.282887) (xy 432.860373 -59.311941) (xy 432.809044 -59.333753) (xy 432.755087 -59.347859)
			(xy 432.69965 -59.353959) (xy 432.643916 -59.351922) (xy 432.589073 -59.341792) (xy 432.536289 -59.323785)
			(xy 432.486689 -59.298284) (xy 432.441331 -59.265833) (xy 432.401182 -59.227124) (xy 432.367096 -59.182981)
			(xy 432.3398 -59.134346) (xy 432.319877 -59.082255) (xy 432.307751 -59.027818) (xy 432.30368 -58.972196)
			(xy 430.556876 -58.972196) (xy 430.569367 -58.985407) (xy 430.602304 -59.032945) (xy 430.62769 -59.084909)
			(xy 430.644944 -59.140108) (xy 430.653672 -59.197279) (xy 430.654206 -59.226196) (xy 430.65372 -59.253447)
			(xy 430.645964 -59.307395) (xy 430.630609 -59.35969) (xy 430.607967 -59.409267) (xy 430.578501 -59.455117)
			(xy 430.54281 -59.496308) (xy 430.501619 -59.531999) (xy 430.455769 -59.561465) (xy 430.406192 -59.584107)
			(xy 430.353897 -59.599462) (xy 430.299949 -59.607218) (xy 430.245447 -59.607218) (xy 430.191499 -59.599462)
			(xy 430.139204 -59.584107) (xy 430.089627 -59.561465) (xy 430.043777 -59.531999) (xy 430.002586 -59.496308)
			(xy 429.966895 -59.455117) (xy 429.937429 -59.409267) (xy 429.914787 -59.35969) (xy 429.899432 -59.307395)
			(xy 429.891676 -59.253447) (xy 429.89119 -59.226196) (xy 429.65624 -59.226196) (xy 429.65624 -59.322716)
			(xy 433.463446 -63.129922) (xy 433.463446 -83.478116) (xy 463.981798 -83.478116) (xy 463.985869 -83.422494)
			(xy 463.997995 -83.368057) (xy 464.017918 -83.315966) (xy 464.045214 -83.267331) (xy 464.0793 -83.223188)
			(xy 464.119449 -83.184479) (xy 464.164807 -83.152028) (xy 464.214407 -83.126527) (xy 464.267191 -83.10852)
			(xy 464.322034 -83.09839) (xy 464.377768 -83.096353) (xy 464.433205 -83.102453) (xy 464.487162 -83.116559)
			(xy 464.538491 -83.138371) (xy 464.586097 -83.167425) (xy 464.628965 -83.2031) (xy 464.666182 -83.244637)
			(xy 464.696955 -83.29115) (xy 464.720627 -83.341647) (xy 464.736695 -83.395054) (xy 464.744815 -83.45023)
			(xy 464.745324 -83.478116) (xy 464.744815 -83.506002) (xy 464.736695 -83.561178) (xy 464.720627 -83.614585)
			(xy 464.696955 -83.665082) (xy 464.666182 -83.711595) (xy 464.628965 -83.753132) (xy 464.586097 -83.788807)
			(xy 464.538491 -83.817861) (xy 464.487162 -83.839673) (xy 464.433205 -83.853779) (xy 464.377768 -83.859879)
			(xy 464.322034 -83.857842) (xy 464.267191 -83.847712) (xy 464.214407 -83.829705) (xy 464.164807 -83.804204)
			(xy 464.119449 -83.771753) (xy 464.0793 -83.733044) (xy 464.045214 -83.688901) (xy 464.017918 -83.640266)
			(xy 463.997995 -83.588175) (xy 463.985869 -83.533738) (xy 463.981798 -83.478116) (xy 433.463446 -83.478116)
			(xy 433.463446 -85.574124) (xy 440.357514 -92.468192) (xy 445.845182 -92.468192) (xy 445.849253 -92.41257)
			(xy 445.861379 -92.358133) (xy 445.881302 -92.306042) (xy 445.908598 -92.257407) (xy 445.942684 -92.213264)
			(xy 445.982833 -92.174555) (xy 446.028191 -92.142104) (xy 446.077791 -92.116603) (xy 446.130575 -92.098596)
			(xy 446.185418 -92.088466) (xy 446.241152 -92.086429) (xy 446.296589 -92.092529) (xy 446.350546 -92.106635)
			(xy 446.401875 -92.128447) (xy 446.449481 -92.157501) (xy 446.492349 -92.193176) (xy 446.529566 -92.234713)
			(xy 446.560339 -92.281226) (xy 446.584011 -92.331723) (xy 446.600079 -92.38513) (xy 446.608199 -92.440306)
			(xy 446.608708 -92.468192) (xy 446.608244 -92.493592) (xy 449.330062 -92.493592) (xy 449.334133 -92.43797)
			(xy 449.346259 -92.383533) (xy 449.366182 -92.331442) (xy 449.393478 -92.282807) (xy 449.427564 -92.238664)
			(xy 449.467713 -92.199955) (xy 449.513071 -92.167504) (xy 449.562671 -92.142003) (xy 449.615455 -92.123996)
			(xy 449.670298 -92.113866) (xy 449.726032 -92.111829) (xy 449.736283 -92.112957) (xy 456.859523 -92.112957)
			(xy 456.859523 -92.058443) (xy 456.867282 -92.004484) (xy 456.882641 -91.952179) (xy 456.905288 -91.902592)
			(xy 456.934763 -91.856733) (xy 456.970464 -91.815535) (xy 457.011665 -91.779839) (xy 457.057527 -91.750369)
			(xy 457.107116 -91.727727) (xy 457.159423 -91.712373) (xy 457.213383 -91.70462) (xy 457.24064 -91.70416)
			(xy 457.266592 -91.704573) (xy 457.318016 -91.711626) (xy 457.36801 -91.725583) (xy 457.41565 -91.746187)
			(xy 457.460059 -91.773057) (xy 457.500417 -91.805697) (xy 457.518516 -91.824302) (xy 457.529321 -91.835131)
			(xy 457.555917 -91.850224) (xy 457.585785 -91.856791) (xy 457.616259 -91.854248) (xy 457.644625 -91.842821)
			(xy 457.668352 -91.823528) (xy 457.677266 -91.811094) (xy 457.692505 -91.78903) (xy 457.728155 -91.748977)
			(xy 457.769065 -91.714313) (xy 457.814428 -91.685723) (xy 457.86335 -91.663771) (xy 457.914864 -91.648889)
			(xy 457.967956 -91.641372) (xy 457.994766 -91.640914) (xy 458.022022 -91.641331) (xy 458.07598 -91.649084)
			(xy 458.128285 -91.664438) (xy 458.177872 -91.68708) (xy 458.223732 -91.716549) (xy 458.264931 -91.752245)
			(xy 458.300631 -91.793441) (xy 458.330104 -91.839298) (xy 458.35275 -91.888883) (xy 458.368109 -91.941187)
			(xy 458.375867 -91.995144) (xy 458.375867 -92.049656) (xy 458.368109 -92.103613) (xy 458.35275 -92.155917)
			(xy 458.330104 -92.205502) (xy 458.300631 -92.251359) (xy 458.264931 -92.292555) (xy 458.223732 -92.328251)
			(xy 458.177872 -92.35772) (xy 458.128285 -92.380362) (xy 458.07598 -92.395716) (xy 458.022022 -92.403469)
			(xy 457.994766 -92.40393) (xy 457.968814 -92.403516) (xy 457.91739 -92.396464) (xy 457.867396 -92.382507)
			(xy 457.819755 -92.361904) (xy 457.775346 -92.335034) (xy 457.734989 -92.302393) (xy 457.71689 -92.283788)
			(xy 457.706091 -92.272949) (xy 457.679495 -92.257841) (xy 457.649623 -92.251265) (xy 457.619141 -92.253809)
			(xy 457.590772 -92.265246) (xy 457.567048 -92.284554) (xy 457.55814 -92.296996) (xy 457.542894 -92.319055)
			(xy 457.507246 -92.359109) (xy 457.466337 -92.393773) (xy 457.420975 -92.422364) (xy 457.372054 -92.444317)
			(xy 457.320541 -92.459199) (xy 457.26745 -92.466718) (xy 457.24064 -92.467176) (xy 457.213383 -92.46678)
			(xy 457.159423 -92.459027) (xy 457.107116 -92.443673) (xy 457.057527 -92.421031) (xy 457.011665 -92.391561)
			(xy 456.970464 -92.355865) (xy 456.934763 -92.314667) (xy 456.905288 -92.268809) (xy 456.882641 -92.219221)
			(xy 456.867282 -92.166916) (xy 456.859523 -92.112957) (xy 449.736283 -92.112957) (xy 449.781469 -92.117929)
			(xy 449.835426 -92.132035) (xy 449.886755 -92.153847) (xy 449.934361 -92.182901) (xy 449.977229 -92.218576)
			(xy 450.014446 -92.260113) (xy 450.045219 -92.306626) (xy 450.068891 -92.357123) (xy 450.084959 -92.41053)
			(xy 450.093079 -92.465706) (xy 450.093588 -92.493592) (xy 450.093079 -92.521478) (xy 450.084959 -92.576654)
			(xy 450.068891 -92.630061) (xy 450.045219 -92.680558) (xy 450.014446 -92.727071) (xy 449.977229 -92.768608)
			(xy 449.934361 -92.804283) (xy 449.886755 -92.833337) (xy 449.835426 -92.855149) (xy 449.781469 -92.869255)
			(xy 449.726032 -92.875355) (xy 449.670298 -92.873318) (xy 449.615455 -92.863188) (xy 449.562671 -92.845181)
			(xy 449.513071 -92.81968) (xy 449.467713 -92.787229) (xy 449.427564 -92.74852) (xy 449.393478 -92.704377)
			(xy 449.366182 -92.655742) (xy 449.346259 -92.603651) (xy 449.334133 -92.549214) (xy 449.330062 -92.493592)
			(xy 446.608244 -92.493592) (xy 446.608199 -92.496078) (xy 446.600079 -92.551254) (xy 446.584011 -92.604661)
			(xy 446.560339 -92.655158) (xy 446.529566 -92.701671) (xy 446.492349 -92.743208) (xy 446.449481 -92.778883)
			(xy 446.401875 -92.807937) (xy 446.350546 -92.829749) (xy 446.296589 -92.843855) (xy 446.241152 -92.849955)
			(xy 446.185418 -92.847918) (xy 446.130575 -92.837788) (xy 446.077791 -92.819781) (xy 446.028191 -92.79428)
			(xy 445.982833 -92.761829) (xy 445.942684 -92.72312) (xy 445.908598 -92.678977) (xy 445.881302 -92.630342)
			(xy 445.861379 -92.578251) (xy 445.849253 -92.523814) (xy 445.845182 -92.468192) (xy 440.357514 -92.468192)
			(xy 441.066428 -93.177106) (xy 441.09894 -93.161612) (xy 441.124832 -93.149757) (xy 441.179256 -93.133005)
			(xy 441.235568 -93.124537) (xy 441.26404 -93.12402) (xy 441.291289 -93.124509) (xy 441.34523 -93.13227)
			(xy 441.397519 -93.147629) (xy 441.447089 -93.170273) (xy 441.492932 -93.199741) (xy 441.534116 -93.235433)
			(xy 441.5698 -93.276622) (xy 441.59926 -93.322471) (xy 441.621895 -93.372045) (xy 441.637244 -93.424336)
			(xy 441.644996 -93.478279) (xy 441.645116 -93.484192) (xy 445.845182 -93.484192) (xy 445.849253 -93.42857)
			(xy 445.861379 -93.374133) (xy 445.881302 -93.322042) (xy 445.908598 -93.273407) (xy 445.942684 -93.229264)
			(xy 445.982833 -93.190555) (xy 446.028191 -93.158104) (xy 446.077791 -93.132603) (xy 446.130575 -93.114596)
			(xy 446.185418 -93.104466) (xy 446.241152 -93.102429) (xy 446.296589 -93.108529) (xy 446.350546 -93.122635)
			(xy 446.401875 -93.144447) (xy 446.449481 -93.173501) (xy 446.492349 -93.209176) (xy 446.529566 -93.250713)
			(xy 446.560339 -93.297226) (xy 446.584011 -93.347723) (xy 446.600079 -93.40113) (xy 446.608199 -93.456306)
			(xy 446.608708 -93.484192) (xy 446.608244 -93.509592) (xy 449.330062 -93.509592) (xy 449.334133 -93.45397)
			(xy 449.346259 -93.399533) (xy 449.366182 -93.347442) (xy 449.393478 -93.298807) (xy 449.427564 -93.254664)
			(xy 449.467713 -93.215955) (xy 449.513071 -93.183504) (xy 449.562671 -93.158003) (xy 449.615455 -93.139996)
			(xy 449.670298 -93.129866) (xy 449.726032 -93.127829) (xy 449.781469 -93.133929) (xy 449.835426 -93.148035)
			(xy 449.886755 -93.169847) (xy 449.934361 -93.198901) (xy 449.977229 -93.234576) (xy 450.014446 -93.276113)
			(xy 450.045219 -93.322626) (xy 450.068891 -93.373123) (xy 450.07579 -93.396054) (xy 464.190586 -93.396054)
			(xy 464.194657 -93.340432) (xy 464.206783 -93.285995) (xy 464.226706 -93.233904) (xy 464.254002 -93.185269)
			(xy 464.288088 -93.141126) (xy 464.328237 -93.102417) (xy 464.373595 -93.069966) (xy 464.423195 -93.044465)
			(xy 464.475979 -93.026458) (xy 464.530822 -93.016328) (xy 464.586556 -93.014291) (xy 464.641993 -93.020391)
			(xy 464.69595 -93.034497) (xy 464.747279 -93.056309) (xy 464.794885 -93.085363) (xy 464.837753 -93.121038)
			(xy 464.87497 -93.162575) (xy 464.905743 -93.209088) (xy 464.929415 -93.259585) (xy 464.945483 -93.312992)
			(xy 464.953603 -93.368168) (xy 464.954112 -93.396054) (xy 464.953603 -93.42394) (xy 464.945483 -93.479116)
			(xy 464.929415 -93.532523) (xy 464.905743 -93.58302) (xy 464.87497 -93.629533) (xy 464.837753 -93.67107)
			(xy 464.794885 -93.706745) (xy 464.747279 -93.735799) (xy 464.69595 -93.757611) (xy 464.641993 -93.771717)
			(xy 464.586556 -93.777817) (xy 464.530822 -93.77578) (xy 464.475979 -93.76565) (xy 464.423195 -93.747643)
			(xy 464.373595 -93.722142) (xy 464.328237 -93.689691) (xy 464.288088 -93.650982) (xy 464.254002 -93.606839)
			(xy 464.226706 -93.558204) (xy 464.206783 -93.506113) (xy 464.194657 -93.451676) (xy 464.190586 -93.396054)
			(xy 450.07579 -93.396054) (xy 450.084959 -93.42653) (xy 450.093079 -93.481706) (xy 450.093588 -93.509592)
			(xy 450.093079 -93.537478) (xy 450.084959 -93.592654) (xy 450.068891 -93.646061) (xy 450.045219 -93.696558)
			(xy 450.014446 -93.743071) (xy 449.977229 -93.784608) (xy 449.934361 -93.820283) (xy 449.886755 -93.849337)
			(xy 449.835426 -93.871149) (xy 449.781469 -93.885255) (xy 449.726032 -93.891355) (xy 449.670298 -93.889318)
			(xy 449.615455 -93.879188) (xy 449.562671 -93.861181) (xy 449.513071 -93.83568) (xy 449.467713 -93.803229)
			(xy 449.427564 -93.76452) (xy 449.393478 -93.720377) (xy 449.366182 -93.671742) (xy 449.346259 -93.619651)
			(xy 449.334133 -93.565214) (xy 449.330062 -93.509592) (xy 446.608244 -93.509592) (xy 446.608199 -93.512078)
			(xy 446.600079 -93.567254) (xy 446.584011 -93.620661) (xy 446.560339 -93.671158) (xy 446.529566 -93.717671)
			(xy 446.492349 -93.759208) (xy 446.449481 -93.794883) (xy 446.401875 -93.823937) (xy 446.350546 -93.845749)
			(xy 446.296589 -93.859855) (xy 446.241152 -93.865955) (xy 446.185418 -93.863918) (xy 446.130575 -93.853788)
			(xy 446.077791 -93.835781) (xy 446.028191 -93.81028) (xy 445.982833 -93.777829) (xy 445.942684 -93.73912)
			(xy 445.908598 -93.694977) (xy 445.881302 -93.646342) (xy 445.861379 -93.594251) (xy 445.849253 -93.539814)
			(xy 445.845182 -93.484192) (xy 441.645116 -93.484192) (xy 441.645548 -93.505528) (xy 441.645018 -93.533999)
			(xy 441.636549 -93.590309) (xy 441.619804 -93.644733) (xy 441.607956 -93.670628) (xy 441.592462 -93.70314)
			(xy 442.49213 -94.602808) (xy 445.878964 -94.602808) (xy 445.883035 -94.547186) (xy 445.895161 -94.492749)
			(xy 445.915084 -94.440658) (xy 445.94238 -94.392023) (xy 445.976466 -94.34788) (xy 446.016615 -94.309171)
			(xy 446.061973 -94.27672) (xy 446.111573 -94.251219) (xy 446.164357 -94.233212) (xy 446.2192 -94.223082)
			(xy 446.274934 -94.221045) (xy 446.330371 -94.227145) (xy 446.384328 -94.241251) (xy 446.435657 -94.263063)
			(xy 446.483263 -94.292117) (xy 446.526131 -94.327792) (xy 446.563348 -94.369329) (xy 446.594121 -94.415842)
			(xy 446.617793 -94.466339) (xy 446.633861 -94.519746) (xy 446.641981 -94.574922) (xy 446.64249 -94.602808)
			(xy 449.269102 -94.602808) (xy 449.273173 -94.547186) (xy 449.285299 -94.492749) (xy 449.305222 -94.440658)
			(xy 449.332518 -94.392023) (xy 449.366604 -94.34788) (xy 449.406753 -94.309171) (xy 449.452111 -94.27672)
			(xy 449.501711 -94.251219) (xy 449.554495 -94.233212) (xy 449.609338 -94.223082) (xy 449.665072 -94.221045)
			(xy 449.720509 -94.227145) (xy 449.774466 -94.241251) (xy 449.825795 -94.263063) (xy 449.873401 -94.292117)
			(xy 449.916269 -94.327792) (xy 449.953486 -94.369329) (xy 449.984259 -94.415842) (xy 450.007931 -94.466339)
			(xy 450.023999 -94.519746) (xy 450.032119 -94.574922) (xy 450.032628 -94.602808) (xy 450.032119 -94.630694)
			(xy 450.023999 -94.68587) (xy 450.007931 -94.739277) (xy 449.984259 -94.789774) (xy 449.953486 -94.836287)
			(xy 449.916269 -94.877824) (xy 449.873401 -94.913499) (xy 449.825795 -94.942553) (xy 449.774466 -94.964365)
			(xy 449.720509 -94.978471) (xy 449.707949 -94.979853) (xy 461.176844 -94.979853) (xy 461.176844 -94.925347)
			(xy 461.1846 -94.871397) (xy 461.199956 -94.819099) (xy 461.222597 -94.769519) (xy 461.252064 -94.723665)
			(xy 461.287757 -94.682472) (xy 461.328948 -94.646777) (xy 461.3748 -94.617308) (xy 461.424378 -94.594664)
			(xy 461.476675 -94.579305) (xy 461.530625 -94.571545) (xy 461.557878 -94.571058) (xy 461.584483 -94.571498)
			(xy 461.637177 -94.578878) (xy 461.688334 -94.593512) (xy 461.73696 -94.615115) (xy 461.78211 -94.643269)
			(xy 461.822909 -94.677426) (xy 461.858563 -94.716922) (xy 461.873854 -94.738698) (xy 461.882188 -94.750178)
			(xy 461.903932 -94.768382) (xy 461.929845 -94.7799) (xy 461.957928 -94.78384) (xy 461.986011 -94.7799)
			(xy 462.011924 -94.768382) (xy 462.033668 -94.750178) (xy 462.042002 -94.738698) (xy 462.057302 -94.716931)
			(xy 462.092965 -94.677449) (xy 462.133767 -94.643304) (xy 462.178916 -94.615157) (xy 462.227537 -94.593554)
			(xy 462.278688 -94.578914) (xy 462.331376 -94.571521) (xy 462.357978 -94.571058) (xy 462.385229 -94.571588)
			(xy 462.439178 -94.579341) (xy 462.491474 -94.594694) (xy 462.541052 -94.617333) (xy 462.586904 -94.646798)
			(xy 462.628096 -94.682489) (xy 462.663789 -94.723678) (xy 462.693256 -94.769528) (xy 462.715898 -94.819106)
			(xy 462.731254 -94.871401) (xy 462.739011 -94.925349) (xy 462.739011 -94.979851) (xy 462.731254 -95.033799)
			(xy 462.715898 -95.086094) (xy 462.693256 -95.135672) (xy 462.663789 -95.181522) (xy 462.628096 -95.222711)
			(xy 462.586904 -95.258402) (xy 462.541052 -95.287867) (xy 462.491474 -95.310506) (xy 462.439178 -95.325859)
			(xy 462.385229 -95.333612) (xy 462.357978 -95.334074) (xy 462.331373 -95.333653) (xy 462.278678 -95.326268)
			(xy 462.227521 -95.31163) (xy 462.178896 -95.290023) (xy 462.133746 -95.261867) (xy 462.092948 -95.227708)
			(xy 462.057294 -95.18821) (xy 462.042002 -95.166434) (xy 462.033668 -95.154954) (xy 462.011924 -95.13675)
			(xy 461.986011 -95.125232) (xy 461.957928 -95.121292) (xy 461.929845 -95.125232) (xy 461.903932 -95.13675)
			(xy 461.882188 -95.154954) (xy 461.873854 -95.166434) (xy 461.858529 -95.188182) (xy 461.822868 -95.227663)
			(xy 461.782071 -95.261809) (xy 461.736926 -95.289957) (xy 461.688309 -95.311563) (xy 461.637163 -95.326208)
			(xy 461.584479 -95.333608) (xy 461.557878 -95.334074) (xy 461.530625 -95.333655) (xy 461.476675 -95.325895)
			(xy 461.424378 -95.310536) (xy 461.3748 -95.287892) (xy 461.328948 -95.258423) (xy 461.287757 -95.222728)
			(xy 461.252064 -95.181535) (xy 461.222597 -95.135681) (xy 461.199956 -95.086101) (xy 461.1846 -95.033803)
			(xy 461.176844 -94.979853) (xy 449.707949 -94.979853) (xy 449.665072 -94.984571) (xy 449.609338 -94.982534)
			(xy 449.554495 -94.972404) (xy 449.501711 -94.954397) (xy 449.452111 -94.928896) (xy 449.406753 -94.896445)
			(xy 449.366604 -94.857736) (xy 449.332518 -94.813593) (xy 449.305222 -94.764958) (xy 449.285299 -94.712867)
			(xy 449.273173 -94.65843) (xy 449.269102 -94.602808) (xy 446.64249 -94.602808) (xy 446.641981 -94.630694)
			(xy 446.633861 -94.68587) (xy 446.617793 -94.739277) (xy 446.594121 -94.789774) (xy 446.563348 -94.836287)
			(xy 446.526131 -94.877824) (xy 446.483263 -94.913499) (xy 446.435657 -94.942553) (xy 446.384328 -94.964365)
			(xy 446.330371 -94.978471) (xy 446.274934 -94.984571) (xy 446.2192 -94.982534) (xy 446.164357 -94.972404)
			(xy 446.111573 -94.954397) (xy 446.061973 -94.928896) (xy 446.016615 -94.896445) (xy 445.976466 -94.857736)
			(xy 445.94238 -94.813593) (xy 445.915084 -94.764958) (xy 445.895161 -94.712867) (xy 445.883035 -94.65843)
			(xy 445.878964 -94.602808) (xy 442.49213 -94.602808) (xy 444.104776 -96.215454) (xy 444.133986 -96.206818)
			(xy 444.160675 -96.199365) (xy 444.215501 -96.191337) (xy 444.243206 -96.190816) (xy 444.270458 -96.19128)
			(xy 444.324407 -96.199038) (xy 444.376703 -96.214394) (xy 444.426281 -96.237038) (xy 444.472131 -96.266506)
			(xy 444.513321 -96.3022) (xy 444.549012 -96.343393) (xy 444.578477 -96.389246) (xy 444.601116 -96.438825)
			(xy 444.616469 -96.491122) (xy 444.624222 -96.545072) (xy 444.624714 -96.572324) (xy 444.624218 -96.600031)
			(xy 444.617407 -96.646492) (xy 448.88277 -96.646492) (xy 448.883138 -96.61975) (xy 448.890634 -96.566795)
			(xy 448.905451 -96.515405) (xy 448.927298 -96.466587) (xy 448.955748 -96.421297) (xy 448.990242 -96.380424)
			(xy 449.030105 -96.344767) (xy 449.074556 -96.315025) (xy 449.122725 -96.291781) (xy 449.173667 -96.27549)
			(xy 449.226385 -96.266472) (xy 449.253102 -96.265238) (xy 449.267008 -96.264343) (xy 449.293598 -96.256057)
			(xy 449.316961 -96.240896) (xy 449.335359 -96.219988) (xy 449.347426 -96.194886) (xy 449.352263 -96.167458)
			(xy 449.34951 -96.139743) (xy 449.339373 -96.113803) (xy 449.331334 -96.102424) (xy 449.313237 -96.077467)
			(xy 449.284519 -96.022919) (xy 449.264933 -95.964468) (xy 449.254986 -95.90363) (xy 449.254372 -95.872808)
			(xy 449.254858 -95.845557) (xy 449.262614 -95.791609) (xy 449.277969 -95.739314) (xy 449.300611 -95.689737)
			(xy 449.330077 -95.643887) (xy 449.365768 -95.602696) (xy 449.406959 -95.567005) (xy 449.452809 -95.537539)
			(xy 449.502386 -95.514897) (xy 449.554681 -95.499542) (xy 449.608629 -95.491786) (xy 449.663131 -95.491786)
			(xy 449.717079 -95.499542) (xy 449.769374 -95.514897) (xy 449.818951 -95.537539) (xy 449.864801 -95.567005)
			(xy 449.905992 -95.602696) (xy 449.941683 -95.643887) (xy 449.971149 -95.689737) (xy 449.993791 -95.739314)
			(xy 450.009146 -95.791609) (xy 450.016902 -95.845557) (xy 450.017388 -95.872808) (xy 450.016964 -95.899547)
			(xy 450.009469 -95.952498) (xy 449.994655 -96.003884) (xy 449.972812 -96.052698) (xy 449.944368 -96.097985)
			(xy 449.90988 -96.138857) (xy 449.870023 -96.174514) (xy 449.825579 -96.204257) (xy 449.777417 -96.227504)
			(xy 449.726482 -96.243799) (xy 449.67377 -96.252824) (xy 449.647056 -96.254062) (xy 449.633149 -96.25493)
			(xy 449.606561 -96.263225) (xy 449.583202 -96.278392) (xy 449.564806 -96.299304) (xy 449.552741 -96.324408)
			(xy 449.547904 -96.351836) (xy 449.550654 -96.379552) (xy 449.560787 -96.405495) (xy 449.568824 -96.416876)
			(xy 449.586916 -96.441837) (xy 449.615636 -96.496383) (xy 449.635224 -96.554833) (xy 449.645172 -96.61567)
			(xy 449.645786 -96.646492) (xy 449.645194 -96.676267) (xy 449.63588 -96.735085) (xy 449.627244 -96.763586)
			(xy 449.623335 -96.777461) (xy 449.622557 -96.806264) (xy 449.629839 -96.834141) (xy 449.644606 -96.858883)
			(xy 449.665686 -96.878526) (xy 449.691406 -96.891512) (xy 449.705476 -96.89465) (xy 449.73143 -96.899908)
			(xy 449.781658 -96.916684) (xy 449.829083 -96.940244) (xy 449.872795 -96.970136) (xy 449.911954 -97.005785)
			(xy 449.945808 -97.046506) (xy 449.973706 -97.091517) (xy 449.995112 -97.139953) (xy 450.009615 -97.190884)
			(xy 450.016936 -97.24333) (xy 450.017388 -97.269808) (xy 450.016902 -97.297059) (xy 450.009146 -97.351007)
			(xy 449.993791 -97.403302) (xy 449.971149 -97.452879) (xy 449.941683 -97.498729) (xy 449.905992 -97.53992)
			(xy 449.864801 -97.575611) (xy 449.818951 -97.605077) (xy 449.769374 -97.627719) (xy 449.717079 -97.643074)
			(xy 449.663131 -97.65083) (xy 449.608629 -97.65083) (xy 449.554681 -97.643074) (xy 449.502386 -97.627719)
			(xy 449.452809 -97.605077) (xy 449.406959 -97.575611) (xy 449.365768 -97.53992) (xy 449.330077 -97.498729)
			(xy 449.300611 -97.452879) (xy 449.277969 -97.403302) (xy 449.262614 -97.351007) (xy 449.254858 -97.297059)
			(xy 449.254372 -97.269808) (xy 449.254962 -97.240033) (xy 449.264277 -97.181215) (xy 449.272914 -97.152714)
			(xy 449.276856 -97.138846) (xy 449.277636 -97.110036) (xy 449.27035 -97.082152) (xy 449.255576 -97.057407)
			(xy 449.234487 -97.037765) (xy 449.208756 -97.024783) (xy 449.194682 -97.02165) (xy 449.168722 -97.016423)
			(xy 449.118494 -96.999641) (xy 449.071069 -96.976076) (xy 449.027357 -96.94618) (xy 448.988199 -96.910528)
			(xy 448.954347 -96.869804) (xy 448.92645 -96.82479) (xy 448.905045 -96.776352) (xy 448.890543 -96.725419)
			(xy 448.883222 -96.672971) (xy 448.88277 -96.646492) (xy 444.617407 -96.646492) (xy 444.61618 -96.654858)
			(xy 444.608712 -96.681544) (xy 444.600076 -96.710754) (xy 445.87033 -97.981008) (xy 445.87033 -98.180144)
			(xy 454.657458 -98.180144) (xy 454.661529 -98.124522) (xy 454.673655 -98.070085) (xy 454.693578 -98.017994)
			(xy 454.720874 -97.969359) (xy 454.75496 -97.925216) (xy 454.795109 -97.886507) (xy 454.840467 -97.854056)
			(xy 454.890067 -97.828555) (xy 454.942851 -97.810548) (xy 454.997694 -97.800418) (xy 455.053428 -97.798381)
			(xy 455.108865 -97.804481) (xy 455.162822 -97.818587) (xy 455.214151 -97.840399) (xy 455.261757 -97.869453)
			(xy 455.304625 -97.905128) (xy 455.341842 -97.946665) (xy 455.372615 -97.993178) (xy 455.396287 -98.043675)
			(xy 455.412355 -98.097082) (xy 455.420475 -98.152258) (xy 455.420984 -98.180144) (xy 455.420475 -98.20803)
			(xy 455.412355 -98.263206) (xy 455.396287 -98.316613) (xy 455.38488 -98.340946) (xy 456.905426 -98.340946)
			(xy 456.905426 -98.286454) (xy 456.913181 -98.232517) (xy 456.928532 -98.180232) (xy 456.951167 -98.130663)
			(xy 456.980626 -98.084821) (xy 457.016309 -98.043637) (xy 457.057489 -98.00795) (xy 457.103328 -97.978486)
			(xy 457.152894 -97.955846) (xy 457.205178 -97.940489) (xy 457.259114 -97.932729) (xy 457.28636 -97.93224)
			(xy 457.309885 -97.932554) (xy 457.356583 -97.938281) (xy 457.402218 -97.949727) (xy 457.424282 -97.957894)
			(xy 457.437571 -97.962579) (xy 457.465619 -97.965171) (xy 457.493308 -97.959999) (xy 457.51853 -97.947457)
			(xy 457.539363 -97.928499) (xy 457.554222 -97.904569) (xy 457.561975 -97.877489) (xy 457.562458 -97.863406)
			(xy 457.563069 -97.836205) (xy 457.570939 -97.782371) (xy 457.586377 -97.730201) (xy 457.609071 -97.680754)
			(xy 457.638559 -97.635033) (xy 457.674244 -97.593965) (xy 457.715402 -97.558383) (xy 457.761197 -97.52901)
			(xy 457.810701 -97.506441) (xy 457.86291 -97.491134) (xy 457.916763 -97.483399) (xy 457.943966 -97.482914)
			(xy 457.971222 -97.483331) (xy 458.02518 -97.491084) (xy 458.077485 -97.506438) (xy 458.127072 -97.52908)
			(xy 458.172932 -97.558549) (xy 458.214131 -97.594245) (xy 458.249831 -97.635441) (xy 458.279304 -97.681298)
			(xy 458.30195 -97.730883) (xy 458.317309 -97.783187) (xy 458.325067 -97.837144) (xy 458.325067 -97.891656)
			(xy 458.317309 -97.945613) (xy 458.30195 -97.997917) (xy 458.279304 -98.047502) (xy 458.249831 -98.093359)
			(xy 458.214131 -98.134555) (xy 458.172932 -98.170251) (xy 458.127072 -98.19972) (xy 458.077485 -98.222362)
			(xy 458.02518 -98.237716) (xy 457.971222 -98.245469) (xy 457.943966 -98.24593) (xy 457.920442 -98.245604)
			(xy 457.873744 -98.239881) (xy 457.828108 -98.22844) (xy 457.806044 -98.220276) (xy 457.792738 -98.21565)
			(xy 457.764699 -98.213054) (xy 457.737019 -98.218219) (xy 457.711803 -98.230752) (xy 457.690972 -98.249699)
			(xy 457.676113 -98.273617) (xy 457.668355 -98.300686) (xy 457.667868 -98.314764) (xy 457.667396 -98.341971)
			(xy 457.659515 -98.395814) (xy 457.644064 -98.44799) (xy 457.621357 -98.497442) (xy 457.591854 -98.543167)
			(xy 457.556154 -98.584236) (xy 457.514982 -98.619817) (xy 457.469172 -98.649187) (xy 457.419655 -98.671751)
			(xy 457.367433 -98.687051) (xy 457.313568 -98.694776) (xy 457.28636 -98.695256) (xy 457.259114 -98.694671)
			(xy 457.205178 -98.686911) (xy 457.152894 -98.671554) (xy 457.103328 -98.648914) (xy 457.057489 -98.61945)
			(xy 457.016309 -98.583763) (xy 456.980626 -98.542579) (xy 456.951167 -98.496737) (xy 456.928532 -98.447168)
			(xy 456.913181 -98.394883) (xy 456.905426 -98.340946) (xy 455.38488 -98.340946) (xy 455.372615 -98.36711)
			(xy 455.341842 -98.413623) (xy 455.304625 -98.45516) (xy 455.261757 -98.490835) (xy 455.214151 -98.519889)
			(xy 455.162822 -98.541701) (xy 455.108865 -98.555807) (xy 455.053428 -98.561907) (xy 454.997694 -98.55987)
			(xy 454.942851 -98.54974) (xy 454.890067 -98.531733) (xy 454.840467 -98.506232) (xy 454.795109 -98.473781)
			(xy 454.75496 -98.435072) (xy 454.720874 -98.390929) (xy 454.693578 -98.342294) (xy 454.673655 -98.290203)
			(xy 454.661529 -98.235766) (xy 454.657458 -98.180144) (xy 445.87033 -98.180144) (xy 445.87033 -101.13245)
			(xy 461.135486 -101.13245) (xy 461.135486 -101.07795) (xy 461.143241 -101.024006) (xy 461.158595 -100.971714)
			(xy 461.181234 -100.92214) (xy 461.210697 -100.876291) (xy 461.246386 -100.835103) (xy 461.287572 -100.799412)
			(xy 461.333418 -100.769945) (xy 461.382992 -100.747303) (xy 461.435282 -100.731947) (xy 461.489226 -100.724187)
			(xy 461.516476 -100.7237) (xy 461.543079 -100.724167) (xy 461.595772 -100.731546) (xy 461.646927 -100.746177)
			(xy 461.695552 -100.767776) (xy 461.740702 -100.795925) (xy 461.781502 -100.830076) (xy 461.817159 -100.869567)
			(xy 461.832452 -100.89134) (xy 461.840786 -100.90282) (xy 461.86253 -100.921024) (xy 461.888443 -100.932542)
			(xy 461.916526 -100.936482) (xy 461.944609 -100.932542) (xy 461.970522 -100.921024) (xy 461.992266 -100.90282)
			(xy 462.0006 -100.89134) (xy 462.015883 -100.869561) (xy 462.051551 -100.830082) (xy 462.092357 -100.795939)
			(xy 462.137509 -100.767795) (xy 462.186132 -100.746194) (xy 462.237284 -100.731555) (xy 462.289973 -100.724163)
			(xy 462.316576 -100.7237) (xy 462.343831 -100.724146) (xy 462.397785 -100.7319) (xy 462.450087 -100.747254)
			(xy 462.499671 -100.769896) (xy 462.545528 -100.799364) (xy 462.586725 -100.835058) (xy 462.622422 -100.876252)
			(xy 462.651893 -100.922108) (xy 462.674537 -100.97169) (xy 462.689895 -101.023991) (xy 462.697653 -101.077945)
			(xy 462.697653 -101.132455) (xy 462.689895 -101.186409) (xy 462.674537 -101.23871) (xy 462.651893 -101.288292)
			(xy 462.622422 -101.334148) (xy 462.586725 -101.375342) (xy 462.545528 -101.411036) (xy 462.499671 -101.440504)
			(xy 462.450087 -101.463146) (xy 462.397785 -101.4785) (xy 462.343831 -101.486254) (xy 462.316576 -101.486716)
			(xy 462.289972 -101.486278) (xy 462.237278 -101.478894) (xy 462.186123 -101.464257) (xy 462.137498 -101.442652)
			(xy 462.092348 -101.414499) (xy 462.051549 -101.380344) (xy 462.015893 -101.34085) (xy 462.0006 -101.319076)
			(xy 461.992266 -101.307596) (xy 461.970522 -101.289392) (xy 461.944609 -101.277874) (xy 461.916526 -101.273934)
			(xy 461.888443 -101.277874) (xy 461.86253 -101.289392) (xy 461.840786 -101.307596) (xy 461.832452 -101.319076)
			(xy 461.817141 -101.340834) (xy 461.781477 -101.380313) (xy 461.740676 -101.414457) (xy 461.695529 -101.442603)
			(xy 461.64691 -101.464208) (xy 461.595763 -101.478851) (xy 461.543077 -101.48625) (xy 461.516476 -101.486716)
			(xy 461.489226 -101.486213) (xy 461.435282 -101.478453) (xy 461.382992 -101.463097) (xy 461.333418 -101.440455)
			(xy 461.287572 -101.410988) (xy 461.246386 -101.375297) (xy 461.210697 -101.334109) (xy 461.181234 -101.28826)
			(xy 461.158595 -101.238686) (xy 461.143241 -101.186394) (xy 461.135486 -101.13245) (xy 445.87033 -101.13245)
			(xy 445.87033 -102.598728) (xy 452.328278 -102.598728) (xy 452.332349 -102.543106) (xy 452.344475 -102.488669)
			(xy 452.364398 -102.436578) (xy 452.391694 -102.387943) (xy 452.42578 -102.3438) (xy 452.465929 -102.305091)
			(xy 452.511287 -102.27264) (xy 452.560887 -102.247139) (xy 452.613671 -102.229132) (xy 452.668514 -102.219002)
			(xy 452.724248 -102.216965) (xy 452.779685 -102.223065) (xy 452.833642 -102.237171) (xy 452.884971 -102.258983)
			(xy 452.932577 -102.288037) (xy 452.975445 -102.323712) (xy 453.012662 -102.365249) (xy 453.043435 -102.411762)
			(xy 453.067107 -102.462259) (xy 453.083175 -102.515666) (xy 453.091295 -102.570842) (xy 453.091804 -102.598728)
			(xy 454.91476 -102.598728) (xy 454.918831 -102.543106) (xy 454.930957 -102.488669) (xy 454.95088 -102.436578)
			(xy 454.978176 -102.387943) (xy 455.012262 -102.3438) (xy 455.052411 -102.305091) (xy 455.097769 -102.27264)
			(xy 455.147369 -102.247139) (xy 455.200153 -102.229132) (xy 455.254996 -102.219002) (xy 455.31073 -102.216965)
			(xy 455.366167 -102.223065) (xy 455.420124 -102.237171) (xy 455.471453 -102.258983) (xy 455.519059 -102.288037)
			(xy 455.561927 -102.323712) (xy 455.599144 -102.365249) (xy 455.629917 -102.411762) (xy 455.653589 -102.462259)
			(xy 455.669657 -102.515666) (xy 455.677777 -102.570842) (xy 455.678286 -102.598728) (xy 455.677777 -102.626614)
			(xy 455.669657 -102.68179) (xy 455.653589 -102.735197) (xy 455.629917 -102.785694) (xy 455.599144 -102.832207)
			(xy 455.561927 -102.873744) (xy 455.519059 -102.909419) (xy 455.471453 -102.938473) (xy 455.420124 -102.960285)
			(xy 455.366167 -102.974391) (xy 455.31073 -102.980491) (xy 455.254996 -102.978454) (xy 455.200153 -102.968324)
			(xy 455.147369 -102.950317) (xy 455.097769 -102.924816) (xy 455.052411 -102.892365) (xy 455.012262 -102.853656)
			(xy 454.978176 -102.809513) (xy 454.95088 -102.760878) (xy 454.930957 -102.708787) (xy 454.918831 -102.65435)
			(xy 454.91476 -102.598728) (xy 453.091804 -102.598728) (xy 453.091295 -102.626614) (xy 453.083175 -102.68179)
			(xy 453.067107 -102.735197) (xy 453.043435 -102.785694) (xy 453.012662 -102.832207) (xy 452.975445 -102.873744)
			(xy 452.932577 -102.909419) (xy 452.884971 -102.938473) (xy 452.833642 -102.960285) (xy 452.779685 -102.974391)
			(xy 452.724248 -102.980491) (xy 452.668514 -102.978454) (xy 452.613671 -102.968324) (xy 452.560887 -102.950317)
			(xy 452.511287 -102.924816) (xy 452.465929 -102.892365) (xy 452.42578 -102.853656) (xy 452.391694 -102.809513)
			(xy 452.364398 -102.760878) (xy 452.344475 -102.708787) (xy 452.332349 -102.65435) (xy 452.328278 -102.598728)
			(xy 445.87033 -102.598728) (xy 445.87033 -103.646224) (xy 455.669648 -103.646224) (xy 455.673719 -103.590602)
			(xy 455.685845 -103.536165) (xy 455.705768 -103.484074) (xy 455.733064 -103.435439) (xy 455.76715 -103.391296)
			(xy 455.807299 -103.352587) (xy 455.852657 -103.320136) (xy 455.902257 -103.294635) (xy 455.955041 -103.276628)
			(xy 456.009884 -103.266498) (xy 456.065618 -103.264461) (xy 456.121055 -103.270561) (xy 456.175012 -103.284667)
			(xy 456.226341 -103.306479) (xy 456.273947 -103.335533) (xy 456.316815 -103.371208) (xy 456.354032 -103.412745)
			(xy 456.384805 -103.459258) (xy 456.408477 -103.509755) (xy 456.424545 -103.563162) (xy 456.432665 -103.618338)
			(xy 456.433174 -103.646224) (xy 456.432665 -103.67411) (xy 456.424545 -103.729286) (xy 456.408477 -103.782693)
			(xy 456.384805 -103.83319) (xy 456.354032 -103.879703) (xy 456.316815 -103.92124) (xy 456.273947 -103.956915)
			(xy 456.226341 -103.985969) (xy 456.175012 -104.007781) (xy 456.121055 -104.021887) (xy 456.065618 -104.027987)
			(xy 456.009884 -104.02595) (xy 455.955041 -104.01582) (xy 455.902257 -103.997813) (xy 455.852657 -103.972312)
			(xy 455.807299 -103.939861) (xy 455.76715 -103.901152) (xy 455.733064 -103.857009) (xy 455.705768 -103.808374)
			(xy 455.685845 -103.756283) (xy 455.673719 -103.701846) (xy 455.669648 -103.646224) (xy 445.87033 -103.646224)
			(xy 445.87033 -104.249728) (xy 452.328278 -104.249728) (xy 452.332349 -104.194106) (xy 452.344475 -104.139669)
			(xy 452.364398 -104.087578) (xy 452.391694 -104.038943) (xy 452.42578 -103.9948) (xy 452.465929 -103.956091)
			(xy 452.511287 -103.92364) (xy 452.560887 -103.898139) (xy 452.613671 -103.880132) (xy 452.668514 -103.870002)
			(xy 452.724248 -103.867965) (xy 452.779685 -103.874065) (xy 452.833642 -103.888171) (xy 452.884971 -103.909983)
			(xy 452.932577 -103.939037) (xy 452.975445 -103.974712) (xy 453.012662 -104.016249) (xy 453.043435 -104.062762)
			(xy 453.067107 -104.113259) (xy 453.083175 -104.166666) (xy 453.091295 -104.221842) (xy 453.091804 -104.249728)
			(xy 453.091295 -104.277614) (xy 453.088558 -104.29621) (xy 454.900282 -104.29621) (xy 454.904353 -104.240588)
			(xy 454.916479 -104.186151) (xy 454.936402 -104.13406) (xy 454.963698 -104.085425) (xy 454.997784 -104.041282)
			(xy 455.037933 -104.002573) (xy 455.083291 -103.970122) (xy 455.132891 -103.944621) (xy 455.185675 -103.926614)
			(xy 455.240518 -103.916484) (xy 455.296252 -103.914447) (xy 455.351689 -103.920547) (xy 455.405646 -103.934653)
			(xy 455.456975 -103.956465) (xy 455.504581 -103.985519) (xy 455.547449 -104.021194) (xy 455.584666 -104.062731)
			(xy 455.615439 -104.109244) (xy 455.639111 -104.159741) (xy 455.655179 -104.213148) (xy 455.663299 -104.268324)
			(xy 455.663456 -104.276949) (xy 460.939906 -104.276949) (xy 460.939906 -104.222451) (xy 460.947662 -104.168508)
			(xy 460.963016 -104.116217) (xy 460.985655 -104.066644) (xy 461.015119 -104.020797) (xy 461.050807 -103.97961)
			(xy 461.091994 -103.943921) (xy 461.13784 -103.914457) (xy 461.187413 -103.891817) (xy 461.239704 -103.876463)
			(xy 461.293647 -103.868706) (xy 461.320896 -103.86822) (xy 461.3475 -103.868663) (xy 461.400194 -103.876045)
			(xy 461.45135 -103.890679) (xy 461.499975 -103.912283) (xy 461.545126 -103.940435) (xy 461.585925 -103.974591)
			(xy 461.62158 -104.014085) (xy 461.636872 -104.03586) (xy 461.645206 -104.04734) (xy 461.66695 -104.065544)
			(xy 461.692863 -104.077062) (xy 461.720946 -104.081002) (xy 461.749029 -104.077062) (xy 461.774942 -104.065544)
			(xy 461.796686 -104.04734) (xy 461.80502 -104.03586) (xy 461.820296 -104.014076) (xy 461.855965 -103.974596)
			(xy 461.896772 -103.940453) (xy 461.941925 -103.912309) (xy 461.990549 -103.890709) (xy 462.041702 -103.876072)
			(xy 462.094393 -103.868681) (xy 462.120996 -103.86822) (xy 462.148251 -103.868627) (xy 462.202206 -103.876384)
			(xy 462.254509 -103.891741) (xy 462.304093 -103.914385) (xy 462.34995 -103.943855) (xy 462.391146 -103.979551)
			(xy 462.426843 -104.020747) (xy 462.456314 -104.066603) (xy 462.478958 -104.116188) (xy 462.494315 -104.16849)
			(xy 462.502073 -104.222445) (xy 462.502073 -104.276955) (xy 462.494315 -104.33091) (xy 462.478958 -104.383212)
			(xy 462.456314 -104.432797) (xy 462.426843 -104.478653) (xy 462.391146 -104.519849) (xy 462.34995 -104.555545)
			(xy 462.304093 -104.585015) (xy 462.254509 -104.607659) (xy 462.202206 -104.623016) (xy 462.148251 -104.630773)
			(xy 462.120996 -104.631236) (xy 462.094391 -104.630818) (xy 462.041695 -104.623434) (xy 461.990537 -104.608797)
			(xy 461.941911 -104.58719) (xy 461.896761 -104.559033) (xy 461.855964 -104.524873) (xy 461.820311 -104.485373)
			(xy 461.80502 -104.463596) (xy 461.796686 -104.452116) (xy 461.774942 -104.433912) (xy 461.749029 -104.422394)
			(xy 461.720946 -104.418454) (xy 461.692863 -104.422394) (xy 461.66695 -104.433912) (xy 461.645206 -104.452116)
			(xy 461.636872 -104.463596) (xy 461.621555 -104.48535) (xy 461.585891 -104.524827) (xy 461.545091 -104.558971)
			(xy 461.499945 -104.587118) (xy 461.451327 -104.608723) (xy 461.400181 -104.623368) (xy 461.347497 -104.630768)
			(xy 461.320896 -104.631236) (xy 461.293647 -104.630694) (xy 461.239704 -104.622937) (xy 461.187413 -104.607583)
			(xy 461.13784 -104.584943) (xy 461.091994 -104.555479) (xy 461.050807 -104.51979) (xy 461.015119 -104.478603)
			(xy 460.985655 -104.432756) (xy 460.963016 -104.383183) (xy 460.947662 -104.330892) (xy 460.939906 -104.276949)
			(xy 455.663456 -104.276949) (xy 455.663808 -104.29621) (xy 455.663299 -104.324096) (xy 455.655179 -104.379272)
			(xy 455.639111 -104.432679) (xy 455.615439 -104.483176) (xy 455.584666 -104.529689) (xy 455.547449 -104.571226)
			(xy 455.504581 -104.606901) (xy 455.456975 -104.635955) (xy 455.405646 -104.657767) (xy 455.351689 -104.671873)
			(xy 455.296252 -104.677973) (xy 455.240518 -104.675936) (xy 455.185675 -104.665806) (xy 455.132891 -104.647799)
			(xy 455.083291 -104.622298) (xy 455.037933 -104.589847) (xy 454.997784 -104.551138) (xy 454.963698 -104.506995)
			(xy 454.936402 -104.45836) (xy 454.916479 -104.406269) (xy 454.904353 -104.351832) (xy 454.900282 -104.29621)
			(xy 453.088558 -104.29621) (xy 453.083175 -104.33279) (xy 453.067107 -104.386197) (xy 453.043435 -104.436694)
			(xy 453.012662 -104.483207) (xy 452.975445 -104.524744) (xy 452.932577 -104.560419) (xy 452.884971 -104.589473)
			(xy 452.833642 -104.611285) (xy 452.779685 -104.625391) (xy 452.724248 -104.631491) (xy 452.668514 -104.629454)
			(xy 452.613671 -104.619324) (xy 452.560887 -104.601317) (xy 452.511287 -104.575816) (xy 452.465929 -104.543365)
			(xy 452.42578 -104.504656) (xy 452.391694 -104.460513) (xy 452.364398 -104.411878) (xy 452.344475 -104.359787)
			(xy 452.332349 -104.30535) (xy 452.328278 -104.249728) (xy 445.87033 -104.249728) (xy 445.87033 -105.011728)
			(xy 462.223102 -105.011728) (xy 462.227173 -104.956106) (xy 462.239299 -104.901669) (xy 462.259222 -104.849578)
			(xy 462.286518 -104.800943) (xy 462.320604 -104.7568) (xy 462.360753 -104.718091) (xy 462.406111 -104.68564)
			(xy 462.455711 -104.660139) (xy 462.508495 -104.642132) (xy 462.563338 -104.632002) (xy 462.619072 -104.629965)
			(xy 462.674509 -104.636065) (xy 462.728466 -104.650171) (xy 462.779795 -104.671983) (xy 462.827401 -104.701037)
			(xy 462.870269 -104.736712) (xy 462.907486 -104.778249) (xy 462.938259 -104.824762) (xy 462.961931 -104.875259)
			(xy 462.977999 -104.928666) (xy 462.986119 -104.983842) (xy 462.986628 -105.011728) (xy 462.986119 -105.039614)
			(xy 462.977999 -105.09479) (xy 462.961931 -105.148197) (xy 462.938259 -105.198694) (xy 462.907486 -105.245207)
			(xy 462.870269 -105.286744) (xy 462.827401 -105.322419) (xy 462.779795 -105.351473) (xy 462.728466 -105.373285)
			(xy 462.674509 -105.387391) (xy 462.619072 -105.393491) (xy 462.563338 -105.391454) (xy 462.508495 -105.381324)
			(xy 462.455711 -105.363317) (xy 462.406111 -105.337816) (xy 462.360753 -105.305365) (xy 462.320604 -105.266656)
			(xy 462.286518 -105.222513) (xy 462.259222 -105.173878) (xy 462.239299 -105.121787) (xy 462.227173 -105.06735)
			(xy 462.223102 -105.011728) (xy 445.87033 -105.011728) (xy 445.87033 -106.408728) (xy 452.328278 -106.408728)
			(xy 452.332349 -106.353106) (xy 452.344475 -106.298669) (xy 452.364398 -106.246578) (xy 452.391694 -106.197943)
			(xy 452.42578 -106.1538) (xy 452.465929 -106.115091) (xy 452.511287 -106.08264) (xy 452.560887 -106.057139)
			(xy 452.613671 -106.039132) (xy 452.668514 -106.029002) (xy 452.724248 -106.026965) (xy 452.779685 -106.033065)
			(xy 452.833642 -106.047171) (xy 452.884971 -106.068983) (xy 452.932577 -106.098037) (xy 452.975445 -106.133712)
			(xy 453.012662 -106.175249) (xy 453.043435 -106.221762) (xy 453.067107 -106.272259) (xy 453.083175 -106.325666)
			(xy 453.08953 -106.36885) (xy 454.871072 -106.36885) (xy 454.875143 -106.313228) (xy 454.887269 -106.258791)
			(xy 454.907192 -106.2067) (xy 454.934488 -106.158065) (xy 454.968574 -106.113922) (xy 455.008723 -106.075213)
			(xy 455.054081 -106.042762) (xy 455.103681 -106.017261) (xy 455.156465 -105.999254) (xy 455.211308 -105.989124)
			(xy 455.267042 -105.987087) (xy 455.322479 -105.993187) (xy 455.376436 -106.007293) (xy 455.424525 -106.027728)
			(xy 459.55915 -106.027728) (xy 459.563221 -105.972106) (xy 459.575347 -105.917669) (xy 459.59527 -105.865578)
			(xy 459.622566 -105.816943) (xy 459.656652 -105.7728) (xy 459.696801 -105.734091) (xy 459.742159 -105.70164)
			(xy 459.791759 -105.676139) (xy 459.844543 -105.658132) (xy 459.899386 -105.648002) (xy 459.95512 -105.645965)
			(xy 460.010557 -105.652065) (xy 460.064514 -105.666171) (xy 460.115843 -105.687983) (xy 460.163449 -105.717037)
			(xy 460.206317 -105.752712) (xy 460.243534 -105.794249) (xy 460.274307 -105.840762) (xy 460.297979 -105.891259)
			(xy 460.314047 -105.944666) (xy 460.322167 -105.999842) (xy 460.322676 -106.027728) (xy 460.322167 -106.055614)
			(xy 460.314047 -106.11079) (xy 460.297979 -106.164197) (xy 460.274307 -106.214694) (xy 460.243534 -106.261207)
			(xy 460.206317 -106.302744) (xy 460.163449 -106.338419) (xy 460.115843 -106.367473) (xy 460.064514 -106.389285)
			(xy 460.010557 -106.403391) (xy 459.95512 -106.409491) (xy 459.899386 -106.407454) (xy 459.844543 -106.397324)
			(xy 459.791759 -106.379317) (xy 459.742159 -106.353816) (xy 459.696801 -106.321365) (xy 459.656652 -106.282656)
			(xy 459.622566 -106.238513) (xy 459.59527 -106.189878) (xy 459.575347 -106.137787) (xy 459.563221 -106.08335)
			(xy 459.55915 -106.027728) (xy 455.424525 -106.027728) (xy 455.427765 -106.029105) (xy 455.475371 -106.058159)
			(xy 455.518239 -106.093834) (xy 455.555456 -106.135371) (xy 455.586229 -106.181884) (xy 455.609901 -106.232381)
			(xy 455.625969 -106.285788) (xy 455.634089 -106.340964) (xy 455.634598 -106.36885) (xy 455.634089 -106.396736)
			(xy 455.625969 -106.451912) (xy 455.609901 -106.505319) (xy 455.586229 -106.555816) (xy 455.555456 -106.602329)
			(xy 455.518239 -106.643866) (xy 455.475371 -106.679541) (xy 455.427765 -106.708595) (xy 455.376436 -106.730407)
			(xy 455.322479 -106.744513) (xy 455.267042 -106.750613) (xy 455.211308 -106.748576) (xy 455.156465 -106.738446)
			(xy 455.103681 -106.720439) (xy 455.054081 -106.694938) (xy 455.008723 -106.662487) (xy 454.968574 -106.623778)
			(xy 454.934488 -106.579635) (xy 454.907192 -106.531) (xy 454.887269 -106.478909) (xy 454.875143 -106.424472)
			(xy 454.871072 -106.36885) (xy 453.08953 -106.36885) (xy 453.091295 -106.380842) (xy 453.091804 -106.408728)
			(xy 453.091295 -106.436614) (xy 453.083175 -106.49179) (xy 453.067107 -106.545197) (xy 453.043435 -106.595694)
			(xy 453.012662 -106.642207) (xy 452.975445 -106.683744) (xy 452.932577 -106.719419) (xy 452.884971 -106.748473)
			(xy 452.833642 -106.770285) (xy 452.779685 -106.784391) (xy 452.724248 -106.790491) (xy 452.668514 -106.788454)
			(xy 452.613671 -106.778324) (xy 452.560887 -106.760317) (xy 452.511287 -106.734816) (xy 452.465929 -106.702365)
			(xy 452.42578 -106.663656) (xy 452.391694 -106.619513) (xy 452.364398 -106.570878) (xy 452.344475 -106.518787)
			(xy 452.332349 -106.46435) (xy 452.328278 -106.408728) (xy 445.87033 -106.408728) (xy 445.87033 -107.018836)
			(xy 455.666854 -107.018836) (xy 455.670925 -106.963214) (xy 455.683051 -106.908777) (xy 455.702974 -106.856686)
			(xy 455.73027 -106.808051) (xy 455.764356 -106.763908) (xy 455.804505 -106.725199) (xy 455.849863 -106.692748)
			(xy 455.899463 -106.667247) (xy 455.952247 -106.64924) (xy 456.00709 -106.63911) (xy 456.062824 -106.637073)
			(xy 456.118261 -106.643173) (xy 456.172218 -106.657279) (xy 456.223547 -106.679091) (xy 456.271153 -106.708145)
			(xy 456.314021 -106.74382) (xy 456.351238 -106.785357) (xy 456.382011 -106.83187) (xy 456.405683 -106.882367)
			(xy 456.421751 -106.935774) (xy 456.429871 -106.99095) (xy 456.43038 -107.018836) (xy 456.429871 -107.046722)
			(xy 456.421751 -107.101898) (xy 456.405683 -107.155305) (xy 456.382011 -107.205802) (xy 456.351238 -107.252315)
			(xy 456.314021 -107.293852) (xy 456.271153 -107.329527) (xy 456.223547 -107.358581) (xy 456.172218 -107.380393)
			(xy 456.118261 -107.394499) (xy 456.062824 -107.400599) (xy 456.00709 -107.398562) (xy 455.952247 -107.388432)
			(xy 455.899463 -107.370425) (xy 455.849863 -107.344924) (xy 455.804505 -107.312473) (xy 455.764356 -107.273764)
			(xy 455.73027 -107.229621) (xy 455.702974 -107.180986) (xy 455.683051 -107.128895) (xy 455.670925 -107.074458)
			(xy 455.666854 -107.018836) (xy 445.87033 -107.018836) (xy 445.87033 -108.059728) (xy 452.328278 -108.059728)
			(xy 452.332349 -108.004106) (xy 452.344475 -107.949669) (xy 452.364398 -107.897578) (xy 452.391694 -107.848943)
			(xy 452.42578 -107.8048) (xy 452.465929 -107.766091) (xy 452.511287 -107.73364) (xy 452.560887 -107.708139)
			(xy 452.613671 -107.690132) (xy 452.668514 -107.680002) (xy 452.724248 -107.677965) (xy 452.779685 -107.684065)
			(xy 452.833642 -107.698171) (xy 452.884971 -107.719983) (xy 452.932577 -107.749037) (xy 452.975445 -107.784712)
			(xy 453.012662 -107.826249) (xy 453.043435 -107.872762) (xy 453.067107 -107.923259) (xy 453.083175 -107.976666)
			(xy 453.091295 -108.031842) (xy 453.091804 -108.059728) (xy 454.841862 -108.059728) (xy 454.845933 -108.004106)
			(xy 454.858059 -107.949669) (xy 454.877982 -107.897578) (xy 454.905278 -107.848943) (xy 454.939364 -107.8048)
			(xy 454.979513 -107.766091) (xy 455.024871 -107.73364) (xy 455.074471 -107.708139) (xy 455.127255 -107.690132)
			(xy 455.182098 -107.680002) (xy 455.237832 -107.677965) (xy 455.293269 -107.684065) (xy 455.347226 -107.698171)
			(xy 455.36553 -107.705949) (xy 460.812906 -107.705949) (xy 460.812906 -107.651451) (xy 460.820662 -107.597508)
			(xy 460.836016 -107.545217) (xy 460.858655 -107.495644) (xy 460.888119 -107.449797) (xy 460.923807 -107.40861)
			(xy 460.964994 -107.372921) (xy 461.01084 -107.343457) (xy 461.060413 -107.320817) (xy 461.112704 -107.305463)
			(xy 461.166647 -107.297706) (xy 461.193896 -107.29722) (xy 461.2205 -107.297663) (xy 461.273194 -107.305045)
			(xy 461.32435 -107.319679) (xy 461.372975 -107.341283) (xy 461.418126 -107.369435) (xy 461.458925 -107.403591)
			(xy 461.49458 -107.443085) (xy 461.509872 -107.46486) (xy 461.518206 -107.47634) (xy 461.53995 -107.494544)
			(xy 461.565863 -107.506062) (xy 461.593946 -107.510002) (xy 461.622029 -107.506062) (xy 461.647942 -107.494544)
			(xy 461.669686 -107.47634) (xy 461.67802 -107.46486) (xy 461.693296 -107.443076) (xy 461.728965 -107.403596)
			(xy 461.769772 -107.369453) (xy 461.814925 -107.341309) (xy 461.863549 -107.319709) (xy 461.914702 -107.305072)
			(xy 461.967393 -107.297681) (xy 461.993996 -107.29722) (xy 462.021251 -107.297627) (xy 462.075206 -107.305384)
			(xy 462.127509 -107.320741) (xy 462.177093 -107.343385) (xy 462.22295 -107.372855) (xy 462.264146 -107.408551)
			(xy 462.299843 -107.449747) (xy 462.329314 -107.495603) (xy 462.351958 -107.545188) (xy 462.367315 -107.59749)
			(xy 462.375073 -107.651445) (xy 462.375073 -107.705955) (xy 462.367315 -107.75991) (xy 462.351958 -107.812212)
			(xy 462.329314 -107.861797) (xy 462.299843 -107.907653) (xy 462.264146 -107.948849) (xy 462.22295 -107.984545)
			(xy 462.177093 -108.014015) (xy 462.127509 -108.036659) (xy 462.075206 -108.052016) (xy 462.021251 -108.059773)
			(xy 461.993996 -108.060236) (xy 461.967391 -108.059818) (xy 461.914695 -108.052434) (xy 461.863537 -108.037797)
			(xy 461.814911 -108.01619) (xy 461.769761 -107.988033) (xy 461.728964 -107.953873) (xy 461.693311 -107.914373)
			(xy 461.67802 -107.892596) (xy 461.669686 -107.881116) (xy 461.647942 -107.862912) (xy 461.622029 -107.851394)
			(xy 461.593946 -107.847454) (xy 461.565863 -107.851394) (xy 461.53995 -107.862912) (xy 461.518206 -107.881116)
			(xy 461.509872 -107.892596) (xy 461.494555 -107.91435) (xy 461.458891 -107.953827) (xy 461.418091 -107.987971)
			(xy 461.372945 -108.016118) (xy 461.324327 -108.037723) (xy 461.273181 -108.052368) (xy 461.220497 -108.059768)
			(xy 461.193896 -108.060236) (xy 461.166647 -108.059694) (xy 461.112704 -108.051937) (xy 461.060413 -108.036583)
			(xy 461.01084 -108.013943) (xy 460.964994 -107.984479) (xy 460.923807 -107.94879) (xy 460.888119 -107.907603)
			(xy 460.858655 -107.861756) (xy 460.836016 -107.812183) (xy 460.820662 -107.759892) (xy 460.812906 -107.705949)
			(xy 455.36553 -107.705949) (xy 455.398555 -107.719983) (xy 455.446161 -107.749037) (xy 455.489029 -107.784712)
			(xy 455.526246 -107.826249) (xy 455.557019 -107.872762) (xy 455.580691 -107.923259) (xy 455.596759 -107.976666)
			(xy 455.604879 -108.031842) (xy 455.605388 -108.059728) (xy 455.604879 -108.087614) (xy 455.596759 -108.14279)
			(xy 455.580691 -108.196197) (xy 455.557019 -108.246694) (xy 455.526246 -108.293207) (xy 455.489029 -108.334744)
			(xy 455.446161 -108.370419) (xy 455.398555 -108.399473) (xy 455.347226 -108.421285) (xy 455.293269 -108.435391)
			(xy 455.237832 -108.441491) (xy 455.182098 -108.439454) (xy 455.127255 -108.429324) (xy 455.074471 -108.411317)
			(xy 455.024871 -108.385816) (xy 454.979513 -108.353365) (xy 454.939364 -108.314656) (xy 454.905278 -108.270513)
			(xy 454.877982 -108.221878) (xy 454.858059 -108.169787) (xy 454.845933 -108.11535) (xy 454.841862 -108.059728)
			(xy 453.091804 -108.059728) (xy 453.091295 -108.087614) (xy 453.083175 -108.14279) (xy 453.067107 -108.196197)
			(xy 453.043435 -108.246694) (xy 453.012662 -108.293207) (xy 452.975445 -108.334744) (xy 452.932577 -108.370419)
			(xy 452.884971 -108.399473) (xy 452.833642 -108.421285) (xy 452.779685 -108.435391) (xy 452.724248 -108.441491)
			(xy 452.668514 -108.439454) (xy 452.613671 -108.429324) (xy 452.560887 -108.411317) (xy 452.511287 -108.385816)
			(xy 452.465929 -108.353365) (xy 452.42578 -108.314656) (xy 452.391694 -108.270513) (xy 452.364398 -108.221878)
			(xy 452.344475 -108.169787) (xy 452.332349 -108.11535) (xy 452.328278 -108.059728) (xy 445.87033 -108.059728)
			(xy 445.87033 -109.656372) (xy 463.654138 -109.656372) (xy 463.658209 -109.60075) (xy 463.670335 -109.546313)
			(xy 463.690258 -109.494222) (xy 463.717554 -109.445587) (xy 463.75164 -109.401444) (xy 463.791789 -109.362735)
			(xy 463.837147 -109.330284) (xy 463.886747 -109.304783) (xy 463.939531 -109.286776) (xy 463.994374 -109.276646)
			(xy 464.050108 -109.274609) (xy 464.105545 -109.280709) (xy 464.159502 -109.294815) (xy 464.210831 -109.316627)
			(xy 464.258437 -109.345681) (xy 464.301305 -109.381356) (xy 464.338522 -109.422893) (xy 464.369295 -109.469406)
			(xy 464.392967 -109.519903) (xy 464.409035 -109.57331) (xy 464.417155 -109.628486) (xy 464.417664 -109.656372)
			(xy 464.417155 -109.684258) (xy 464.409035 -109.739434) (xy 464.392967 -109.792841) (xy 464.369295 -109.843338)
			(xy 464.338522 -109.889851) (xy 464.301305 -109.931388) (xy 464.258437 -109.967063) (xy 464.210831 -109.996117)
			(xy 464.159502 -110.017929) (xy 464.105545 -110.032035) (xy 464.050108 -110.038135) (xy 463.994374 -110.036098)
			(xy 463.939531 -110.025968) (xy 463.886747 -110.007961) (xy 463.837147 -109.98246) (xy 463.791789 -109.950009)
			(xy 463.75164 -109.9113) (xy 463.717554 -109.867157) (xy 463.690258 -109.818522) (xy 463.670335 -109.766431)
			(xy 463.658209 -109.711994) (xy 463.654138 -109.656372) (xy 445.87033 -109.656372) (xy 445.87033 -110.313724)
			(xy 445.870814 -110.328374) (xy 445.879131 -110.356469) (xy 445.895074 -110.381052) (xy 445.917334 -110.400103)
			(xy 445.944084 -110.412059) (xy 445.973126 -110.415938) (xy 446.002076 -110.41142) (xy 446.028556 -110.398878)
			(xy 446.039748 -110.389416) (xy 446.060859 -110.371098) (xy 446.107433 -110.340197) (xy 446.158016 -110.316419)
			(xy 446.211525 -110.300272) (xy 446.266818 -110.292101) (xy 446.294764 -110.291626) (xy 446.322016 -110.292087)
			(xy 446.375966 -110.299839) (xy 446.428264 -110.31519) (xy 446.477844 -110.337829) (xy 446.523697 -110.367293)
			(xy 446.564891 -110.402984) (xy 446.600585 -110.444174) (xy 446.630054 -110.490024) (xy 446.652697 -110.539603)
			(xy 446.668053 -110.591899) (xy 446.675811 -110.645848) (xy 446.675811 -110.700352) (xy 446.668053 -110.754301)
			(xy 446.652697 -110.806597) (xy 446.630054 -110.856176) (xy 446.600585 -110.902026) (xy 446.564891 -110.943216)
			(xy 446.523697 -110.978907) (xy 446.477844 -111.008371) (xy 446.428264 -111.03101) (xy 446.375966 -111.046361)
			(xy 446.322016 -111.054113) (xy 446.294764 -111.054642) (xy 446.266816 -111.054157) (xy 446.211518 -111.046007)
			(xy 446.158002 -111.029872) (xy 446.107415 -111.006097) (xy 446.060841 -110.975193) (xy 446.039748 -110.956852)
			(xy 446.028517 -110.947427) (xy 446.002042 -110.934856) (xy 445.973087 -110.930316) (xy 445.944035 -110.934182)
			(xy 445.917275 -110.946134) (xy 445.895008 -110.965191) (xy 445.879066 -110.989783) (xy 445.870759 -111.01789)
			(xy 445.87033 -111.032544) (xy 445.87033 -111.308388) (xy 450.180962 -111.308388) (xy 450.185033 -111.252766)
			(xy 450.197159 -111.198329) (xy 450.217082 -111.146238) (xy 450.244378 -111.097603) (xy 450.278464 -111.05346)
			(xy 450.318613 -111.014751) (xy 450.363971 -110.9823) (xy 450.413571 -110.956799) (xy 450.466355 -110.938792)
			(xy 450.521198 -110.928662) (xy 450.576932 -110.926625) (xy 450.632369 -110.932725) (xy 450.686326 -110.946831)
			(xy 450.737655 -110.968643) (xy 450.785261 -110.997697) (xy 450.828129 -111.033372) (xy 450.865346 -111.074909)
			(xy 450.896119 -111.121422) (xy 450.919791 -111.171919) (xy 450.935859 -111.225326) (xy 450.943979 -111.280502)
			(xy 450.944488 -111.308388) (xy 450.943979 -111.336274) (xy 450.935859 -111.39145) (xy 450.919791 -111.444857)
			(xy 450.896119 -111.495354) (xy 450.865346 -111.541867) (xy 450.828129 -111.583404) (xy 450.785261 -111.619079)
			(xy 450.737655 -111.648133) (xy 450.686326 -111.669945) (xy 450.632369 -111.684051) (xy 450.576932 -111.690151)
			(xy 450.521198 -111.688114) (xy 450.466355 -111.677984) (xy 450.413571 -111.659977) (xy 450.363971 -111.634476)
			(xy 450.318613 -111.602025) (xy 450.278464 -111.563316) (xy 450.244378 -111.519173) (xy 450.217082 -111.470538)
			(xy 450.197159 -111.418447) (xy 450.185033 -111.36401) (xy 450.180962 -111.308388) (xy 445.87033 -111.308388)
			(xy 445.87033 -113.572798) (xy 452.353172 -113.572798) (xy 452.353588 -113.546193) (xy 452.360971 -113.493497)
			(xy 452.375609 -113.442339) (xy 452.397216 -113.393713) (xy 452.425374 -113.348562) (xy 452.459534 -113.307765)
			(xy 452.499035 -113.272113) (xy 452.520812 -113.256822) (xy 452.532244 -113.248427) (xy 452.550444 -113.226697)
			(xy 452.561962 -113.200797) (xy 452.565908 -113.172727) (xy 452.561977 -113.144655) (xy 452.550473 -113.118749)
			(xy 452.532284 -113.097009) (xy 452.520812 -113.088674) (xy 452.499015 -113.073416) (xy 452.459537 -113.037743)
			(xy 452.425397 -112.996932) (xy 452.397255 -112.951776) (xy 452.375657 -112.903149) (xy 452.361022 -112.851994)
			(xy 452.353633 -112.799302) (xy 452.353172 -112.772698) (xy 452.353658 -112.745447) (xy 452.361414 -112.691499)
			(xy 452.376769 -112.639204) (xy 452.399411 -112.589627) (xy 452.428877 -112.543777) (xy 452.464568 -112.502586)
			(xy 452.505759 -112.466895) (xy 452.551609 -112.437429) (xy 452.601186 -112.414787) (xy 452.653481 -112.399432)
			(xy 452.707429 -112.391676) (xy 452.761931 -112.391676) (xy 452.815879 -112.399432) (xy 452.868174 -112.414787)
			(xy 452.917751 -112.437429) (xy 452.963601 -112.466895) (xy 453.004792 -112.502586) (xy 453.040483 -112.543777)
			(xy 453.069949 -112.589627) (xy 453.092591 -112.639204) (xy 453.107946 -112.691499) (xy 453.115702 -112.745447)
			(xy 453.116188 -112.772698) (xy 453.115743 -112.799302) (xy 453.108361 -112.851996) (xy 453.093727 -112.903152)
			(xy 453.072124 -112.951777) (xy 453.043971 -112.996927) (xy 453.009817 -113.037726) (xy 452.970322 -113.073381)
			(xy 452.948548 -113.088674) (xy 452.937017 -113.096946) (xy 452.918803 -113.118701) (xy 452.907283 -113.144629)
			(xy 452.903346 -113.172727) (xy 452.907298 -113.200823) (xy 452.918832 -113.226745) (xy 452.937057 -113.24849)
			(xy 452.948548 -113.256822) (xy 452.970335 -113.272095) (xy 453.009814 -113.307764) (xy 453.043956 -113.348572)
			(xy 453.0721 -113.393725) (xy 453.0937 -113.44235) (xy 453.108337 -113.493504) (xy 453.115727 -113.546195)
			(xy 453.116188 -113.572798) (xy 453.115702 -113.600049) (xy 453.107946 -113.653997) (xy 453.092591 -113.706292)
			(xy 453.069949 -113.755869) (xy 453.040483 -113.801719) (xy 453.004792 -113.84291) (xy 452.963601 -113.878601)
			(xy 452.917751 -113.908067) (xy 452.868174 -113.930709) (xy 452.815879 -113.946064) (xy 452.761931 -113.95382)
			(xy 452.707429 -113.95382) (xy 452.653481 -113.946064) (xy 452.601186 -113.930709) (xy 452.551609 -113.908067)
			(xy 452.505759 -113.878601) (xy 452.464568 -113.84291) (xy 452.428877 -113.801719) (xy 452.399411 -113.755869)
			(xy 452.376769 -113.706292) (xy 452.361414 -113.653997) (xy 452.353658 -113.600049) (xy 452.353172 -113.572798)
			(xy 445.87033 -113.572798) (xy 445.87033 -114.82451) (xy 452.111362 -114.82451) (xy 452.115433 -114.768888)
			(xy 452.127559 -114.714451) (xy 452.147482 -114.66236) (xy 452.174778 -114.613725) (xy 452.208864 -114.569582)
			(xy 452.249013 -114.530873) (xy 452.294371 -114.498422) (xy 452.343971 -114.472921) (xy 452.396755 -114.454914)
			(xy 452.451598 -114.444784) (xy 452.507332 -114.442747) (xy 452.562769 -114.448847) (xy 452.616726 -114.462953)
			(xy 452.668055 -114.484765) (xy 452.715661 -114.513819) (xy 452.758529 -114.549494) (xy 452.795746 -114.591031)
			(xy 452.79847 -114.595148) (xy 455.807062 -114.595148) (xy 455.811133 -114.539526) (xy 455.823259 -114.485089)
			(xy 455.843182 -114.432998) (xy 455.870478 -114.384363) (xy 455.904564 -114.34022) (xy 455.944713 -114.301511)
			(xy 455.990071 -114.26906) (xy 456.039671 -114.243559) (xy 456.092455 -114.225552) (xy 456.147298 -114.215422)
			(xy 456.203032 -114.213385) (xy 456.258469 -114.219485) (xy 456.312426 -114.233591) (xy 456.363755 -114.255403)
			(xy 456.411361 -114.284457) (xy 456.454229 -114.320132) (xy 456.491446 -114.361669) (xy 456.522219 -114.408182)
			(xy 456.545891 -114.458679) (xy 456.561959 -114.512086) (xy 456.570079 -114.567262) (xy 456.570588 -114.595148)
			(xy 456.570079 -114.623034) (xy 456.561959 -114.67821) (xy 456.545891 -114.731617) (xy 456.522219 -114.782114)
			(xy 456.491446 -114.828627) (xy 456.454229 -114.870164) (xy 456.411361 -114.905839) (xy 456.363755 -114.934893)
			(xy 456.312426 -114.956705) (xy 456.258469 -114.970811) (xy 456.203032 -114.976911) (xy 456.147298 -114.974874)
			(xy 456.092455 -114.964744) (xy 456.039671 -114.946737) (xy 455.990071 -114.921236) (xy 455.944713 -114.888785)
			(xy 455.904564 -114.850076) (xy 455.870478 -114.805933) (xy 455.843182 -114.757298) (xy 455.823259 -114.705207)
			(xy 455.811133 -114.65077) (xy 455.807062 -114.595148) (xy 452.79847 -114.595148) (xy 452.826519 -114.637544)
			(xy 452.850191 -114.688041) (xy 452.866259 -114.741448) (xy 452.874379 -114.796624) (xy 452.874888 -114.82451)
			(xy 452.874379 -114.852396) (xy 452.866259 -114.907572) (xy 452.850191 -114.960979) (xy 452.826519 -115.011476)
			(xy 452.795746 -115.057989) (xy 452.758529 -115.099526) (xy 452.715661 -115.135201) (xy 452.668055 -115.164255)
			(xy 452.616726 -115.186067) (xy 452.562769 -115.200173) (xy 452.507332 -115.206273) (xy 452.451598 -115.204236)
			(xy 452.396755 -115.194106) (xy 452.343971 -115.176099) (xy 452.294371 -115.150598) (xy 452.249013 -115.118147)
			(xy 452.208864 -115.079438) (xy 452.174778 -115.035295) (xy 452.147482 -114.98666) (xy 452.127559 -114.934569)
			(xy 452.115433 -114.880132) (xy 452.111362 -114.82451) (xy 445.87033 -114.82451) (xy 445.87033 -116.335048)
			(xy 448.098162 -116.335048) (xy 448.102233 -116.279426) (xy 448.114359 -116.224989) (xy 448.134282 -116.172898)
			(xy 448.161578 -116.124263) (xy 448.195664 -116.08012) (xy 448.235813 -116.041411) (xy 448.281171 -116.00896)
			(xy 448.330771 -115.983459) (xy 448.383555 -115.965452) (xy 448.438398 -115.955322) (xy 448.494132 -115.953285)
			(xy 448.549569 -115.959385) (xy 448.603526 -115.973491) (xy 448.654855 -115.995303) (xy 448.702461 -116.024357)
			(xy 448.745329 -116.060032) (xy 448.782546 -116.101569) (xy 448.813319 -116.148082) (xy 448.836991 -116.198579)
			(xy 448.853059 -116.251986) (xy 448.861179 -116.307162) (xy 448.861688 -116.335048) (xy 448.861179 -116.362934)
			(xy 448.853059 -116.41811) (xy 448.836991 -116.471517) (xy 448.813319 -116.522014) (xy 448.782546 -116.568527)
			(xy 448.745329 -116.610064) (xy 448.702461 -116.645739) (xy 448.654855 -116.674793) (xy 448.603526 -116.696605)
			(xy 448.549569 -116.710711) (xy 448.494132 -116.716811) (xy 448.438398 -116.714774) (xy 448.383555 -116.704644)
			(xy 448.330771 -116.686637) (xy 448.281171 -116.661136) (xy 448.235813 -116.628685) (xy 448.195664 -116.589976)
			(xy 448.161578 -116.545833) (xy 448.134282 -116.497198) (xy 448.114359 -116.445107) (xy 448.102233 -116.39067)
			(xy 448.098162 -116.335048) (xy 445.87033 -116.335048) (xy 445.87033 -117.193822) (xy 446.061082 -117.193822)
			(xy 446.065153 -117.1382) (xy 446.077279 -117.083763) (xy 446.097202 -117.031672) (xy 446.124498 -116.983037)
			(xy 446.158584 -116.938894) (xy 446.198733 -116.900185) (xy 446.244091 -116.867734) (xy 446.293691 -116.842233)
			(xy 446.346475 -116.824226) (xy 446.401318 -116.814096) (xy 446.457052 -116.812059) (xy 446.512489 -116.818159)
			(xy 446.566446 -116.832265) (xy 446.617775 -116.854077) (xy 446.665381 -116.883131) (xy 446.708249 -116.918806)
			(xy 446.745466 -116.960343) (xy 446.776239 -117.006856) (xy 446.799911 -117.057353) (xy 446.815979 -117.11076)
			(xy 446.824099 -117.165936) (xy 446.824608 -117.193822) (xy 448.512182 -117.193822) (xy 448.516253 -117.1382)
			(xy 448.528379 -117.083763) (xy 448.548302 -117.031672) (xy 448.575598 -116.983037) (xy 448.609684 -116.938894)
			(xy 448.649833 -116.900185) (xy 448.695191 -116.867734) (xy 448.744791 -116.842233) (xy 448.797575 -116.824226)
			(xy 448.852418 -116.814096) (xy 448.908152 -116.812059) (xy 448.963589 -116.818159) (xy 449.017546 -116.832265)
			(xy 449.068875 -116.854077) (xy 449.116481 -116.883131) (xy 449.159349 -116.918806) (xy 449.196566 -116.960343)
			(xy 449.227339 -117.006856) (xy 449.251011 -117.057353) (xy 449.267079 -117.11076) (xy 449.275199 -117.165936)
			(xy 449.275708 -117.193822) (xy 449.275199 -117.221708) (xy 449.267079 -117.276884) (xy 449.251011 -117.330291)
			(xy 449.227339 -117.380788) (xy 449.196566 -117.427301) (xy 449.159349 -117.468838) (xy 449.116481 -117.504513)
			(xy 449.068875 -117.533567) (xy 449.017546 -117.555379) (xy 448.963589 -117.569485) (xy 448.908152 -117.575585)
			(xy 448.852418 -117.573548) (xy 448.797575 -117.563418) (xy 448.744791 -117.545411) (xy 448.695191 -117.51991)
			(xy 448.649833 -117.487459) (xy 448.609684 -117.44875) (xy 448.575598 -117.404607) (xy 448.548302 -117.355972)
			(xy 448.528379 -117.303881) (xy 448.516253 -117.249444) (xy 448.512182 -117.193822) (xy 446.824608 -117.193822)
			(xy 446.824099 -117.221708) (xy 446.815979 -117.276884) (xy 446.799911 -117.330291) (xy 446.776239 -117.380788)
			(xy 446.745466 -117.427301) (xy 446.708249 -117.468838) (xy 446.665381 -117.504513) (xy 446.617775 -117.533567)
			(xy 446.566446 -117.555379) (xy 446.512489 -117.569485) (xy 446.457052 -117.575585) (xy 446.401318 -117.573548)
			(xy 446.346475 -117.563418) (xy 446.293691 -117.545411) (xy 446.244091 -117.51991) (xy 446.198733 -117.487459)
			(xy 446.158584 -117.44875) (xy 446.124498 -117.404607) (xy 446.097202 -117.355972) (xy 446.077279 -117.303881)
			(xy 446.065153 -117.249444) (xy 446.061082 -117.193822) (xy 445.87033 -117.193822) (xy 445.87033 -118.336822)
			(xy 448.512182 -118.336822) (xy 448.516253 -118.2812) (xy 448.528379 -118.226763) (xy 448.548302 -118.174672)
			(xy 448.575598 -118.126037) (xy 448.609684 -118.081894) (xy 448.649833 -118.043185) (xy 448.695191 -118.010734)
			(xy 448.744791 -117.985233) (xy 448.797575 -117.967226) (xy 448.852418 -117.957096) (xy 448.908152 -117.955059)
			(xy 448.963589 -117.961159) (xy 449.017546 -117.975265) (xy 449.068875 -117.997077) (xy 449.116481 -118.026131)
			(xy 449.159349 -118.061806) (xy 449.196566 -118.103343) (xy 449.227339 -118.149856) (xy 449.251011 -118.200353)
			(xy 449.267079 -118.25376) (xy 449.275199 -118.308936) (xy 449.275708 -118.336822) (xy 449.275199 -118.364708)
			(xy 449.267079 -118.419884) (xy 449.251011 -118.473291) (xy 449.227339 -118.523788) (xy 449.196566 -118.570301)
			(xy 449.159349 -118.611838) (xy 449.116481 -118.647513) (xy 449.068875 -118.676567) (xy 449.017546 -118.698379)
			(xy 448.963589 -118.712485) (xy 448.908152 -118.718585) (xy 448.852418 -118.716548) (xy 448.797575 -118.706418)
			(xy 448.744791 -118.688411) (xy 448.695191 -118.66291) (xy 448.649833 -118.630459) (xy 448.609684 -118.59175)
			(xy 448.575598 -118.547607) (xy 448.548302 -118.498972) (xy 448.528379 -118.446881) (xy 448.516253 -118.392444)
			(xy 448.512182 -118.336822) (xy 445.87033 -118.336822) (xy 445.87033 -119.164608) (xy 447.344292 -120.63857)
			(xy 447.344292 -136.943957) (xy 448.198123 -136.943957) (xy 448.198123 -136.889443) (xy 448.205882 -136.835484)
			(xy 448.221241 -136.783179) (xy 448.243888 -136.733592) (xy 448.273363 -136.687733) (xy 448.309064 -136.646535)
			(xy 448.350265 -136.610839) (xy 448.396127 -136.581369) (xy 448.445716 -136.558727) (xy 448.498023 -136.543373)
			(xy 448.551983 -136.53562) (xy 448.57924 -136.53516) (xy 448.60661 -136.535647) (xy 448.660788 -136.543457)
			(xy 448.713292 -136.558941) (xy 448.763039 -136.581778) (xy 448.809006 -136.6115) (xy 448.829938 -136.62914)
			(xy 448.841266 -136.638376) (xy 448.867823 -136.650552) (xy 448.89674 -136.654725) (xy 448.925657 -136.650552)
			(xy 448.952214 -136.638376) (xy 448.963542 -136.62914) (xy 448.98449 -136.611521) (xy 449.030458 -136.581805)
			(xy 449.080201 -136.558964) (xy 449.132699 -136.543469) (xy 449.186872 -136.535636) (xy 449.21424 -136.53516)
			(xy 449.241487 -136.535713) (xy 449.295426 -136.543473) (xy 449.347711 -136.558831) (xy 449.397279 -136.581472)
			(xy 449.443121 -136.610937) (xy 449.484303 -136.646626) (xy 449.519987 -136.687811) (xy 449.549447 -136.733656)
			(xy 449.572083 -136.783226) (xy 449.587435 -136.835513) (xy 449.59519 -136.889453) (xy 449.59519 -136.943947)
			(xy 449.587435 -136.997887) (xy 449.572083 -137.050174) (xy 449.549447 -137.099744) (xy 449.519987 -137.145589)
			(xy 449.484303 -137.186774) (xy 449.443121 -137.222463) (xy 449.397279 -137.251928) (xy 449.347711 -137.274569)
			(xy 449.295426 -137.289927) (xy 449.241487 -137.297687) (xy 449.21424 -137.298176) (xy 449.18687 -137.297692)
			(xy 449.132692 -137.28988) (xy 449.080189 -137.274395) (xy 449.030441 -137.251557) (xy 448.984474 -137.221836)
			(xy 448.963542 -137.204196) (xy 448.952214 -137.19496) (xy 448.925657 -137.182784) (xy 448.89674 -137.178611)
			(xy 448.867823 -137.182784) (xy 448.841266 -137.19496) (xy 448.829938 -137.204196) (xy 448.809002 -137.22183)
			(xy 448.76303 -137.251543) (xy 448.713284 -137.27438) (xy 448.660784 -137.289872) (xy 448.606609 -137.297701)
			(xy 448.57924 -137.298176) (xy 448.551983 -137.29778) (xy 448.498023 -137.290027) (xy 448.445716 -137.274673)
			(xy 448.396127 -137.252031) (xy 448.350265 -137.222561) (xy 448.309064 -137.186865) (xy 448.273363 -137.145667)
			(xy 448.243888 -137.099809) (xy 448.221241 -137.050221) (xy 448.205882 -136.997916) (xy 448.198123 -136.943957)
			(xy 447.344292 -136.943957) (xy 447.344292 -139.233148) (xy 444.829692 -141.747748) (xy 436.3974 -141.747748)
			(xy 435.6862 -142.458948) (xy 435.6862 -146.497548) (xy 436.7784 -147.589748) (xy 445.027558 -147.589748)
			(xy 447.344292 -149.906482) (xy 447.344292 -150.596457) (xy 450.763523 -150.596457) (xy 450.763523 -150.541943)
			(xy 450.771282 -150.487984) (xy 450.786641 -150.435679) (xy 450.809288 -150.386092) (xy 450.838763 -150.340233)
			(xy 450.874464 -150.299035) (xy 450.915665 -150.263339) (xy 450.961527 -150.233869) (xy 451.011116 -150.211227)
			(xy 451.063423 -150.195873) (xy 451.117383 -150.18812) (xy 451.14464 -150.18766) (xy 451.157894 -150.187804)
			(xy 451.184334 -150.189711) (xy 451.197472 -150.19147) (xy 451.210812 -150.192969) (xy 451.237441 -150.189644)
			(xy 451.262282 -150.179486) (xy 451.283611 -150.163199) (xy 451.299953 -150.141912) (xy 451.310176 -150.117099)
			(xy 451.31228 -150.10384) (xy 451.316264 -150.076592) (xy 451.331102 -150.023562) (xy 451.353407 -149.973214)
			(xy 451.382716 -149.926594) (xy 451.41842 -149.88467) (xy 451.459777 -149.848311) (xy 451.505931 -149.818273)
			(xy 451.555921 -149.795179) (xy 451.608712 -149.779509) (xy 451.663206 -149.771587) (xy 451.69074 -149.7711)
			(xy 451.71799 -149.771573) (xy 451.771934 -149.779334) (xy 451.824226 -149.794693) (xy 451.873799 -149.817337)
			(xy 451.919645 -149.846805) (xy 451.960831 -149.882497) (xy 451.996519 -149.923687) (xy 452.025983 -149.969536)
			(xy 452.048621 -150.019112) (xy 452.063975 -150.071405) (xy 452.07173 -150.12535) (xy 452.07173 -150.17985)
			(xy 452.063975 -150.233795) (xy 452.048621 -150.286088) (xy 452.025983 -150.335664) (xy 451.996519 -150.381513)
			(xy 451.960831 -150.422703) (xy 451.919645 -150.458395) (xy 451.873799 -150.487863) (xy 451.824226 -150.510507)
			(xy 451.771934 -150.525866) (xy 451.71799 -150.533627) (xy 451.69074 -150.534116) (xy 451.677486 -150.533973)
			(xy 451.651046 -150.532065) (xy 451.637908 -150.530306) (xy 451.624569 -150.528808) (xy 451.597941 -150.532137)
			(xy 451.573103 -150.542296) (xy 451.554543 -150.556468) (xy 452.174862 -150.556468) (xy 452.178933 -150.500846)
			(xy 452.191059 -150.446409) (xy 452.210982 -150.394318) (xy 452.238278 -150.345683) (xy 452.272364 -150.30154)
			(xy 452.312513 -150.262831) (xy 452.357871 -150.23038) (xy 452.407471 -150.204879) (xy 452.460255 -150.186872)
			(xy 452.515098 -150.176742) (xy 452.570832 -150.174705) (xy 452.626269 -150.180805) (xy 452.680226 -150.194911)
			(xy 452.731555 -150.216723) (xy 452.779161 -150.245777) (xy 452.822029 -150.281452) (xy 452.859246 -150.322989)
			(xy 452.890019 -150.369502) (xy 452.913691 -150.419999) (xy 452.929759 -150.473406) (xy 452.937879 -150.528582)
			(xy 452.938388 -150.556468) (xy 452.937879 -150.584354) (xy 452.929759 -150.63953) (xy 452.913691 -150.692937)
			(xy 452.890019 -150.743434) (xy 452.859246 -150.789947) (xy 452.822029 -150.831484) (xy 452.779161 -150.867159)
			(xy 452.731555 -150.896213) (xy 452.680226 -150.918025) (xy 452.626269 -150.932131) (xy 452.570832 -150.938231)
			(xy 452.515098 -150.936194) (xy 452.460255 -150.926064) (xy 452.407471 -150.908057) (xy 452.357871 -150.882556)
			(xy 452.312513 -150.850105) (xy 452.272364 -150.811396) (xy 452.238278 -150.767253) (xy 452.210982 -150.718618)
			(xy 452.191059 -150.666527) (xy 452.178933 -150.61209) (xy 452.174862 -150.556468) (xy 451.554543 -150.556468)
			(xy 451.551775 -150.558582) (xy 451.535432 -150.579868) (xy 451.525206 -150.604678) (xy 451.5231 -150.617936)
			(xy 451.519116 -150.645184) (xy 451.50428 -150.698216) (xy 451.481977 -150.748565) (xy 451.452669 -150.795186)
			(xy 451.416965 -150.837111) (xy 451.375607 -150.873471) (xy 451.329453 -150.903508) (xy 451.279461 -150.926602)
			(xy 451.226669 -150.942271) (xy 451.172174 -150.950191) (xy 451.14464 -150.950676) (xy 451.117383 -150.95028)
			(xy 451.063423 -150.942527) (xy 451.011116 -150.927173) (xy 450.961527 -150.904531) (xy 450.915665 -150.875061)
			(xy 450.874464 -150.839365) (xy 450.838763 -150.798167) (xy 450.809288 -150.752309) (xy 450.786641 -150.702721)
			(xy 450.771282 -150.650416) (xy 450.763523 -150.596457) (xy 447.344292 -150.596457) (xy 447.344292 -152.968706)
			(xy 447.3448 -152.972516) (xy 447.359036 -153.072166) (xy 447.381109 -153.272274) (xy 447.395854 -153.473055)
			(xy 447.403252 -153.674241) (xy 447.403728 -153.774902) (xy 447.403251 -153.876044) (xy 447.395796 -154.07819)
			(xy 447.380923 -154.279926) (xy 447.35865 -154.480979) (xy 447.344292 -154.581098) (xy 447.344292 -171.378626)
			(xy 449.652136 -173.68647) (xy 454.757534 -173.68647) (xy 454.761605 -173.630848) (xy 454.773731 -173.576411)
			(xy 454.793654 -173.52432) (xy 454.82095 -173.475685) (xy 454.855036 -173.431542) (xy 454.895185 -173.392833)
			(xy 454.940543 -173.360382) (xy 454.990143 -173.334881) (xy 455.042927 -173.316874) (xy 455.09777 -173.306744)
			(xy 455.153504 -173.304707) (xy 455.208941 -173.310807) (xy 455.262898 -173.324913) (xy 455.314227 -173.346725)
			(xy 455.361833 -173.375779) (xy 455.404701 -173.411454) (xy 455.441918 -173.452991) (xy 455.472691 -173.499504)
			(xy 455.496363 -173.550001) (xy 455.512431 -173.603408) (xy 455.520551 -173.658584) (xy 455.52106 -173.68647)
			(xy 455.520551 -173.714356) (xy 455.512431 -173.769532) (xy 455.496363 -173.822939) (xy 455.472691 -173.873436)
			(xy 455.441918 -173.919949) (xy 455.404701 -173.961486) (xy 455.361833 -173.997161) (xy 455.314227 -174.026215)
			(xy 455.262898 -174.048027) (xy 455.208941 -174.062133) (xy 455.153504 -174.068233) (xy 455.09777 -174.066196)
			(xy 455.042927 -174.056066) (xy 454.990143 -174.038059) (xy 454.940543 -174.012558) (xy 454.895185 -173.980107)
			(xy 454.855036 -173.941398) (xy 454.82095 -173.897255) (xy 454.793654 -173.84862) (xy 454.773731 -173.796529)
			(xy 454.761605 -173.742092) (xy 454.757534 -173.68647) (xy 449.652136 -173.68647) (xy 450.353938 -174.388272)
			(xy 459.997048 -174.388272) (xy 461.9625 -176.353724) (xy 461.9625 -188.201808) (xy 462.232248 -188.201808)
			(xy 462.274522 -188.202298) (xy 462.358709 -188.210104) (xy 462.441817 -188.225643) (xy 462.523136 -188.248784)
			(xy 462.601974 -188.27933) (xy 462.677657 -188.317019) (xy 462.749539 -188.36153) (xy 462.817009 -188.412484)
			(xy 462.879489 -188.469445) (xy 462.936447 -188.531928) (xy 462.987397 -188.5994) (xy 463.031904 -188.671285)
			(xy 463.06959 -188.74697) (xy 463.100131 -188.825809) (xy 463.123268 -188.90713) (xy 463.138803 -188.990239)
			(xy 463.146604 -189.074426) (xy 463.146604 -189.158974) (xy 463.138803 -189.243161) (xy 463.123268 -189.32627)
			(xy 463.100131 -189.407591) (xy 463.06959 -189.48643) (xy 463.031904 -189.562115) (xy 462.987397 -189.634)
			(xy 462.936447 -189.701472) (xy 462.879489 -189.763955) (xy 462.817009 -189.820916) (xy 462.749539 -189.87187)
			(xy 462.677657 -189.916381) (xy 462.601974 -189.95407) (xy 462.523136 -189.984616) (xy 462.441817 -190.007757)
			(xy 462.358709 -190.023296) (xy 462.274522 -190.031102) (xy 462.232248 -190.031624) (xy 461.9625 -190.031624)
			(xy 461.9625 -194.793341) (xy 462.199472 -194.793341) (xy 462.199472 -194.740043) (xy 462.207415 -194.687339)
			(xy 462.223125 -194.636409) (xy 462.246251 -194.588388) (xy 462.276275 -194.544351) (xy 462.312527 -194.50528)
			(xy 462.354198 -194.472049) (xy 462.400356 -194.4454) (xy 462.44997 -194.425928) (xy 462.501932 -194.414068)
			(xy 462.555082 -194.410085) (xy 462.608232 -194.414068) (xy 462.660194 -194.425928) (xy 462.709808 -194.4454)
			(xy 462.755966 -194.472049) (xy 462.797637 -194.50528) (xy 462.833889 -194.544351) (xy 462.863913 -194.588388)
			(xy 462.887039 -194.636409) (xy 462.902749 -194.687339) (xy 462.910692 -194.740043) (xy 462.91119 -194.766692)
			(xy 462.910692 -194.793341) (xy 464.409272 -194.793341) (xy 464.409272 -194.740043) (xy 464.417215 -194.687339)
			(xy 464.432925 -194.636409) (xy 464.456051 -194.588388) (xy 464.486075 -194.544351) (xy 464.522327 -194.50528)
			(xy 464.563998 -194.472049) (xy 464.610156 -194.4454) (xy 464.65977 -194.425928) (xy 464.711732 -194.414068)
			(xy 464.764882 -194.410085) (xy 464.818032 -194.414068) (xy 464.869994 -194.425928) (xy 464.919608 -194.4454)
			(xy 464.965766 -194.472049) (xy 465.007437 -194.50528) (xy 465.043689 -194.544351) (xy 465.073713 -194.588388)
			(xy 465.096839 -194.636409) (xy 465.112549 -194.687339) (xy 465.120492 -194.740043) (xy 465.12099 -194.766692)
			(xy 465.120492 -194.793341) (xy 465.112549 -194.846045) (xy 465.096839 -194.896975) (xy 465.073713 -194.944996)
			(xy 465.043689 -194.989033) (xy 465.007437 -195.028104) (xy 464.965766 -195.061335) (xy 464.919608 -195.087984)
			(xy 464.869994 -195.107456) (xy 464.818032 -195.119316) (xy 464.764882 -195.1233) (xy 464.711732 -195.119316)
			(xy 464.65977 -195.107456) (xy 464.610156 -195.087984) (xy 464.563998 -195.061335) (xy 464.522327 -195.028104)
			(xy 464.486075 -194.989033) (xy 464.456051 -194.944996) (xy 464.432925 -194.896975) (xy 464.417215 -194.846045)
			(xy 464.409272 -194.793341) (xy 462.910692 -194.793341) (xy 462.902749 -194.846045) (xy 462.887039 -194.896975)
			(xy 462.863913 -194.944996) (xy 462.833889 -194.989033) (xy 462.797637 -195.028104) (xy 462.755966 -195.061335)
			(xy 462.709808 -195.087984) (xy 462.660194 -195.107456) (xy 462.608232 -195.119316) (xy 462.555082 -195.1233)
			(xy 462.501932 -195.119316) (xy 462.44997 -195.107456) (xy 462.400356 -195.087984) (xy 462.354198 -195.061335)
			(xy 462.312527 -195.028104) (xy 462.276275 -194.989033) (xy 462.246251 -194.944996) (xy 462.223125 -194.896975)
			(xy 462.207415 -194.846045) (xy 462.199472 -194.793341) (xy 461.9625 -194.793341) (xy 461.9625 -196.493363)
			(xy 462.199472 -196.493363) (xy 462.199472 -196.440065) (xy 462.207415 -196.387361) (xy 462.223125 -196.336431)
			(xy 462.246251 -196.28841) (xy 462.276275 -196.244373) (xy 462.312527 -196.205302) (xy 462.354198 -196.172071)
			(xy 462.400356 -196.145422) (xy 462.44997 -196.12595) (xy 462.501932 -196.11409) (xy 462.555082 -196.110107)
			(xy 462.608232 -196.11409) (xy 462.660194 -196.12595) (xy 462.709808 -196.145422) (xy 462.755966 -196.172071)
			(xy 462.797637 -196.205302) (xy 462.833889 -196.244373) (xy 462.863913 -196.28841) (xy 462.887039 -196.336431)
			(xy 462.902749 -196.387361) (xy 462.910692 -196.440065) (xy 462.91119 -196.466714) (xy 462.910692 -196.493363)
			(xy 464.409272 -196.493363) (xy 464.409272 -196.440065) (xy 464.417215 -196.387361) (xy 464.432925 -196.336431)
			(xy 464.456051 -196.28841) (xy 464.486075 -196.244373) (xy 464.522327 -196.205302) (xy 464.563998 -196.172071)
			(xy 464.610156 -196.145422) (xy 464.65977 -196.12595) (xy 464.711732 -196.11409) (xy 464.764882 -196.110107)
			(xy 464.818032 -196.11409) (xy 464.869994 -196.12595) (xy 464.919608 -196.145422) (xy 464.965766 -196.172071)
			(xy 465.007437 -196.205302) (xy 465.043689 -196.244373) (xy 465.073713 -196.28841) (xy 465.096839 -196.336431)
			(xy 465.112549 -196.387361) (xy 465.120492 -196.440065) (xy 465.12099 -196.466714) (xy 465.120492 -196.493363)
			(xy 465.112549 -196.546067) (xy 465.096839 -196.596997) (xy 465.073713 -196.645018) (xy 465.043689 -196.689055)
			(xy 465.007437 -196.728126) (xy 464.965766 -196.761357) (xy 464.919608 -196.788006) (xy 464.869994 -196.807478)
			(xy 464.818032 -196.819338) (xy 464.764882 -196.823322) (xy 464.711732 -196.819338) (xy 464.65977 -196.807478)
			(xy 464.610156 -196.788006) (xy 464.563998 -196.761357) (xy 464.522327 -196.728126) (xy 464.486075 -196.689055)
			(xy 464.456051 -196.645018) (xy 464.432925 -196.596997) (xy 464.417215 -196.546067) (xy 464.409272 -196.493363)
			(xy 462.910692 -196.493363) (xy 462.902749 -196.546067) (xy 462.887039 -196.596997) (xy 462.863913 -196.645018)
			(xy 462.833889 -196.689055) (xy 462.797637 -196.728126) (xy 462.755966 -196.761357) (xy 462.709808 -196.788006)
			(xy 462.660194 -196.807478) (xy 462.608232 -196.819338) (xy 462.555082 -196.823322) (xy 462.501932 -196.819338)
			(xy 462.44997 -196.807478) (xy 462.400356 -196.788006) (xy 462.354198 -196.761357) (xy 462.312527 -196.728126)
			(xy 462.276275 -196.689055) (xy 462.246251 -196.645018) (xy 462.223125 -196.596997) (xy 462.207415 -196.546067)
			(xy 462.199472 -196.493363) (xy 461.9625 -196.493363) (xy 461.9625 -198.193385) (xy 462.199472 -198.193385)
			(xy 462.199472 -198.140087) (xy 462.207415 -198.087383) (xy 462.223125 -198.036453) (xy 462.246251 -197.988432)
			(xy 462.276275 -197.944395) (xy 462.312527 -197.905324) (xy 462.354198 -197.872093) (xy 462.400356 -197.845444)
			(xy 462.44997 -197.825972) (xy 462.501932 -197.814112) (xy 462.555082 -197.810129) (xy 462.608232 -197.814112)
			(xy 462.660194 -197.825972) (xy 462.709808 -197.845444) (xy 462.755966 -197.872093) (xy 462.797637 -197.905324)
			(xy 462.833889 -197.944395) (xy 462.863913 -197.988432) (xy 462.887039 -198.036453) (xy 462.902749 -198.087383)
			(xy 462.910692 -198.140087) (xy 462.91119 -198.166736) (xy 462.910692 -198.193385) (xy 464.409272 -198.193385)
			(xy 464.409272 -198.140087) (xy 464.417215 -198.087383) (xy 464.432925 -198.036453) (xy 464.456051 -197.988432)
			(xy 464.486075 -197.944395) (xy 464.522327 -197.905324) (xy 464.563998 -197.872093) (xy 464.610156 -197.845444)
			(xy 464.65977 -197.825972) (xy 464.711732 -197.814112) (xy 464.764882 -197.810129) (xy 464.818032 -197.814112)
			(xy 464.869994 -197.825972) (xy 464.919608 -197.845444) (xy 464.965766 -197.872093) (xy 465.007437 -197.905324)
			(xy 465.043689 -197.944395) (xy 465.073713 -197.988432) (xy 465.096839 -198.036453) (xy 465.112549 -198.087383)
			(xy 465.120492 -198.140087) (xy 465.12099 -198.166736) (xy 465.120492 -198.193385) (xy 465.112549 -198.246089)
			(xy 465.096839 -198.297019) (xy 465.073713 -198.34504) (xy 465.043689 -198.389077) (xy 465.007437 -198.428148)
			(xy 464.965766 -198.461379) (xy 464.919608 -198.488028) (xy 464.869994 -198.5075) (xy 464.818032 -198.51936)
			(xy 464.764882 -198.523344) (xy 464.711732 -198.51936) (xy 464.65977 -198.5075) (xy 464.610156 -198.488028)
			(xy 464.563998 -198.461379) (xy 464.522327 -198.428148) (xy 464.486075 -198.389077) (xy 464.456051 -198.34504)
			(xy 464.432925 -198.297019) (xy 464.417215 -198.246089) (xy 464.409272 -198.193385) (xy 462.910692 -198.193385)
			(xy 462.902749 -198.246089) (xy 462.887039 -198.297019) (xy 462.863913 -198.34504) (xy 462.833889 -198.389077)
			(xy 462.797637 -198.428148) (xy 462.755966 -198.461379) (xy 462.709808 -198.488028) (xy 462.660194 -198.5075)
			(xy 462.608232 -198.51936) (xy 462.555082 -198.523344) (xy 462.501932 -198.51936) (xy 462.44997 -198.5075)
			(xy 462.400356 -198.488028) (xy 462.354198 -198.461379) (xy 462.312527 -198.428148) (xy 462.276275 -198.389077)
			(xy 462.246251 -198.34504) (xy 462.223125 -198.297019) (xy 462.207415 -198.246089) (xy 462.199472 -198.193385)
			(xy 461.9625 -198.193385) (xy 461.9625 -200.743291) (xy 462.199472 -200.743291) (xy 462.199472 -200.689993)
			(xy 462.207415 -200.637289) (xy 462.223125 -200.586359) (xy 462.246251 -200.538338) (xy 462.276275 -200.494301)
			(xy 462.312527 -200.45523) (xy 462.354198 -200.421999) (xy 462.400356 -200.39535) (xy 462.44997 -200.375878)
			(xy 462.501932 -200.364018) (xy 462.555082 -200.360035) (xy 462.608232 -200.364018) (xy 462.660194 -200.375878)
			(xy 462.709808 -200.39535) (xy 462.755966 -200.421999) (xy 462.797637 -200.45523) (xy 462.833889 -200.494301)
			(xy 462.863913 -200.538338) (xy 462.887039 -200.586359) (xy 462.902749 -200.637289) (xy 462.910692 -200.689993)
			(xy 462.91119 -200.716642) (xy 462.910692 -200.743291) (xy 464.409272 -200.743291) (xy 464.409272 -200.689993)
			(xy 464.417215 -200.637289) (xy 464.432925 -200.586359) (xy 464.456051 -200.538338) (xy 464.486075 -200.494301)
			(xy 464.522327 -200.45523) (xy 464.563998 -200.421999) (xy 464.610156 -200.39535) (xy 464.65977 -200.375878)
			(xy 464.711732 -200.364018) (xy 464.764882 -200.360035) (xy 464.818032 -200.364018) (xy 464.869994 -200.375878)
			(xy 464.919608 -200.39535) (xy 464.965766 -200.421999) (xy 465.007437 -200.45523) (xy 465.043689 -200.494301)
			(xy 465.073713 -200.538338) (xy 465.096839 -200.586359) (xy 465.112549 -200.637289) (xy 465.120492 -200.689993)
			(xy 465.12099 -200.716642) (xy 465.120492 -200.743291) (xy 465.112549 -200.795995) (xy 465.096839 -200.846925)
			(xy 465.073713 -200.894946) (xy 465.043689 -200.938983) (xy 465.007437 -200.978054) (xy 464.965766 -201.011285)
			(xy 464.919608 -201.037934) (xy 464.869994 -201.057406) (xy 464.818032 -201.069266) (xy 464.764882 -201.07325)
			(xy 464.711732 -201.069266) (xy 464.65977 -201.057406) (xy 464.610156 -201.037934) (xy 464.563998 -201.011285)
			(xy 464.522327 -200.978054) (xy 464.486075 -200.938983) (xy 464.456051 -200.894946) (xy 464.432925 -200.846925)
			(xy 464.417215 -200.795995) (xy 464.409272 -200.743291) (xy 462.910692 -200.743291) (xy 462.902749 -200.795995)
			(xy 462.887039 -200.846925) (xy 462.863913 -200.894946) (xy 462.833889 -200.938983) (xy 462.797637 -200.978054)
			(xy 462.755966 -201.011285) (xy 462.709808 -201.037934) (xy 462.660194 -201.057406) (xy 462.608232 -201.069266)
			(xy 462.555082 -201.07325) (xy 462.501932 -201.069266) (xy 462.44997 -201.057406) (xy 462.400356 -201.037934)
			(xy 462.354198 -201.011285) (xy 462.312527 -200.978054) (xy 462.276275 -200.938983) (xy 462.246251 -200.894946)
			(xy 462.223125 -200.846925) (xy 462.207415 -200.795995) (xy 462.199472 -200.743291) (xy 461.9625 -200.743291)
			(xy 461.9625 -202.443313) (xy 462.199472 -202.443313) (xy 462.199472 -202.390015) (xy 462.207415 -202.337311)
			(xy 462.223125 -202.286381) (xy 462.246251 -202.23836) (xy 462.276275 -202.194323) (xy 462.312527 -202.155252)
			(xy 462.354198 -202.122021) (xy 462.400356 -202.095372) (xy 462.44997 -202.0759) (xy 462.501932 -202.06404)
			(xy 462.555082 -202.060057) (xy 462.608232 -202.06404) (xy 462.660194 -202.0759) (xy 462.709808 -202.095372)
			(xy 462.755966 -202.122021) (xy 462.797637 -202.155252) (xy 462.833889 -202.194323) (xy 462.863913 -202.23836)
			(xy 462.887039 -202.286381) (xy 462.902749 -202.337311) (xy 462.910692 -202.390015) (xy 462.91119 -202.416664)
			(xy 462.910692 -202.443313) (xy 464.409272 -202.443313) (xy 464.409272 -202.390015) (xy 464.417215 -202.337311)
			(xy 464.432925 -202.286381) (xy 464.456051 -202.23836) (xy 464.486075 -202.194323) (xy 464.522327 -202.155252)
			(xy 464.563998 -202.122021) (xy 464.610156 -202.095372) (xy 464.65977 -202.0759) (xy 464.711732 -202.06404)
			(xy 464.764882 -202.060057) (xy 464.818032 -202.06404) (xy 464.869994 -202.0759) (xy 464.919608 -202.095372)
			(xy 464.965766 -202.122021) (xy 465.007437 -202.155252) (xy 465.043689 -202.194323) (xy 465.073713 -202.23836)
			(xy 465.096839 -202.286381) (xy 465.112549 -202.337311) (xy 465.120492 -202.390015) (xy 465.12099 -202.416664)
			(xy 465.120492 -202.443313) (xy 465.112549 -202.496017) (xy 465.096839 -202.546947) (xy 465.073713 -202.594968)
			(xy 465.043689 -202.639005) (xy 465.007437 -202.678076) (xy 464.965766 -202.711307) (xy 464.919608 -202.737956)
			(xy 464.869994 -202.757428) (xy 464.818032 -202.769288) (xy 464.764882 -202.773272) (xy 464.711732 -202.769288)
			(xy 464.65977 -202.757428) (xy 464.610156 -202.737956) (xy 464.563998 -202.711307) (xy 464.522327 -202.678076)
			(xy 464.486075 -202.639005) (xy 464.456051 -202.594968) (xy 464.432925 -202.546947) (xy 464.417215 -202.496017)
			(xy 464.409272 -202.443313) (xy 462.910692 -202.443313) (xy 462.902749 -202.496017) (xy 462.887039 -202.546947)
			(xy 462.863913 -202.594968) (xy 462.833889 -202.639005) (xy 462.797637 -202.678076) (xy 462.755966 -202.711307)
			(xy 462.709808 -202.737956) (xy 462.660194 -202.757428) (xy 462.608232 -202.769288) (xy 462.555082 -202.773272)
			(xy 462.501932 -202.769288) (xy 462.44997 -202.757428) (xy 462.400356 -202.737956) (xy 462.354198 -202.711307)
			(xy 462.312527 -202.678076) (xy 462.276275 -202.639005) (xy 462.246251 -202.594968) (xy 462.223125 -202.546947)
			(xy 462.207415 -202.496017) (xy 462.199472 -202.443313) (xy 461.9625 -202.443313) (xy 461.9625 -204.143335)
			(xy 462.199472 -204.143335) (xy 462.199472 -204.090037) (xy 462.207415 -204.037333) (xy 462.223125 -203.986403)
			(xy 462.246251 -203.938382) (xy 462.276275 -203.894345) (xy 462.312527 -203.855274) (xy 462.354198 -203.822043)
			(xy 462.400356 -203.795394) (xy 462.44997 -203.775922) (xy 462.501932 -203.764062) (xy 462.555082 -203.760079)
			(xy 462.608232 -203.764062) (xy 462.660194 -203.775922) (xy 462.709808 -203.795394) (xy 462.755966 -203.822043)
			(xy 462.797637 -203.855274) (xy 462.833889 -203.894345) (xy 462.863913 -203.938382) (xy 462.887039 -203.986403)
			(xy 462.902749 -204.037333) (xy 462.910692 -204.090037) (xy 462.91119 -204.116686) (xy 462.910692 -204.143335)
			(xy 464.409272 -204.143335) (xy 464.409272 -204.090037) (xy 464.417215 -204.037333) (xy 464.432925 -203.986403)
			(xy 464.456051 -203.938382) (xy 464.486075 -203.894345) (xy 464.522327 -203.855274) (xy 464.563998 -203.822043)
			(xy 464.610156 -203.795394) (xy 464.65977 -203.775922) (xy 464.711732 -203.764062) (xy 464.764882 -203.760079)
			(xy 464.818032 -203.764062) (xy 464.869994 -203.775922) (xy 464.919608 -203.795394) (xy 464.965766 -203.822043)
			(xy 465.007437 -203.855274) (xy 465.043689 -203.894345) (xy 465.073713 -203.938382) (xy 465.096839 -203.986403)
			(xy 465.112549 -204.037333) (xy 465.120492 -204.090037) (xy 465.12099 -204.116686) (xy 465.120492 -204.143335)
			(xy 465.112549 -204.196039) (xy 465.096839 -204.246969) (xy 465.073713 -204.29499) (xy 465.043689 -204.339027)
			(xy 465.007437 -204.378098) (xy 464.965766 -204.411329) (xy 464.919608 -204.437978) (xy 464.869994 -204.45745)
			(xy 464.818032 -204.46931) (xy 464.764882 -204.473294) (xy 464.711732 -204.46931) (xy 464.65977 -204.45745)
			(xy 464.610156 -204.437978) (xy 464.563998 -204.411329) (xy 464.522327 -204.378098) (xy 464.486075 -204.339027)
			(xy 464.456051 -204.29499) (xy 464.432925 -204.246969) (xy 464.417215 -204.196039) (xy 464.409272 -204.143335)
			(xy 462.910692 -204.143335) (xy 462.902749 -204.196039) (xy 462.887039 -204.246969) (xy 462.863913 -204.29499)
			(xy 462.833889 -204.339027) (xy 462.797637 -204.378098) (xy 462.755966 -204.411329) (xy 462.709808 -204.437978)
			(xy 462.660194 -204.45745) (xy 462.608232 -204.46931) (xy 462.555082 -204.473294) (xy 462.501932 -204.46931)
			(xy 462.44997 -204.45745) (xy 462.400356 -204.437978) (xy 462.354198 -204.411329) (xy 462.312527 -204.378098)
			(xy 462.276275 -204.339027) (xy 462.246251 -204.29499) (xy 462.223125 -204.246969) (xy 462.207415 -204.196039)
			(xy 462.199472 -204.143335) (xy 461.9625 -204.143335) (xy 461.9625 -205.843357) (xy 462.199472 -205.843357)
			(xy 462.199472 -205.790059) (xy 462.207415 -205.737355) (xy 462.223125 -205.686425) (xy 462.246251 -205.638404)
			(xy 462.276275 -205.594367) (xy 462.312527 -205.555296) (xy 462.354198 -205.522065) (xy 462.400356 -205.495416)
			(xy 462.44997 -205.475944) (xy 462.501932 -205.464084) (xy 462.555082 -205.460101) (xy 462.608232 -205.464084)
			(xy 462.660194 -205.475944) (xy 462.709808 -205.495416) (xy 462.755966 -205.522065) (xy 462.797637 -205.555296)
			(xy 462.833889 -205.594367) (xy 462.863913 -205.638404) (xy 462.887039 -205.686425) (xy 462.902749 -205.737355)
			(xy 462.910692 -205.790059) (xy 462.91119 -205.816708) (xy 462.910692 -205.843357) (xy 464.409272 -205.843357)
			(xy 464.409272 -205.790059) (xy 464.417215 -205.737355) (xy 464.432925 -205.686425) (xy 464.456051 -205.638404)
			(xy 464.486075 -205.594367) (xy 464.522327 -205.555296) (xy 464.563998 -205.522065) (xy 464.610156 -205.495416)
			(xy 464.65977 -205.475944) (xy 464.711732 -205.464084) (xy 464.764882 -205.460101) (xy 464.818032 -205.464084)
			(xy 464.869994 -205.475944) (xy 464.919608 -205.495416) (xy 464.965766 -205.522065) (xy 465.007437 -205.555296)
			(xy 465.043689 -205.594367) (xy 465.073713 -205.638404) (xy 465.096839 -205.686425) (xy 465.112549 -205.737355)
			(xy 465.120492 -205.790059) (xy 465.12099 -205.816708) (xy 465.120492 -205.843357) (xy 465.112549 -205.896061)
			(xy 465.096839 -205.946991) (xy 465.073713 -205.995012) (xy 465.043689 -206.039049) (xy 465.007437 -206.07812)
			(xy 464.965766 -206.111351) (xy 464.919608 -206.138) (xy 464.869994 -206.157472) (xy 464.818032 -206.169332)
			(xy 464.764882 -206.173316) (xy 464.711732 -206.169332) (xy 464.65977 -206.157472) (xy 464.610156 -206.138)
			(xy 464.563998 -206.111351) (xy 464.522327 -206.07812) (xy 464.486075 -206.039049) (xy 464.456051 -205.995012)
			(xy 464.432925 -205.946991) (xy 464.417215 -205.896061) (xy 464.409272 -205.843357) (xy 462.910692 -205.843357)
			(xy 462.902749 -205.896061) (xy 462.887039 -205.946991) (xy 462.863913 -205.995012) (xy 462.833889 -206.039049)
			(xy 462.797637 -206.07812) (xy 462.755966 -206.111351) (xy 462.709808 -206.138) (xy 462.660194 -206.157472)
			(xy 462.608232 -206.169332) (xy 462.555082 -206.173316) (xy 462.501932 -206.169332) (xy 462.44997 -206.157472)
			(xy 462.400356 -206.138) (xy 462.354198 -206.111351) (xy 462.312527 -206.07812) (xy 462.276275 -206.039049)
			(xy 462.246251 -205.995012) (xy 462.223125 -205.946991) (xy 462.207415 -205.896061) (xy 462.199472 -205.843357)
			(xy 461.9625 -205.843357) (xy 461.9625 -207.543379) (xy 462.199472 -207.543379) (xy 462.199472 -207.490081)
			(xy 462.207415 -207.437377) (xy 462.223125 -207.386447) (xy 462.246251 -207.338426) (xy 462.276275 -207.294389)
			(xy 462.312527 -207.255318) (xy 462.354198 -207.222087) (xy 462.400356 -207.195438) (xy 462.44997 -207.175966)
			(xy 462.501932 -207.164106) (xy 462.555082 -207.160123) (xy 462.608232 -207.164106) (xy 462.660194 -207.175966)
			(xy 462.709808 -207.195438) (xy 462.755966 -207.222087) (xy 462.797637 -207.255318) (xy 462.833889 -207.294389)
			(xy 462.863913 -207.338426) (xy 462.887039 -207.386447) (xy 462.902749 -207.437377) (xy 462.910692 -207.490081)
			(xy 462.91119 -207.51673) (xy 462.910692 -207.543379) (xy 464.409272 -207.543379) (xy 464.409272 -207.490081)
			(xy 464.417215 -207.437377) (xy 464.432925 -207.386447) (xy 464.456051 -207.338426) (xy 464.486075 -207.294389)
			(xy 464.522327 -207.255318) (xy 464.563998 -207.222087) (xy 464.610156 -207.195438) (xy 464.65977 -207.175966)
			(xy 464.711732 -207.164106) (xy 464.764882 -207.160123) (xy 464.818032 -207.164106) (xy 464.869994 -207.175966)
			(xy 464.919608 -207.195438) (xy 464.965766 -207.222087) (xy 465.007437 -207.255318) (xy 465.043689 -207.294389)
			(xy 465.073713 -207.338426) (xy 465.096839 -207.386447) (xy 465.112549 -207.437377) (xy 465.120492 -207.490081)
			(xy 465.12099 -207.51673) (xy 465.120492 -207.543379) (xy 465.112549 -207.596083) (xy 465.096839 -207.647013)
			(xy 465.073713 -207.695034) (xy 465.043689 -207.739071) (xy 465.007437 -207.778142) (xy 464.965766 -207.811373)
			(xy 464.919608 -207.838022) (xy 464.869994 -207.857494) (xy 464.818032 -207.869354) (xy 464.764882 -207.873338)
			(xy 464.711732 -207.869354) (xy 464.65977 -207.857494) (xy 464.610156 -207.838022) (xy 464.563998 -207.811373)
			(xy 464.522327 -207.778142) (xy 464.486075 -207.739071) (xy 464.456051 -207.695034) (xy 464.432925 -207.647013)
			(xy 464.417215 -207.596083) (xy 464.409272 -207.543379) (xy 462.910692 -207.543379) (xy 462.902749 -207.596083)
			(xy 462.887039 -207.647013) (xy 462.863913 -207.695034) (xy 462.833889 -207.739071) (xy 462.797637 -207.778142)
			(xy 462.755966 -207.811373) (xy 462.709808 -207.838022) (xy 462.660194 -207.857494) (xy 462.608232 -207.869354)
			(xy 462.555082 -207.873338) (xy 462.501932 -207.869354) (xy 462.44997 -207.857494) (xy 462.400356 -207.838022)
			(xy 462.354198 -207.811373) (xy 462.312527 -207.778142) (xy 462.276275 -207.739071) (xy 462.246251 -207.695034)
			(xy 462.223125 -207.647013) (xy 462.207415 -207.596083) (xy 462.199472 -207.543379) (xy 461.9625 -207.543379)
			(xy 461.9625 -210.093285) (xy 462.199472 -210.093285) (xy 462.199472 -210.039987) (xy 462.207415 -209.987283)
			(xy 462.223125 -209.936353) (xy 462.246251 -209.888332) (xy 462.276275 -209.844295) (xy 462.312527 -209.805224)
			(xy 462.354198 -209.771993) (xy 462.400356 -209.745344) (xy 462.44997 -209.725872) (xy 462.501932 -209.714012)
			(xy 462.555082 -209.710029) (xy 462.608232 -209.714012) (xy 462.660194 -209.725872) (xy 462.709808 -209.745344)
			(xy 462.755966 -209.771993) (xy 462.797637 -209.805224) (xy 462.833889 -209.844295) (xy 462.863913 -209.888332)
			(xy 462.887039 -209.936353) (xy 462.902749 -209.987283) (xy 462.910692 -210.039987) (xy 462.91119 -210.066636)
			(xy 462.910692 -210.093285) (xy 464.409272 -210.093285) (xy 464.409272 -210.039987) (xy 464.417215 -209.987283)
			(xy 464.432925 -209.936353) (xy 464.456051 -209.888332) (xy 464.486075 -209.844295) (xy 464.522327 -209.805224)
			(xy 464.563998 -209.771993) (xy 464.610156 -209.745344) (xy 464.65977 -209.725872) (xy 464.711732 -209.714012)
			(xy 464.764882 -209.710029) (xy 464.818032 -209.714012) (xy 464.869994 -209.725872) (xy 464.919608 -209.745344)
			(xy 464.965766 -209.771993) (xy 465.007437 -209.805224) (xy 465.043689 -209.844295) (xy 465.073713 -209.888332)
			(xy 465.096839 -209.936353) (xy 465.112549 -209.987283) (xy 465.120492 -210.039987) (xy 465.12099 -210.066636)
			(xy 465.120492 -210.093285) (xy 465.112549 -210.145989) (xy 465.096839 -210.196919) (xy 465.073713 -210.24494)
			(xy 465.043689 -210.288977) (xy 465.007437 -210.328048) (xy 464.965766 -210.361279) (xy 464.919608 -210.387928)
			(xy 464.869994 -210.4074) (xy 464.818032 -210.41926) (xy 464.764882 -210.423244) (xy 464.711732 -210.41926)
			(xy 464.65977 -210.4074) (xy 464.610156 -210.387928) (xy 464.563998 -210.361279) (xy 464.522327 -210.328048)
			(xy 464.486075 -210.288977) (xy 464.456051 -210.24494) (xy 464.432925 -210.196919) (xy 464.417215 -210.145989)
			(xy 464.409272 -210.093285) (xy 462.910692 -210.093285) (xy 462.902749 -210.145989) (xy 462.887039 -210.196919)
			(xy 462.863913 -210.24494) (xy 462.833889 -210.288977) (xy 462.797637 -210.328048) (xy 462.755966 -210.361279)
			(xy 462.709808 -210.387928) (xy 462.660194 -210.4074) (xy 462.608232 -210.41926) (xy 462.555082 -210.423244)
			(xy 462.501932 -210.41926) (xy 462.44997 -210.4074) (xy 462.400356 -210.387928) (xy 462.354198 -210.361279)
			(xy 462.312527 -210.328048) (xy 462.276275 -210.288977) (xy 462.246251 -210.24494) (xy 462.223125 -210.196919)
			(xy 462.207415 -210.145989) (xy 462.199472 -210.093285) (xy 461.9625 -210.093285) (xy 461.9625 -211.793307)
			(xy 462.199472 -211.793307) (xy 462.199472 -211.740009) (xy 462.207415 -211.687305) (xy 462.223125 -211.636375)
			(xy 462.246251 -211.588354) (xy 462.276275 -211.544317) (xy 462.312527 -211.505246) (xy 462.354198 -211.472015)
			(xy 462.400356 -211.445366) (xy 462.44997 -211.425894) (xy 462.501932 -211.414034) (xy 462.555082 -211.410051)
			(xy 462.608232 -211.414034) (xy 462.660194 -211.425894) (xy 462.709808 -211.445366) (xy 462.755966 -211.472015)
			(xy 462.797637 -211.505246) (xy 462.833889 -211.544317) (xy 462.863913 -211.588354) (xy 462.887039 -211.636375)
			(xy 462.902749 -211.687305) (xy 462.910692 -211.740009) (xy 462.91119 -211.766658) (xy 462.910692 -211.793307)
			(xy 464.409272 -211.793307) (xy 464.409272 -211.740009) (xy 464.417215 -211.687305) (xy 464.432925 -211.636375)
			(xy 464.456051 -211.588354) (xy 464.486075 -211.544317) (xy 464.522327 -211.505246) (xy 464.563998 -211.472015)
			(xy 464.610156 -211.445366) (xy 464.65977 -211.425894) (xy 464.711732 -211.414034) (xy 464.764882 -211.410051)
			(xy 464.818032 -211.414034) (xy 464.869994 -211.425894) (xy 464.919608 -211.445366) (xy 464.965766 -211.472015)
			(xy 465.007437 -211.505246) (xy 465.043689 -211.544317) (xy 465.073713 -211.588354) (xy 465.096839 -211.636375)
			(xy 465.112549 -211.687305) (xy 465.120492 -211.740009) (xy 465.12099 -211.766658) (xy 465.120492 -211.793307)
			(xy 465.112549 -211.846011) (xy 465.096839 -211.896941) (xy 465.073713 -211.944962) (xy 465.043689 -211.988999)
			(xy 465.007437 -212.02807) (xy 464.965766 -212.061301) (xy 464.919608 -212.08795) (xy 464.869994 -212.107422)
			(xy 464.818032 -212.119282) (xy 464.764882 -212.123266) (xy 464.711732 -212.119282) (xy 464.65977 -212.107422)
			(xy 464.610156 -212.08795) (xy 464.563998 -212.061301) (xy 464.522327 -212.02807) (xy 464.486075 -211.988999)
			(xy 464.456051 -211.944962) (xy 464.432925 -211.896941) (xy 464.417215 -211.846011) (xy 464.409272 -211.793307)
			(xy 462.910692 -211.793307) (xy 462.902749 -211.846011) (xy 462.887039 -211.896941) (xy 462.863913 -211.944962)
			(xy 462.833889 -211.988999) (xy 462.797637 -212.02807) (xy 462.755966 -212.061301) (xy 462.709808 -212.08795)
			(xy 462.660194 -212.107422) (xy 462.608232 -212.119282) (xy 462.555082 -212.123266) (xy 462.501932 -212.119282)
			(xy 462.44997 -212.107422) (xy 462.400356 -212.08795) (xy 462.354198 -212.061301) (xy 462.312527 -212.02807)
			(xy 462.276275 -211.988999) (xy 462.246251 -211.944962) (xy 462.223125 -211.896941) (xy 462.207415 -211.846011)
			(xy 462.199472 -211.793307) (xy 461.9625 -211.793307) (xy 461.9625 -213.493329) (xy 462.199472 -213.493329)
			(xy 462.199472 -213.440031) (xy 462.207415 -213.387327) (xy 462.223125 -213.336397) (xy 462.246251 -213.288376)
			(xy 462.276275 -213.244339) (xy 462.312527 -213.205268) (xy 462.354198 -213.172037) (xy 462.400356 -213.145388)
			(xy 462.44997 -213.125916) (xy 462.501932 -213.114056) (xy 462.555082 -213.110073) (xy 462.608232 -213.114056)
			(xy 462.660194 -213.125916) (xy 462.709808 -213.145388) (xy 462.755966 -213.172037) (xy 462.797637 -213.205268)
			(xy 462.833889 -213.244339) (xy 462.863913 -213.288376) (xy 462.887039 -213.336397) (xy 462.902749 -213.387327)
			(xy 462.910692 -213.440031) (xy 462.91119 -213.46668) (xy 462.910692 -213.493329) (xy 464.409272 -213.493329)
			(xy 464.409272 -213.440031) (xy 464.417215 -213.387327) (xy 464.432925 -213.336397) (xy 464.456051 -213.288376)
			(xy 464.486075 -213.244339) (xy 464.522327 -213.205268) (xy 464.563998 -213.172037) (xy 464.610156 -213.145388)
			(xy 464.65977 -213.125916) (xy 464.711732 -213.114056) (xy 464.764882 -213.110073) (xy 464.818032 -213.114056)
			(xy 464.869994 -213.125916) (xy 464.919608 -213.145388) (xy 464.965766 -213.172037) (xy 465.007437 -213.205268)
			(xy 465.043689 -213.244339) (xy 465.073713 -213.288376) (xy 465.096839 -213.336397) (xy 465.112549 -213.387327)
			(xy 465.120492 -213.440031) (xy 465.12099 -213.46668) (xy 465.120492 -213.493329) (xy 465.112549 -213.546033)
			(xy 465.096839 -213.596963) (xy 465.073713 -213.644984) (xy 465.043689 -213.689021) (xy 465.007437 -213.728092)
			(xy 464.965766 -213.761323) (xy 464.919608 -213.787972) (xy 464.869994 -213.807444) (xy 464.818032 -213.819304)
			(xy 464.764882 -213.823288) (xy 464.711732 -213.819304) (xy 464.65977 -213.807444) (xy 464.610156 -213.787972)
			(xy 464.563998 -213.761323) (xy 464.522327 -213.728092) (xy 464.486075 -213.689021) (xy 464.456051 -213.644984)
			(xy 464.432925 -213.596963) (xy 464.417215 -213.546033) (xy 464.409272 -213.493329) (xy 462.910692 -213.493329)
			(xy 462.902749 -213.546033) (xy 462.887039 -213.596963) (xy 462.863913 -213.644984) (xy 462.833889 -213.689021)
			(xy 462.797637 -213.728092) (xy 462.755966 -213.761323) (xy 462.709808 -213.787972) (xy 462.660194 -213.807444)
			(xy 462.608232 -213.819304) (xy 462.555082 -213.823288) (xy 462.501932 -213.819304) (xy 462.44997 -213.807444)
			(xy 462.400356 -213.787972) (xy 462.354198 -213.761323) (xy 462.312527 -213.728092) (xy 462.276275 -213.689021)
			(xy 462.246251 -213.644984) (xy 462.223125 -213.596963) (xy 462.207415 -213.546033) (xy 462.199472 -213.493329)
			(xy 461.9625 -213.493329) (xy 461.9625 -215.193351) (xy 462.199472 -215.193351) (xy 462.199472 -215.140053)
			(xy 462.207415 -215.087349) (xy 462.223125 -215.036419) (xy 462.246251 -214.988398) (xy 462.276275 -214.944361)
			(xy 462.312527 -214.90529) (xy 462.354198 -214.872059) (xy 462.400356 -214.84541) (xy 462.44997 -214.825938)
			(xy 462.501932 -214.814078) (xy 462.555082 -214.810095) (xy 462.608232 -214.814078) (xy 462.660194 -214.825938)
			(xy 462.709808 -214.84541) (xy 462.755966 -214.872059) (xy 462.797637 -214.90529) (xy 462.833889 -214.944361)
			(xy 462.863913 -214.988398) (xy 462.887039 -215.036419) (xy 462.902749 -215.087349) (xy 462.910692 -215.140053)
			(xy 462.91119 -215.166702) (xy 462.910692 -215.193351) (xy 464.409272 -215.193351) (xy 464.409272 -215.140053)
			(xy 464.417215 -215.087349) (xy 464.432925 -215.036419) (xy 464.456051 -214.988398) (xy 464.486075 -214.944361)
			(xy 464.522327 -214.90529) (xy 464.563998 -214.872059) (xy 464.610156 -214.84541) (xy 464.65977 -214.825938)
			(xy 464.711732 -214.814078) (xy 464.764882 -214.810095) (xy 464.818032 -214.814078) (xy 464.869994 -214.825938)
			(xy 464.919608 -214.84541) (xy 464.965766 -214.872059) (xy 465.007437 -214.90529) (xy 465.043689 -214.944361)
			(xy 465.073713 -214.988398) (xy 465.096839 -215.036419) (xy 465.112549 -215.087349) (xy 465.120492 -215.140053)
			(xy 465.12099 -215.166702) (xy 465.120492 -215.193351) (xy 465.112549 -215.246055) (xy 465.096839 -215.296985)
			(xy 465.073713 -215.345006) (xy 465.043689 -215.389043) (xy 465.007437 -215.428114) (xy 464.965766 -215.461345)
			(xy 464.919608 -215.487994) (xy 464.869994 -215.507466) (xy 464.818032 -215.519326) (xy 464.764882 -215.52331)
			(xy 464.711732 -215.519326) (xy 464.65977 -215.507466) (xy 464.610156 -215.487994) (xy 464.563998 -215.461345)
			(xy 464.522327 -215.428114) (xy 464.486075 -215.389043) (xy 464.456051 -215.345006) (xy 464.432925 -215.296985)
			(xy 464.417215 -215.246055) (xy 464.409272 -215.193351) (xy 462.910692 -215.193351) (xy 462.902749 -215.246055)
			(xy 462.887039 -215.296985) (xy 462.863913 -215.345006) (xy 462.833889 -215.389043) (xy 462.797637 -215.428114)
			(xy 462.755966 -215.461345) (xy 462.709808 -215.487994) (xy 462.660194 -215.507466) (xy 462.608232 -215.519326)
			(xy 462.555082 -215.52331) (xy 462.501932 -215.519326) (xy 462.44997 -215.507466) (xy 462.400356 -215.487994)
			(xy 462.354198 -215.461345) (xy 462.312527 -215.428114) (xy 462.276275 -215.389043) (xy 462.246251 -215.345006)
			(xy 462.223125 -215.296985) (xy 462.207415 -215.246055) (xy 462.199472 -215.193351) (xy 461.9625 -215.193351)
			(xy 461.9625 -216.893373) (xy 462.199472 -216.893373) (xy 462.199472 -216.840075) (xy 462.207415 -216.787371)
			(xy 462.223125 -216.736441) (xy 462.246251 -216.68842) (xy 462.276275 -216.644383) (xy 462.312527 -216.605312)
			(xy 462.354198 -216.572081) (xy 462.400356 -216.545432) (xy 462.44997 -216.52596) (xy 462.501932 -216.5141)
			(xy 462.555082 -216.510117) (xy 462.608232 -216.5141) (xy 462.660194 -216.52596) (xy 462.709808 -216.545432)
			(xy 462.755966 -216.572081) (xy 462.797637 -216.605312) (xy 462.833889 -216.644383) (xy 462.863913 -216.68842)
			(xy 462.887039 -216.736441) (xy 462.902749 -216.787371) (xy 462.910692 -216.840075) (xy 462.91119 -216.866724)
			(xy 462.910692 -216.893373) (xy 464.409272 -216.893373) (xy 464.409272 -216.840075) (xy 464.417215 -216.787371)
			(xy 464.432925 -216.736441) (xy 464.456051 -216.68842) (xy 464.486075 -216.644383) (xy 464.522327 -216.605312)
			(xy 464.563998 -216.572081) (xy 464.610156 -216.545432) (xy 464.65977 -216.52596) (xy 464.711732 -216.5141)
			(xy 464.764882 -216.510117) (xy 464.818032 -216.5141) (xy 464.869994 -216.52596) (xy 464.919608 -216.545432)
			(xy 464.965766 -216.572081) (xy 465.007437 -216.605312) (xy 465.043689 -216.644383) (xy 465.073713 -216.68842)
			(xy 465.096839 -216.736441) (xy 465.112549 -216.787371) (xy 465.120492 -216.840075) (xy 465.12099 -216.866724)
			(xy 465.120492 -216.893373) (xy 465.112549 -216.946077) (xy 465.096839 -216.997007) (xy 465.073713 -217.045028)
			(xy 465.043689 -217.089065) (xy 465.007437 -217.128136) (xy 464.965766 -217.161367) (xy 464.919608 -217.188016)
			(xy 464.869994 -217.207488) (xy 464.818032 -217.219348) (xy 464.764882 -217.223332) (xy 464.711732 -217.219348)
			(xy 464.65977 -217.207488) (xy 464.610156 -217.188016) (xy 464.563998 -217.161367) (xy 464.522327 -217.128136)
			(xy 464.486075 -217.089065) (xy 464.456051 -217.045028) (xy 464.432925 -216.997007) (xy 464.417215 -216.946077)
			(xy 464.409272 -216.893373) (xy 462.910692 -216.893373) (xy 462.902749 -216.946077) (xy 462.887039 -216.997007)
			(xy 462.863913 -217.045028) (xy 462.833889 -217.089065) (xy 462.797637 -217.128136) (xy 462.755966 -217.161367)
			(xy 462.709808 -217.188016) (xy 462.660194 -217.207488) (xy 462.608232 -217.219348) (xy 462.555082 -217.223332)
			(xy 462.501932 -217.219348) (xy 462.44997 -217.207488) (xy 462.400356 -217.188016) (xy 462.354198 -217.161367)
			(xy 462.312527 -217.128136) (xy 462.276275 -217.089065) (xy 462.246251 -217.045028) (xy 462.223125 -216.997007)
			(xy 462.207415 -216.946077) (xy 462.199472 -216.893373) (xy 461.9625 -216.893373) (xy 461.9625 -219.443279)
			(xy 462.199472 -219.443279) (xy 462.199472 -219.389981) (xy 462.207415 -219.337277) (xy 462.223125 -219.286347)
			(xy 462.246251 -219.238326) (xy 462.276275 -219.194289) (xy 462.312527 -219.155218) (xy 462.354198 -219.121987)
			(xy 462.400356 -219.095338) (xy 462.44997 -219.075866) (xy 462.501932 -219.064006) (xy 462.555082 -219.060023)
			(xy 462.608232 -219.064006) (xy 462.660194 -219.075866) (xy 462.709808 -219.095338) (xy 462.755966 -219.121987)
			(xy 462.797637 -219.155218) (xy 462.833889 -219.194289) (xy 462.863913 -219.238326) (xy 462.887039 -219.286347)
			(xy 462.902749 -219.337277) (xy 462.910692 -219.389981) (xy 462.91119 -219.41663) (xy 462.910692 -219.443279)
			(xy 464.409272 -219.443279) (xy 464.409272 -219.389981) (xy 464.417215 -219.337277) (xy 464.432925 -219.286347)
			(xy 464.456051 -219.238326) (xy 464.486075 -219.194289) (xy 464.522327 -219.155218) (xy 464.563998 -219.121987)
			(xy 464.610156 -219.095338) (xy 464.65977 -219.075866) (xy 464.711732 -219.064006) (xy 464.764882 -219.060023)
			(xy 464.818032 -219.064006) (xy 464.869994 -219.075866) (xy 464.919608 -219.095338) (xy 464.965766 -219.121987)
			(xy 465.007437 -219.155218) (xy 465.043689 -219.194289) (xy 465.073713 -219.238326) (xy 465.096839 -219.286347)
			(xy 465.112549 -219.337277) (xy 465.120492 -219.389981) (xy 465.12099 -219.41663) (xy 465.120492 -219.443279)
			(xy 465.112549 -219.495983) (xy 465.096839 -219.546913) (xy 465.073713 -219.594934) (xy 465.043689 -219.638971)
			(xy 465.007437 -219.678042) (xy 464.965766 -219.711273) (xy 464.919608 -219.737922) (xy 464.869994 -219.757394)
			(xy 464.818032 -219.769254) (xy 464.764882 -219.773238) (xy 464.711732 -219.769254) (xy 464.65977 -219.757394)
			(xy 464.610156 -219.737922) (xy 464.563998 -219.711273) (xy 464.522327 -219.678042) (xy 464.486075 -219.638971)
			(xy 464.456051 -219.594934) (xy 464.432925 -219.546913) (xy 464.417215 -219.495983) (xy 464.409272 -219.443279)
			(xy 462.910692 -219.443279) (xy 462.902749 -219.495983) (xy 462.887039 -219.546913) (xy 462.863913 -219.594934)
			(xy 462.833889 -219.638971) (xy 462.797637 -219.678042) (xy 462.755966 -219.711273) (xy 462.709808 -219.737922)
			(xy 462.660194 -219.757394) (xy 462.608232 -219.769254) (xy 462.555082 -219.773238) (xy 462.501932 -219.769254)
			(xy 462.44997 -219.757394) (xy 462.400356 -219.737922) (xy 462.354198 -219.711273) (xy 462.312527 -219.678042)
			(xy 462.276275 -219.638971) (xy 462.246251 -219.594934) (xy 462.223125 -219.546913) (xy 462.207415 -219.495983)
			(xy 462.199472 -219.443279) (xy 461.9625 -219.443279) (xy 461.9625 -221.143301) (xy 462.199472 -221.143301)
			(xy 462.199472 -221.090003) (xy 462.207415 -221.037299) (xy 462.223125 -220.986369) (xy 462.246251 -220.938348)
			(xy 462.276275 -220.894311) (xy 462.312527 -220.85524) (xy 462.354198 -220.822009) (xy 462.400356 -220.79536)
			(xy 462.44997 -220.775888) (xy 462.501932 -220.764028) (xy 462.555082 -220.760045) (xy 462.608232 -220.764028)
			(xy 462.660194 -220.775888) (xy 462.709808 -220.79536) (xy 462.755966 -220.822009) (xy 462.797637 -220.85524)
			(xy 462.833889 -220.894311) (xy 462.863913 -220.938348) (xy 462.887039 -220.986369) (xy 462.902749 -221.037299)
			(xy 462.910692 -221.090003) (xy 462.91119 -221.116652) (xy 462.910692 -221.143301) (xy 464.409272 -221.143301)
			(xy 464.409272 -221.090003) (xy 464.417215 -221.037299) (xy 464.432925 -220.986369) (xy 464.456051 -220.938348)
			(xy 464.486075 -220.894311) (xy 464.522327 -220.85524) (xy 464.563998 -220.822009) (xy 464.610156 -220.79536)
			(xy 464.65977 -220.775888) (xy 464.711732 -220.764028) (xy 464.764882 -220.760045) (xy 464.818032 -220.764028)
			(xy 464.869994 -220.775888) (xy 464.919608 -220.79536) (xy 464.965766 -220.822009) (xy 465.007437 -220.85524)
			(xy 465.043689 -220.894311) (xy 465.073713 -220.938348) (xy 465.096839 -220.986369) (xy 465.112549 -221.037299)
			(xy 465.120492 -221.090003) (xy 465.12099 -221.116652) (xy 465.120492 -221.143301) (xy 465.112549 -221.196005)
			(xy 465.096839 -221.246935) (xy 465.073713 -221.294956) (xy 465.043689 -221.338993) (xy 465.007437 -221.378064)
			(xy 464.965766 -221.411295) (xy 464.919608 -221.437944) (xy 464.869994 -221.457416) (xy 464.818032 -221.469276)
			(xy 464.764882 -221.47326) (xy 464.711732 -221.469276) (xy 464.65977 -221.457416) (xy 464.610156 -221.437944)
			(xy 464.563998 -221.411295) (xy 464.522327 -221.378064) (xy 464.486075 -221.338993) (xy 464.456051 -221.294956)
			(xy 464.432925 -221.246935) (xy 464.417215 -221.196005) (xy 464.409272 -221.143301) (xy 462.910692 -221.143301)
			(xy 462.902749 -221.196005) (xy 462.887039 -221.246935) (xy 462.863913 -221.294956) (xy 462.833889 -221.338993)
			(xy 462.797637 -221.378064) (xy 462.755966 -221.411295) (xy 462.709808 -221.437944) (xy 462.660194 -221.457416)
			(xy 462.608232 -221.469276) (xy 462.555082 -221.47326) (xy 462.501932 -221.469276) (xy 462.44997 -221.457416)
			(xy 462.400356 -221.437944) (xy 462.354198 -221.411295) (xy 462.312527 -221.378064) (xy 462.276275 -221.338993)
			(xy 462.246251 -221.294956) (xy 462.223125 -221.246935) (xy 462.207415 -221.196005) (xy 462.199472 -221.143301)
			(xy 461.9625 -221.143301) (xy 461.9625 -222.843323) (xy 462.199472 -222.843323) (xy 462.199472 -222.790025)
			(xy 462.207415 -222.737321) (xy 462.223125 -222.686391) (xy 462.246251 -222.63837) (xy 462.276275 -222.594333)
			(xy 462.312527 -222.555262) (xy 462.354198 -222.522031) (xy 462.400356 -222.495382) (xy 462.44997 -222.47591)
			(xy 462.501932 -222.46405) (xy 462.555082 -222.460067) (xy 462.608232 -222.46405) (xy 462.660194 -222.47591)
			(xy 462.709808 -222.495382) (xy 462.755966 -222.522031) (xy 462.797637 -222.555262) (xy 462.833889 -222.594333)
			(xy 462.863913 -222.63837) (xy 462.887039 -222.686391) (xy 462.902749 -222.737321) (xy 462.910692 -222.790025)
			(xy 462.91119 -222.816674) (xy 462.910692 -222.843323) (xy 464.409272 -222.843323) (xy 464.409272 -222.790025)
			(xy 464.417215 -222.737321) (xy 464.432925 -222.686391) (xy 464.456051 -222.63837) (xy 464.486075 -222.594333)
			(xy 464.522327 -222.555262) (xy 464.563998 -222.522031) (xy 464.610156 -222.495382) (xy 464.65977 -222.47591)
			(xy 464.711732 -222.46405) (xy 464.764882 -222.460067) (xy 464.818032 -222.46405) (xy 464.869994 -222.47591)
			(xy 464.919608 -222.495382) (xy 464.965766 -222.522031) (xy 465.007437 -222.555262) (xy 465.043689 -222.594333)
			(xy 465.073713 -222.63837) (xy 465.096839 -222.686391) (xy 465.112549 -222.737321) (xy 465.120492 -222.790025)
			(xy 465.12099 -222.816674) (xy 465.120492 -222.843323) (xy 465.112549 -222.896027) (xy 465.096839 -222.946957)
			(xy 465.073713 -222.994978) (xy 465.043689 -223.039015) (xy 465.007437 -223.078086) (xy 464.965766 -223.111317)
			(xy 464.919608 -223.137966) (xy 464.869994 -223.157438) (xy 464.818032 -223.169298) (xy 464.764882 -223.173282)
			(xy 464.711732 -223.169298) (xy 464.65977 -223.157438) (xy 464.610156 -223.137966) (xy 464.563998 -223.111317)
			(xy 464.522327 -223.078086) (xy 464.486075 -223.039015) (xy 464.456051 -222.994978) (xy 464.432925 -222.946957)
			(xy 464.417215 -222.896027) (xy 464.409272 -222.843323) (xy 462.910692 -222.843323) (xy 462.902749 -222.896027)
			(xy 462.887039 -222.946957) (xy 462.863913 -222.994978) (xy 462.833889 -223.039015) (xy 462.797637 -223.078086)
			(xy 462.755966 -223.111317) (xy 462.709808 -223.137966) (xy 462.660194 -223.157438) (xy 462.608232 -223.169298)
			(xy 462.555082 -223.173282) (xy 462.501932 -223.169298) (xy 462.44997 -223.157438) (xy 462.400356 -223.137966)
			(xy 462.354198 -223.111317) (xy 462.312527 -223.078086) (xy 462.276275 -223.039015) (xy 462.246251 -222.994978)
			(xy 462.223125 -222.946957) (xy 462.207415 -222.896027) (xy 462.199472 -222.843323) (xy 461.9625 -222.843323)
			(xy 461.9625 -224.543345) (xy 462.199472 -224.543345) (xy 462.199472 -224.490047) (xy 462.207415 -224.437343)
			(xy 462.223125 -224.386413) (xy 462.246251 -224.338392) (xy 462.276275 -224.294355) (xy 462.312527 -224.255284)
			(xy 462.354198 -224.222053) (xy 462.400356 -224.195404) (xy 462.44997 -224.175932) (xy 462.501932 -224.164072)
			(xy 462.555082 -224.160089) (xy 462.608232 -224.164072) (xy 462.660194 -224.175932) (xy 462.709808 -224.195404)
			(xy 462.755966 -224.222053) (xy 462.797637 -224.255284) (xy 462.833889 -224.294355) (xy 462.863913 -224.338392)
			(xy 462.887039 -224.386413) (xy 462.902749 -224.437343) (xy 462.910692 -224.490047) (xy 462.91119 -224.516696)
			(xy 462.910692 -224.543345) (xy 464.409272 -224.543345) (xy 464.409272 -224.490047) (xy 464.417215 -224.437343)
			(xy 464.432925 -224.386413) (xy 464.456051 -224.338392) (xy 464.486075 -224.294355) (xy 464.522327 -224.255284)
			(xy 464.563998 -224.222053) (xy 464.610156 -224.195404) (xy 464.65977 -224.175932) (xy 464.711732 -224.164072)
			(xy 464.764882 -224.160089) (xy 464.818032 -224.164072) (xy 464.869994 -224.175932) (xy 464.919608 -224.195404)
			(xy 464.965766 -224.222053) (xy 465.007437 -224.255284) (xy 465.043689 -224.294355) (xy 465.073713 -224.338392)
			(xy 465.096839 -224.386413) (xy 465.112549 -224.437343) (xy 465.120492 -224.490047) (xy 465.12099 -224.516696)
			(xy 465.120492 -224.543345) (xy 465.112549 -224.596049) (xy 465.096839 -224.646979) (xy 465.073713 -224.695)
			(xy 465.043689 -224.739037) (xy 465.007437 -224.778108) (xy 464.965766 -224.811339) (xy 464.919608 -224.837988)
			(xy 464.869994 -224.85746) (xy 464.818032 -224.86932) (xy 464.764882 -224.873304) (xy 464.711732 -224.86932)
			(xy 464.65977 -224.85746) (xy 464.610156 -224.837988) (xy 464.563998 -224.811339) (xy 464.522327 -224.778108)
			(xy 464.486075 -224.739037) (xy 464.456051 -224.695) (xy 464.432925 -224.646979) (xy 464.417215 -224.596049)
			(xy 464.409272 -224.543345) (xy 462.910692 -224.543345) (xy 462.902749 -224.596049) (xy 462.887039 -224.646979)
			(xy 462.863913 -224.695) (xy 462.833889 -224.739037) (xy 462.797637 -224.778108) (xy 462.755966 -224.811339)
			(xy 462.709808 -224.837988) (xy 462.660194 -224.85746) (xy 462.608232 -224.86932) (xy 462.555082 -224.873304)
			(xy 462.501932 -224.86932) (xy 462.44997 -224.85746) (xy 462.400356 -224.837988) (xy 462.354198 -224.811339)
			(xy 462.312527 -224.778108) (xy 462.276275 -224.739037) (xy 462.246251 -224.695) (xy 462.223125 -224.646979)
			(xy 462.207415 -224.596049) (xy 462.199472 -224.543345) (xy 461.9625 -224.543345) (xy 461.9625 -226.243367)
			(xy 462.199472 -226.243367) (xy 462.199472 -226.190069) (xy 462.207415 -226.137365) (xy 462.223125 -226.086435)
			(xy 462.246251 -226.038414) (xy 462.276275 -225.994377) (xy 462.312527 -225.955306) (xy 462.354198 -225.922075)
			(xy 462.400356 -225.895426) (xy 462.44997 -225.875954) (xy 462.501932 -225.864094) (xy 462.555082 -225.860111)
			(xy 462.608232 -225.864094) (xy 462.660194 -225.875954) (xy 462.709808 -225.895426) (xy 462.755966 -225.922075)
			(xy 462.797637 -225.955306) (xy 462.833889 -225.994377) (xy 462.863913 -226.038414) (xy 462.887039 -226.086435)
			(xy 462.902749 -226.137365) (xy 462.910692 -226.190069) (xy 462.91119 -226.216718) (xy 462.910692 -226.243367)
			(xy 464.409272 -226.243367) (xy 464.409272 -226.190069) (xy 464.417215 -226.137365) (xy 464.432925 -226.086435)
			(xy 464.456051 -226.038414) (xy 464.486075 -225.994377) (xy 464.522327 -225.955306) (xy 464.563998 -225.922075)
			(xy 464.610156 -225.895426) (xy 464.65977 -225.875954) (xy 464.711732 -225.864094) (xy 464.764882 -225.860111)
			(xy 464.818032 -225.864094) (xy 464.869994 -225.875954) (xy 464.919608 -225.895426) (xy 464.965766 -225.922075)
			(xy 465.007437 -225.955306) (xy 465.043689 -225.994377) (xy 465.073713 -226.038414) (xy 465.096839 -226.086435)
			(xy 465.112549 -226.137365) (xy 465.120492 -226.190069) (xy 465.12099 -226.216718) (xy 465.120492 -226.243367)
			(xy 465.112549 -226.296071) (xy 465.096839 -226.347001) (xy 465.073713 -226.395022) (xy 465.043689 -226.439059)
			(xy 465.007437 -226.47813) (xy 464.965766 -226.511361) (xy 464.919608 -226.53801) (xy 464.869994 -226.557482)
			(xy 464.818032 -226.569342) (xy 464.764882 -226.573326) (xy 464.711732 -226.569342) (xy 464.65977 -226.557482)
			(xy 464.610156 -226.53801) (xy 464.563998 -226.511361) (xy 464.522327 -226.47813) (xy 464.486075 -226.439059)
			(xy 464.456051 -226.395022) (xy 464.432925 -226.347001) (xy 464.417215 -226.296071) (xy 464.409272 -226.243367)
			(xy 462.910692 -226.243367) (xy 462.902749 -226.296071) (xy 462.887039 -226.347001) (xy 462.863913 -226.395022)
			(xy 462.833889 -226.439059) (xy 462.797637 -226.47813) (xy 462.755966 -226.511361) (xy 462.709808 -226.53801)
			(xy 462.660194 -226.557482) (xy 462.608232 -226.569342) (xy 462.555082 -226.573326) (xy 462.501932 -226.569342)
			(xy 462.44997 -226.557482) (xy 462.400356 -226.53801) (xy 462.354198 -226.511361) (xy 462.312527 -226.47813)
			(xy 462.276275 -226.439059) (xy 462.246251 -226.395022) (xy 462.223125 -226.347001) (xy 462.207415 -226.296071)
			(xy 462.199472 -226.243367) (xy 461.9625 -226.243367) (xy 461.9625 -228.793273) (xy 462.199472 -228.793273)
			(xy 462.199472 -228.739975) (xy 462.207415 -228.687271) (xy 462.223125 -228.636341) (xy 462.246251 -228.58832)
			(xy 462.276275 -228.544283) (xy 462.312527 -228.505212) (xy 462.354198 -228.471981) (xy 462.400356 -228.445332)
			(xy 462.44997 -228.42586) (xy 462.501932 -228.414) (xy 462.555082 -228.410017) (xy 462.608232 -228.414)
			(xy 462.660194 -228.42586) (xy 462.709808 -228.445332) (xy 462.755966 -228.471981) (xy 462.797637 -228.505212)
			(xy 462.833889 -228.544283) (xy 462.863913 -228.58832) (xy 462.887039 -228.636341) (xy 462.902749 -228.687271)
			(xy 462.910692 -228.739975) (xy 462.91119 -228.766624) (xy 462.910692 -228.793273) (xy 464.409272 -228.793273)
			(xy 464.409272 -228.739975) (xy 464.417215 -228.687271) (xy 464.432925 -228.636341) (xy 464.456051 -228.58832)
			(xy 464.486075 -228.544283) (xy 464.522327 -228.505212) (xy 464.563998 -228.471981) (xy 464.610156 -228.445332)
			(xy 464.65977 -228.42586) (xy 464.711732 -228.414) (xy 464.764882 -228.410017) (xy 464.818032 -228.414)
			(xy 464.869994 -228.42586) (xy 464.919608 -228.445332) (xy 464.965766 -228.471981) (xy 465.007437 -228.505212)
			(xy 465.043689 -228.544283) (xy 465.073713 -228.58832) (xy 465.096839 -228.636341) (xy 465.112549 -228.687271)
			(xy 465.120492 -228.739975) (xy 465.12099 -228.766624) (xy 465.120492 -228.793273) (xy 465.112549 -228.845977)
			(xy 465.096839 -228.896907) (xy 465.073713 -228.944928) (xy 465.043689 -228.988965) (xy 465.007437 -229.028036)
			(xy 464.965766 -229.061267) (xy 464.919608 -229.087916) (xy 464.869994 -229.107388) (xy 464.818032 -229.119248)
			(xy 464.764882 -229.123232) (xy 464.711732 -229.119248) (xy 464.65977 -229.107388) (xy 464.610156 -229.087916)
			(xy 464.563998 -229.061267) (xy 464.522327 -229.028036) (xy 464.486075 -228.988965) (xy 464.456051 -228.944928)
			(xy 464.432925 -228.896907) (xy 464.417215 -228.845977) (xy 464.409272 -228.793273) (xy 462.910692 -228.793273)
			(xy 462.902749 -228.845977) (xy 462.887039 -228.896907) (xy 462.863913 -228.944928) (xy 462.833889 -228.988965)
			(xy 462.797637 -229.028036) (xy 462.755966 -229.061267) (xy 462.709808 -229.087916) (xy 462.660194 -229.107388)
			(xy 462.608232 -229.119248) (xy 462.555082 -229.123232) (xy 462.501932 -229.119248) (xy 462.44997 -229.107388)
			(xy 462.400356 -229.087916) (xy 462.354198 -229.061267) (xy 462.312527 -229.028036) (xy 462.276275 -228.988965)
			(xy 462.246251 -228.944928) (xy 462.223125 -228.896907) (xy 462.207415 -228.845977) (xy 462.199472 -228.793273)
			(xy 461.9625 -228.793273) (xy 461.9625 -230.493295) (xy 462.199472 -230.493295) (xy 462.199472 -230.439997)
			(xy 462.207415 -230.387293) (xy 462.223125 -230.336363) (xy 462.246251 -230.288342) (xy 462.276275 -230.244305)
			(xy 462.312527 -230.205234) (xy 462.354198 -230.172003) (xy 462.400356 -230.145354) (xy 462.44997 -230.125882)
			(xy 462.501932 -230.114022) (xy 462.555082 -230.110039) (xy 462.608232 -230.114022) (xy 462.660194 -230.125882)
			(xy 462.709808 -230.145354) (xy 462.755966 -230.172003) (xy 462.797637 -230.205234) (xy 462.833889 -230.244305)
			(xy 462.863913 -230.288342) (xy 462.887039 -230.336363) (xy 462.902749 -230.387293) (xy 462.910692 -230.439997)
			(xy 462.91119 -230.466646) (xy 462.910692 -230.493295) (xy 464.409272 -230.493295) (xy 464.409272 -230.439997)
			(xy 464.417215 -230.387293) (xy 464.432925 -230.336363) (xy 464.456051 -230.288342) (xy 464.486075 -230.244305)
			(xy 464.522327 -230.205234) (xy 464.563998 -230.172003) (xy 464.610156 -230.145354) (xy 464.65977 -230.125882)
			(xy 464.711732 -230.114022) (xy 464.764882 -230.110039) (xy 464.818032 -230.114022) (xy 464.869994 -230.125882)
			(xy 464.919608 -230.145354) (xy 464.965766 -230.172003) (xy 465.007437 -230.205234) (xy 465.043689 -230.244305)
			(xy 465.073713 -230.288342) (xy 465.096839 -230.336363) (xy 465.112549 -230.387293) (xy 465.120492 -230.439997)
			(xy 465.12099 -230.466646) (xy 465.120492 -230.493295) (xy 465.112549 -230.545999) (xy 465.096839 -230.596929)
			(xy 465.073713 -230.64495) (xy 465.043689 -230.688987) (xy 465.007437 -230.728058) (xy 464.965766 -230.761289)
			(xy 464.919608 -230.787938) (xy 464.869994 -230.80741) (xy 464.818032 -230.81927) (xy 464.764882 -230.823254)
			(xy 464.711732 -230.81927) (xy 464.65977 -230.80741) (xy 464.610156 -230.787938) (xy 464.563998 -230.761289)
			(xy 464.522327 -230.728058) (xy 464.486075 -230.688987) (xy 464.456051 -230.64495) (xy 464.432925 -230.596929)
			(xy 464.417215 -230.545999) (xy 464.409272 -230.493295) (xy 462.910692 -230.493295) (xy 462.902749 -230.545999)
			(xy 462.887039 -230.596929) (xy 462.863913 -230.64495) (xy 462.833889 -230.688987) (xy 462.797637 -230.728058)
			(xy 462.755966 -230.761289) (xy 462.709808 -230.787938) (xy 462.660194 -230.80741) (xy 462.608232 -230.81927)
			(xy 462.555082 -230.823254) (xy 462.501932 -230.81927) (xy 462.44997 -230.80741) (xy 462.400356 -230.787938)
			(xy 462.354198 -230.761289) (xy 462.312527 -230.728058) (xy 462.276275 -230.688987) (xy 462.246251 -230.64495)
			(xy 462.223125 -230.596929) (xy 462.207415 -230.545999) (xy 462.199472 -230.493295) (xy 461.9625 -230.493295)
			(xy 461.9625 -232.193317) (xy 462.199472 -232.193317) (xy 462.199472 -232.140019) (xy 462.207415 -232.087315)
			(xy 462.223125 -232.036385) (xy 462.246251 -231.988364) (xy 462.276275 -231.944327) (xy 462.312527 -231.905256)
			(xy 462.354198 -231.872025) (xy 462.400356 -231.845376) (xy 462.44997 -231.825904) (xy 462.501932 -231.814044)
			(xy 462.555082 -231.810061) (xy 462.608232 -231.814044) (xy 462.660194 -231.825904) (xy 462.709808 -231.845376)
			(xy 462.755966 -231.872025) (xy 462.797637 -231.905256) (xy 462.833889 -231.944327) (xy 462.863913 -231.988364)
			(xy 462.887039 -232.036385) (xy 462.902749 -232.087315) (xy 462.910692 -232.140019) (xy 462.91119 -232.166668)
			(xy 462.910692 -232.193317) (xy 464.409272 -232.193317) (xy 464.409272 -232.140019) (xy 464.417215 -232.087315)
			(xy 464.432925 -232.036385) (xy 464.456051 -231.988364) (xy 464.486075 -231.944327) (xy 464.522327 -231.905256)
			(xy 464.563998 -231.872025) (xy 464.610156 -231.845376) (xy 464.65977 -231.825904) (xy 464.711732 -231.814044)
			(xy 464.764882 -231.810061) (xy 464.818032 -231.814044) (xy 464.869994 -231.825904) (xy 464.919608 -231.845376)
			(xy 464.965766 -231.872025) (xy 465.007437 -231.905256) (xy 465.043689 -231.944327) (xy 465.073713 -231.988364)
			(xy 465.096839 -232.036385) (xy 465.112549 -232.087315) (xy 465.120492 -232.140019) (xy 465.12099 -232.166668)
			(xy 465.120492 -232.193317) (xy 465.112549 -232.246021) (xy 465.096839 -232.296951) (xy 465.073713 -232.344972)
			(xy 465.043689 -232.389009) (xy 465.007437 -232.42808) (xy 464.965766 -232.461311) (xy 464.919608 -232.48796)
			(xy 464.869994 -232.507432) (xy 464.818032 -232.519292) (xy 464.764882 -232.523276) (xy 464.711732 -232.519292)
			(xy 464.65977 -232.507432) (xy 464.610156 -232.48796) (xy 464.563998 -232.461311) (xy 464.522327 -232.42808)
			(xy 464.486075 -232.389009) (xy 464.456051 -232.344972) (xy 464.432925 -232.296951) (xy 464.417215 -232.246021)
			(xy 464.409272 -232.193317) (xy 462.910692 -232.193317) (xy 462.902749 -232.246021) (xy 462.887039 -232.296951)
			(xy 462.863913 -232.344972) (xy 462.833889 -232.389009) (xy 462.797637 -232.42808) (xy 462.755966 -232.461311)
			(xy 462.709808 -232.48796) (xy 462.660194 -232.507432) (xy 462.608232 -232.519292) (xy 462.555082 -232.523276)
			(xy 462.501932 -232.519292) (xy 462.44997 -232.507432) (xy 462.400356 -232.48796) (xy 462.354198 -232.461311)
			(xy 462.312527 -232.42808) (xy 462.276275 -232.389009) (xy 462.246251 -232.344972) (xy 462.223125 -232.296951)
			(xy 462.207415 -232.246021) (xy 462.199472 -232.193317) (xy 461.9625 -232.193317) (xy 461.9625 -233.893339)
			(xy 462.199472 -233.893339) (xy 462.199472 -233.840041) (xy 462.207415 -233.787337) (xy 462.223125 -233.736407)
			(xy 462.246251 -233.688386) (xy 462.276275 -233.644349) (xy 462.312527 -233.605278) (xy 462.354198 -233.572047)
			(xy 462.400356 -233.545398) (xy 462.44997 -233.525926) (xy 462.501932 -233.514066) (xy 462.555082 -233.510083)
			(xy 462.608232 -233.514066) (xy 462.660194 -233.525926) (xy 462.709808 -233.545398) (xy 462.755966 -233.572047)
			(xy 462.797637 -233.605278) (xy 462.833889 -233.644349) (xy 462.863913 -233.688386) (xy 462.887039 -233.736407)
			(xy 462.902749 -233.787337) (xy 462.910692 -233.840041) (xy 462.91119 -233.86669) (xy 462.910692 -233.893339)
			(xy 464.409272 -233.893339) (xy 464.409272 -233.840041) (xy 464.417215 -233.787337) (xy 464.432925 -233.736407)
			(xy 464.456051 -233.688386) (xy 464.486075 -233.644349) (xy 464.522327 -233.605278) (xy 464.563998 -233.572047)
			(xy 464.610156 -233.545398) (xy 464.65977 -233.525926) (xy 464.711732 -233.514066) (xy 464.764882 -233.510083)
			(xy 464.818032 -233.514066) (xy 464.869994 -233.525926) (xy 464.919608 -233.545398) (xy 464.965766 -233.572047)
			(xy 465.007437 -233.605278) (xy 465.043689 -233.644349) (xy 465.073713 -233.688386) (xy 465.096839 -233.736407)
			(xy 465.112549 -233.787337) (xy 465.120492 -233.840041) (xy 465.12099 -233.86669) (xy 465.120492 -233.893339)
			(xy 465.112549 -233.946043) (xy 465.096839 -233.996973) (xy 465.073713 -234.044994) (xy 465.043689 -234.089031)
			(xy 465.007437 -234.128102) (xy 464.965766 -234.161333) (xy 464.919608 -234.187982) (xy 464.869994 -234.207454)
			(xy 464.818032 -234.219314) (xy 464.764882 -234.223298) (xy 464.711732 -234.219314) (xy 464.65977 -234.207454)
			(xy 464.610156 -234.187982) (xy 464.563998 -234.161333) (xy 464.522327 -234.128102) (xy 464.486075 -234.089031)
			(xy 464.456051 -234.044994) (xy 464.432925 -233.996973) (xy 464.417215 -233.946043) (xy 464.409272 -233.893339)
			(xy 462.910692 -233.893339) (xy 462.902749 -233.946043) (xy 462.887039 -233.996973) (xy 462.863913 -234.044994)
			(xy 462.833889 -234.089031) (xy 462.797637 -234.128102) (xy 462.755966 -234.161333) (xy 462.709808 -234.187982)
			(xy 462.660194 -234.207454) (xy 462.608232 -234.219314) (xy 462.555082 -234.223298) (xy 462.501932 -234.219314)
			(xy 462.44997 -234.207454) (xy 462.400356 -234.187982) (xy 462.354198 -234.161333) (xy 462.312527 -234.128102)
			(xy 462.276275 -234.089031) (xy 462.246251 -234.044994) (xy 462.223125 -233.996973) (xy 462.207415 -233.946043)
			(xy 462.199472 -233.893339) (xy 461.9625 -233.893339) (xy 461.9625 -235.593361) (xy 462.199472 -235.593361)
			(xy 462.199472 -235.540063) (xy 462.207415 -235.487359) (xy 462.223125 -235.436429) (xy 462.246251 -235.388408)
			(xy 462.276275 -235.344371) (xy 462.312527 -235.3053) (xy 462.354198 -235.272069) (xy 462.400356 -235.24542)
			(xy 462.44997 -235.225948) (xy 462.501932 -235.214088) (xy 462.555082 -235.210105) (xy 462.608232 -235.214088)
			(xy 462.660194 -235.225948) (xy 462.709808 -235.24542) (xy 462.755966 -235.272069) (xy 462.797637 -235.3053)
			(xy 462.833889 -235.344371) (xy 462.863913 -235.388408) (xy 462.887039 -235.436429) (xy 462.902749 -235.487359)
			(xy 462.910692 -235.540063) (xy 462.91119 -235.566712) (xy 462.910692 -235.593361) (xy 464.409272 -235.593361)
			(xy 464.409272 -235.540063) (xy 464.417215 -235.487359) (xy 464.432925 -235.436429) (xy 464.456051 -235.388408)
			(xy 464.486075 -235.344371) (xy 464.522327 -235.3053) (xy 464.563998 -235.272069) (xy 464.610156 -235.24542)
			(xy 464.65977 -235.225948) (xy 464.711732 -235.214088) (xy 464.764882 -235.210105) (xy 464.818032 -235.214088)
			(xy 464.869994 -235.225948) (xy 464.919608 -235.24542) (xy 464.965766 -235.272069) (xy 465.007437 -235.3053)
			(xy 465.043689 -235.344371) (xy 465.073713 -235.388408) (xy 465.096839 -235.436429) (xy 465.112549 -235.487359)
			(xy 465.120492 -235.540063) (xy 465.12099 -235.566712) (xy 465.120492 -235.593361) (xy 465.112549 -235.646065)
			(xy 465.096839 -235.696995) (xy 465.073713 -235.745016) (xy 465.043689 -235.789053) (xy 465.007437 -235.828124)
			(xy 464.965766 -235.861355) (xy 464.919608 -235.888004) (xy 464.869994 -235.907476) (xy 464.818032 -235.919336)
			(xy 464.764882 -235.92332) (xy 464.711732 -235.919336) (xy 464.65977 -235.907476) (xy 464.610156 -235.888004)
			(xy 464.563998 -235.861355) (xy 464.522327 -235.828124) (xy 464.486075 -235.789053) (xy 464.456051 -235.745016)
			(xy 464.432925 -235.696995) (xy 464.417215 -235.646065) (xy 464.409272 -235.593361) (xy 462.910692 -235.593361)
			(xy 462.902749 -235.646065) (xy 462.887039 -235.696995) (xy 462.863913 -235.745016) (xy 462.833889 -235.789053)
			(xy 462.797637 -235.828124) (xy 462.755966 -235.861355) (xy 462.709808 -235.888004) (xy 462.660194 -235.907476)
			(xy 462.608232 -235.919336) (xy 462.555082 -235.92332) (xy 462.501932 -235.919336) (xy 462.44997 -235.907476)
			(xy 462.400356 -235.888004) (xy 462.354198 -235.861355) (xy 462.312527 -235.828124) (xy 462.276275 -235.789053)
			(xy 462.246251 -235.745016) (xy 462.223125 -235.696995) (xy 462.207415 -235.646065) (xy 462.199472 -235.593361)
			(xy 461.9625 -235.593361) (xy 461.9625 -238.143267) (xy 462.199472 -238.143267) (xy 462.199472 -238.089969)
			(xy 462.207415 -238.037265) (xy 462.223125 -237.986335) (xy 462.246251 -237.938314) (xy 462.276275 -237.894277)
			(xy 462.312527 -237.855206) (xy 462.354198 -237.821975) (xy 462.400356 -237.795326) (xy 462.44997 -237.775854)
			(xy 462.501932 -237.763994) (xy 462.555082 -237.760011) (xy 462.608232 -237.763994) (xy 462.660194 -237.775854)
			(xy 462.709808 -237.795326) (xy 462.755966 -237.821975) (xy 462.797637 -237.855206) (xy 462.833889 -237.894277)
			(xy 462.863913 -237.938314) (xy 462.887039 -237.986335) (xy 462.902749 -238.037265) (xy 462.910692 -238.089969)
			(xy 462.91119 -238.116618) (xy 462.910692 -238.143267) (xy 464.409272 -238.143267) (xy 464.409272 -238.089969)
			(xy 464.417215 -238.037265) (xy 464.432925 -237.986335) (xy 464.456051 -237.938314) (xy 464.486075 -237.894277)
			(xy 464.522327 -237.855206) (xy 464.563998 -237.821975) (xy 464.610156 -237.795326) (xy 464.65977 -237.775854)
			(xy 464.711732 -237.763994) (xy 464.764882 -237.760011) (xy 464.818032 -237.763994) (xy 464.869994 -237.775854)
			(xy 464.919608 -237.795326) (xy 464.965766 -237.821975) (xy 465.007437 -237.855206) (xy 465.043689 -237.894277)
			(xy 465.073713 -237.938314) (xy 465.096839 -237.986335) (xy 465.112549 -238.037265) (xy 465.120492 -238.089969)
			(xy 465.12099 -238.116618) (xy 465.120492 -238.143267) (xy 465.112549 -238.195971) (xy 465.096839 -238.246901)
			(xy 465.073713 -238.294922) (xy 465.043689 -238.338959) (xy 465.007437 -238.37803) (xy 464.965766 -238.411261)
			(xy 464.919608 -238.43791) (xy 464.869994 -238.457382) (xy 464.818032 -238.469242) (xy 464.764882 -238.473226)
			(xy 464.711732 -238.469242) (xy 464.65977 -238.457382) (xy 464.610156 -238.43791) (xy 464.563998 -238.411261)
			(xy 464.522327 -238.37803) (xy 464.486075 -238.338959) (xy 464.456051 -238.294922) (xy 464.432925 -238.246901)
			(xy 464.417215 -238.195971) (xy 464.409272 -238.143267) (xy 462.910692 -238.143267) (xy 462.902749 -238.195971)
			(xy 462.887039 -238.246901) (xy 462.863913 -238.294922) (xy 462.833889 -238.338959) (xy 462.797637 -238.37803)
			(xy 462.755966 -238.411261) (xy 462.709808 -238.43791) (xy 462.660194 -238.457382) (xy 462.608232 -238.469242)
			(xy 462.555082 -238.473226) (xy 462.501932 -238.469242) (xy 462.44997 -238.457382) (xy 462.400356 -238.43791)
			(xy 462.354198 -238.411261) (xy 462.312527 -238.37803) (xy 462.276275 -238.338959) (xy 462.246251 -238.294922)
			(xy 462.223125 -238.246901) (xy 462.207415 -238.195971) (xy 462.199472 -238.143267) (xy 461.9625 -238.143267)
			(xy 461.9625 -239.843289) (xy 462.199472 -239.843289) (xy 462.199472 -239.789991) (xy 462.207415 -239.737287)
			(xy 462.223125 -239.686357) (xy 462.246251 -239.638336) (xy 462.276275 -239.594299) (xy 462.312527 -239.555228)
			(xy 462.354198 -239.521997) (xy 462.400356 -239.495348) (xy 462.44997 -239.475876) (xy 462.501932 -239.464016)
			(xy 462.555082 -239.460033) (xy 462.608232 -239.464016) (xy 462.660194 -239.475876) (xy 462.709808 -239.495348)
			(xy 462.755966 -239.521997) (xy 462.797637 -239.555228) (xy 462.833889 -239.594299) (xy 462.863913 -239.638336)
			(xy 462.887039 -239.686357) (xy 462.902749 -239.737287) (xy 462.910692 -239.789991) (xy 462.91119 -239.81664)
			(xy 462.910692 -239.843289) (xy 464.409272 -239.843289) (xy 464.409272 -239.789991) (xy 464.417215 -239.737287)
			(xy 464.432925 -239.686357) (xy 464.456051 -239.638336) (xy 464.486075 -239.594299) (xy 464.522327 -239.555228)
			(xy 464.563998 -239.521997) (xy 464.610156 -239.495348) (xy 464.65977 -239.475876) (xy 464.711732 -239.464016)
			(xy 464.764882 -239.460033) (xy 464.818032 -239.464016) (xy 464.869994 -239.475876) (xy 464.919608 -239.495348)
			(xy 464.965766 -239.521997) (xy 465.007437 -239.555228) (xy 465.043689 -239.594299) (xy 465.073713 -239.638336)
			(xy 465.096839 -239.686357) (xy 465.112549 -239.737287) (xy 465.120492 -239.789991) (xy 465.12099 -239.81664)
			(xy 465.120492 -239.843289) (xy 465.112549 -239.895993) (xy 465.096839 -239.946923) (xy 465.073713 -239.994944)
			(xy 465.043689 -240.038981) (xy 465.007437 -240.078052) (xy 464.965766 -240.111283) (xy 464.919608 -240.137932)
			(xy 464.869994 -240.157404) (xy 464.818032 -240.169264) (xy 464.764882 -240.173248) (xy 464.711732 -240.169264)
			(xy 464.65977 -240.157404) (xy 464.610156 -240.137932) (xy 464.563998 -240.111283) (xy 464.522327 -240.078052)
			(xy 464.486075 -240.038981) (xy 464.456051 -239.994944) (xy 464.432925 -239.946923) (xy 464.417215 -239.895993)
			(xy 464.409272 -239.843289) (xy 462.910692 -239.843289) (xy 462.902749 -239.895993) (xy 462.887039 -239.946923)
			(xy 462.863913 -239.994944) (xy 462.833889 -240.038981) (xy 462.797637 -240.078052) (xy 462.755966 -240.111283)
			(xy 462.709808 -240.137932) (xy 462.660194 -240.157404) (xy 462.608232 -240.169264) (xy 462.555082 -240.173248)
			(xy 462.501932 -240.169264) (xy 462.44997 -240.157404) (xy 462.400356 -240.137932) (xy 462.354198 -240.111283)
			(xy 462.312527 -240.078052) (xy 462.276275 -240.038981) (xy 462.246251 -239.994944) (xy 462.223125 -239.946923)
			(xy 462.207415 -239.895993) (xy 462.199472 -239.843289) (xy 461.9625 -239.843289) (xy 461.9625 -241.543311)
			(xy 462.199472 -241.543311) (xy 462.199472 -241.490013) (xy 462.207415 -241.437309) (xy 462.223125 -241.386379)
			(xy 462.246251 -241.338358) (xy 462.276275 -241.294321) (xy 462.312527 -241.25525) (xy 462.354198 -241.222019)
			(xy 462.400356 -241.19537) (xy 462.44997 -241.175898) (xy 462.501932 -241.164038) (xy 462.555082 -241.160055)
			(xy 462.608232 -241.164038) (xy 462.660194 -241.175898) (xy 462.709808 -241.19537) (xy 462.755966 -241.222019)
			(xy 462.797637 -241.25525) (xy 462.833889 -241.294321) (xy 462.863913 -241.338358) (xy 462.887039 -241.386379)
			(xy 462.902749 -241.437309) (xy 462.910692 -241.490013) (xy 462.91119 -241.516662) (xy 462.910692 -241.543311)
			(xy 464.409272 -241.543311) (xy 464.409272 -241.490013) (xy 464.417215 -241.437309) (xy 464.432925 -241.386379)
			(xy 464.456051 -241.338358) (xy 464.486075 -241.294321) (xy 464.522327 -241.25525) (xy 464.563998 -241.222019)
			(xy 464.610156 -241.19537) (xy 464.65977 -241.175898) (xy 464.711732 -241.164038) (xy 464.764882 -241.160055)
			(xy 464.818032 -241.164038) (xy 464.869994 -241.175898) (xy 464.919608 -241.19537) (xy 464.965766 -241.222019)
			(xy 465.007437 -241.25525) (xy 465.043689 -241.294321) (xy 465.073713 -241.338358) (xy 465.096839 -241.386379)
			(xy 465.112549 -241.437309) (xy 465.120492 -241.490013) (xy 465.12099 -241.516662) (xy 465.120492 -241.543311)
			(xy 465.112549 -241.596015) (xy 465.096839 -241.646945) (xy 465.073713 -241.694966) (xy 465.043689 -241.739003)
			(xy 465.007437 -241.778074) (xy 464.965766 -241.811305) (xy 464.919608 -241.837954) (xy 464.869994 -241.857426)
			(xy 464.818032 -241.869286) (xy 464.764882 -241.87327) (xy 464.711732 -241.869286) (xy 464.65977 -241.857426)
			(xy 464.610156 -241.837954) (xy 464.563998 -241.811305) (xy 464.522327 -241.778074) (xy 464.486075 -241.739003)
			(xy 464.456051 -241.694966) (xy 464.432925 -241.646945) (xy 464.417215 -241.596015) (xy 464.409272 -241.543311)
			(xy 462.910692 -241.543311) (xy 462.902749 -241.596015) (xy 462.887039 -241.646945) (xy 462.863913 -241.694966)
			(xy 462.833889 -241.739003) (xy 462.797637 -241.778074) (xy 462.755966 -241.811305) (xy 462.709808 -241.837954)
			(xy 462.660194 -241.857426) (xy 462.608232 -241.869286) (xy 462.555082 -241.87327) (xy 462.501932 -241.869286)
			(xy 462.44997 -241.857426) (xy 462.400356 -241.837954) (xy 462.354198 -241.811305) (xy 462.312527 -241.778074)
			(xy 462.276275 -241.739003) (xy 462.246251 -241.694966) (xy 462.223125 -241.646945) (xy 462.207415 -241.596015)
			(xy 462.199472 -241.543311) (xy 461.9625 -241.543311) (xy 461.9625 -242.393449) (xy 462.174072 -242.393449)
			(xy 462.174072 -242.340151) (xy 462.182015 -242.287447) (xy 462.197725 -242.236517) (xy 462.220851 -242.188496)
			(xy 462.250875 -242.144459) (xy 462.287127 -242.105388) (xy 462.328798 -242.072157) (xy 462.374956 -242.045508)
			(xy 462.42457 -242.026036) (xy 462.476532 -242.014176) (xy 462.529682 -242.010193) (xy 462.582832 -242.014176)
			(xy 462.634794 -242.026036) (xy 462.684408 -242.045508) (xy 462.730566 -242.072157) (xy 462.772237 -242.105388)
			(xy 462.808489 -242.144459) (xy 462.838513 -242.188496) (xy 462.861639 -242.236517) (xy 462.877349 -242.287447)
			(xy 462.885292 -242.340151) (xy 462.88579 -242.3668) (xy 462.885292 -242.393449) (xy 462.877349 -242.446153)
			(xy 462.861639 -242.497083) (xy 462.838513 -242.545104) (xy 462.808489 -242.589141) (xy 462.772237 -242.628212)
			(xy 462.730566 -242.661443) (xy 462.684408 -242.688092) (xy 462.634794 -242.707564) (xy 462.582832 -242.719424)
			(xy 462.529682 -242.723408) (xy 462.476532 -242.719424) (xy 462.42457 -242.707564) (xy 462.374956 -242.688092)
			(xy 462.328798 -242.661443) (xy 462.287127 -242.628212) (xy 462.250875 -242.589141) (xy 462.220851 -242.545104)
			(xy 462.197725 -242.497083) (xy 462.182015 -242.446153) (xy 462.174072 -242.393449) (xy 461.9625 -242.393449)
			(xy 461.9625 -243.243333) (xy 462.174072 -243.243333) (xy 462.174072 -243.190035) (xy 462.182015 -243.137331)
			(xy 462.197725 -243.086401) (xy 462.220851 -243.03838) (xy 462.250875 -242.994343) (xy 462.287127 -242.955272)
			(xy 462.328798 -242.922041) (xy 462.374956 -242.895392) (xy 462.42457 -242.87592) (xy 462.476532 -242.86406)
			(xy 462.529682 -242.860077) (xy 462.582832 -242.86406) (xy 462.634794 -242.87592) (xy 462.684408 -242.895392)
			(xy 462.730566 -242.922041) (xy 462.772237 -242.955272) (xy 462.808489 -242.994343) (xy 462.838513 -243.03838)
			(xy 462.861639 -243.086401) (xy 462.877349 -243.137331) (xy 462.885292 -243.190035) (xy 462.88579 -243.216684)
			(xy 462.885292 -243.243333) (xy 462.877349 -243.296037) (xy 462.861639 -243.346967) (xy 462.838513 -243.394988)
			(xy 462.808489 -243.439025) (xy 462.772237 -243.478096) (xy 462.730566 -243.511327) (xy 462.684408 -243.537976)
			(xy 462.634794 -243.557448) (xy 462.582832 -243.569308) (xy 462.529682 -243.573292) (xy 462.476532 -243.569308)
			(xy 462.42457 -243.557448) (xy 462.374956 -243.537976) (xy 462.328798 -243.511327) (xy 462.287127 -243.478096)
			(xy 462.250875 -243.439025) (xy 462.220851 -243.394988) (xy 462.197725 -243.346967) (xy 462.182015 -243.296037)
			(xy 462.174072 -243.243333) (xy 461.9625 -243.243333) (xy 461.9625 -244.093217) (xy 462.199472 -244.093217)
			(xy 462.199472 -244.039919) (xy 462.207415 -243.987215) (xy 462.223125 -243.936285) (xy 462.246251 -243.888264)
			(xy 462.276275 -243.844227) (xy 462.312527 -243.805156) (xy 462.354198 -243.771925) (xy 462.400356 -243.745276)
			(xy 462.44997 -243.725804) (xy 462.501932 -243.713944) (xy 462.555082 -243.709961) (xy 462.608232 -243.713944)
			(xy 462.660194 -243.725804) (xy 462.709808 -243.745276) (xy 462.755966 -243.771925) (xy 462.797637 -243.805156)
			(xy 462.833889 -243.844227) (xy 462.863913 -243.888264) (xy 462.887039 -243.936285) (xy 462.902749 -243.987215)
			(xy 462.910692 -244.039919) (xy 462.91119 -244.066568) (xy 462.910692 -244.093217) (xy 464.409272 -244.093217)
			(xy 464.409272 -244.039919) (xy 464.417215 -243.987215) (xy 464.432925 -243.936285) (xy 464.456051 -243.888264)
			(xy 464.486075 -243.844227) (xy 464.522327 -243.805156) (xy 464.563998 -243.771925) (xy 464.610156 -243.745276)
			(xy 464.65977 -243.725804) (xy 464.711732 -243.713944) (xy 464.764882 -243.709961) (xy 464.818032 -243.713944)
			(xy 464.869994 -243.725804) (xy 464.919608 -243.745276) (xy 464.965766 -243.771925) (xy 465.007437 -243.805156)
			(xy 465.043689 -243.844227) (xy 465.073713 -243.888264) (xy 465.096839 -243.936285) (xy 465.112549 -243.987215)
			(xy 465.120492 -244.039919) (xy 465.12099 -244.066568) (xy 465.120492 -244.093217) (xy 465.112549 -244.145921)
			(xy 465.096839 -244.196851) (xy 465.073713 -244.244872) (xy 465.043689 -244.288909) (xy 465.007437 -244.32798)
			(xy 464.965766 -244.361211) (xy 464.919608 -244.38786) (xy 464.869994 -244.407332) (xy 464.818032 -244.419192)
			(xy 464.764882 -244.423176) (xy 464.711732 -244.419192) (xy 464.65977 -244.407332) (xy 464.610156 -244.38786)
			(xy 464.563998 -244.361211) (xy 464.522327 -244.32798) (xy 464.486075 -244.288909) (xy 464.456051 -244.244872)
			(xy 464.432925 -244.196851) (xy 464.417215 -244.145921) (xy 464.409272 -244.093217) (xy 462.910692 -244.093217)
			(xy 462.902749 -244.145921) (xy 462.887039 -244.196851) (xy 462.863913 -244.244872) (xy 462.833889 -244.288909)
			(xy 462.797637 -244.32798) (xy 462.755966 -244.361211) (xy 462.709808 -244.38786) (xy 462.660194 -244.407332)
			(xy 462.608232 -244.419192) (xy 462.555082 -244.423176) (xy 462.501932 -244.419192) (xy 462.44997 -244.407332)
			(xy 462.400356 -244.38786) (xy 462.354198 -244.361211) (xy 462.312527 -244.32798) (xy 462.276275 -244.288909)
			(xy 462.246251 -244.244872) (xy 462.223125 -244.196851) (xy 462.207415 -244.145921) (xy 462.199472 -244.093217)
			(xy 461.9625 -244.093217) (xy 461.9625 -244.943355) (xy 462.199472 -244.943355) (xy 462.199472 -244.890057)
			(xy 462.207415 -244.837353) (xy 462.223125 -244.786423) (xy 462.246251 -244.738402) (xy 462.276275 -244.694365)
			(xy 462.312527 -244.655294) (xy 462.354198 -244.622063) (xy 462.400356 -244.595414) (xy 462.44997 -244.575942)
			(xy 462.501932 -244.564082) (xy 462.555082 -244.560099) (xy 462.608232 -244.564082) (xy 462.660194 -244.575942)
			(xy 462.709808 -244.595414) (xy 462.755966 -244.622063) (xy 462.797637 -244.655294) (xy 462.833889 -244.694365)
			(xy 462.863913 -244.738402) (xy 462.887039 -244.786423) (xy 462.902749 -244.837353) (xy 462.910692 -244.890057)
			(xy 462.91119 -244.916706) (xy 462.910692 -244.943355) (xy 462.902749 -244.996059) (xy 462.887039 -245.046989)
			(xy 462.863913 -245.09501) (xy 462.833889 -245.139047) (xy 462.797637 -245.178118) (xy 462.755966 -245.211349)
			(xy 462.709808 -245.237998) (xy 462.660194 -245.25747) (xy 462.608232 -245.26933) (xy 462.555082 -245.273314)
			(xy 462.501932 -245.26933) (xy 462.44997 -245.25747) (xy 462.400356 -245.237998) (xy 462.354198 -245.211349)
			(xy 462.312527 -245.178118) (xy 462.276275 -245.139047) (xy 462.246251 -245.09501) (xy 462.223125 -245.046989)
			(xy 462.207415 -244.996059) (xy 462.199472 -244.943355) (xy 461.9625 -244.943355) (xy 461.9625 -245.793239)
			(xy 462.199472 -245.793239) (xy 462.199472 -245.739941) (xy 462.207415 -245.687237) (xy 462.223125 -245.636307)
			(xy 462.246251 -245.588286) (xy 462.276275 -245.544249) (xy 462.312527 -245.505178) (xy 462.354198 -245.471947)
			(xy 462.400356 -245.445298) (xy 462.44997 -245.425826) (xy 462.501932 -245.413966) (xy 462.555082 -245.409983)
			(xy 462.608232 -245.413966) (xy 462.660194 -245.425826) (xy 462.709808 -245.445298) (xy 462.755966 -245.471947)
			(xy 462.797637 -245.505178) (xy 462.833889 -245.544249) (xy 462.863913 -245.588286) (xy 462.887039 -245.636307)
			(xy 462.902749 -245.687237) (xy 462.910692 -245.739941) (xy 462.91119 -245.76659) (xy 462.910692 -245.793239)
			(xy 464.409272 -245.793239) (xy 464.409272 -245.739941) (xy 464.417215 -245.687237) (xy 464.432925 -245.636307)
			(xy 464.456051 -245.588286) (xy 464.486075 -245.544249) (xy 464.522327 -245.505178) (xy 464.563998 -245.471947)
			(xy 464.610156 -245.445298) (xy 464.65977 -245.425826) (xy 464.711732 -245.413966) (xy 464.764882 -245.409983)
			(xy 464.818032 -245.413966) (xy 464.869994 -245.425826) (xy 464.919608 -245.445298) (xy 464.965766 -245.471947)
			(xy 465.007437 -245.505178) (xy 465.043689 -245.544249) (xy 465.073713 -245.588286) (xy 465.096839 -245.636307)
			(xy 465.112549 -245.687237) (xy 465.120492 -245.739941) (xy 465.12099 -245.76659) (xy 465.120492 -245.793239)
			(xy 465.112549 -245.845943) (xy 465.096839 -245.896873) (xy 465.073713 -245.944894) (xy 465.043689 -245.988931)
			(xy 465.007437 -246.028002) (xy 464.965766 -246.061233) (xy 464.919608 -246.087882) (xy 464.869994 -246.107354)
			(xy 464.818032 -246.119214) (xy 464.764882 -246.123198) (xy 464.711732 -246.119214) (xy 464.65977 -246.107354)
			(xy 464.610156 -246.087882) (xy 464.563998 -246.061233) (xy 464.522327 -246.028002) (xy 464.486075 -245.988931)
			(xy 464.456051 -245.944894) (xy 464.432925 -245.896873) (xy 464.417215 -245.845943) (xy 464.409272 -245.793239)
			(xy 462.910692 -245.793239) (xy 462.902749 -245.845943) (xy 462.887039 -245.896873) (xy 462.863913 -245.944894)
			(xy 462.833889 -245.988931) (xy 462.797637 -246.028002) (xy 462.755966 -246.061233) (xy 462.709808 -246.087882)
			(xy 462.660194 -246.107354) (xy 462.608232 -246.119214) (xy 462.555082 -246.123198) (xy 462.501932 -246.119214)
			(xy 462.44997 -246.107354) (xy 462.400356 -246.087882) (xy 462.354198 -246.061233) (xy 462.312527 -246.028002)
			(xy 462.276275 -245.988931) (xy 462.246251 -245.944894) (xy 462.223125 -245.896873) (xy 462.207415 -245.845943)
			(xy 462.199472 -245.793239) (xy 461.9625 -245.793239) (xy 461.9625 -247.493261) (xy 462.199472 -247.493261)
			(xy 462.199472 -247.439963) (xy 462.207415 -247.387259) (xy 462.223125 -247.336329) (xy 462.246251 -247.288308)
			(xy 462.276275 -247.244271) (xy 462.312527 -247.2052) (xy 462.354198 -247.171969) (xy 462.400356 -247.14532)
			(xy 462.44997 -247.125848) (xy 462.501932 -247.113988) (xy 462.555082 -247.110005) (xy 462.608232 -247.113988)
			(xy 462.660194 -247.125848) (xy 462.709808 -247.14532) (xy 462.755966 -247.171969) (xy 462.797637 -247.2052)
			(xy 462.833889 -247.244271) (xy 462.863913 -247.288308) (xy 462.887039 -247.336329) (xy 462.902749 -247.387259)
			(xy 462.910692 -247.439963) (xy 462.91119 -247.466612) (xy 462.910692 -247.493261) (xy 464.409272 -247.493261)
			(xy 464.409272 -247.439963) (xy 464.417215 -247.387259) (xy 464.432925 -247.336329) (xy 464.456051 -247.288308)
			(xy 464.486075 -247.244271) (xy 464.522327 -247.2052) (xy 464.563998 -247.171969) (xy 464.610156 -247.14532)
			(xy 464.65977 -247.125848) (xy 464.711732 -247.113988) (xy 464.764882 -247.110005) (xy 464.818032 -247.113988)
			(xy 464.869994 -247.125848) (xy 464.919608 -247.14532) (xy 464.965766 -247.171969) (xy 465.007437 -247.2052)
			(xy 465.043689 -247.244271) (xy 465.073713 -247.288308) (xy 465.096839 -247.336329) (xy 465.112549 -247.387259)
			(xy 465.120492 -247.439963) (xy 465.12099 -247.466612) (xy 465.120492 -247.493261) (xy 465.112549 -247.545965)
			(xy 465.096839 -247.596895) (xy 465.073713 -247.644916) (xy 465.043689 -247.688953) (xy 465.007437 -247.728024)
			(xy 464.965766 -247.761255) (xy 464.919608 -247.787904) (xy 464.869994 -247.807376) (xy 464.818032 -247.819236)
			(xy 464.764882 -247.82322) (xy 464.711732 -247.819236) (xy 464.65977 -247.807376) (xy 464.610156 -247.787904)
			(xy 464.563998 -247.761255) (xy 464.522327 -247.728024) (xy 464.486075 -247.688953) (xy 464.456051 -247.644916)
			(xy 464.432925 -247.596895) (xy 464.417215 -247.545965) (xy 464.409272 -247.493261) (xy 462.910692 -247.493261)
			(xy 462.902749 -247.545965) (xy 462.887039 -247.596895) (xy 462.863913 -247.644916) (xy 462.833889 -247.688953)
			(xy 462.797637 -247.728024) (xy 462.755966 -247.761255) (xy 462.709808 -247.787904) (xy 462.660194 -247.807376)
			(xy 462.608232 -247.819236) (xy 462.555082 -247.82322) (xy 462.501932 -247.819236) (xy 462.44997 -247.807376)
			(xy 462.400356 -247.787904) (xy 462.354198 -247.761255) (xy 462.312527 -247.728024) (xy 462.276275 -247.688953)
			(xy 462.246251 -247.644916) (xy 462.223125 -247.596895) (xy 462.207415 -247.545965) (xy 462.199472 -247.493261)
			(xy 461.9625 -247.493261) (xy 461.9625 -249.193283) (xy 462.199472 -249.193283) (xy 462.199472 -249.139985)
			(xy 462.207415 -249.087281) (xy 462.223125 -249.036351) (xy 462.246251 -248.98833) (xy 462.276275 -248.944293)
			(xy 462.312527 -248.905222) (xy 462.354198 -248.871991) (xy 462.400356 -248.845342) (xy 462.44997 -248.82587)
			(xy 462.501932 -248.81401) (xy 462.555082 -248.810027) (xy 462.608232 -248.81401) (xy 462.660194 -248.82587)
			(xy 462.709808 -248.845342) (xy 462.755966 -248.871991) (xy 462.797637 -248.905222) (xy 462.833889 -248.944293)
			(xy 462.863913 -248.98833) (xy 462.887039 -249.036351) (xy 462.902749 -249.087281) (xy 462.910692 -249.139985)
			(xy 462.91119 -249.166634) (xy 462.910692 -249.193283) (xy 464.409272 -249.193283) (xy 464.409272 -249.139985)
			(xy 464.417215 -249.087281) (xy 464.432925 -249.036351) (xy 464.456051 -248.98833) (xy 464.486075 -248.944293)
			(xy 464.522327 -248.905222) (xy 464.563998 -248.871991) (xy 464.610156 -248.845342) (xy 464.65977 -248.82587)
			(xy 464.711732 -248.81401) (xy 464.764882 -248.810027) (xy 464.818032 -248.81401) (xy 464.869994 -248.82587)
			(xy 464.919608 -248.845342) (xy 464.965766 -248.871991) (xy 465.007437 -248.905222) (xy 465.043689 -248.944293)
			(xy 465.073713 -248.98833) (xy 465.096839 -249.036351) (xy 465.112549 -249.087281) (xy 465.120492 -249.139985)
			(xy 465.12099 -249.166634) (xy 465.120492 -249.193283) (xy 465.112549 -249.245987) (xy 465.096839 -249.296917)
			(xy 465.073713 -249.344938) (xy 465.043689 -249.388975) (xy 465.007437 -249.428046) (xy 464.965766 -249.461277)
			(xy 464.919608 -249.487926) (xy 464.869994 -249.507398) (xy 464.818032 -249.519258) (xy 464.764882 -249.523242)
			(xy 464.711732 -249.519258) (xy 464.65977 -249.507398) (xy 464.610156 -249.487926) (xy 464.563998 -249.461277)
			(xy 464.522327 -249.428046) (xy 464.486075 -249.388975) (xy 464.456051 -249.344938) (xy 464.432925 -249.296917)
			(xy 464.417215 -249.245987) (xy 464.409272 -249.193283) (xy 462.910692 -249.193283) (xy 462.902749 -249.245987)
			(xy 462.887039 -249.296917) (xy 462.863913 -249.344938) (xy 462.833889 -249.388975) (xy 462.797637 -249.428046)
			(xy 462.755966 -249.461277) (xy 462.709808 -249.487926) (xy 462.660194 -249.507398) (xy 462.608232 -249.519258)
			(xy 462.555082 -249.523242) (xy 462.501932 -249.519258) (xy 462.44997 -249.507398) (xy 462.400356 -249.487926)
			(xy 462.354198 -249.461277) (xy 462.312527 -249.428046) (xy 462.276275 -249.388975) (xy 462.246251 -249.344938)
			(xy 462.223125 -249.296917) (xy 462.207415 -249.245987) (xy 462.199472 -249.193283) (xy 461.9625 -249.193283)
			(xy 461.9625 -250.893305) (xy 462.199472 -250.893305) (xy 462.199472 -250.840007) (xy 462.207415 -250.787303)
			(xy 462.223125 -250.736373) (xy 462.246251 -250.688352) (xy 462.276275 -250.644315) (xy 462.312527 -250.605244)
			(xy 462.354198 -250.572013) (xy 462.400356 -250.545364) (xy 462.44997 -250.525892) (xy 462.501932 -250.514032)
			(xy 462.555082 -250.510049) (xy 462.608232 -250.514032) (xy 462.660194 -250.525892) (xy 462.709808 -250.545364)
			(xy 462.755966 -250.572013) (xy 462.797637 -250.605244) (xy 462.833889 -250.644315) (xy 462.863913 -250.688352)
			(xy 462.887039 -250.736373) (xy 462.902749 -250.787303) (xy 462.910692 -250.840007) (xy 462.91119 -250.866656)
			(xy 462.910692 -250.893305) (xy 464.409272 -250.893305) (xy 464.409272 -250.840007) (xy 464.417215 -250.787303)
			(xy 464.432925 -250.736373) (xy 464.456051 -250.688352) (xy 464.486075 -250.644315) (xy 464.522327 -250.605244)
			(xy 464.563998 -250.572013) (xy 464.610156 -250.545364) (xy 464.65977 -250.525892) (xy 464.711732 -250.514032)
			(xy 464.764882 -250.510049) (xy 464.818032 -250.514032) (xy 464.869994 -250.525892) (xy 464.919608 -250.545364)
			(xy 464.965766 -250.572013) (xy 465.007437 -250.605244) (xy 465.043689 -250.644315) (xy 465.073713 -250.688352)
			(xy 465.096839 -250.736373) (xy 465.112549 -250.787303) (xy 465.120492 -250.840007) (xy 465.12099 -250.866656)
			(xy 465.120492 -250.893305) (xy 465.112549 -250.946009) (xy 465.096839 -250.996939) (xy 465.073713 -251.04496)
			(xy 465.043689 -251.088997) (xy 465.007437 -251.128068) (xy 464.965766 -251.161299) (xy 464.919608 -251.187948)
			(xy 464.869994 -251.20742) (xy 464.818032 -251.21928) (xy 464.764882 -251.223264) (xy 464.711732 -251.21928)
			(xy 464.65977 -251.20742) (xy 464.610156 -251.187948) (xy 464.563998 -251.161299) (xy 464.522327 -251.128068)
			(xy 464.486075 -251.088997) (xy 464.456051 -251.04496) (xy 464.432925 -250.996939) (xy 464.417215 -250.946009)
			(xy 464.409272 -250.893305) (xy 462.910692 -250.893305) (xy 462.902749 -250.946009) (xy 462.887039 -250.996939)
			(xy 462.863913 -251.04496) (xy 462.833889 -251.088997) (xy 462.797637 -251.128068) (xy 462.755966 -251.161299)
			(xy 462.709808 -251.187948) (xy 462.660194 -251.20742) (xy 462.608232 -251.21928) (xy 462.555082 -251.223264)
			(xy 462.501932 -251.21928) (xy 462.44997 -251.20742) (xy 462.400356 -251.187948) (xy 462.354198 -251.161299)
			(xy 462.312527 -251.128068) (xy 462.276275 -251.088997) (xy 462.246251 -251.04496) (xy 462.223125 -250.996939)
			(xy 462.207415 -250.946009) (xy 462.199472 -250.893305) (xy 461.9625 -250.893305) (xy 461.9625 -252.593327)
			(xy 462.174072 -252.593327) (xy 462.174072 -252.540029) (xy 462.182015 -252.487325) (xy 462.197725 -252.436395)
			(xy 462.220851 -252.388374) (xy 462.250875 -252.344337) (xy 462.287127 -252.305266) (xy 462.328798 -252.272035)
			(xy 462.374956 -252.245386) (xy 462.42457 -252.225914) (xy 462.476532 -252.214054) (xy 462.529682 -252.210071)
			(xy 462.582832 -252.214054) (xy 462.634794 -252.225914) (xy 462.684408 -252.245386) (xy 462.730566 -252.272035)
			(xy 462.772237 -252.305266) (xy 462.808489 -252.344337) (xy 462.838513 -252.388374) (xy 462.861639 -252.436395)
			(xy 462.877349 -252.487325) (xy 462.885292 -252.540029) (xy 462.88579 -252.566678) (xy 462.885292 -252.593327)
			(xy 462.877349 -252.646031) (xy 462.861639 -252.696961) (xy 462.838513 -252.744982) (xy 462.808489 -252.789019)
			(xy 462.772237 -252.82809) (xy 462.730566 -252.861321) (xy 462.684408 -252.88797) (xy 462.634794 -252.907442)
			(xy 462.582832 -252.919302) (xy 462.529682 -252.923286) (xy 462.476532 -252.919302) (xy 462.42457 -252.907442)
			(xy 462.374956 -252.88797) (xy 462.328798 -252.861321) (xy 462.287127 -252.82809) (xy 462.250875 -252.789019)
			(xy 462.220851 -252.744982) (xy 462.197725 -252.696961) (xy 462.182015 -252.646031) (xy 462.174072 -252.593327)
			(xy 461.9625 -252.593327) (xy 461.9625 -253.302008) (xy 462.232248 -253.302008) (xy 462.274513 -253.302498)
			(xy 462.358681 -253.310302) (xy 462.441771 -253.325838) (xy 462.523073 -253.348974) (xy 462.601893 -253.379513)
			(xy 462.677559 -253.417194) (xy 462.749426 -253.461695) (xy 462.816881 -253.512638) (xy 462.879347 -253.569587)
			(xy 462.936293 -253.632056) (xy 462.987232 -253.699513) (xy 463.03173 -253.771383) (xy 463.069407 -253.847051)
			(xy 463.099941 -253.925873) (xy 463.123073 -254.007176) (xy 463.138605 -254.090266) (xy 463.146404 -254.174435)
			(xy 463.146404 -254.258965) (xy 463.138605 -254.343134) (xy 463.123073 -254.426224) (xy 463.099941 -254.507527)
			(xy 463.069407 -254.586349) (xy 463.03173 -254.662017) (xy 462.987232 -254.733887) (xy 462.936293 -254.801344)
			(xy 462.879347 -254.863813) (xy 462.816881 -254.920762) (xy 462.749426 -254.971705) (xy 462.677559 -255.016206)
			(xy 462.601893 -255.053887) (xy 462.523073 -255.084426) (xy 462.441771 -255.107562) (xy 462.358681 -255.123098)
			(xy 462.274513 -255.130902) (xy 462.232248 -255.131316) (xy 461.9625 -255.131316) (xy 461.9625 -258.543277)
			(xy 462.199472 -258.543277) (xy 462.199472 -258.489979) (xy 462.207415 -258.437275) (xy 462.223125 -258.386345)
			(xy 462.246251 -258.338324) (xy 462.276275 -258.294287) (xy 462.312527 -258.255216) (xy 462.354198 -258.221985)
			(xy 462.400356 -258.195336) (xy 462.44997 -258.175864) (xy 462.501932 -258.164004) (xy 462.555082 -258.160021)
			(xy 462.608232 -258.164004) (xy 462.660194 -258.175864) (xy 462.709808 -258.195336) (xy 462.755966 -258.221985)
			(xy 462.797637 -258.255216) (xy 462.833889 -258.294287) (xy 462.863913 -258.338324) (xy 462.887039 -258.386345)
			(xy 462.902749 -258.437275) (xy 462.910692 -258.489979) (xy 462.91119 -258.516628) (xy 462.910692 -258.543277)
			(xy 464.409272 -258.543277) (xy 464.409272 -258.489979) (xy 464.417215 -258.437275) (xy 464.432925 -258.386345)
			(xy 464.456051 -258.338324) (xy 464.486075 -258.294287) (xy 464.522327 -258.255216) (xy 464.563998 -258.221985)
			(xy 464.610156 -258.195336) (xy 464.65977 -258.175864) (xy 464.711732 -258.164004) (xy 464.764882 -258.160021)
			(xy 464.818032 -258.164004) (xy 464.869994 -258.175864) (xy 464.919608 -258.195336) (xy 464.965766 -258.221985)
			(xy 465.007437 -258.255216) (xy 465.043689 -258.294287) (xy 465.073713 -258.338324) (xy 465.096839 -258.386345)
			(xy 465.112549 -258.437275) (xy 465.120492 -258.489979) (xy 465.12099 -258.516628) (xy 465.120492 -258.543277)
			(xy 465.112549 -258.595981) (xy 465.096839 -258.646911) (xy 465.073713 -258.694932) (xy 465.043689 -258.738969)
			(xy 465.007437 -258.77804) (xy 464.965766 -258.811271) (xy 464.919608 -258.83792) (xy 464.869994 -258.857392)
			(xy 464.818032 -258.869252) (xy 464.764882 -258.873236) (xy 464.711732 -258.869252) (xy 464.65977 -258.857392)
			(xy 464.610156 -258.83792) (xy 464.563998 -258.811271) (xy 464.522327 -258.77804) (xy 464.486075 -258.738969)
			(xy 464.456051 -258.694932) (xy 464.432925 -258.646911) (xy 464.417215 -258.595981) (xy 464.409272 -258.543277)
			(xy 462.910692 -258.543277) (xy 462.902749 -258.595981) (xy 462.887039 -258.646911) (xy 462.863913 -258.694932)
			(xy 462.833889 -258.738969) (xy 462.797637 -258.77804) (xy 462.755966 -258.811271) (xy 462.709808 -258.83792)
			(xy 462.660194 -258.857392) (xy 462.608232 -258.869252) (xy 462.555082 -258.873236) (xy 462.501932 -258.869252)
			(xy 462.44997 -258.857392) (xy 462.400356 -258.83792) (xy 462.354198 -258.811271) (xy 462.312527 -258.77804)
			(xy 462.276275 -258.738969) (xy 462.246251 -258.694932) (xy 462.223125 -258.646911) (xy 462.207415 -258.595981)
			(xy 462.199472 -258.543277) (xy 461.9625 -258.543277) (xy 461.9625 -259.393415) (xy 462.199472 -259.393415)
			(xy 462.199472 -259.340117) (xy 462.207415 -259.287413) (xy 462.223125 -259.236483) (xy 462.246251 -259.188462)
			(xy 462.276275 -259.144425) (xy 462.312527 -259.105354) (xy 462.354198 -259.072123) (xy 462.400356 -259.045474)
			(xy 462.44997 -259.026002) (xy 462.501932 -259.014142) (xy 462.555082 -259.010159) (xy 462.608232 -259.014142)
			(xy 462.660194 -259.026002) (xy 462.709808 -259.045474) (xy 462.755966 -259.072123) (xy 462.797637 -259.105354)
			(xy 462.833889 -259.144425) (xy 462.863913 -259.188462) (xy 462.887039 -259.236483) (xy 462.902749 -259.287413)
			(xy 462.910692 -259.340117) (xy 462.91119 -259.366766) (xy 462.910692 -259.393415) (xy 462.902749 -259.446119)
			(xy 462.887039 -259.497049) (xy 462.863913 -259.54507) (xy 462.833889 -259.589107) (xy 462.797637 -259.628178)
			(xy 462.755966 -259.661409) (xy 462.709808 -259.688058) (xy 462.660194 -259.70753) (xy 462.608232 -259.71939)
			(xy 462.555082 -259.723374) (xy 462.501932 -259.71939) (xy 462.44997 -259.70753) (xy 462.400356 -259.688058)
			(xy 462.354198 -259.661409) (xy 462.312527 -259.628178) (xy 462.276275 -259.589107) (xy 462.246251 -259.54507)
			(xy 462.223125 -259.497049) (xy 462.207415 -259.446119) (xy 462.199472 -259.393415) (xy 461.9625 -259.393415)
			(xy 461.9625 -260.243299) (xy 462.199472 -260.243299) (xy 462.199472 -260.190001) (xy 462.207415 -260.137297)
			(xy 462.223125 -260.086367) (xy 462.246251 -260.038346) (xy 462.276275 -259.994309) (xy 462.312527 -259.955238)
			(xy 462.354198 -259.922007) (xy 462.400356 -259.895358) (xy 462.44997 -259.875886) (xy 462.501932 -259.864026)
			(xy 462.555082 -259.860043) (xy 462.608232 -259.864026) (xy 462.660194 -259.875886) (xy 462.709808 -259.895358)
			(xy 462.755966 -259.922007) (xy 462.797637 -259.955238) (xy 462.833889 -259.994309) (xy 462.863913 -260.038346)
			(xy 462.887039 -260.086367) (xy 462.902749 -260.137297) (xy 462.910692 -260.190001) (xy 462.91119 -260.21665)
			(xy 462.910692 -260.243299) (xy 462.902749 -260.296003) (xy 462.887039 -260.346933) (xy 462.863913 -260.394954)
			(xy 462.833889 -260.438991) (xy 462.797637 -260.478062) (xy 462.755966 -260.511293) (xy 462.709808 -260.537942)
			(xy 462.660194 -260.557414) (xy 462.608232 -260.569274) (xy 462.555082 -260.573258) (xy 462.501932 -260.569274)
			(xy 462.44997 -260.557414) (xy 462.400356 -260.537942) (xy 462.354198 -260.511293) (xy 462.312527 -260.478062)
			(xy 462.276275 -260.438991) (xy 462.246251 -260.394954) (xy 462.223125 -260.346933) (xy 462.207415 -260.296003)
			(xy 462.199472 -260.243299) (xy 461.9625 -260.243299) (xy 461.9625 -261.093437) (xy 462.199472 -261.093437)
			(xy 462.199472 -261.040139) (xy 462.207415 -260.987435) (xy 462.223125 -260.936505) (xy 462.246251 -260.888484)
			(xy 462.276275 -260.844447) (xy 462.312527 -260.805376) (xy 462.354198 -260.772145) (xy 462.400356 -260.745496)
			(xy 462.44997 -260.726024) (xy 462.501932 -260.714164) (xy 462.555082 -260.710181) (xy 462.608232 -260.714164)
			(xy 462.660194 -260.726024) (xy 462.709808 -260.745496) (xy 462.755966 -260.772145) (xy 462.797637 -260.805376)
			(xy 462.833889 -260.844447) (xy 462.863913 -260.888484) (xy 462.887039 -260.936505) (xy 462.902749 -260.987435)
			(xy 462.910692 -261.040139) (xy 462.91119 -261.066788) (xy 462.910692 -261.093437) (xy 464.409272 -261.093437)
			(xy 464.409272 -261.040139) (xy 464.417215 -260.987435) (xy 464.432925 -260.936505) (xy 464.456051 -260.888484)
			(xy 464.486075 -260.844447) (xy 464.522327 -260.805376) (xy 464.563998 -260.772145) (xy 464.610156 -260.745496)
			(xy 464.65977 -260.726024) (xy 464.711732 -260.714164) (xy 464.764882 -260.710181) (xy 464.818032 -260.714164)
			(xy 464.869994 -260.726024) (xy 464.919608 -260.745496) (xy 464.965766 -260.772145) (xy 465.007437 -260.805376)
			(xy 465.043689 -260.844447) (xy 465.073713 -260.888484) (xy 465.096839 -260.936505) (xy 465.112549 -260.987435)
			(xy 465.120492 -261.040139) (xy 465.12099 -261.066788) (xy 465.120492 -261.093437) (xy 465.112549 -261.146141)
			(xy 465.096839 -261.197071) (xy 465.073713 -261.245092) (xy 465.043689 -261.289129) (xy 465.007437 -261.3282)
			(xy 464.965766 -261.361431) (xy 464.919608 -261.38808) (xy 464.869994 -261.407552) (xy 464.818032 -261.419412)
			(xy 464.764882 -261.423396) (xy 464.711732 -261.419412) (xy 464.65977 -261.407552) (xy 464.610156 -261.38808)
			(xy 464.563998 -261.361431) (xy 464.522327 -261.3282) (xy 464.486075 -261.289129) (xy 464.456051 -261.245092)
			(xy 464.432925 -261.197071) (xy 464.417215 -261.146141) (xy 464.409272 -261.093437) (xy 462.910692 -261.093437)
			(xy 462.902749 -261.146141) (xy 462.887039 -261.197071) (xy 462.863913 -261.245092) (xy 462.833889 -261.289129)
			(xy 462.797637 -261.3282) (xy 462.755966 -261.361431) (xy 462.709808 -261.38808) (xy 462.660194 -261.407552)
			(xy 462.608232 -261.419412) (xy 462.555082 -261.423396) (xy 462.501932 -261.419412) (xy 462.44997 -261.407552)
			(xy 462.400356 -261.38808) (xy 462.354198 -261.361431) (xy 462.312527 -261.3282) (xy 462.276275 -261.289129)
			(xy 462.246251 -261.245092) (xy 462.223125 -261.197071) (xy 462.207415 -261.146141) (xy 462.199472 -261.093437)
			(xy 461.9625 -261.093437) (xy 461.9625 -262.793459) (xy 462.199472 -262.793459) (xy 462.199472 -262.740161)
			(xy 462.207415 -262.687457) (xy 462.223125 -262.636527) (xy 462.246251 -262.588506) (xy 462.276275 -262.544469)
			(xy 462.312527 -262.505398) (xy 462.354198 -262.472167) (xy 462.400356 -262.445518) (xy 462.44997 -262.426046)
			(xy 462.501932 -262.414186) (xy 462.555082 -262.410203) (xy 462.608232 -262.414186) (xy 462.660194 -262.426046)
			(xy 462.709808 -262.445518) (xy 462.755966 -262.472167) (xy 462.797637 -262.505398) (xy 462.833889 -262.544469)
			(xy 462.863913 -262.588506) (xy 462.887039 -262.636527) (xy 462.902749 -262.687457) (xy 462.910692 -262.740161)
			(xy 462.91119 -262.76681) (xy 462.910692 -262.793459) (xy 464.409272 -262.793459) (xy 464.409272 -262.740161)
			(xy 464.417215 -262.687457) (xy 464.432925 -262.636527) (xy 464.456051 -262.588506) (xy 464.486075 -262.544469)
			(xy 464.522327 -262.505398) (xy 464.563998 -262.472167) (xy 464.610156 -262.445518) (xy 464.65977 -262.426046)
			(xy 464.711732 -262.414186) (xy 464.764882 -262.410203) (xy 464.818032 -262.414186) (xy 464.869994 -262.426046)
			(xy 464.919608 -262.445518) (xy 464.965766 -262.472167) (xy 465.007437 -262.505398) (xy 465.043689 -262.544469)
			(xy 465.073713 -262.588506) (xy 465.096839 -262.636527) (xy 465.112549 -262.687457) (xy 465.120492 -262.740161)
			(xy 465.12099 -262.76681) (xy 465.120492 -262.793459) (xy 465.112549 -262.846163) (xy 465.096839 -262.897093)
			(xy 465.073713 -262.945114) (xy 465.043689 -262.989151) (xy 465.007437 -263.028222) (xy 464.965766 -263.061453)
			(xy 464.919608 -263.088102) (xy 464.869994 -263.107574) (xy 464.818032 -263.119434) (xy 464.764882 -263.123418)
			(xy 464.711732 -263.119434) (xy 464.65977 -263.107574) (xy 464.610156 -263.088102) (xy 464.563998 -263.061453)
			(xy 464.522327 -263.028222) (xy 464.486075 -262.989151) (xy 464.456051 -262.945114) (xy 464.432925 -262.897093)
			(xy 464.417215 -262.846163) (xy 464.409272 -262.793459) (xy 462.910692 -262.793459) (xy 462.902749 -262.846163)
			(xy 462.887039 -262.897093) (xy 462.863913 -262.945114) (xy 462.833889 -262.989151) (xy 462.797637 -263.028222)
			(xy 462.755966 -263.061453) (xy 462.709808 -263.088102) (xy 462.660194 -263.107574) (xy 462.608232 -263.119434)
			(xy 462.555082 -263.123418) (xy 462.501932 -263.119434) (xy 462.44997 -263.107574) (xy 462.400356 -263.088102)
			(xy 462.354198 -263.061453) (xy 462.312527 -263.028222) (xy 462.276275 -262.989151) (xy 462.246251 -262.945114)
			(xy 462.223125 -262.897093) (xy 462.207415 -262.846163) (xy 462.199472 -262.793459) (xy 461.9625 -262.793459)
			(xy 461.9625 -264.493227) (xy 462.199472 -264.493227) (xy 462.199472 -264.439929) (xy 462.207415 -264.387225)
			(xy 462.223125 -264.336295) (xy 462.246251 -264.288274) (xy 462.276275 -264.244237) (xy 462.312527 -264.205166)
			(xy 462.354198 -264.171935) (xy 462.400356 -264.145286) (xy 462.44997 -264.125814) (xy 462.501932 -264.113954)
			(xy 462.555082 -264.109971) (xy 462.608232 -264.113954) (xy 462.660194 -264.125814) (xy 462.709808 -264.145286)
			(xy 462.755966 -264.171935) (xy 462.797637 -264.205166) (xy 462.833889 -264.244237) (xy 462.863913 -264.288274)
			(xy 462.887039 -264.336295) (xy 462.902749 -264.387225) (xy 462.910692 -264.439929) (xy 462.91119 -264.466578)
			(xy 462.910692 -264.493227) (xy 464.409272 -264.493227) (xy 464.409272 -264.439929) (xy 464.417215 -264.387225)
			(xy 464.432925 -264.336295) (xy 464.456051 -264.288274) (xy 464.486075 -264.244237) (xy 464.522327 -264.205166)
			(xy 464.563998 -264.171935) (xy 464.610156 -264.145286) (xy 464.65977 -264.125814) (xy 464.711732 -264.113954)
			(xy 464.764882 -264.109971) (xy 464.818032 -264.113954) (xy 464.869994 -264.125814) (xy 464.919608 -264.145286)
			(xy 464.965766 -264.171935) (xy 465.007437 -264.205166) (xy 465.043689 -264.244237) (xy 465.073713 -264.288274)
			(xy 465.096839 -264.336295) (xy 465.112549 -264.387225) (xy 465.120492 -264.439929) (xy 465.12099 -264.466578)
			(xy 465.120492 -264.493227) (xy 465.112549 -264.545931) (xy 465.096839 -264.596861) (xy 465.073713 -264.644882)
			(xy 465.043689 -264.688919) (xy 465.007437 -264.72799) (xy 464.965766 -264.761221) (xy 464.919608 -264.78787)
			(xy 464.869994 -264.807342) (xy 464.818032 -264.819202) (xy 464.764882 -264.823186) (xy 464.711732 -264.819202)
			(xy 464.65977 -264.807342) (xy 464.610156 -264.78787) (xy 464.563998 -264.761221) (xy 464.522327 -264.72799)
			(xy 464.486075 -264.688919) (xy 464.456051 -264.644882) (xy 464.432925 -264.596861) (xy 464.417215 -264.545931)
			(xy 464.409272 -264.493227) (xy 462.910692 -264.493227) (xy 462.902749 -264.545931) (xy 462.887039 -264.596861)
			(xy 462.863913 -264.644882) (xy 462.833889 -264.688919) (xy 462.797637 -264.72799) (xy 462.755966 -264.761221)
			(xy 462.709808 -264.78787) (xy 462.660194 -264.807342) (xy 462.608232 -264.819202) (xy 462.555082 -264.823186)
			(xy 462.501932 -264.819202) (xy 462.44997 -264.807342) (xy 462.400356 -264.78787) (xy 462.354198 -264.761221)
			(xy 462.312527 -264.72799) (xy 462.276275 -264.688919) (xy 462.246251 -264.644882) (xy 462.223125 -264.596861)
			(xy 462.207415 -264.545931) (xy 462.199472 -264.493227) (xy 461.9625 -264.493227) (xy 461.9625 -266.193249)
			(xy 462.199472 -266.193249) (xy 462.199472 -266.139951) (xy 462.207415 -266.087247) (xy 462.223125 -266.036317)
			(xy 462.246251 -265.988296) (xy 462.276275 -265.944259) (xy 462.312527 -265.905188) (xy 462.354198 -265.871957)
			(xy 462.400356 -265.845308) (xy 462.44997 -265.825836) (xy 462.501932 -265.813976) (xy 462.555082 -265.809993)
			(xy 462.608232 -265.813976) (xy 462.660194 -265.825836) (xy 462.709808 -265.845308) (xy 462.755966 -265.871957)
			(xy 462.797637 -265.905188) (xy 462.833889 -265.944259) (xy 462.863913 -265.988296) (xy 462.887039 -266.036317)
			(xy 462.902749 -266.087247) (xy 462.910692 -266.139951) (xy 462.91119 -266.1666) (xy 462.910692 -266.193249)
			(xy 464.409272 -266.193249) (xy 464.409272 -266.139951) (xy 464.417215 -266.087247) (xy 464.432925 -266.036317)
			(xy 464.456051 -265.988296) (xy 464.486075 -265.944259) (xy 464.522327 -265.905188) (xy 464.563998 -265.871957)
			(xy 464.610156 -265.845308) (xy 464.65977 -265.825836) (xy 464.711732 -265.813976) (xy 464.764882 -265.809993)
			(xy 464.818032 -265.813976) (xy 464.869994 -265.825836) (xy 464.919608 -265.845308) (xy 464.965766 -265.871957)
			(xy 465.007437 -265.905188) (xy 465.043689 -265.944259) (xy 465.073713 -265.988296) (xy 465.096839 -266.036317)
			(xy 465.112549 -266.087247) (xy 465.120492 -266.139951) (xy 465.12099 -266.1666) (xy 465.120492 -266.193249)
			(xy 465.112549 -266.245953) (xy 465.096839 -266.296883) (xy 465.073713 -266.344904) (xy 465.043689 -266.388941)
			(xy 465.007437 -266.428012) (xy 464.965766 -266.461243) (xy 464.919608 -266.487892) (xy 464.869994 -266.507364)
			(xy 464.818032 -266.519224) (xy 464.764882 -266.523208) (xy 464.711732 -266.519224) (xy 464.65977 -266.507364)
			(xy 464.610156 -266.487892) (xy 464.563998 -266.461243) (xy 464.522327 -266.428012) (xy 464.486075 -266.388941)
			(xy 464.456051 -266.344904) (xy 464.432925 -266.296883) (xy 464.417215 -266.245953) (xy 464.409272 -266.193249)
			(xy 462.910692 -266.193249) (xy 462.902749 -266.245953) (xy 462.887039 -266.296883) (xy 462.863913 -266.344904)
			(xy 462.833889 -266.388941) (xy 462.797637 -266.428012) (xy 462.755966 -266.461243) (xy 462.709808 -266.487892)
			(xy 462.660194 -266.507364) (xy 462.608232 -266.519224) (xy 462.555082 -266.523208) (xy 462.501932 -266.519224)
			(xy 462.44997 -266.507364) (xy 462.400356 -266.487892) (xy 462.354198 -266.461243) (xy 462.312527 -266.428012)
			(xy 462.276275 -266.388941) (xy 462.246251 -266.344904) (xy 462.223125 -266.296883) (xy 462.207415 -266.245953)
			(xy 462.199472 -266.193249) (xy 461.9625 -266.193249) (xy 461.9625 -267.043387) (xy 462.199472 -267.043387)
			(xy 462.199472 -266.990089) (xy 462.207415 -266.937385) (xy 462.223125 -266.886455) (xy 462.246251 -266.838434)
			(xy 462.276275 -266.794397) (xy 462.312527 -266.755326) (xy 462.354198 -266.722095) (xy 462.400356 -266.695446)
			(xy 462.44997 -266.675974) (xy 462.501932 -266.664114) (xy 462.555082 -266.660131) (xy 462.608232 -266.664114)
			(xy 462.660194 -266.675974) (xy 462.709808 -266.695446) (xy 462.755966 -266.722095) (xy 462.797637 -266.755326)
			(xy 462.833889 -266.794397) (xy 462.863913 -266.838434) (xy 462.887039 -266.886455) (xy 462.902749 -266.937385)
			(xy 462.910692 -266.990089) (xy 462.91119 -267.016738) (xy 462.910692 -267.043387) (xy 462.902749 -267.096091)
			(xy 462.887039 -267.147021) (xy 462.863913 -267.195042) (xy 462.833889 -267.239079) (xy 462.797637 -267.27815)
			(xy 462.755966 -267.311381) (xy 462.709808 -267.33803) (xy 462.660194 -267.357502) (xy 462.608232 -267.369362)
			(xy 462.555082 -267.373346) (xy 462.501932 -267.369362) (xy 462.44997 -267.357502) (xy 462.400356 -267.33803)
			(xy 462.354198 -267.311381) (xy 462.312527 -267.27815) (xy 462.276275 -267.239079) (xy 462.246251 -267.195042)
			(xy 462.223125 -267.147021) (xy 462.207415 -267.096091) (xy 462.199472 -267.043387) (xy 461.9625 -267.043387)
			(xy 461.9625 -267.893271) (xy 462.199472 -267.893271) (xy 462.199472 -267.839973) (xy 462.207415 -267.787269)
			(xy 462.223125 -267.736339) (xy 462.246251 -267.688318) (xy 462.276275 -267.644281) (xy 462.312527 -267.60521)
			(xy 462.354198 -267.571979) (xy 462.400356 -267.54533) (xy 462.44997 -267.525858) (xy 462.501932 -267.513998)
			(xy 462.555082 -267.510015) (xy 462.608232 -267.513998) (xy 462.660194 -267.525858) (xy 462.709808 -267.54533)
			(xy 462.755966 -267.571979) (xy 462.797637 -267.60521) (xy 462.833889 -267.644281) (xy 462.863913 -267.688318)
			(xy 462.887039 -267.736339) (xy 462.902749 -267.787269) (xy 462.910692 -267.839973) (xy 462.91119 -267.866622)
			(xy 462.910692 -267.893271) (xy 464.409272 -267.893271) (xy 464.409272 -267.839973) (xy 464.417215 -267.787269)
			(xy 464.432925 -267.736339) (xy 464.456051 -267.688318) (xy 464.486075 -267.644281) (xy 464.522327 -267.60521)
			(xy 464.563998 -267.571979) (xy 464.610156 -267.54533) (xy 464.65977 -267.525858) (xy 464.711732 -267.513998)
			(xy 464.764882 -267.510015) (xy 464.818032 -267.513998) (xy 464.869994 -267.525858) (xy 464.919608 -267.54533)
			(xy 464.965766 -267.571979) (xy 465.007437 -267.60521) (xy 465.043689 -267.644281) (xy 465.073713 -267.688318)
			(xy 465.096839 -267.736339) (xy 465.112549 -267.787269) (xy 465.120492 -267.839973) (xy 465.12099 -267.866622)
			(xy 465.120492 -267.893271) (xy 465.112549 -267.945975) (xy 465.096839 -267.996905) (xy 465.073713 -268.044926)
			(xy 465.043689 -268.088963) (xy 465.007437 -268.128034) (xy 464.965766 -268.161265) (xy 464.919608 -268.187914)
			(xy 464.869994 -268.207386) (xy 464.818032 -268.219246) (xy 464.764882 -268.22323) (xy 464.711732 -268.219246)
			(xy 464.65977 -268.207386) (xy 464.610156 -268.187914) (xy 464.563998 -268.161265) (xy 464.522327 -268.128034)
			(xy 464.486075 -268.088963) (xy 464.456051 -268.044926) (xy 464.432925 -267.996905) (xy 464.417215 -267.945975)
			(xy 464.409272 -267.893271) (xy 462.910692 -267.893271) (xy 462.902749 -267.945975) (xy 462.887039 -267.996905)
			(xy 462.863913 -268.044926) (xy 462.833889 -268.088963) (xy 462.797637 -268.128034) (xy 462.755966 -268.161265)
			(xy 462.709808 -268.187914) (xy 462.660194 -268.207386) (xy 462.608232 -268.219246) (xy 462.555082 -268.22323)
			(xy 462.501932 -268.219246) (xy 462.44997 -268.207386) (xy 462.400356 -268.187914) (xy 462.354198 -268.161265)
			(xy 462.312527 -268.128034) (xy 462.276275 -268.088963) (xy 462.246251 -268.044926) (xy 462.223125 -267.996905)
			(xy 462.207415 -267.945975) (xy 462.199472 -267.893271) (xy 461.9625 -267.893271) (xy 461.9625 -269.593293)
			(xy 462.199472 -269.593293) (xy 462.199472 -269.539995) (xy 462.207415 -269.487291) (xy 462.223125 -269.436361)
			(xy 462.246251 -269.38834) (xy 462.276275 -269.344303) (xy 462.312527 -269.305232) (xy 462.354198 -269.272001)
			(xy 462.400356 -269.245352) (xy 462.44997 -269.22588) (xy 462.501932 -269.21402) (xy 462.555082 -269.210037)
			(xy 462.608232 -269.21402) (xy 462.660194 -269.22588) (xy 462.709808 -269.245352) (xy 462.755966 -269.272001)
			(xy 462.797637 -269.305232) (xy 462.833889 -269.344303) (xy 462.863913 -269.38834) (xy 462.887039 -269.436361)
			(xy 462.902749 -269.487291) (xy 462.910692 -269.539995) (xy 462.91119 -269.566644) (xy 462.910692 -269.593293)
			(xy 464.409272 -269.593293) (xy 464.409272 -269.539995) (xy 464.417215 -269.487291) (xy 464.432925 -269.436361)
			(xy 464.456051 -269.38834) (xy 464.486075 -269.344303) (xy 464.522327 -269.305232) (xy 464.563998 -269.272001)
			(xy 464.610156 -269.245352) (xy 464.65977 -269.22588) (xy 464.711732 -269.21402) (xy 464.764882 -269.210037)
			(xy 464.818032 -269.21402) (xy 464.869994 -269.22588) (xy 464.919608 -269.245352) (xy 464.965766 -269.272001)
			(xy 465.007437 -269.305232) (xy 465.043689 -269.344303) (xy 465.073713 -269.38834) (xy 465.096839 -269.436361)
			(xy 465.112549 -269.487291) (xy 465.120492 -269.539995) (xy 465.12099 -269.566644) (xy 465.120492 -269.593293)
			(xy 465.112549 -269.645997) (xy 465.096839 -269.696927) (xy 465.073713 -269.744948) (xy 465.043689 -269.788985)
			(xy 465.007437 -269.828056) (xy 464.965766 -269.861287) (xy 464.919608 -269.887936) (xy 464.869994 -269.907408)
			(xy 464.818032 -269.919268) (xy 464.764882 -269.923252) (xy 464.711732 -269.919268) (xy 464.65977 -269.907408)
			(xy 464.610156 -269.887936) (xy 464.563998 -269.861287) (xy 464.522327 -269.828056) (xy 464.486075 -269.788985)
			(xy 464.456051 -269.744948) (xy 464.432925 -269.696927) (xy 464.417215 -269.645997) (xy 464.409272 -269.593293)
			(xy 462.910692 -269.593293) (xy 462.902749 -269.645997) (xy 462.887039 -269.696927) (xy 462.863913 -269.744948)
			(xy 462.833889 -269.788985) (xy 462.797637 -269.828056) (xy 462.755966 -269.861287) (xy 462.709808 -269.887936)
			(xy 462.660194 -269.907408) (xy 462.608232 -269.919268) (xy 462.555082 -269.923252) (xy 462.501932 -269.919268)
			(xy 462.44997 -269.907408) (xy 462.400356 -269.887936) (xy 462.354198 -269.861287) (xy 462.312527 -269.828056)
			(xy 462.276275 -269.788985) (xy 462.246251 -269.744948) (xy 462.223125 -269.696927) (xy 462.207415 -269.645997)
			(xy 462.199472 -269.593293) (xy 461.9625 -269.593293) (xy 461.9625 -271.293315) (xy 462.199472 -271.293315)
			(xy 462.199472 -271.240017) (xy 462.207415 -271.187313) (xy 462.223125 -271.136383) (xy 462.246251 -271.088362)
			(xy 462.276275 -271.044325) (xy 462.312527 -271.005254) (xy 462.354198 -270.972023) (xy 462.400356 -270.945374)
			(xy 462.44997 -270.925902) (xy 462.501932 -270.914042) (xy 462.555082 -270.910059) (xy 462.608232 -270.914042)
			(xy 462.660194 -270.925902) (xy 462.709808 -270.945374) (xy 462.755966 -270.972023) (xy 462.797637 -271.005254)
			(xy 462.833889 -271.044325) (xy 462.863913 -271.088362) (xy 462.887039 -271.136383) (xy 462.902749 -271.187313)
			(xy 462.910692 -271.240017) (xy 462.91119 -271.266666) (xy 462.910692 -271.293315) (xy 464.409272 -271.293315)
			(xy 464.409272 -271.240017) (xy 464.417215 -271.187313) (xy 464.432925 -271.136383) (xy 464.456051 -271.088362)
			(xy 464.486075 -271.044325) (xy 464.522327 -271.005254) (xy 464.563998 -270.972023) (xy 464.610156 -270.945374)
			(xy 464.65977 -270.925902) (xy 464.711732 -270.914042) (xy 464.764882 -270.910059) (xy 464.818032 -270.914042)
			(xy 464.869994 -270.925902) (xy 464.919608 -270.945374) (xy 464.965766 -270.972023) (xy 465.007437 -271.005254)
			(xy 465.043689 -271.044325) (xy 465.073713 -271.088362) (xy 465.096839 -271.136383) (xy 465.112549 -271.187313)
			(xy 465.120492 -271.240017) (xy 465.12099 -271.266666) (xy 465.120492 -271.293315) (xy 465.112549 -271.346019)
			(xy 465.096839 -271.396949) (xy 465.073713 -271.44497) (xy 465.043689 -271.489007) (xy 465.007437 -271.528078)
			(xy 464.965766 -271.561309) (xy 464.919608 -271.587958) (xy 464.869994 -271.60743) (xy 464.818032 -271.61929)
			(xy 464.764882 -271.623274) (xy 464.711732 -271.61929) (xy 464.65977 -271.60743) (xy 464.610156 -271.587958)
			(xy 464.563998 -271.561309) (xy 464.522327 -271.528078) (xy 464.486075 -271.489007) (xy 464.456051 -271.44497)
			(xy 464.432925 -271.396949) (xy 464.417215 -271.346019) (xy 464.409272 -271.293315) (xy 462.910692 -271.293315)
			(xy 462.902749 -271.346019) (xy 462.887039 -271.396949) (xy 462.863913 -271.44497) (xy 462.833889 -271.489007)
			(xy 462.797637 -271.528078) (xy 462.755966 -271.561309) (xy 462.709808 -271.587958) (xy 462.660194 -271.60743)
			(xy 462.608232 -271.61929) (xy 462.555082 -271.623274) (xy 462.501932 -271.61929) (xy 462.44997 -271.60743)
			(xy 462.400356 -271.587958) (xy 462.354198 -271.561309) (xy 462.312527 -271.528078) (xy 462.276275 -271.489007)
			(xy 462.246251 -271.44497) (xy 462.223125 -271.396949) (xy 462.207415 -271.346019) (xy 462.199472 -271.293315)
			(xy 461.9625 -271.293315) (xy 461.9625 -272.993337) (xy 462.199472 -272.993337) (xy 462.199472 -272.940039)
			(xy 462.207415 -272.887335) (xy 462.223125 -272.836405) (xy 462.246251 -272.788384) (xy 462.276275 -272.744347)
			(xy 462.312527 -272.705276) (xy 462.354198 -272.672045) (xy 462.400356 -272.645396) (xy 462.44997 -272.625924)
			(xy 462.501932 -272.614064) (xy 462.555082 -272.610081) (xy 462.608232 -272.614064) (xy 462.660194 -272.625924)
			(xy 462.709808 -272.645396) (xy 462.755966 -272.672045) (xy 462.797637 -272.705276) (xy 462.833889 -272.744347)
			(xy 462.863913 -272.788384) (xy 462.887039 -272.836405) (xy 462.902749 -272.887335) (xy 462.910692 -272.940039)
			(xy 462.91119 -272.966688) (xy 462.910692 -272.993337) (xy 464.409272 -272.993337) (xy 464.409272 -272.940039)
			(xy 464.417215 -272.887335) (xy 464.432925 -272.836405) (xy 464.456051 -272.788384) (xy 464.486075 -272.744347)
			(xy 464.522327 -272.705276) (xy 464.563998 -272.672045) (xy 464.610156 -272.645396) (xy 464.65977 -272.625924)
			(xy 464.711732 -272.614064) (xy 464.764882 -272.610081) (xy 464.818032 -272.614064) (xy 464.869994 -272.625924)
			(xy 464.919608 -272.645396) (xy 464.965766 -272.672045) (xy 465.007437 -272.705276) (xy 465.043689 -272.744347)
			(xy 465.073713 -272.788384) (xy 465.096839 -272.836405) (xy 465.112549 -272.887335) (xy 465.120492 -272.940039)
			(xy 465.12099 -272.966688) (xy 465.120492 -272.993337) (xy 465.112549 -273.046041) (xy 465.096839 -273.096971)
			(xy 465.073713 -273.144992) (xy 465.043689 -273.189029) (xy 465.007437 -273.2281) (xy 464.965766 -273.261331)
			(xy 464.919608 -273.28798) (xy 464.869994 -273.307452) (xy 464.818032 -273.319312) (xy 464.764882 -273.323296)
			(xy 464.711732 -273.319312) (xy 464.65977 -273.307452) (xy 464.610156 -273.28798) (xy 464.563998 -273.261331)
			(xy 464.522327 -273.2281) (xy 464.486075 -273.189029) (xy 464.456051 -273.144992) (xy 464.432925 -273.096971)
			(xy 464.417215 -273.046041) (xy 464.409272 -272.993337) (xy 462.910692 -272.993337) (xy 462.902749 -273.046041)
			(xy 462.887039 -273.096971) (xy 462.863913 -273.144992) (xy 462.833889 -273.189029) (xy 462.797637 -273.2281)
			(xy 462.755966 -273.261331) (xy 462.709808 -273.28798) (xy 462.660194 -273.307452) (xy 462.608232 -273.319312)
			(xy 462.555082 -273.323296) (xy 462.501932 -273.319312) (xy 462.44997 -273.307452) (xy 462.400356 -273.28798)
			(xy 462.354198 -273.261331) (xy 462.312527 -273.2281) (xy 462.276275 -273.189029) (xy 462.246251 -273.144992)
			(xy 462.223125 -273.096971) (xy 462.207415 -273.046041) (xy 462.199472 -272.993337) (xy 461.9625 -272.993337)
			(xy 461.9625 -275.543243) (xy 462.199472 -275.543243) (xy 462.199472 -275.489945) (xy 462.207415 -275.437241)
			(xy 462.223125 -275.386311) (xy 462.246251 -275.33829) (xy 462.276275 -275.294253) (xy 462.312527 -275.255182)
			(xy 462.354198 -275.221951) (xy 462.400356 -275.195302) (xy 462.44997 -275.17583) (xy 462.501932 -275.16397)
			(xy 462.555082 -275.159987) (xy 462.608232 -275.16397) (xy 462.660194 -275.17583) (xy 462.709808 -275.195302)
			(xy 462.755966 -275.221951) (xy 462.797637 -275.255182) (xy 462.833889 -275.294253) (xy 462.863913 -275.33829)
			(xy 462.887039 -275.386311) (xy 462.902749 -275.437241) (xy 462.910692 -275.489945) (xy 462.91119 -275.516594)
			(xy 462.910692 -275.543243) (xy 464.409272 -275.543243) (xy 464.409272 -275.489945) (xy 464.417215 -275.437241)
			(xy 464.432925 -275.386311) (xy 464.456051 -275.33829) (xy 464.486075 -275.294253) (xy 464.522327 -275.255182)
			(xy 464.563998 -275.221951) (xy 464.610156 -275.195302) (xy 464.65977 -275.17583) (xy 464.711732 -275.16397)
			(xy 464.764882 -275.159987) (xy 464.818032 -275.16397) (xy 464.869994 -275.17583) (xy 464.919608 -275.195302)
			(xy 464.965766 -275.221951) (xy 465.007437 -275.255182) (xy 465.043689 -275.294253) (xy 465.073713 -275.33829)
			(xy 465.096839 -275.386311) (xy 465.112549 -275.437241) (xy 465.120492 -275.489945) (xy 465.12099 -275.516594)
			(xy 465.120492 -275.543243) (xy 465.112549 -275.595947) (xy 465.096839 -275.646877) (xy 465.073713 -275.694898)
			(xy 465.043689 -275.738935) (xy 465.007437 -275.778006) (xy 464.965766 -275.811237) (xy 464.919608 -275.837886)
			(xy 464.869994 -275.857358) (xy 464.818032 -275.869218) (xy 464.764882 -275.873202) (xy 464.711732 -275.869218)
			(xy 464.65977 -275.857358) (xy 464.610156 -275.837886) (xy 464.563998 -275.811237) (xy 464.522327 -275.778006)
			(xy 464.486075 -275.738935) (xy 464.456051 -275.694898) (xy 464.432925 -275.646877) (xy 464.417215 -275.595947)
			(xy 464.409272 -275.543243) (xy 462.910692 -275.543243) (xy 462.902749 -275.595947) (xy 462.887039 -275.646877)
			(xy 462.863913 -275.694898) (xy 462.833889 -275.738935) (xy 462.797637 -275.778006) (xy 462.755966 -275.811237)
			(xy 462.709808 -275.837886) (xy 462.660194 -275.857358) (xy 462.608232 -275.869218) (xy 462.555082 -275.873202)
			(xy 462.501932 -275.869218) (xy 462.44997 -275.857358) (xy 462.400356 -275.837886) (xy 462.354198 -275.811237)
			(xy 462.312527 -275.778006) (xy 462.276275 -275.738935) (xy 462.246251 -275.694898) (xy 462.223125 -275.646877)
			(xy 462.207415 -275.595947) (xy 462.199472 -275.543243) (xy 461.9625 -275.543243) (xy 461.9625 -277.243265)
			(xy 462.199472 -277.243265) (xy 462.199472 -277.189967) (xy 462.207415 -277.137263) (xy 462.223125 -277.086333)
			(xy 462.246251 -277.038312) (xy 462.276275 -276.994275) (xy 462.312527 -276.955204) (xy 462.354198 -276.921973)
			(xy 462.400356 -276.895324) (xy 462.44997 -276.875852) (xy 462.501932 -276.863992) (xy 462.555082 -276.860009)
			(xy 462.608232 -276.863992) (xy 462.660194 -276.875852) (xy 462.709808 -276.895324) (xy 462.755966 -276.921973)
			(xy 462.797637 -276.955204) (xy 462.833889 -276.994275) (xy 462.863913 -277.038312) (xy 462.887039 -277.086333)
			(xy 462.902749 -277.137263) (xy 462.910692 -277.189967) (xy 462.91119 -277.216616) (xy 462.910692 -277.243265)
			(xy 464.409272 -277.243265) (xy 464.409272 -277.189967) (xy 464.417215 -277.137263) (xy 464.432925 -277.086333)
			(xy 464.456051 -277.038312) (xy 464.486075 -276.994275) (xy 464.522327 -276.955204) (xy 464.563998 -276.921973)
			(xy 464.610156 -276.895324) (xy 464.65977 -276.875852) (xy 464.711732 -276.863992) (xy 464.764882 -276.860009)
			(xy 464.818032 -276.863992) (xy 464.869994 -276.875852) (xy 464.919608 -276.895324) (xy 464.965766 -276.921973)
			(xy 465.007437 -276.955204) (xy 465.043689 -276.994275) (xy 465.073713 -277.038312) (xy 465.096839 -277.086333)
			(xy 465.112549 -277.137263) (xy 465.120492 -277.189967) (xy 465.12099 -277.216616) (xy 465.120492 -277.243265)
			(xy 465.112549 -277.295969) (xy 465.096839 -277.346899) (xy 465.073713 -277.39492) (xy 465.043689 -277.438957)
			(xy 465.007437 -277.478028) (xy 464.965766 -277.511259) (xy 464.919608 -277.537908) (xy 464.869994 -277.55738)
			(xy 464.818032 -277.56924) (xy 464.764882 -277.573224) (xy 464.711732 -277.56924) (xy 464.65977 -277.55738)
			(xy 464.610156 -277.537908) (xy 464.563998 -277.511259) (xy 464.522327 -277.478028) (xy 464.486075 -277.438957)
			(xy 464.456051 -277.39492) (xy 464.432925 -277.346899) (xy 464.417215 -277.295969) (xy 464.409272 -277.243265)
			(xy 462.910692 -277.243265) (xy 462.902749 -277.295969) (xy 462.887039 -277.346899) (xy 462.863913 -277.39492)
			(xy 462.833889 -277.438957) (xy 462.797637 -277.478028) (xy 462.755966 -277.511259) (xy 462.709808 -277.537908)
			(xy 462.660194 -277.55738) (xy 462.608232 -277.56924) (xy 462.555082 -277.573224) (xy 462.501932 -277.56924)
			(xy 462.44997 -277.55738) (xy 462.400356 -277.537908) (xy 462.354198 -277.511259) (xy 462.312527 -277.478028)
			(xy 462.276275 -277.438957) (xy 462.246251 -277.39492) (xy 462.223125 -277.346899) (xy 462.207415 -277.295969)
			(xy 462.199472 -277.243265) (xy 461.9625 -277.243265) (xy 461.9625 -278.943287) (xy 462.199472 -278.943287)
			(xy 462.199472 -278.889989) (xy 462.207415 -278.837285) (xy 462.223125 -278.786355) (xy 462.246251 -278.738334)
			(xy 462.276275 -278.694297) (xy 462.312527 -278.655226) (xy 462.354198 -278.621995) (xy 462.400356 -278.595346)
			(xy 462.44997 -278.575874) (xy 462.501932 -278.564014) (xy 462.555082 -278.560031) (xy 462.608232 -278.564014)
			(xy 462.660194 -278.575874) (xy 462.709808 -278.595346) (xy 462.755966 -278.621995) (xy 462.797637 -278.655226)
			(xy 462.833889 -278.694297) (xy 462.863913 -278.738334) (xy 462.887039 -278.786355) (xy 462.902749 -278.837285)
			(xy 462.910692 -278.889989) (xy 462.91119 -278.916638) (xy 462.910692 -278.943287) (xy 464.409272 -278.943287)
			(xy 464.409272 -278.889989) (xy 464.417215 -278.837285) (xy 464.432925 -278.786355) (xy 464.456051 -278.738334)
			(xy 464.486075 -278.694297) (xy 464.522327 -278.655226) (xy 464.563998 -278.621995) (xy 464.610156 -278.595346)
			(xy 464.65977 -278.575874) (xy 464.711732 -278.564014) (xy 464.764882 -278.560031) (xy 464.818032 -278.564014)
			(xy 464.869994 -278.575874) (xy 464.919608 -278.595346) (xy 464.965766 -278.621995) (xy 465.007437 -278.655226)
			(xy 465.043689 -278.694297) (xy 465.073713 -278.738334) (xy 465.096839 -278.786355) (xy 465.112549 -278.837285)
			(xy 465.120492 -278.889989) (xy 465.12099 -278.916638) (xy 465.120492 -278.943287) (xy 465.112549 -278.995991)
			(xy 465.096839 -279.046921) (xy 465.073713 -279.094942) (xy 465.043689 -279.138979) (xy 465.007437 -279.17805)
			(xy 464.965766 -279.211281) (xy 464.919608 -279.23793) (xy 464.869994 -279.257402) (xy 464.818032 -279.269262)
			(xy 464.764882 -279.273246) (xy 464.711732 -279.269262) (xy 464.65977 -279.257402) (xy 464.610156 -279.23793)
			(xy 464.563998 -279.211281) (xy 464.522327 -279.17805) (xy 464.486075 -279.138979) (xy 464.456051 -279.094942)
			(xy 464.432925 -279.046921) (xy 464.417215 -278.995991) (xy 464.409272 -278.943287) (xy 462.910692 -278.943287)
			(xy 462.902749 -278.995991) (xy 462.887039 -279.046921) (xy 462.863913 -279.094942) (xy 462.833889 -279.138979)
			(xy 462.797637 -279.17805) (xy 462.755966 -279.211281) (xy 462.709808 -279.23793) (xy 462.660194 -279.257402)
			(xy 462.608232 -279.269262) (xy 462.555082 -279.273246) (xy 462.501932 -279.269262) (xy 462.44997 -279.257402)
			(xy 462.400356 -279.23793) (xy 462.354198 -279.211281) (xy 462.312527 -279.17805) (xy 462.276275 -279.138979)
			(xy 462.246251 -279.094942) (xy 462.223125 -279.046921) (xy 462.207415 -278.995991) (xy 462.199472 -278.943287)
			(xy 461.9625 -278.943287) (xy 461.9625 -280.643309) (xy 462.199472 -280.643309) (xy 462.199472 -280.590011)
			(xy 462.207415 -280.537307) (xy 462.223125 -280.486377) (xy 462.246251 -280.438356) (xy 462.276275 -280.394319)
			(xy 462.312527 -280.355248) (xy 462.354198 -280.322017) (xy 462.400356 -280.295368) (xy 462.44997 -280.275896)
			(xy 462.501932 -280.264036) (xy 462.555082 -280.260053) (xy 462.608232 -280.264036) (xy 462.660194 -280.275896)
			(xy 462.709808 -280.295368) (xy 462.755966 -280.322017) (xy 462.797637 -280.355248) (xy 462.833889 -280.394319)
			(xy 462.863913 -280.438356) (xy 462.887039 -280.486377) (xy 462.902749 -280.537307) (xy 462.910692 -280.590011)
			(xy 462.91119 -280.61666) (xy 462.910692 -280.643309) (xy 464.409272 -280.643309) (xy 464.409272 -280.590011)
			(xy 464.417215 -280.537307) (xy 464.432925 -280.486377) (xy 464.456051 -280.438356) (xy 464.486075 -280.394319)
			(xy 464.522327 -280.355248) (xy 464.563998 -280.322017) (xy 464.610156 -280.295368) (xy 464.65977 -280.275896)
			(xy 464.711732 -280.264036) (xy 464.764882 -280.260053) (xy 464.818032 -280.264036) (xy 464.869994 -280.275896)
			(xy 464.919608 -280.295368) (xy 464.965766 -280.322017) (xy 465.007437 -280.355248) (xy 465.043689 -280.394319)
			(xy 465.073713 -280.438356) (xy 465.096839 -280.486377) (xy 465.112549 -280.537307) (xy 465.120492 -280.590011)
			(xy 465.12099 -280.61666) (xy 465.120492 -280.643309) (xy 465.112549 -280.696013) (xy 465.096839 -280.746943)
			(xy 465.073713 -280.794964) (xy 465.043689 -280.839001) (xy 465.007437 -280.878072) (xy 464.965766 -280.911303)
			(xy 464.919608 -280.937952) (xy 464.869994 -280.957424) (xy 464.818032 -280.969284) (xy 464.764882 -280.973268)
			(xy 464.711732 -280.969284) (xy 464.65977 -280.957424) (xy 464.610156 -280.937952) (xy 464.563998 -280.911303)
			(xy 464.522327 -280.878072) (xy 464.486075 -280.839001) (xy 464.456051 -280.794964) (xy 464.432925 -280.746943)
			(xy 464.417215 -280.696013) (xy 464.409272 -280.643309) (xy 462.910692 -280.643309) (xy 462.902749 -280.696013)
			(xy 462.887039 -280.746943) (xy 462.863913 -280.794964) (xy 462.833889 -280.839001) (xy 462.797637 -280.878072)
			(xy 462.755966 -280.911303) (xy 462.709808 -280.937952) (xy 462.660194 -280.957424) (xy 462.608232 -280.969284)
			(xy 462.555082 -280.973268) (xy 462.501932 -280.969284) (xy 462.44997 -280.957424) (xy 462.400356 -280.937952)
			(xy 462.354198 -280.911303) (xy 462.312527 -280.878072) (xy 462.276275 -280.839001) (xy 462.246251 -280.794964)
			(xy 462.223125 -280.746943) (xy 462.207415 -280.696013) (xy 462.199472 -280.643309) (xy 461.9625 -280.643309)
			(xy 461.9625 -282.343331) (xy 462.199472 -282.343331) (xy 462.199472 -282.290033) (xy 462.207415 -282.237329)
			(xy 462.223125 -282.186399) (xy 462.246251 -282.138378) (xy 462.276275 -282.094341) (xy 462.312527 -282.05527)
			(xy 462.354198 -282.022039) (xy 462.400356 -281.99539) (xy 462.44997 -281.975918) (xy 462.501932 -281.964058)
			(xy 462.555082 -281.960075) (xy 462.608232 -281.964058) (xy 462.660194 -281.975918) (xy 462.709808 -281.99539)
			(xy 462.755966 -282.022039) (xy 462.797637 -282.05527) (xy 462.833889 -282.094341) (xy 462.863913 -282.138378)
			(xy 462.887039 -282.186399) (xy 462.902749 -282.237329) (xy 462.910692 -282.290033) (xy 462.91119 -282.316682)
			(xy 462.910692 -282.343331) (xy 464.409272 -282.343331) (xy 464.409272 -282.290033) (xy 464.417215 -282.237329)
			(xy 464.432925 -282.186399) (xy 464.456051 -282.138378) (xy 464.486075 -282.094341) (xy 464.522327 -282.05527)
			(xy 464.563998 -282.022039) (xy 464.610156 -281.99539) (xy 464.65977 -281.975918) (xy 464.711732 -281.964058)
			(xy 464.764882 -281.960075) (xy 464.818032 -281.964058) (xy 464.869994 -281.975918) (xy 464.919608 -281.99539)
			(xy 464.965766 -282.022039) (xy 465.007437 -282.05527) (xy 465.043689 -282.094341) (xy 465.073713 -282.138378)
			(xy 465.096839 -282.186399) (xy 465.112549 -282.237329) (xy 465.120492 -282.290033) (xy 465.12099 -282.316682)
			(xy 465.120492 -282.343331) (xy 465.112549 -282.396035) (xy 465.096839 -282.446965) (xy 465.073713 -282.494986)
			(xy 465.043689 -282.539023) (xy 465.007437 -282.578094) (xy 464.965766 -282.611325) (xy 464.919608 -282.637974)
			(xy 464.869994 -282.657446) (xy 464.818032 -282.669306) (xy 464.764882 -282.67329) (xy 464.711732 -282.669306)
			(xy 464.65977 -282.657446) (xy 464.610156 -282.637974) (xy 464.563998 -282.611325) (xy 464.522327 -282.578094)
			(xy 464.486075 -282.539023) (xy 464.456051 -282.494986) (xy 464.432925 -282.446965) (xy 464.417215 -282.396035)
			(xy 464.409272 -282.343331) (xy 462.910692 -282.343331) (xy 462.902749 -282.396035) (xy 462.887039 -282.446965)
			(xy 462.863913 -282.494986) (xy 462.833889 -282.539023) (xy 462.797637 -282.578094) (xy 462.755966 -282.611325)
			(xy 462.709808 -282.637974) (xy 462.660194 -282.657446) (xy 462.608232 -282.669306) (xy 462.555082 -282.67329)
			(xy 462.501932 -282.669306) (xy 462.44997 -282.657446) (xy 462.400356 -282.637974) (xy 462.354198 -282.611325)
			(xy 462.312527 -282.578094) (xy 462.276275 -282.539023) (xy 462.246251 -282.494986) (xy 462.223125 -282.446965)
			(xy 462.207415 -282.396035) (xy 462.199472 -282.343331) (xy 461.9625 -282.343331) (xy 461.9625 -284.893237)
			(xy 462.199472 -284.893237) (xy 462.199472 -284.839939) (xy 462.207415 -284.787235) (xy 462.223125 -284.736305)
			(xy 462.246251 -284.688284) (xy 462.276275 -284.644247) (xy 462.312527 -284.605176) (xy 462.354198 -284.571945)
			(xy 462.400356 -284.545296) (xy 462.44997 -284.525824) (xy 462.501932 -284.513964) (xy 462.555082 -284.509981)
			(xy 462.608232 -284.513964) (xy 462.660194 -284.525824) (xy 462.709808 -284.545296) (xy 462.755966 -284.571945)
			(xy 462.797637 -284.605176) (xy 462.833889 -284.644247) (xy 462.863913 -284.688284) (xy 462.887039 -284.736305)
			(xy 462.902749 -284.787235) (xy 462.910692 -284.839939) (xy 462.91119 -284.866588) (xy 462.910692 -284.893237)
			(xy 464.409272 -284.893237) (xy 464.409272 -284.839939) (xy 464.417215 -284.787235) (xy 464.432925 -284.736305)
			(xy 464.456051 -284.688284) (xy 464.486075 -284.644247) (xy 464.522327 -284.605176) (xy 464.563998 -284.571945)
			(xy 464.610156 -284.545296) (xy 464.65977 -284.525824) (xy 464.711732 -284.513964) (xy 464.764882 -284.509981)
			(xy 464.818032 -284.513964) (xy 464.869994 -284.525824) (xy 464.919608 -284.545296) (xy 464.965766 -284.571945)
			(xy 465.007437 -284.605176) (xy 465.043689 -284.644247) (xy 465.073713 -284.688284) (xy 465.096839 -284.736305)
			(xy 465.112549 -284.787235) (xy 465.120492 -284.839939) (xy 465.12099 -284.866588) (xy 465.120492 -284.893237)
			(xy 465.112549 -284.945941) (xy 465.096839 -284.996871) (xy 465.073713 -285.044892) (xy 465.043689 -285.088929)
			(xy 465.007437 -285.128) (xy 464.965766 -285.161231) (xy 464.919608 -285.18788) (xy 464.869994 -285.207352)
			(xy 464.818032 -285.219212) (xy 464.764882 -285.223196) (xy 464.711732 -285.219212) (xy 464.65977 -285.207352)
			(xy 464.610156 -285.18788) (xy 464.563998 -285.161231) (xy 464.522327 -285.128) (xy 464.486075 -285.088929)
			(xy 464.456051 -285.044892) (xy 464.432925 -284.996871) (xy 464.417215 -284.945941) (xy 464.409272 -284.893237)
			(xy 462.910692 -284.893237) (xy 462.902749 -284.945941) (xy 462.887039 -284.996871) (xy 462.863913 -285.044892)
			(xy 462.833889 -285.088929) (xy 462.797637 -285.128) (xy 462.755966 -285.161231) (xy 462.709808 -285.18788)
			(xy 462.660194 -285.207352) (xy 462.608232 -285.219212) (xy 462.555082 -285.223196) (xy 462.501932 -285.219212)
			(xy 462.44997 -285.207352) (xy 462.400356 -285.18788) (xy 462.354198 -285.161231) (xy 462.312527 -285.128)
			(xy 462.276275 -285.088929) (xy 462.246251 -285.044892) (xy 462.223125 -284.996871) (xy 462.207415 -284.945941)
			(xy 462.199472 -284.893237) (xy 461.9625 -284.893237) (xy 461.9625 -286.593259) (xy 462.199472 -286.593259)
			(xy 462.199472 -286.539961) (xy 462.207415 -286.487257) (xy 462.223125 -286.436327) (xy 462.246251 -286.388306)
			(xy 462.276275 -286.344269) (xy 462.312527 -286.305198) (xy 462.354198 -286.271967) (xy 462.400356 -286.245318)
			(xy 462.44997 -286.225846) (xy 462.501932 -286.213986) (xy 462.555082 -286.210003) (xy 462.608232 -286.213986)
			(xy 462.660194 -286.225846) (xy 462.709808 -286.245318) (xy 462.755966 -286.271967) (xy 462.797637 -286.305198)
			(xy 462.833889 -286.344269) (xy 462.863913 -286.388306) (xy 462.887039 -286.436327) (xy 462.902749 -286.487257)
			(xy 462.910692 -286.539961) (xy 462.91119 -286.56661) (xy 462.910692 -286.593259) (xy 464.409272 -286.593259)
			(xy 464.409272 -286.539961) (xy 464.417215 -286.487257) (xy 464.432925 -286.436327) (xy 464.456051 -286.388306)
			(xy 464.486075 -286.344269) (xy 464.522327 -286.305198) (xy 464.563998 -286.271967) (xy 464.610156 -286.245318)
			(xy 464.65977 -286.225846) (xy 464.711732 -286.213986) (xy 464.764882 -286.210003) (xy 464.818032 -286.213986)
			(xy 464.869994 -286.225846) (xy 464.919608 -286.245318) (xy 464.965766 -286.271967) (xy 465.007437 -286.305198)
			(xy 465.043689 -286.344269) (xy 465.073713 -286.388306) (xy 465.096839 -286.436327) (xy 465.112549 -286.487257)
			(xy 465.120492 -286.539961) (xy 465.12099 -286.56661) (xy 465.120492 -286.593259) (xy 465.112549 -286.645963)
			(xy 465.096839 -286.696893) (xy 465.073713 -286.744914) (xy 465.043689 -286.788951) (xy 465.007437 -286.828022)
			(xy 464.965766 -286.861253) (xy 464.919608 -286.887902) (xy 464.869994 -286.907374) (xy 464.818032 -286.919234)
			(xy 464.764882 -286.923218) (xy 464.711732 -286.919234) (xy 464.65977 -286.907374) (xy 464.610156 -286.887902)
			(xy 464.563998 -286.861253) (xy 464.522327 -286.828022) (xy 464.486075 -286.788951) (xy 464.456051 -286.744914)
			(xy 464.432925 -286.696893) (xy 464.417215 -286.645963) (xy 464.409272 -286.593259) (xy 462.910692 -286.593259)
			(xy 462.902749 -286.645963) (xy 462.887039 -286.696893) (xy 462.863913 -286.744914) (xy 462.833889 -286.788951)
			(xy 462.797637 -286.828022) (xy 462.755966 -286.861253) (xy 462.709808 -286.887902) (xy 462.660194 -286.907374)
			(xy 462.608232 -286.919234) (xy 462.555082 -286.923218) (xy 462.501932 -286.919234) (xy 462.44997 -286.907374)
			(xy 462.400356 -286.887902) (xy 462.354198 -286.861253) (xy 462.312527 -286.828022) (xy 462.276275 -286.788951)
			(xy 462.246251 -286.744914) (xy 462.223125 -286.696893) (xy 462.207415 -286.645963) (xy 462.199472 -286.593259)
			(xy 461.9625 -286.593259) (xy 461.9625 -288.293281) (xy 462.199472 -288.293281) (xy 462.199472 -288.239983)
			(xy 462.207415 -288.187279) (xy 462.223125 -288.136349) (xy 462.246251 -288.088328) (xy 462.276275 -288.044291)
			(xy 462.312527 -288.00522) (xy 462.354198 -287.971989) (xy 462.400356 -287.94534) (xy 462.44997 -287.925868)
			(xy 462.501932 -287.914008) (xy 462.555082 -287.910025) (xy 462.608232 -287.914008) (xy 462.660194 -287.925868)
			(xy 462.709808 -287.94534) (xy 462.755966 -287.971989) (xy 462.797637 -288.00522) (xy 462.833889 -288.044291)
			(xy 462.863913 -288.088328) (xy 462.887039 -288.136349) (xy 462.902749 -288.187279) (xy 462.910692 -288.239983)
			(xy 462.91119 -288.266632) (xy 462.910692 -288.293281) (xy 464.409272 -288.293281) (xy 464.409272 -288.239983)
			(xy 464.417215 -288.187279) (xy 464.432925 -288.136349) (xy 464.456051 -288.088328) (xy 464.486075 -288.044291)
			(xy 464.522327 -288.00522) (xy 464.563998 -287.971989) (xy 464.610156 -287.94534) (xy 464.65977 -287.925868)
			(xy 464.711732 -287.914008) (xy 464.764882 -287.910025) (xy 464.818032 -287.914008) (xy 464.869994 -287.925868)
			(xy 464.919608 -287.94534) (xy 464.965766 -287.971989) (xy 465.007437 -288.00522) (xy 465.043689 -288.044291)
			(xy 465.073713 -288.088328) (xy 465.096839 -288.136349) (xy 465.112549 -288.187279) (xy 465.120492 -288.239983)
			(xy 465.12099 -288.266632) (xy 465.120492 -288.293281) (xy 465.112549 -288.345985) (xy 465.096839 -288.396915)
			(xy 465.073713 -288.444936) (xy 465.043689 -288.488973) (xy 465.007437 -288.528044) (xy 464.965766 -288.561275)
			(xy 464.919608 -288.587924) (xy 464.869994 -288.607396) (xy 464.818032 -288.619256) (xy 464.764882 -288.62324)
			(xy 464.711732 -288.619256) (xy 464.65977 -288.607396) (xy 464.610156 -288.587924) (xy 464.563998 -288.561275)
			(xy 464.522327 -288.528044) (xy 464.486075 -288.488973) (xy 464.456051 -288.444936) (xy 464.432925 -288.396915)
			(xy 464.417215 -288.345985) (xy 464.409272 -288.293281) (xy 462.910692 -288.293281) (xy 462.902749 -288.345985)
			(xy 462.887039 -288.396915) (xy 462.863913 -288.444936) (xy 462.833889 -288.488973) (xy 462.797637 -288.528044)
			(xy 462.755966 -288.561275) (xy 462.709808 -288.587924) (xy 462.660194 -288.607396) (xy 462.608232 -288.619256)
			(xy 462.555082 -288.62324) (xy 462.501932 -288.619256) (xy 462.44997 -288.607396) (xy 462.400356 -288.587924)
			(xy 462.354198 -288.561275) (xy 462.312527 -288.528044) (xy 462.276275 -288.488973) (xy 462.246251 -288.444936)
			(xy 462.223125 -288.396915) (xy 462.207415 -288.345985) (xy 462.199472 -288.293281) (xy 461.9625 -288.293281)
			(xy 461.9625 -289.993303) (xy 462.199472 -289.993303) (xy 462.199472 -289.940005) (xy 462.207415 -289.887301)
			(xy 462.223125 -289.836371) (xy 462.246251 -289.78835) (xy 462.276275 -289.744313) (xy 462.312527 -289.705242)
			(xy 462.354198 -289.672011) (xy 462.400356 -289.645362) (xy 462.44997 -289.62589) (xy 462.501932 -289.61403)
			(xy 462.555082 -289.610047) (xy 462.608232 -289.61403) (xy 462.660194 -289.62589) (xy 462.709808 -289.645362)
			(xy 462.755966 -289.672011) (xy 462.797637 -289.705242) (xy 462.833889 -289.744313) (xy 462.863913 -289.78835)
			(xy 462.887039 -289.836371) (xy 462.902749 -289.887301) (xy 462.910692 -289.940005) (xy 462.91119 -289.966654)
			(xy 462.910692 -289.993303) (xy 464.409272 -289.993303) (xy 464.409272 -289.940005) (xy 464.417215 -289.887301)
			(xy 464.432925 -289.836371) (xy 464.456051 -289.78835) (xy 464.486075 -289.744313) (xy 464.522327 -289.705242)
			(xy 464.563998 -289.672011) (xy 464.610156 -289.645362) (xy 464.65977 -289.62589) (xy 464.711732 -289.61403)
			(xy 464.764882 -289.610047) (xy 464.818032 -289.61403) (xy 464.869994 -289.62589) (xy 464.919608 -289.645362)
			(xy 464.965766 -289.672011) (xy 465.007437 -289.705242) (xy 465.043689 -289.744313) (xy 465.073713 -289.78835)
			(xy 465.096839 -289.836371) (xy 465.112549 -289.887301) (xy 465.120492 -289.940005) (xy 465.12099 -289.966654)
			(xy 465.120492 -289.993303) (xy 465.112549 -290.046007) (xy 465.096839 -290.096937) (xy 465.073713 -290.144958)
			(xy 465.043689 -290.188995) (xy 465.007437 -290.228066) (xy 464.965766 -290.261297) (xy 464.919608 -290.287946)
			(xy 464.869994 -290.307418) (xy 464.818032 -290.319278) (xy 464.764882 -290.323262) (xy 464.711732 -290.319278)
			(xy 464.65977 -290.307418) (xy 464.610156 -290.287946) (xy 464.563998 -290.261297) (xy 464.522327 -290.228066)
			(xy 464.486075 -290.188995) (xy 464.456051 -290.144958) (xy 464.432925 -290.096937) (xy 464.417215 -290.046007)
			(xy 464.409272 -289.993303) (xy 462.910692 -289.993303) (xy 462.902749 -290.046007) (xy 462.887039 -290.096937)
			(xy 462.863913 -290.144958) (xy 462.833889 -290.188995) (xy 462.797637 -290.228066) (xy 462.755966 -290.261297)
			(xy 462.709808 -290.287946) (xy 462.660194 -290.307418) (xy 462.608232 -290.319278) (xy 462.555082 -290.323262)
			(xy 462.501932 -290.319278) (xy 462.44997 -290.307418) (xy 462.400356 -290.287946) (xy 462.354198 -290.261297)
			(xy 462.312527 -290.228066) (xy 462.276275 -290.188995) (xy 462.246251 -290.144958) (xy 462.223125 -290.096937)
			(xy 462.207415 -290.046007) (xy 462.199472 -289.993303) (xy 461.9625 -289.993303) (xy 461.9625 -291.693325)
			(xy 462.199472 -291.693325) (xy 462.199472 -291.640027) (xy 462.207415 -291.587323) (xy 462.223125 -291.536393)
			(xy 462.246251 -291.488372) (xy 462.276275 -291.444335) (xy 462.312527 -291.405264) (xy 462.354198 -291.372033)
			(xy 462.400356 -291.345384) (xy 462.44997 -291.325912) (xy 462.501932 -291.314052) (xy 462.555082 -291.310069)
			(xy 462.608232 -291.314052) (xy 462.660194 -291.325912) (xy 462.709808 -291.345384) (xy 462.755966 -291.372033)
			(xy 462.797637 -291.405264) (xy 462.833889 -291.444335) (xy 462.863913 -291.488372) (xy 462.887039 -291.536393)
			(xy 462.902749 -291.587323) (xy 462.910692 -291.640027) (xy 462.91119 -291.666676) (xy 462.910692 -291.693325)
			(xy 464.409272 -291.693325) (xy 464.409272 -291.640027) (xy 464.417215 -291.587323) (xy 464.432925 -291.536393)
			(xy 464.456051 -291.488372) (xy 464.486075 -291.444335) (xy 464.522327 -291.405264) (xy 464.563998 -291.372033)
			(xy 464.610156 -291.345384) (xy 464.65977 -291.325912) (xy 464.711732 -291.314052) (xy 464.764882 -291.310069)
			(xy 464.818032 -291.314052) (xy 464.869994 -291.325912) (xy 464.919608 -291.345384) (xy 464.965766 -291.372033)
			(xy 465.007437 -291.405264) (xy 465.043689 -291.444335) (xy 465.073713 -291.488372) (xy 465.096839 -291.536393)
			(xy 465.112549 -291.587323) (xy 465.120492 -291.640027) (xy 465.12099 -291.666676) (xy 465.120492 -291.693325)
			(xy 465.112549 -291.746029) (xy 465.096839 -291.796959) (xy 465.073713 -291.84498) (xy 465.043689 -291.889017)
			(xy 465.007437 -291.928088) (xy 464.965766 -291.961319) (xy 464.919608 -291.987968) (xy 464.869994 -292.00744)
			(xy 464.818032 -292.0193) (xy 464.764882 -292.023284) (xy 464.711732 -292.0193) (xy 464.65977 -292.00744)
			(xy 464.610156 -291.987968) (xy 464.563998 -291.961319) (xy 464.522327 -291.928088) (xy 464.486075 -291.889017)
			(xy 464.456051 -291.84498) (xy 464.432925 -291.796959) (xy 464.417215 -291.746029) (xy 464.409272 -291.693325)
			(xy 462.910692 -291.693325) (xy 462.902749 -291.746029) (xy 462.887039 -291.796959) (xy 462.863913 -291.84498)
			(xy 462.833889 -291.889017) (xy 462.797637 -291.928088) (xy 462.755966 -291.961319) (xy 462.709808 -291.987968)
			(xy 462.660194 -292.00744) (xy 462.608232 -292.0193) (xy 462.555082 -292.023284) (xy 462.501932 -292.0193)
			(xy 462.44997 -292.00744) (xy 462.400356 -291.987968) (xy 462.354198 -291.961319) (xy 462.312527 -291.928088)
			(xy 462.276275 -291.889017) (xy 462.246251 -291.84498) (xy 462.223125 -291.796959) (xy 462.207415 -291.746029)
			(xy 462.199472 -291.693325) (xy 461.9625 -291.693325) (xy 461.9625 -294.243231) (xy 462.199472 -294.243231)
			(xy 462.199472 -294.189933) (xy 462.207415 -294.137229) (xy 462.223125 -294.086299) (xy 462.246251 -294.038278)
			(xy 462.276275 -293.994241) (xy 462.312527 -293.95517) (xy 462.354198 -293.921939) (xy 462.400356 -293.89529)
			(xy 462.44997 -293.875818) (xy 462.501932 -293.863958) (xy 462.555082 -293.859975) (xy 462.608232 -293.863958)
			(xy 462.660194 -293.875818) (xy 462.709808 -293.89529) (xy 462.755966 -293.921939) (xy 462.797637 -293.95517)
			(xy 462.833889 -293.994241) (xy 462.863913 -294.038278) (xy 462.887039 -294.086299) (xy 462.902749 -294.137229)
			(xy 462.910692 -294.189933) (xy 462.91119 -294.216582) (xy 462.910692 -294.243231) (xy 464.409272 -294.243231)
			(xy 464.409272 -294.189933) (xy 464.417215 -294.137229) (xy 464.432925 -294.086299) (xy 464.456051 -294.038278)
			(xy 464.486075 -293.994241) (xy 464.522327 -293.95517) (xy 464.563998 -293.921939) (xy 464.610156 -293.89529)
			(xy 464.65977 -293.875818) (xy 464.711732 -293.863958) (xy 464.764882 -293.859975) (xy 464.818032 -293.863958)
			(xy 464.869994 -293.875818) (xy 464.919608 -293.89529) (xy 464.965766 -293.921939) (xy 465.007437 -293.95517)
			(xy 465.043689 -293.994241) (xy 465.073713 -294.038278) (xy 465.096839 -294.086299) (xy 465.112549 -294.137229)
			(xy 465.120492 -294.189933) (xy 465.12099 -294.216582) (xy 465.120492 -294.243231) (xy 465.112549 -294.295935)
			(xy 465.096839 -294.346865) (xy 465.073713 -294.394886) (xy 465.043689 -294.438923) (xy 465.007437 -294.477994)
			(xy 464.965766 -294.511225) (xy 464.919608 -294.537874) (xy 464.869994 -294.557346) (xy 464.818032 -294.569206)
			(xy 464.764882 -294.57319) (xy 464.711732 -294.569206) (xy 464.65977 -294.557346) (xy 464.610156 -294.537874)
			(xy 464.563998 -294.511225) (xy 464.522327 -294.477994) (xy 464.486075 -294.438923) (xy 464.456051 -294.394886)
			(xy 464.432925 -294.346865) (xy 464.417215 -294.295935) (xy 464.409272 -294.243231) (xy 462.910692 -294.243231)
			(xy 462.902749 -294.295935) (xy 462.887039 -294.346865) (xy 462.863913 -294.394886) (xy 462.833889 -294.438923)
			(xy 462.797637 -294.477994) (xy 462.755966 -294.511225) (xy 462.709808 -294.537874) (xy 462.660194 -294.557346)
			(xy 462.608232 -294.569206) (xy 462.555082 -294.57319) (xy 462.501932 -294.569206) (xy 462.44997 -294.557346)
			(xy 462.400356 -294.537874) (xy 462.354198 -294.511225) (xy 462.312527 -294.477994) (xy 462.276275 -294.438923)
			(xy 462.246251 -294.394886) (xy 462.223125 -294.346865) (xy 462.207415 -294.295935) (xy 462.199472 -294.243231)
			(xy 461.9625 -294.243231) (xy 461.9625 -295.943253) (xy 462.199472 -295.943253) (xy 462.199472 -295.889955)
			(xy 462.207415 -295.837251) (xy 462.223125 -295.786321) (xy 462.246251 -295.7383) (xy 462.276275 -295.694263)
			(xy 462.312527 -295.655192) (xy 462.354198 -295.621961) (xy 462.400356 -295.595312) (xy 462.44997 -295.57584)
			(xy 462.501932 -295.56398) (xy 462.555082 -295.559997) (xy 462.608232 -295.56398) (xy 462.660194 -295.57584)
			(xy 462.709808 -295.595312) (xy 462.755966 -295.621961) (xy 462.797637 -295.655192) (xy 462.833889 -295.694263)
			(xy 462.863913 -295.7383) (xy 462.887039 -295.786321) (xy 462.902749 -295.837251) (xy 462.910692 -295.889955)
			(xy 462.91119 -295.916604) (xy 462.910692 -295.943253) (xy 464.409272 -295.943253) (xy 464.409272 -295.889955)
			(xy 464.417215 -295.837251) (xy 464.432925 -295.786321) (xy 464.456051 -295.7383) (xy 464.486075 -295.694263)
			(xy 464.522327 -295.655192) (xy 464.563998 -295.621961) (xy 464.610156 -295.595312) (xy 464.65977 -295.57584)
			(xy 464.711732 -295.56398) (xy 464.764882 -295.559997) (xy 464.818032 -295.56398) (xy 464.869994 -295.57584)
			(xy 464.919608 -295.595312) (xy 464.965766 -295.621961) (xy 465.007437 -295.655192) (xy 465.043689 -295.694263)
			(xy 465.073713 -295.7383) (xy 465.096839 -295.786321) (xy 465.112549 -295.837251) (xy 465.120492 -295.889955)
			(xy 465.12099 -295.916604) (xy 465.120492 -295.943253) (xy 465.112549 -295.995957) (xy 465.096839 -296.046887)
			(xy 465.073713 -296.094908) (xy 465.043689 -296.138945) (xy 465.007437 -296.178016) (xy 464.965766 -296.211247)
			(xy 464.919608 -296.237896) (xy 464.869994 -296.257368) (xy 464.818032 -296.269228) (xy 464.764882 -296.273212)
			(xy 464.711732 -296.269228) (xy 464.65977 -296.257368) (xy 464.610156 -296.237896) (xy 464.563998 -296.211247)
			(xy 464.522327 -296.178016) (xy 464.486075 -296.138945) (xy 464.456051 -296.094908) (xy 464.432925 -296.046887)
			(xy 464.417215 -295.995957) (xy 464.409272 -295.943253) (xy 462.910692 -295.943253) (xy 462.902749 -295.995957)
			(xy 462.887039 -296.046887) (xy 462.863913 -296.094908) (xy 462.833889 -296.138945) (xy 462.797637 -296.178016)
			(xy 462.755966 -296.211247) (xy 462.709808 -296.237896) (xy 462.660194 -296.257368) (xy 462.608232 -296.269228)
			(xy 462.555082 -296.273212) (xy 462.501932 -296.269228) (xy 462.44997 -296.257368) (xy 462.400356 -296.237896)
			(xy 462.354198 -296.211247) (xy 462.312527 -296.178016) (xy 462.276275 -296.138945) (xy 462.246251 -296.094908)
			(xy 462.223125 -296.046887) (xy 462.207415 -295.995957) (xy 462.199472 -295.943253) (xy 461.9625 -295.943253)
			(xy 461.9625 -297.643275) (xy 462.199472 -297.643275) (xy 462.199472 -297.589977) (xy 462.207415 -297.537273)
			(xy 462.223125 -297.486343) (xy 462.246251 -297.438322) (xy 462.276275 -297.394285) (xy 462.312527 -297.355214)
			(xy 462.354198 -297.321983) (xy 462.400356 -297.295334) (xy 462.44997 -297.275862) (xy 462.501932 -297.264002)
			(xy 462.555082 -297.260019) (xy 462.608232 -297.264002) (xy 462.660194 -297.275862) (xy 462.709808 -297.295334)
			(xy 462.755966 -297.321983) (xy 462.797637 -297.355214) (xy 462.833889 -297.394285) (xy 462.863913 -297.438322)
			(xy 462.887039 -297.486343) (xy 462.902749 -297.537273) (xy 462.910692 -297.589977) (xy 462.91119 -297.616626)
			(xy 462.910692 -297.643275) (xy 464.409272 -297.643275) (xy 464.409272 -297.589977) (xy 464.417215 -297.537273)
			(xy 464.432925 -297.486343) (xy 464.456051 -297.438322) (xy 464.486075 -297.394285) (xy 464.522327 -297.355214)
			(xy 464.563998 -297.321983) (xy 464.610156 -297.295334) (xy 464.65977 -297.275862) (xy 464.711732 -297.264002)
			(xy 464.764882 -297.260019) (xy 464.818032 -297.264002) (xy 464.869994 -297.275862) (xy 464.919608 -297.295334)
			(xy 464.965766 -297.321983) (xy 465.007437 -297.355214) (xy 465.043689 -297.394285) (xy 465.073713 -297.438322)
			(xy 465.096839 -297.486343) (xy 465.112549 -297.537273) (xy 465.120492 -297.589977) (xy 465.12099 -297.616626)
			(xy 465.120492 -297.643275) (xy 465.112549 -297.695979) (xy 465.096839 -297.746909) (xy 465.073713 -297.79493)
			(xy 465.043689 -297.838967) (xy 465.007437 -297.878038) (xy 464.965766 -297.911269) (xy 464.919608 -297.937918)
			(xy 464.869994 -297.95739) (xy 464.818032 -297.96925) (xy 464.764882 -297.973234) (xy 464.711732 -297.96925)
			(xy 464.65977 -297.95739) (xy 464.610156 -297.937918) (xy 464.563998 -297.911269) (xy 464.522327 -297.878038)
			(xy 464.486075 -297.838967) (xy 464.456051 -297.79493) (xy 464.432925 -297.746909) (xy 464.417215 -297.695979)
			(xy 464.409272 -297.643275) (xy 462.910692 -297.643275) (xy 462.902749 -297.695979) (xy 462.887039 -297.746909)
			(xy 462.863913 -297.79493) (xy 462.833889 -297.838967) (xy 462.797637 -297.878038) (xy 462.755966 -297.911269)
			(xy 462.709808 -297.937918) (xy 462.660194 -297.95739) (xy 462.608232 -297.96925) (xy 462.555082 -297.973234)
			(xy 462.501932 -297.96925) (xy 462.44997 -297.95739) (xy 462.400356 -297.937918) (xy 462.354198 -297.911269)
			(xy 462.312527 -297.878038) (xy 462.276275 -297.838967) (xy 462.246251 -297.79493) (xy 462.223125 -297.746909)
			(xy 462.207415 -297.695979) (xy 462.199472 -297.643275) (xy 461.9625 -297.643275) (xy 461.9625 -299.343297)
			(xy 462.199472 -299.343297) (xy 462.199472 -299.289999) (xy 462.207415 -299.237295) (xy 462.223125 -299.186365)
			(xy 462.246251 -299.138344) (xy 462.276275 -299.094307) (xy 462.312527 -299.055236) (xy 462.354198 -299.022005)
			(xy 462.400356 -298.995356) (xy 462.44997 -298.975884) (xy 462.501932 -298.964024) (xy 462.555082 -298.960041)
			(xy 462.608232 -298.964024) (xy 462.660194 -298.975884) (xy 462.709808 -298.995356) (xy 462.755966 -299.022005)
			(xy 462.797637 -299.055236) (xy 462.833889 -299.094307) (xy 462.863913 -299.138344) (xy 462.887039 -299.186365)
			(xy 462.902749 -299.237295) (xy 462.910692 -299.289999) (xy 462.91119 -299.316648) (xy 462.910692 -299.343297)
			(xy 464.409272 -299.343297) (xy 464.409272 -299.289999) (xy 464.417215 -299.237295) (xy 464.432925 -299.186365)
			(xy 464.456051 -299.138344) (xy 464.486075 -299.094307) (xy 464.522327 -299.055236) (xy 464.563998 -299.022005)
			(xy 464.610156 -298.995356) (xy 464.65977 -298.975884) (xy 464.711732 -298.964024) (xy 464.764882 -298.960041)
			(xy 464.818032 -298.964024) (xy 464.869994 -298.975884) (xy 464.919608 -298.995356) (xy 464.965766 -299.022005)
			(xy 465.007437 -299.055236) (xy 465.043689 -299.094307) (xy 465.073713 -299.138344) (xy 465.096839 -299.186365)
			(xy 465.112549 -299.237295) (xy 465.120492 -299.289999) (xy 465.12099 -299.316648) (xy 465.120492 -299.343297)
			(xy 465.112549 -299.396001) (xy 465.096839 -299.446931) (xy 465.073713 -299.494952) (xy 465.043689 -299.538989)
			(xy 465.007437 -299.57806) (xy 464.965766 -299.611291) (xy 464.919608 -299.63794) (xy 464.869994 -299.657412)
			(xy 464.818032 -299.669272) (xy 464.764882 -299.673256) (xy 464.711732 -299.669272) (xy 464.65977 -299.657412)
			(xy 464.610156 -299.63794) (xy 464.563998 -299.611291) (xy 464.522327 -299.57806) (xy 464.486075 -299.538989)
			(xy 464.456051 -299.494952) (xy 464.432925 -299.446931) (xy 464.417215 -299.396001) (xy 464.409272 -299.343297)
			(xy 462.910692 -299.343297) (xy 462.902749 -299.396001) (xy 462.887039 -299.446931) (xy 462.863913 -299.494952)
			(xy 462.833889 -299.538989) (xy 462.797637 -299.57806) (xy 462.755966 -299.611291) (xy 462.709808 -299.63794)
			(xy 462.660194 -299.657412) (xy 462.608232 -299.669272) (xy 462.555082 -299.673256) (xy 462.501932 -299.669272)
			(xy 462.44997 -299.657412) (xy 462.400356 -299.63794) (xy 462.354198 -299.611291) (xy 462.312527 -299.57806)
			(xy 462.276275 -299.538989) (xy 462.246251 -299.494952) (xy 462.223125 -299.446931) (xy 462.207415 -299.396001)
			(xy 462.199472 -299.343297) (xy 461.9625 -299.343297) (xy 461.9625 -301.043319) (xy 462.199472 -301.043319)
			(xy 462.199472 -300.990021) (xy 462.207415 -300.937317) (xy 462.223125 -300.886387) (xy 462.246251 -300.838366)
			(xy 462.276275 -300.794329) (xy 462.312527 -300.755258) (xy 462.354198 -300.722027) (xy 462.400356 -300.695378)
			(xy 462.44997 -300.675906) (xy 462.501932 -300.664046) (xy 462.555082 -300.660063) (xy 462.608232 -300.664046)
			(xy 462.660194 -300.675906) (xy 462.709808 -300.695378) (xy 462.755966 -300.722027) (xy 462.797637 -300.755258)
			(xy 462.833889 -300.794329) (xy 462.863913 -300.838366) (xy 462.887039 -300.886387) (xy 462.902749 -300.937317)
			(xy 462.910692 -300.990021) (xy 462.91119 -301.01667) (xy 462.910692 -301.043319) (xy 464.409272 -301.043319)
			(xy 464.409272 -300.990021) (xy 464.417215 -300.937317) (xy 464.432925 -300.886387) (xy 464.456051 -300.838366)
			(xy 464.486075 -300.794329) (xy 464.522327 -300.755258) (xy 464.563998 -300.722027) (xy 464.610156 -300.695378)
			(xy 464.65977 -300.675906) (xy 464.711732 -300.664046) (xy 464.764882 -300.660063) (xy 464.818032 -300.664046)
			(xy 464.869994 -300.675906) (xy 464.919608 -300.695378) (xy 464.965766 -300.722027) (xy 465.007437 -300.755258)
			(xy 465.043689 -300.794329) (xy 465.073713 -300.838366) (xy 465.096839 -300.886387) (xy 465.112549 -300.937317)
			(xy 465.120492 -300.990021) (xy 465.12099 -301.01667) (xy 465.120492 -301.043319) (xy 465.112549 -301.096023)
			(xy 465.096839 -301.146953) (xy 465.073713 -301.194974) (xy 465.043689 -301.239011) (xy 465.007437 -301.278082)
			(xy 464.965766 -301.311313) (xy 464.919608 -301.337962) (xy 464.869994 -301.357434) (xy 464.818032 -301.369294)
			(xy 464.764882 -301.373278) (xy 464.711732 -301.369294) (xy 464.65977 -301.357434) (xy 464.610156 -301.337962)
			(xy 464.563998 -301.311313) (xy 464.522327 -301.278082) (xy 464.486075 -301.239011) (xy 464.456051 -301.194974)
			(xy 464.432925 -301.146953) (xy 464.417215 -301.096023) (xy 464.409272 -301.043319) (xy 462.910692 -301.043319)
			(xy 462.902749 -301.096023) (xy 462.887039 -301.146953) (xy 462.863913 -301.194974) (xy 462.833889 -301.239011)
			(xy 462.797637 -301.278082) (xy 462.755966 -301.311313) (xy 462.709808 -301.337962) (xy 462.660194 -301.357434)
			(xy 462.608232 -301.369294) (xy 462.555082 -301.373278) (xy 462.501932 -301.369294) (xy 462.44997 -301.357434)
			(xy 462.400356 -301.337962) (xy 462.354198 -301.311313) (xy 462.312527 -301.278082) (xy 462.276275 -301.239011)
			(xy 462.246251 -301.194974) (xy 462.223125 -301.146953) (xy 462.207415 -301.096023) (xy 462.199472 -301.043319)
			(xy 461.9625 -301.043319) (xy 461.9625 -303.593225) (xy 462.199472 -303.593225) (xy 462.199472 -303.539927)
			(xy 462.207415 -303.487223) (xy 462.223125 -303.436293) (xy 462.246251 -303.388272) (xy 462.276275 -303.344235)
			(xy 462.312527 -303.305164) (xy 462.354198 -303.271933) (xy 462.400356 -303.245284) (xy 462.44997 -303.225812)
			(xy 462.501932 -303.213952) (xy 462.555082 -303.209969) (xy 462.608232 -303.213952) (xy 462.660194 -303.225812)
			(xy 462.709808 -303.245284) (xy 462.755966 -303.271933) (xy 462.797637 -303.305164) (xy 462.833889 -303.344235)
			(xy 462.863913 -303.388272) (xy 462.887039 -303.436293) (xy 462.902749 -303.487223) (xy 462.910692 -303.539927)
			(xy 462.91119 -303.566576) (xy 462.910692 -303.593225) (xy 464.409272 -303.593225) (xy 464.409272 -303.539927)
			(xy 464.417215 -303.487223) (xy 464.432925 -303.436293) (xy 464.456051 -303.388272) (xy 464.486075 -303.344235)
			(xy 464.522327 -303.305164) (xy 464.563998 -303.271933) (xy 464.610156 -303.245284) (xy 464.65977 -303.225812)
			(xy 464.711732 -303.213952) (xy 464.764882 -303.209969) (xy 464.818032 -303.213952) (xy 464.869994 -303.225812)
			(xy 464.919608 -303.245284) (xy 464.965766 -303.271933) (xy 465.007437 -303.305164) (xy 465.043689 -303.344235)
			(xy 465.073713 -303.388272) (xy 465.096839 -303.436293) (xy 465.112549 -303.487223) (xy 465.120492 -303.539927)
			(xy 465.12099 -303.566576) (xy 465.120492 -303.593225) (xy 465.112549 -303.645929) (xy 465.096839 -303.696859)
			(xy 465.073713 -303.74488) (xy 465.043689 -303.788917) (xy 465.007437 -303.827988) (xy 464.965766 -303.861219)
			(xy 464.919608 -303.887868) (xy 464.869994 -303.90734) (xy 464.818032 -303.9192) (xy 464.764882 -303.923184)
			(xy 464.711732 -303.9192) (xy 464.65977 -303.90734) (xy 464.610156 -303.887868) (xy 464.563998 -303.861219)
			(xy 464.522327 -303.827988) (xy 464.486075 -303.788917) (xy 464.456051 -303.74488) (xy 464.432925 -303.696859)
			(xy 464.417215 -303.645929) (xy 464.409272 -303.593225) (xy 462.910692 -303.593225) (xy 462.902749 -303.645929)
			(xy 462.887039 -303.696859) (xy 462.863913 -303.74488) (xy 462.833889 -303.788917) (xy 462.797637 -303.827988)
			(xy 462.755966 -303.861219) (xy 462.709808 -303.887868) (xy 462.660194 -303.90734) (xy 462.608232 -303.9192)
			(xy 462.555082 -303.923184) (xy 462.501932 -303.9192) (xy 462.44997 -303.90734) (xy 462.400356 -303.887868)
			(xy 462.354198 -303.861219) (xy 462.312527 -303.827988) (xy 462.276275 -303.788917) (xy 462.246251 -303.74488)
			(xy 462.223125 -303.696859) (xy 462.207415 -303.645929) (xy 462.199472 -303.593225) (xy 461.9625 -303.593225)
			(xy 461.9625 -305.293247) (xy 462.199472 -305.293247) (xy 462.199472 -305.239949) (xy 462.207415 -305.187245)
			(xy 462.223125 -305.136315) (xy 462.246251 -305.088294) (xy 462.276275 -305.044257) (xy 462.312527 -305.005186)
			(xy 462.354198 -304.971955) (xy 462.400356 -304.945306) (xy 462.44997 -304.925834) (xy 462.501932 -304.913974)
			(xy 462.555082 -304.909991) (xy 462.608232 -304.913974) (xy 462.660194 -304.925834) (xy 462.709808 -304.945306)
			(xy 462.755966 -304.971955) (xy 462.797637 -305.005186) (xy 462.833889 -305.044257) (xy 462.863913 -305.088294)
			(xy 462.887039 -305.136315) (xy 462.902749 -305.187245) (xy 462.910692 -305.239949) (xy 462.91119 -305.266598)
			(xy 462.910692 -305.293247) (xy 464.409272 -305.293247) (xy 464.409272 -305.239949) (xy 464.417215 -305.187245)
			(xy 464.432925 -305.136315) (xy 464.456051 -305.088294) (xy 464.486075 -305.044257) (xy 464.522327 -305.005186)
			(xy 464.563998 -304.971955) (xy 464.610156 -304.945306) (xy 464.65977 -304.925834) (xy 464.711732 -304.913974)
			(xy 464.764882 -304.909991) (xy 464.818032 -304.913974) (xy 464.869994 -304.925834) (xy 464.919608 -304.945306)
			(xy 464.965766 -304.971955) (xy 465.007437 -305.005186) (xy 465.043689 -305.044257) (xy 465.073713 -305.088294)
			(xy 465.096839 -305.136315) (xy 465.112549 -305.187245) (xy 465.120492 -305.239949) (xy 465.12099 -305.266598)
			(xy 465.120492 -305.293247) (xy 465.112549 -305.345951) (xy 465.096839 -305.396881) (xy 465.073713 -305.444902)
			(xy 465.043689 -305.488939) (xy 465.007437 -305.52801) (xy 464.965766 -305.561241) (xy 464.919608 -305.58789)
			(xy 464.869994 -305.607362) (xy 464.818032 -305.619222) (xy 464.764882 -305.623206) (xy 464.711732 -305.619222)
			(xy 464.65977 -305.607362) (xy 464.610156 -305.58789) (xy 464.563998 -305.561241) (xy 464.522327 -305.52801)
			(xy 464.486075 -305.488939) (xy 464.456051 -305.444902) (xy 464.432925 -305.396881) (xy 464.417215 -305.345951)
			(xy 464.409272 -305.293247) (xy 462.910692 -305.293247) (xy 462.902749 -305.345951) (xy 462.887039 -305.396881)
			(xy 462.863913 -305.444902) (xy 462.833889 -305.488939) (xy 462.797637 -305.52801) (xy 462.755966 -305.561241)
			(xy 462.709808 -305.58789) (xy 462.660194 -305.607362) (xy 462.608232 -305.619222) (xy 462.555082 -305.623206)
			(xy 462.501932 -305.619222) (xy 462.44997 -305.607362) (xy 462.400356 -305.58789) (xy 462.354198 -305.561241)
			(xy 462.312527 -305.52801) (xy 462.276275 -305.488939) (xy 462.246251 -305.444902) (xy 462.223125 -305.396881)
			(xy 462.207415 -305.345951) (xy 462.199472 -305.293247) (xy 461.9625 -305.293247) (xy 461.9625 -306.993269)
			(xy 462.199472 -306.993269) (xy 462.199472 -306.939971) (xy 462.207415 -306.887267) (xy 462.223125 -306.836337)
			(xy 462.246251 -306.788316) (xy 462.276275 -306.744279) (xy 462.312527 -306.705208) (xy 462.354198 -306.671977)
			(xy 462.400356 -306.645328) (xy 462.44997 -306.625856) (xy 462.501932 -306.613996) (xy 462.555082 -306.610013)
			(xy 462.608232 -306.613996) (xy 462.660194 -306.625856) (xy 462.709808 -306.645328) (xy 462.755966 -306.671977)
			(xy 462.797637 -306.705208) (xy 462.833889 -306.744279) (xy 462.863913 -306.788316) (xy 462.887039 -306.836337)
			(xy 462.902749 -306.887267) (xy 462.910692 -306.939971) (xy 462.91119 -306.96662) (xy 462.910692 -306.993269)
			(xy 464.409272 -306.993269) (xy 464.409272 -306.939971) (xy 464.417215 -306.887267) (xy 464.432925 -306.836337)
			(xy 464.456051 -306.788316) (xy 464.486075 -306.744279) (xy 464.522327 -306.705208) (xy 464.563998 -306.671977)
			(xy 464.610156 -306.645328) (xy 464.65977 -306.625856) (xy 464.711732 -306.613996) (xy 464.764882 -306.610013)
			(xy 464.818032 -306.613996) (xy 464.869994 -306.625856) (xy 464.919608 -306.645328) (xy 464.965766 -306.671977)
			(xy 465.007437 -306.705208) (xy 465.043689 -306.744279) (xy 465.073713 -306.788316) (xy 465.096839 -306.836337)
			(xy 465.112549 -306.887267) (xy 465.120492 -306.939971) (xy 465.12099 -306.96662) (xy 465.120492 -306.993269)
			(xy 465.112549 -307.045973) (xy 465.096839 -307.096903) (xy 465.073713 -307.144924) (xy 465.043689 -307.188961)
			(xy 465.007437 -307.228032) (xy 464.965766 -307.261263) (xy 464.919608 -307.287912) (xy 464.869994 -307.307384)
			(xy 464.818032 -307.319244) (xy 464.764882 -307.323228) (xy 464.711732 -307.319244) (xy 464.65977 -307.307384)
			(xy 464.610156 -307.287912) (xy 464.563998 -307.261263) (xy 464.522327 -307.228032) (xy 464.486075 -307.188961)
			(xy 464.456051 -307.144924) (xy 464.432925 -307.096903) (xy 464.417215 -307.045973) (xy 464.409272 -306.993269)
			(xy 462.910692 -306.993269) (xy 462.902749 -307.045973) (xy 462.887039 -307.096903) (xy 462.863913 -307.144924)
			(xy 462.833889 -307.188961) (xy 462.797637 -307.228032) (xy 462.755966 -307.261263) (xy 462.709808 -307.287912)
			(xy 462.660194 -307.307384) (xy 462.608232 -307.319244) (xy 462.555082 -307.323228) (xy 462.501932 -307.319244)
			(xy 462.44997 -307.307384) (xy 462.400356 -307.287912) (xy 462.354198 -307.261263) (xy 462.312527 -307.228032)
			(xy 462.276275 -307.188961) (xy 462.246251 -307.144924) (xy 462.223125 -307.096903) (xy 462.207415 -307.045973)
			(xy 462.199472 -306.993269) (xy 461.9625 -306.993269) (xy 461.9625 -308.693291) (xy 462.199472 -308.693291)
			(xy 462.199472 -308.639993) (xy 462.207415 -308.587289) (xy 462.223125 -308.536359) (xy 462.246251 -308.488338)
			(xy 462.276275 -308.444301) (xy 462.312527 -308.40523) (xy 462.354198 -308.371999) (xy 462.400356 -308.34535)
			(xy 462.44997 -308.325878) (xy 462.501932 -308.314018) (xy 462.555082 -308.310035) (xy 462.608232 -308.314018)
			(xy 462.660194 -308.325878) (xy 462.709808 -308.34535) (xy 462.755966 -308.371999) (xy 462.797637 -308.40523)
			(xy 462.833889 -308.444301) (xy 462.863913 -308.488338) (xy 462.887039 -308.536359) (xy 462.902749 -308.587289)
			(xy 462.910692 -308.639993) (xy 462.91119 -308.666642) (xy 462.910692 -308.693291) (xy 464.409272 -308.693291)
			(xy 464.409272 -308.639993) (xy 464.417215 -308.587289) (xy 464.432925 -308.536359) (xy 464.456051 -308.488338)
			(xy 464.486075 -308.444301) (xy 464.522327 -308.40523) (xy 464.563998 -308.371999) (xy 464.610156 -308.34535)
			(xy 464.65977 -308.325878) (xy 464.711732 -308.314018) (xy 464.764882 -308.310035) (xy 464.818032 -308.314018)
			(xy 464.869994 -308.325878) (xy 464.919608 -308.34535) (xy 464.965766 -308.371999) (xy 465.007437 -308.40523)
			(xy 465.043689 -308.444301) (xy 465.073713 -308.488338) (xy 465.096839 -308.536359) (xy 465.112549 -308.587289)
			(xy 465.120492 -308.639993) (xy 465.12099 -308.666642) (xy 465.120492 -308.693291) (xy 465.112549 -308.745995)
			(xy 465.096839 -308.796925) (xy 465.073713 -308.844946) (xy 465.043689 -308.888983) (xy 465.007437 -308.928054)
			(xy 464.965766 -308.961285) (xy 464.919608 -308.987934) (xy 464.869994 -309.007406) (xy 464.818032 -309.019266)
			(xy 464.764882 -309.02325) (xy 464.711732 -309.019266) (xy 464.65977 -309.007406) (xy 464.610156 -308.987934)
			(xy 464.563998 -308.961285) (xy 464.522327 -308.928054) (xy 464.486075 -308.888983) (xy 464.456051 -308.844946)
			(xy 464.432925 -308.796925) (xy 464.417215 -308.745995) (xy 464.409272 -308.693291) (xy 462.910692 -308.693291)
			(xy 462.902749 -308.745995) (xy 462.887039 -308.796925) (xy 462.863913 -308.844946) (xy 462.833889 -308.888983)
			(xy 462.797637 -308.928054) (xy 462.755966 -308.961285) (xy 462.709808 -308.987934) (xy 462.660194 -309.007406)
			(xy 462.608232 -309.019266) (xy 462.555082 -309.02325) (xy 462.501932 -309.019266) (xy 462.44997 -309.007406)
			(xy 462.400356 -308.987934) (xy 462.354198 -308.961285) (xy 462.312527 -308.928054) (xy 462.276275 -308.888983)
			(xy 462.246251 -308.844946) (xy 462.223125 -308.796925) (xy 462.207415 -308.745995) (xy 462.199472 -308.693291)
			(xy 461.9625 -308.693291) (xy 461.9625 -310.393313) (xy 462.199472 -310.393313) (xy 462.199472 -310.340015)
			(xy 462.207415 -310.287311) (xy 462.223125 -310.236381) (xy 462.246251 -310.18836) (xy 462.276275 -310.144323)
			(xy 462.312527 -310.105252) (xy 462.354198 -310.072021) (xy 462.400356 -310.045372) (xy 462.44997 -310.0259)
			(xy 462.501932 -310.01404) (xy 462.555082 -310.010057) (xy 462.608232 -310.01404) (xy 462.660194 -310.0259)
			(xy 462.709808 -310.045372) (xy 462.755966 -310.072021) (xy 462.797637 -310.105252) (xy 462.833889 -310.144323)
			(xy 462.863913 -310.18836) (xy 462.887039 -310.236381) (xy 462.902749 -310.287311) (xy 462.910692 -310.340015)
			(xy 462.91119 -310.366664) (xy 462.910692 -310.393313) (xy 464.409272 -310.393313) (xy 464.409272 -310.340015)
			(xy 464.417215 -310.287311) (xy 464.432925 -310.236381) (xy 464.456051 -310.18836) (xy 464.486075 -310.144323)
			(xy 464.522327 -310.105252) (xy 464.563998 -310.072021) (xy 464.610156 -310.045372) (xy 464.65977 -310.0259)
			(xy 464.711732 -310.01404) (xy 464.764882 -310.010057) (xy 464.818032 -310.01404) (xy 464.869994 -310.0259)
			(xy 464.919608 -310.045372) (xy 464.965766 -310.072021) (xy 465.007437 -310.105252) (xy 465.043689 -310.144323)
			(xy 465.073713 -310.18836) (xy 465.096839 -310.236381) (xy 465.112549 -310.287311) (xy 465.120492 -310.340015)
			(xy 465.12099 -310.366664) (xy 465.120492 -310.393313) (xy 465.112549 -310.446017) (xy 465.096839 -310.496947)
			(xy 465.073713 -310.544968) (xy 465.043689 -310.589005) (xy 465.007437 -310.628076) (xy 464.965766 -310.661307)
			(xy 464.919608 -310.687956) (xy 464.869994 -310.707428) (xy 464.818032 -310.719288) (xy 464.764882 -310.723272)
			(xy 464.711732 -310.719288) (xy 464.65977 -310.707428) (xy 464.610156 -310.687956) (xy 464.563998 -310.661307)
			(xy 464.522327 -310.628076) (xy 464.486075 -310.589005) (xy 464.456051 -310.544968) (xy 464.432925 -310.496947)
			(xy 464.417215 -310.446017) (xy 464.409272 -310.393313) (xy 462.910692 -310.393313) (xy 462.902749 -310.446017)
			(xy 462.887039 -310.496947) (xy 462.863913 -310.544968) (xy 462.833889 -310.589005) (xy 462.797637 -310.628076)
			(xy 462.755966 -310.661307) (xy 462.709808 -310.687956) (xy 462.660194 -310.707428) (xy 462.608232 -310.719288)
			(xy 462.555082 -310.723272) (xy 462.501932 -310.719288) (xy 462.44997 -310.707428) (xy 462.400356 -310.687956)
			(xy 462.354198 -310.661307) (xy 462.312527 -310.628076) (xy 462.276275 -310.589005) (xy 462.246251 -310.544968)
			(xy 462.223125 -310.496947) (xy 462.207415 -310.446017) (xy 462.199472 -310.393313) (xy 461.9625 -310.393313)
			(xy 461.9625 -312.943219) (xy 462.199472 -312.943219) (xy 462.199472 -312.889921) (xy 462.207415 -312.837217)
			(xy 462.223125 -312.786287) (xy 462.246251 -312.738266) (xy 462.276275 -312.694229) (xy 462.312527 -312.655158)
			(xy 462.354198 -312.621927) (xy 462.400356 -312.595278) (xy 462.44997 -312.575806) (xy 462.501932 -312.563946)
			(xy 462.555082 -312.559963) (xy 462.608232 -312.563946) (xy 462.660194 -312.575806) (xy 462.709808 -312.595278)
			(xy 462.755966 -312.621927) (xy 462.797637 -312.655158) (xy 462.833889 -312.694229) (xy 462.863913 -312.738266)
			(xy 462.887039 -312.786287) (xy 462.902749 -312.837217) (xy 462.910692 -312.889921) (xy 462.91119 -312.91657)
			(xy 462.910692 -312.943219) (xy 464.409272 -312.943219) (xy 464.409272 -312.889921) (xy 464.417215 -312.837217)
			(xy 464.432925 -312.786287) (xy 464.456051 -312.738266) (xy 464.486075 -312.694229) (xy 464.522327 -312.655158)
			(xy 464.563998 -312.621927) (xy 464.610156 -312.595278) (xy 464.65977 -312.575806) (xy 464.711732 -312.563946)
			(xy 464.764882 -312.559963) (xy 464.818032 -312.563946) (xy 464.869994 -312.575806) (xy 464.919608 -312.595278)
			(xy 464.965766 -312.621927) (xy 465.007437 -312.655158) (xy 465.043689 -312.694229) (xy 465.073713 -312.738266)
			(xy 465.096839 -312.786287) (xy 465.112549 -312.837217) (xy 465.120492 -312.889921) (xy 465.12099 -312.91657)
			(xy 465.120492 -312.943219) (xy 465.112549 -312.995923) (xy 465.096839 -313.046853) (xy 465.073713 -313.094874)
			(xy 465.043689 -313.138911) (xy 465.007437 -313.177982) (xy 464.965766 -313.211213) (xy 464.919608 -313.237862)
			(xy 464.869994 -313.257334) (xy 464.818032 -313.269194) (xy 464.764882 -313.273178) (xy 464.711732 -313.269194)
			(xy 464.65977 -313.257334) (xy 464.610156 -313.237862) (xy 464.563998 -313.211213) (xy 464.522327 -313.177982)
			(xy 464.486075 -313.138911) (xy 464.456051 -313.094874) (xy 464.432925 -313.046853) (xy 464.417215 -312.995923)
			(xy 464.409272 -312.943219) (xy 462.910692 -312.943219) (xy 462.902749 -312.995923) (xy 462.887039 -313.046853)
			(xy 462.863913 -313.094874) (xy 462.833889 -313.138911) (xy 462.797637 -313.177982) (xy 462.755966 -313.211213)
			(xy 462.709808 -313.237862) (xy 462.660194 -313.257334) (xy 462.608232 -313.269194) (xy 462.555082 -313.273178)
			(xy 462.501932 -313.269194) (xy 462.44997 -313.257334) (xy 462.400356 -313.237862) (xy 462.354198 -313.211213)
			(xy 462.312527 -313.177982) (xy 462.276275 -313.138911) (xy 462.246251 -313.094874) (xy 462.223125 -313.046853)
			(xy 462.207415 -312.995923) (xy 462.199472 -312.943219) (xy 461.9625 -312.943219) (xy 461.9625 -314.643241)
			(xy 462.199472 -314.643241) (xy 462.199472 -314.589943) (xy 462.207415 -314.537239) (xy 462.223125 -314.486309)
			(xy 462.246251 -314.438288) (xy 462.276275 -314.394251) (xy 462.312527 -314.35518) (xy 462.354198 -314.321949)
			(xy 462.400356 -314.2953) (xy 462.44997 -314.275828) (xy 462.501932 -314.263968) (xy 462.555082 -314.259985)
			(xy 462.608232 -314.263968) (xy 462.660194 -314.275828) (xy 462.709808 -314.2953) (xy 462.755966 -314.321949)
			(xy 462.797637 -314.35518) (xy 462.833889 -314.394251) (xy 462.863913 -314.438288) (xy 462.887039 -314.486309)
			(xy 462.902749 -314.537239) (xy 462.910692 -314.589943) (xy 462.91119 -314.616592) (xy 462.910692 -314.643241)
			(xy 464.409272 -314.643241) (xy 464.409272 -314.589943) (xy 464.417215 -314.537239) (xy 464.432925 -314.486309)
			(xy 464.456051 -314.438288) (xy 464.486075 -314.394251) (xy 464.522327 -314.35518) (xy 464.563998 -314.321949)
			(xy 464.610156 -314.2953) (xy 464.65977 -314.275828) (xy 464.711732 -314.263968) (xy 464.764882 -314.259985)
			(xy 464.818032 -314.263968) (xy 464.869994 -314.275828) (xy 464.919608 -314.2953) (xy 464.965766 -314.321949)
			(xy 465.007437 -314.35518) (xy 465.043689 -314.394251) (xy 465.073713 -314.438288) (xy 465.096839 -314.486309)
			(xy 465.112549 -314.537239) (xy 465.120492 -314.589943) (xy 465.12099 -314.616592) (xy 465.120492 -314.643241)
			(xy 465.112549 -314.695945) (xy 465.096839 -314.746875) (xy 465.073713 -314.794896) (xy 465.043689 -314.838933)
			(xy 465.007437 -314.878004) (xy 464.965766 -314.911235) (xy 464.919608 -314.937884) (xy 464.869994 -314.957356)
			(xy 464.818032 -314.969216) (xy 464.764882 -314.9732) (xy 464.711732 -314.969216) (xy 464.65977 -314.957356)
			(xy 464.610156 -314.937884) (xy 464.563998 -314.911235) (xy 464.522327 -314.878004) (xy 464.486075 -314.838933)
			(xy 464.456051 -314.794896) (xy 464.432925 -314.746875) (xy 464.417215 -314.695945) (xy 464.409272 -314.643241)
			(xy 462.910692 -314.643241) (xy 462.902749 -314.695945) (xy 462.887039 -314.746875) (xy 462.863913 -314.794896)
			(xy 462.833889 -314.838933) (xy 462.797637 -314.878004) (xy 462.755966 -314.911235) (xy 462.709808 -314.937884)
			(xy 462.660194 -314.957356) (xy 462.608232 -314.969216) (xy 462.555082 -314.9732) (xy 462.501932 -314.969216)
			(xy 462.44997 -314.957356) (xy 462.400356 -314.937884) (xy 462.354198 -314.911235) (xy 462.312527 -314.878004)
			(xy 462.276275 -314.838933) (xy 462.246251 -314.794896) (xy 462.223125 -314.746875) (xy 462.207415 -314.695945)
			(xy 462.199472 -314.643241) (xy 461.9625 -314.643241) (xy 461.9625 -316.316614) (xy 462.198974 -316.316614)
			(xy 462.199472 -316.289965) (xy 462.207415 -316.237261) (xy 462.223125 -316.186331) (xy 462.246251 -316.13831)
			(xy 462.276275 -316.094273) (xy 462.312527 -316.055202) (xy 462.354198 -316.021971) (xy 462.400356 -315.995322)
			(xy 462.44997 -315.97585) (xy 462.501932 -315.96399) (xy 462.555082 -315.960007) (xy 462.608232 -315.96399)
			(xy 462.660194 -315.97585) (xy 462.709808 -315.995322) (xy 462.755966 -316.021971) (xy 462.797637 -316.055202)
			(xy 462.833889 -316.094273) (xy 462.863913 -316.13831) (xy 462.887039 -316.186331) (xy 462.902749 -316.237261)
			(xy 462.910692 -316.289965) (xy 462.91119 -316.316614) (xy 462.91073 -316.34263) (xy 462.910637 -316.343263)
			(xy 464.409272 -316.343263) (xy 464.409272 -316.289965) (xy 464.417215 -316.237261) (xy 464.432925 -316.186331)
			(xy 464.456051 -316.13831) (xy 464.486075 -316.094273) (xy 464.522327 -316.055202) (xy 464.563998 -316.021971)
			(xy 464.610156 -315.995322) (xy 464.65977 -315.97585) (xy 464.711732 -315.96399) (xy 464.764882 -315.960007)
			(xy 464.818032 -315.96399) (xy 464.869994 -315.97585) (xy 464.919608 -315.995322) (xy 464.965766 -316.021971)
			(xy 465.007437 -316.055202) (xy 465.043689 -316.094273) (xy 465.073713 -316.13831) (xy 465.096839 -316.186331)
			(xy 465.112549 -316.237261) (xy 465.120492 -316.289965) (xy 465.12099 -316.316614) (xy 465.120492 -316.343263)
			(xy 465.112549 -316.395967) (xy 465.096839 -316.446897) (xy 465.073713 -316.494918) (xy 465.043689 -316.538955)
			(xy 465.007437 -316.578026) (xy 464.965766 -316.611257) (xy 464.919608 -316.637906) (xy 464.869994 -316.657378)
			(xy 464.818032 -316.669238) (xy 464.764882 -316.673222) (xy 464.711732 -316.669238) (xy 464.65977 -316.657378)
			(xy 464.610156 -316.637906) (xy 464.563998 -316.611257) (xy 464.522327 -316.578026) (xy 464.486075 -316.538955)
			(xy 464.456051 -316.494918) (xy 464.432925 -316.446897) (xy 464.417215 -316.395967) (xy 464.409272 -316.343263)
			(xy 462.910637 -316.343263) (xy 462.903151 -316.394107) (xy 462.888158 -316.443933) (xy 462.866069 -316.491044)
			(xy 462.837356 -316.534436) (xy 462.80263 -316.573185) (xy 462.78292 -316.590172) (xy 462.771499 -316.600266)
			(xy 462.754858 -316.625791) (xy 462.746484 -316.655088) (xy 462.747124 -316.685552) (xy 462.756719 -316.714473)
			(xy 462.774418 -316.739277) (xy 462.786222 -316.748922) (xy 462.807469 -316.765901) (xy 462.845059 -316.805206)
			(xy 462.876237 -316.849768) (xy 462.900279 -316.898552) (xy 462.916626 -316.950423) (xy 462.924898 -317.004177)
			(xy 462.925414 -317.03137) (xy 462.924916 -317.058019) (xy 462.916973 -317.110723) (xy 462.901263 -317.161653)
			(xy 462.878137 -317.209674) (xy 462.848113 -317.253711) (xy 462.811861 -317.292782) (xy 462.77019 -317.326013)
			(xy 462.724032 -317.352662) (xy 462.674418 -317.372134) (xy 462.622456 -317.383994) (xy 462.569306 -317.387978)
			(xy 462.516156 -317.383994) (xy 462.464194 -317.372134) (xy 462.41458 -317.352662) (xy 462.368422 -317.326013)
			(xy 462.326751 -317.292782) (xy 462.290499 -317.253711) (xy 462.260475 -317.209674) (xy 462.237349 -317.161653)
			(xy 462.221639 -317.110723) (xy 462.213696 -317.058019) (xy 462.213198 -317.03137) (xy 462.213651 -317.005354)
			(xy 462.221232 -316.953876) (xy 462.236227 -316.904051) (xy 462.258317 -316.85694) (xy 462.287031 -316.813548)
			(xy 462.321758 -316.774799) (xy 462.341468 -316.757812) (xy 462.352907 -316.747736) (xy 462.36955 -316.722206)
			(xy 462.377922 -316.692904) (xy 462.37728 -316.662435) (xy 462.367679 -316.633512) (xy 462.349974 -316.608707)
			(xy 462.338166 -316.599062) (xy 462.316908 -316.582095) (xy 462.27932 -316.542787) (xy 462.248143 -316.498223)
			(xy 462.224103 -316.449436) (xy 462.207759 -316.397563) (xy 462.199489 -316.343808) (xy 462.198974 -316.316614)
			(xy 461.9625 -316.316614) (xy 461.9625 -317.617581) (xy 464.560656 -317.617581) (xy 464.560656 -317.564283)
			(xy 464.568599 -317.511579) (xy 464.584309 -317.460649) (xy 464.607435 -317.412628) (xy 464.637459 -317.368591)
			(xy 464.673711 -317.32952) (xy 464.715382 -317.296289) (xy 464.76154 -317.26964) (xy 464.811154 -317.250168)
			(xy 464.863116 -317.238308) (xy 464.916266 -317.234325) (xy 464.969416 -317.238308) (xy 465.021378 -317.250168)
			(xy 465.070992 -317.26964) (xy 465.11715 -317.296289) (xy 465.158821 -317.32952) (xy 465.195073 -317.368591)
			(xy 465.225097 -317.412628) (xy 465.248223 -317.460649) (xy 465.263933 -317.511579) (xy 465.271876 -317.564283)
			(xy 465.272374 -317.590932) (xy 465.271876 -317.617581) (xy 465.263933 -317.670285) (xy 465.248223 -317.721215)
			(xy 465.225097 -317.769236) (xy 465.195073 -317.813273) (xy 465.158821 -317.852344) (xy 465.11715 -317.885575)
			(xy 465.070992 -317.912224) (xy 465.021378 -317.931696) (xy 464.969416 -317.943556) (xy 464.916266 -317.94754)
			(xy 464.863116 -317.943556) (xy 464.811154 -317.931696) (xy 464.76154 -317.912224) (xy 464.715382 -317.885575)
			(xy 464.673711 -317.852344) (xy 464.637459 -317.813273) (xy 464.607435 -317.769236) (xy 464.584309 -317.721215)
			(xy 464.568599 -317.670285) (xy 464.560656 -317.617581) (xy 461.9625 -317.617581) (xy 461.9625 -318.055498)
			(xy 461.963031 -318.070959) (xy 461.972264 -318.10047) (xy 461.989913 -318.12586) (xy 462.014357 -318.144797)
			(xy 462.043352 -318.155541) (xy 462.058766 -318.156844) (xy 462.086198 -318.159384) (xy 462.101347 -318.160816)
			(xy 462.131333 -318.15574) (xy 462.15849 -318.142052) (xy 462.180407 -318.120967) (xy 462.195136 -318.09436)
			(xy 462.201368 -318.064593) (xy 462.200498 -318.049402) (xy 462.198974 -318.016636) (xy 462.199477 -317.989554)
			(xy 462.207674 -317.936013) (xy 462.223884 -317.88433) (xy 462.247734 -317.835699) (xy 462.278673 -317.79124)
			(xy 462.315988 -317.751979) (xy 462.358817 -317.718821) (xy 462.406175 -317.692531) (xy 462.456967 -317.673717)
			(xy 462.510022 -317.66281) (xy 462.564117 -317.660064) (xy 462.618004 -317.665541) (xy 462.670441 -317.679116)
			(xy 462.720217 -317.700474) (xy 462.766184 -317.729124) (xy 462.807283 -317.764404) (xy 462.842566 -317.805501)
			(xy 462.871218 -317.851467) (xy 462.892579 -317.901242) (xy 462.906156 -317.953678) (xy 462.911636 -318.007565)
			(xy 462.908892 -318.06166) (xy 462.897988 -318.114716) (xy 462.879176 -318.165509) (xy 462.852889 -318.212867)
			(xy 462.819733 -318.255699) (xy 462.780474 -318.293016) (xy 462.736017 -318.323957) (xy 462.687386 -318.347809)
			(xy 462.635705 -318.364022) (xy 462.582164 -318.372222) (xy 462.555082 -318.372744) (xy 462.543427 -318.37265)
			(xy 462.520167 -318.371124) (xy 462.5086 -318.369696) (xy 462.49345 -318.368264) (xy 462.463463 -318.373341)
			(xy 462.436303 -318.387029) (xy 462.414384 -318.408113) (xy 462.399651 -318.434721) (xy 462.393413 -318.464488)
			(xy 462.3943 -318.479678) (xy 462.395824 -318.512444) (xy 462.395319 -318.539472) (xy 462.387143 -318.592906)
			(xy 462.370985 -318.64449) (xy 462.347217 -318.69304) (xy 462.316385 -318.73744) (xy 462.279197 -318.776671)
			(xy 462.236507 -318.809831) (xy 462.189295 -318.836158) (xy 462.138647 -318.855047) (xy 462.085727 -318.866066)
			(xy 462.058766 -318.868044) (xy 462.04337 -318.869407) (xy 462.014417 -318.88019) (xy 461.990003 -318.899121)
			(xy 461.97235 -318.924476) (xy 461.963069 -318.953944) (xy 461.9625 -318.96939) (xy 461.9625 -319.640437)
			(xy 464.44407 -319.640437) (xy 464.44407 -319.587139) (xy 464.452013 -319.534435) (xy 464.467723 -319.483505)
			(xy 464.490849 -319.435484) (xy 464.520873 -319.391447) (xy 464.557125 -319.352376) (xy 464.598796 -319.319145)
			(xy 464.644954 -319.292496) (xy 464.694568 -319.273024) (xy 464.74653 -319.261164) (xy 464.79968 -319.257181)
			(xy 464.85283 -319.261164) (xy 464.904792 -319.273024) (xy 464.954406 -319.292496) (xy 465.000564 -319.319145)
			(xy 465.042235 -319.352376) (xy 465.078487 -319.391447) (xy 465.108511 -319.435484) (xy 465.131637 -319.483505)
			(xy 465.147347 -319.534435) (xy 465.15529 -319.587139) (xy 465.155788 -319.613788) (xy 465.15529 -319.640437)
			(xy 465.147347 -319.693141) (xy 465.131637 -319.744071) (xy 465.108511 -319.792092) (xy 465.078487 -319.836129)
			(xy 465.042235 -319.8752) (xy 465.000564 -319.908431) (xy 464.954406 -319.93508) (xy 464.904792 -319.954552)
			(xy 464.85283 -319.966412) (xy 464.79968 -319.970396) (xy 464.74653 -319.966412) (xy 464.694568 -319.954552)
			(xy 464.644954 -319.93508) (xy 464.598796 -319.908431) (xy 464.557125 -319.8752) (xy 464.520873 -319.836129)
			(xy 464.490849 -319.792092) (xy 464.467723 -319.744071) (xy 464.452013 -319.693141) (xy 464.44407 -319.640437)
			(xy 461.9625 -319.640437) (xy 461.9625 -320.200274) (xy 461.569329 -320.593445) (xy 462.199472 -320.593445)
			(xy 462.199472 -320.540147) (xy 462.207415 -320.487443) (xy 462.223125 -320.436513) (xy 462.246251 -320.388492)
			(xy 462.276275 -320.344455) (xy 462.312527 -320.305384) (xy 462.354198 -320.272153) (xy 462.400356 -320.245504)
			(xy 462.44997 -320.226032) (xy 462.501932 -320.214172) (xy 462.555082 -320.210189) (xy 462.608232 -320.214172)
			(xy 462.660194 -320.226032) (xy 462.709808 -320.245504) (xy 462.755966 -320.272153) (xy 462.797637 -320.305384)
			(xy 462.833889 -320.344455) (xy 462.863913 -320.388492) (xy 462.887039 -320.436513) (xy 462.902749 -320.487443)
			(xy 462.910692 -320.540147) (xy 462.91119 -320.566796) (xy 462.910692 -320.593445) (xy 462.902749 -320.646149)
			(xy 462.887039 -320.697079) (xy 462.863913 -320.7451) (xy 462.833889 -320.789137) (xy 462.797637 -320.828208)
			(xy 462.755966 -320.861439) (xy 462.709808 -320.888088) (xy 462.660194 -320.90756) (xy 462.608232 -320.91942)
			(xy 462.555082 -320.923404) (xy 462.501932 -320.91942) (xy 462.44997 -320.90756) (xy 462.400356 -320.888088)
			(xy 462.354198 -320.861439) (xy 462.312527 -320.828208) (xy 462.276275 -320.789137) (xy 462.246251 -320.7451)
			(xy 462.223125 -320.697079) (xy 462.207415 -320.646149) (xy 462.199472 -320.593445) (xy 461.569329 -320.593445)
			(xy 461.165977 -320.996797) (xy 464.44915 -320.996797) (xy 464.44915 -320.943499) (xy 464.457093 -320.890795)
			(xy 464.472803 -320.839865) (xy 464.495929 -320.791844) (xy 464.525953 -320.747807) (xy 464.562205 -320.708736)
			(xy 464.603876 -320.675505) (xy 464.650034 -320.648856) (xy 464.699648 -320.629384) (xy 464.75161 -320.617524)
			(xy 464.80476 -320.613541) (xy 464.85791 -320.617524) (xy 464.909872 -320.629384) (xy 464.959486 -320.648856)
			(xy 465.005644 -320.675505) (xy 465.047315 -320.708736) (xy 465.083567 -320.747807) (xy 465.113591 -320.791844)
			(xy 465.136717 -320.839865) (xy 465.152427 -320.890795) (xy 465.16037 -320.943499) (xy 465.160868 -320.970148)
			(xy 465.16037 -320.996797) (xy 465.152427 -321.049501) (xy 465.136717 -321.100431) (xy 465.113591 -321.148452)
			(xy 465.083567 -321.192489) (xy 465.047315 -321.23156) (xy 465.005644 -321.264791) (xy 464.959486 -321.29144)
			(xy 464.909872 -321.310912) (xy 464.85791 -321.322772) (xy 464.80476 -321.326756) (xy 464.75161 -321.322772)
			(xy 464.699648 -321.310912) (xy 464.650034 -321.29144) (xy 464.603876 -321.264791) (xy 464.562205 -321.23156)
			(xy 464.525953 -321.192489) (xy 464.495929 -321.148452) (xy 464.472803 -321.100431) (xy 464.457093 -321.049501)
			(xy 464.44915 -320.996797) (xy 461.165977 -320.996797) (xy 460.856838 -321.305936) (xy 458.912722 -321.305936)
			(xy 458.899224 -321.306351) (xy 458.873171 -321.313417) (xy 458.849878 -321.327062) (xy 458.830973 -321.346332)
			(xy 458.817777 -321.369882) (xy 458.811211 -321.396066) (xy 458.811122 -321.409568) (xy 458.811122 -321.41668)
			(xy 458.810624 -321.443329) (xy 462.199472 -321.443329) (xy 462.199472 -321.390031) (xy 462.207415 -321.337327)
			(xy 462.223125 -321.286397) (xy 462.246251 -321.238376) (xy 462.276275 -321.194339) (xy 462.312527 -321.155268)
			(xy 462.354198 -321.122037) (xy 462.400356 -321.095388) (xy 462.44997 -321.075916) (xy 462.501932 -321.064056)
			(xy 462.555082 -321.060073) (xy 462.608232 -321.064056) (xy 462.660194 -321.075916) (xy 462.709808 -321.095388)
			(xy 462.755966 -321.122037) (xy 462.797637 -321.155268) (xy 462.833889 -321.194339) (xy 462.863913 -321.238376)
			(xy 462.887039 -321.286397) (xy 462.902749 -321.337327) (xy 462.910692 -321.390031) (xy 462.91119 -321.41668)
			(xy 462.910692 -321.443329) (xy 462.902749 -321.496033) (xy 462.887039 -321.546963) (xy 462.863913 -321.594984)
			(xy 462.833889 -321.639021) (xy 462.797637 -321.678092) (xy 462.755966 -321.711323) (xy 462.709808 -321.737972)
			(xy 462.660194 -321.757444) (xy 462.608232 -321.769304) (xy 462.555082 -321.773288) (xy 462.501932 -321.769304)
			(xy 462.44997 -321.757444) (xy 462.400356 -321.737972) (xy 462.354198 -321.711323) (xy 462.312527 -321.678092)
			(xy 462.276275 -321.639021) (xy 462.246251 -321.594984) (xy 462.223125 -321.546963) (xy 462.207415 -321.496033)
			(xy 462.199472 -321.443329) (xy 458.810624 -321.443329) (xy 458.802681 -321.496033) (xy 458.786971 -321.546963)
			(xy 458.763845 -321.594984) (xy 458.733821 -321.639021) (xy 458.697569 -321.678092) (xy 458.655898 -321.711323)
			(xy 458.60974 -321.737972) (xy 458.560126 -321.757444) (xy 458.508164 -321.769304) (xy 458.455014 -321.773288)
			(xy 458.401864 -321.769304) (xy 458.349902 -321.757444) (xy 458.300288 -321.737972) (xy 458.25413 -321.711323)
			(xy 458.212459 -321.678092) (xy 458.176207 -321.639021) (xy 458.146183 -321.594984) (xy 458.123057 -321.546963)
			(xy 458.107347 -321.496033) (xy 458.099404 -321.443329) (xy 458.098906 -321.41668) (xy 458.098906 -321.409568)
			(xy 458.098762 -321.396064) (xy 458.092218 -321.369872) (xy 458.079039 -321.346311) (xy 458.060145 -321.327027)
			(xy 458.036857 -321.313369) (xy 458.010804 -321.306292) (xy 457.997306 -321.305936) (xy 455.46899 -321.305936)
			(xy 455.455495 -321.306355) (xy 455.429449 -321.313426) (xy 455.406163 -321.327073) (xy 455.387266 -321.346343)
			(xy 455.374074 -321.369889) (xy 455.367511 -321.396068) (xy 455.36739 -321.409568) (xy 455.36739 -321.41668)
			(xy 455.366871 -321.444666) (xy 455.358118 -321.499949) (xy 455.340823 -321.553182) (xy 455.315414 -321.603053)
			(xy 455.282515 -321.648336) (xy 455.242937 -321.687914) (xy 455.197655 -321.720813) (xy 455.147783 -321.746222)
			(xy 455.094551 -321.763517) (xy 455.039268 -321.772271) (xy 455.011282 -321.772788) (xy 454.984474 -321.772308)
			(xy 454.931464 -321.764278) (xy 454.880258 -321.748386) (xy 454.832015 -321.724994) (xy 454.787827 -321.694629)
			(xy 454.748694 -321.65798) (xy 454.715501 -321.615875) (xy 454.688999 -321.569267) (xy 454.669789 -321.519212)
			(xy 454.663556 -321.493134) (xy 454.660241 -321.479974) (xy 454.647668 -321.455937) (xy 454.629201 -321.436065)
			(xy 454.606148 -321.421765) (xy 454.580141 -321.41405) (xy 454.553019 -321.413465) (xy 454.526703 -321.420051)
			(xy 454.503055 -321.433343) (xy 454.493122 -321.442588) (xy 454.473006 -321.461609) (xy 454.427985 -321.493824)
			(xy 454.378524 -321.518691) (xy 454.325813 -321.535611) (xy 454.27112 -321.544177) (xy 454.24344 -321.544696)
			(xy 454.217942 -321.544256) (xy 454.167469 -321.536975) (xy 454.11855 -321.52257) (xy 454.072185 -321.501336)
			(xy 454.029322 -321.473707) (xy 453.990838 -321.440248) (xy 453.957518 -321.401642) (xy 453.930045 -321.35868)
			(xy 453.919082 -321.335654) (xy 453.90562 -321.305936) (xy 451.368922 -321.305936) (xy 451.355424 -321.306351)
			(xy 451.329371 -321.313417) (xy 451.306078 -321.327062) (xy 451.287173 -321.346332) (xy 451.273977 -321.369882)
			(xy 451.267411 -321.396066) (xy 451.267322 -321.409568) (xy 451.267322 -321.41668) (xy 451.266824 -321.443329)
			(xy 451.258881 -321.496033) (xy 451.243171 -321.546963) (xy 451.220045 -321.594984) (xy 451.190021 -321.639021)
			(xy 451.153769 -321.678092) (xy 451.112098 -321.711323) (xy 451.06594 -321.737972) (xy 451.016326 -321.757444)
			(xy 450.964364 -321.769304) (xy 450.911214 -321.773288) (xy 450.858064 -321.769304) (xy 450.806102 -321.757444)
			(xy 450.756488 -321.737972) (xy 450.71033 -321.711323) (xy 450.668659 -321.678092) (xy 450.632407 -321.639021)
			(xy 450.602383 -321.594984) (xy 450.579257 -321.546963) (xy 450.563547 -321.496033) (xy 450.555604 -321.443329)
			(xy 450.555106 -321.41668) (xy 450.555106 -321.409568) (xy 450.554962 -321.396064) (xy 450.548418 -321.369872)
			(xy 450.535239 -321.346311) (xy 450.516345 -321.327027) (xy 450.493057 -321.313369) (xy 450.467004 -321.306292)
			(xy 450.453506 -321.305936) (xy 447.92519 -321.305936) (xy 447.911695 -321.306355) (xy 447.885649 -321.313426)
			(xy 447.862363 -321.327073) (xy 447.843466 -321.346343) (xy 447.830274 -321.369889) (xy 447.823711 -321.396068)
			(xy 447.82359 -321.409568) (xy 447.82359 -321.41668) (xy 447.823092 -321.443329) (xy 447.815149 -321.496033)
			(xy 447.799439 -321.546963) (xy 447.776313 -321.594984) (xy 447.746289 -321.639021) (xy 447.710037 -321.678092)
			(xy 447.668366 -321.711323) (xy 447.622208 -321.737972) (xy 447.572594 -321.757444) (xy 447.520632 -321.769304)
			(xy 447.467482 -321.773288) (xy 447.414332 -321.769304) (xy 447.36237 -321.757444) (xy 447.312756 -321.737972)
			(xy 447.266598 -321.711323) (xy 447.224927 -321.678092) (xy 447.188675 -321.639021) (xy 447.158651 -321.594984)
			(xy 447.135525 -321.546963) (xy 447.119815 -321.496033) (xy 447.111872 -321.443329) (xy 447.111374 -321.41668)
			(xy 447.111374 -321.409568) (xy 447.11123 -321.396065) (xy 447.104686 -321.369877) (xy 447.091505 -321.346319)
			(xy 447.07261 -321.327041) (xy 447.049323 -321.31339) (xy 447.023271 -321.30632) (xy 447.009774 -321.305936)
			(xy 443.825122 -321.305936) (xy 443.811624 -321.306351) (xy 443.785571 -321.313417) (xy 443.762278 -321.327062)
			(xy 443.743373 -321.346332) (xy 443.730177 -321.369882) (xy 443.723611 -321.396066) (xy 443.723522 -321.409568)
			(xy 443.723522 -321.41668) (xy 443.723024 -321.443329) (xy 443.715081 -321.496033) (xy 443.699371 -321.546963)
			(xy 443.676245 -321.594984) (xy 443.646221 -321.639021) (xy 443.609969 -321.678092) (xy 443.568298 -321.711323)
			(xy 443.52214 -321.737972) (xy 443.472526 -321.757444) (xy 443.420564 -321.769304) (xy 443.367414 -321.773288)
			(xy 443.314264 -321.769304) (xy 443.262302 -321.757444) (xy 443.212688 -321.737972) (xy 443.16653 -321.711323)
			(xy 443.124859 -321.678092) (xy 443.088607 -321.639021) (xy 443.058583 -321.594984) (xy 443.035457 -321.546963)
			(xy 443.019747 -321.496033) (xy 443.011804 -321.443329) (xy 443.011306 -321.41668) (xy 443.011306 -321.409568)
			(xy 443.011162 -321.396064) (xy 443.004618 -321.369872) (xy 442.991439 -321.346311) (xy 442.972545 -321.327027)
			(xy 442.949257 -321.313369) (xy 442.923204 -321.306292) (xy 442.909706 -321.305936) (xy 440.297316 -321.305936)
			(xy 440.261502 -321.34175) (xy 440.265058 -321.366896) (xy 440.266718 -321.379275) (xy 440.268497 -321.404191)
			(xy 440.268614 -321.41668) (xy 440.268095 -321.444667) (xy 440.259342 -321.499951) (xy 440.242048 -321.553185)
			(xy 440.216639 -321.603059) (xy 440.183741 -321.648343) (xy 440.144163 -321.687924) (xy 440.098881 -321.720826)
			(xy 440.049009 -321.746238) (xy 439.995776 -321.763536) (xy 439.940493 -321.772293) (xy 439.912506 -321.772788)
			(xy 439.900017 -321.772659) (xy 439.875102 -321.77088) (xy 439.862722 -321.769232) (xy 439.837576 -321.765676)
			(xy 438.173852 -323.4294) (xy 440.304968 -323.4294) (xy 440.308951 -323.376251) (xy 440.32081 -323.32429)
			(xy 440.34028 -323.274676) (xy 440.366927 -323.228517) (xy 440.400155 -323.186846) (xy 440.439222 -323.150591)
			(xy 440.483256 -323.120564) (xy 440.531274 -323.097434) (xy 440.582202 -323.081719) (xy 440.634903 -323.073769)
			(xy 440.661552 -323.073268) (xy 440.687959 -323.07379) (xy 440.740195 -323.081584) (xy 440.790707 -323.097008)
			(xy 440.838387 -323.119723) (xy 440.882188 -323.149232) (xy 440.921151 -323.184887) (xy 440.938158 -323.205094)
			(xy 440.948095 -323.216487) (xy 440.973148 -323.233378) (xy 441.002044 -323.242209) (xy 441.03226 -323.242209)
			(xy 441.061156 -323.233378) (xy 441.086209 -323.216487) (xy 441.096146 -323.205094) (xy 441.113172 -323.184902)
			(xy 441.152129 -323.149239) (xy 441.195925 -323.119721) (xy 441.2436 -323.096994) (xy 441.29411 -323.081558)
			(xy 441.346344 -323.073751) (xy 441.372752 -323.073268) (xy 441.399404 -323.073786) (xy 441.452113 -323.081724)
			(xy 441.503049 -323.09743) (xy 441.551076 -323.120552) (xy 441.59512 -323.150576) (xy 441.634197 -323.186828)
			(xy 441.667433 -323.2285) (xy 441.694087 -323.274661) (xy 441.713562 -323.324279) (xy 441.725424 -323.376246)
			(xy 441.729408 -323.4294) (xy 443.784768 -323.4294) (xy 443.788751 -323.376251) (xy 443.80061 -323.32429)
			(xy 443.82008 -323.274676) (xy 443.846727 -323.228517) (xy 443.879955 -323.186846) (xy 443.919022 -323.150591)
			(xy 443.963056 -323.120564) (xy 444.011074 -323.097434) (xy 444.062002 -323.081719) (xy 444.114703 -323.073769)
			(xy 444.141352 -323.073268) (xy 444.167759 -323.07379) (xy 444.219995 -323.081584) (xy 444.270507 -323.097008)
			(xy 444.318187 -323.119723) (xy 444.361988 -323.149232) (xy 444.400951 -323.184887) (xy 444.417958 -323.205094)
			(xy 444.427895 -323.216487) (xy 444.452948 -323.233378) (xy 444.481844 -323.242209) (xy 444.51206 -323.242209)
			(xy 444.540956 -323.233378) (xy 444.566009 -323.216487) (xy 444.575946 -323.205094) (xy 444.592972 -323.184902)
			(xy 444.631929 -323.149239) (xy 444.675725 -323.119721) (xy 444.7234 -323.096994) (xy 444.77391 -323.081558)
			(xy 444.826144 -323.073751) (xy 444.852552 -323.073268) (xy 444.879204 -323.073786) (xy 444.931913 -323.081724)
			(xy 444.982849 -323.09743) (xy 445.030876 -323.120552) (xy 445.07492 -323.150576) (xy 445.113997 -323.186828)
			(xy 445.147233 -323.2285) (xy 445.173887 -323.274661) (xy 445.193362 -323.324279) (xy 445.205224 -323.376246)
			(xy 445.209208 -323.4294) (xy 447.848768 -323.4294) (xy 447.852751 -323.376251) (xy 447.86461 -323.32429)
			(xy 447.88408 -323.274676) (xy 447.910727 -323.228517) (xy 447.943955 -323.186846) (xy 447.983022 -323.150591)
			(xy 448.027056 -323.120564) (xy 448.075074 -323.097434) (xy 448.126002 -323.081719) (xy 448.178703 -323.073769)
			(xy 448.205352 -323.073268) (xy 448.231759 -323.07379) (xy 448.283995 -323.081584) (xy 448.334507 -323.097008)
			(xy 448.382187 -323.119723) (xy 448.425988 -323.149232) (xy 448.464951 -323.184887) (xy 448.481958 -323.205094)
			(xy 448.491895 -323.216487) (xy 448.516948 -323.233378) (xy 448.545844 -323.242209) (xy 448.57606 -323.242209)
			(xy 448.604956 -323.233378) (xy 448.630009 -323.216487) (xy 448.639946 -323.205094) (xy 448.656972 -323.184902)
			(xy 448.695929 -323.149239) (xy 448.739725 -323.119721) (xy 448.7874 -323.096994) (xy 448.83791 -323.081558)
			(xy 448.890144 -323.073751) (xy 448.916552 -323.073268) (xy 448.943204 -323.073786) (xy 448.995913 -323.081724)
			(xy 449.046849 -323.09743) (xy 449.094876 -323.120552) (xy 449.13892 -323.150576) (xy 449.177997 -323.186828)
			(xy 449.211233 -323.2285) (xy 449.237887 -323.274661) (xy 449.257362 -323.324279) (xy 449.269224 -323.376246)
			(xy 449.273208 -323.4294) (xy 451.328568 -323.4294) (xy 451.332551 -323.376251) (xy 451.34441 -323.32429)
			(xy 451.36388 -323.274676) (xy 451.390527 -323.228517) (xy 451.423755 -323.186846) (xy 451.462822 -323.150591)
			(xy 451.506856 -323.120564) (xy 451.554874 -323.097434) (xy 451.605802 -323.081719) (xy 451.658503 -323.073769)
			(xy 451.685152 -323.073268) (xy 451.711559 -323.07379) (xy 451.763795 -323.081584) (xy 451.814307 -323.097008)
			(xy 451.861987 -323.119723) (xy 451.905788 -323.149232) (xy 451.944751 -323.184887) (xy 451.961758 -323.205094)
			(xy 451.971695 -323.216487) (xy 451.996748 -323.233378) (xy 452.025644 -323.242209) (xy 452.05586 -323.242209)
			(xy 452.084756 -323.233378) (xy 452.109809 -323.216487) (xy 452.119746 -323.205094) (xy 452.136772 -323.184902)
			(xy 452.175729 -323.149239) (xy 452.219525 -323.119721) (xy 452.2672 -323.096994) (xy 452.31771 -323.081558)
			(xy 452.369944 -323.073751) (xy 452.396352 -323.073268) (xy 452.423004 -323.073786) (xy 452.475713 -323.081724)
			(xy 452.526649 -323.09743) (xy 452.574676 -323.120552) (xy 452.61872 -323.150576) (xy 452.657797 -323.186828)
			(xy 452.691033 -323.2285) (xy 452.717687 -323.274661) (xy 452.737162 -323.324279) (xy 452.749024 -323.376246)
			(xy 452.753008 -323.4294) (xy 455.392568 -323.4294) (xy 455.396551 -323.376251) (xy 455.40841 -323.32429)
			(xy 455.42788 -323.274676) (xy 455.454527 -323.228517) (xy 455.487755 -323.186846) (xy 455.526822 -323.150591)
			(xy 455.570856 -323.120564) (xy 455.618874 -323.097434) (xy 455.669802 -323.081719) (xy 455.722503 -323.073769)
			(xy 455.749152 -323.073268) (xy 455.775559 -323.07379) (xy 455.827795 -323.081584) (xy 455.878307 -323.097008)
			(xy 455.925987 -323.119723) (xy 455.969788 -323.149232) (xy 456.008751 -323.184887) (xy 456.025758 -323.205094)
			(xy 456.035695 -323.216487) (xy 456.060748 -323.233378) (xy 456.089644 -323.242209) (xy 456.11986 -323.242209)
			(xy 456.148756 -323.233378) (xy 456.173809 -323.216487) (xy 456.183746 -323.205094) (xy 456.200772 -323.184902)
			(xy 456.239729 -323.149239) (xy 456.283525 -323.119721) (xy 456.3312 -323.096994) (xy 456.38171 -323.081558)
			(xy 456.433944 -323.073751) (xy 456.460352 -323.073268) (xy 456.487004 -323.073786) (xy 456.539713 -323.081724)
			(xy 456.590649 -323.09743) (xy 456.638676 -323.120552) (xy 456.68272 -323.150576) (xy 456.721797 -323.186828)
			(xy 456.755033 -323.2285) (xy 456.781687 -323.274661) (xy 456.801162 -323.324279) (xy 456.813024 -323.376246)
			(xy 456.817008 -323.4294) (xy 458.872368 -323.4294) (xy 458.876351 -323.376251) (xy 458.88821 -323.32429)
			(xy 458.90768 -323.274676) (xy 458.934327 -323.228517) (xy 458.967555 -323.186846) (xy 459.006622 -323.150591)
			(xy 459.050656 -323.120564) (xy 459.098674 -323.097434) (xy 459.149602 -323.081719) (xy 459.202303 -323.073769)
			(xy 459.228952 -323.073268) (xy 459.255359 -323.07379) (xy 459.307595 -323.081584) (xy 459.358107 -323.097008)
			(xy 459.405787 -323.119723) (xy 459.449588 -323.149232) (xy 459.488551 -323.184887) (xy 459.505558 -323.205094)
			(xy 459.515495 -323.216487) (xy 459.540548 -323.233378) (xy 459.569444 -323.242209) (xy 459.59966 -323.242209)
			(xy 459.628556 -323.233378) (xy 459.653609 -323.216487) (xy 459.663546 -323.205094) (xy 459.680572 -323.184902)
			(xy 459.719529 -323.149239) (xy 459.763325 -323.119721) (xy 459.811 -323.096994) (xy 459.86151 -323.081558)
			(xy 459.913744 -323.073751) (xy 459.940152 -323.073268) (xy 459.966804 -323.073786) (xy 460.019513 -323.081724)
			(xy 460.070449 -323.09743) (xy 460.118476 -323.120552) (xy 460.16252 -323.150576) (xy 460.201597 -323.186828)
			(xy 460.234833 -323.2285) (xy 460.261487 -323.274661) (xy 460.280962 -323.324279) (xy 460.287564 -323.3532)
			(xy 460.751968 -323.3532) (xy 460.755951 -323.300051) (xy 460.76781 -323.24809) (xy 460.78728 -323.198476)
			(xy 460.813927 -323.152317) (xy 460.847155 -323.110646) (xy 460.886222 -323.074391) (xy 460.930256 -323.044364)
			(xy 460.978274 -323.021234) (xy 461.029202 -323.005519) (xy 461.081903 -322.997569) (xy 461.108552 -322.997068)
			(xy 461.134959 -322.99759) (xy 461.187195 -323.005384) (xy 461.237707 -323.020808) (xy 461.285387 -323.043523)
			(xy 461.329188 -323.073032) (xy 461.368151 -323.108687) (xy 461.385158 -323.128894) (xy 461.395095 -323.140287)
			(xy 461.420148 -323.157178) (xy 461.449044 -323.166009) (xy 461.47926 -323.166009) (xy 461.508156 -323.157178)
			(xy 461.533209 -323.140287) (xy 461.543146 -323.128894) (xy 461.560172 -323.108702) (xy 461.599129 -323.073039)
			(xy 461.642925 -323.043521) (xy 461.6906 -323.020794) (xy 461.74111 -323.005358) (xy 461.793344 -322.997551)
			(xy 461.819752 -322.997068) (xy 461.846404 -322.997586) (xy 461.899113 -323.005524) (xy 461.950049 -323.02123)
			(xy 461.998076 -323.044352) (xy 462.04212 -323.074376) (xy 462.081197 -323.110628) (xy 462.114433 -323.1523)
			(xy 462.141087 -323.198461) (xy 462.160562 -323.248079) (xy 462.172424 -323.300046) (xy 462.176408 -323.3532)
			(xy 462.172424 -323.406354) (xy 462.160562 -323.458321) (xy 462.141087 -323.507939) (xy 462.114433 -323.5541)
			(xy 462.081197 -323.595772) (xy 462.04212 -323.632024) (xy 461.998076 -323.662048) (xy 461.950049 -323.68517)
			(xy 461.899113 -323.700876) (xy 461.846404 -323.708814) (xy 461.819752 -323.709284) (xy 461.793344 -323.708777)
			(xy 461.741107 -323.700982) (xy 461.690594 -323.685557) (xy 461.642914 -323.662838) (xy 461.599113 -323.633326)
			(xy 461.560152 -323.597667) (xy 461.543146 -323.577458) (xy 461.533209 -323.566065) (xy 461.508156 -323.549174)
			(xy 461.47926 -323.540343) (xy 461.449044 -323.540343) (xy 461.420148 -323.549174) (xy 461.395095 -323.566065)
			(xy 461.385158 -323.577458) (xy 461.368118 -323.597638) (xy 461.329166 -323.633304) (xy 461.285373 -323.662825)
			(xy 461.2377 -323.685554) (xy 461.187192 -323.700992) (xy 461.134959 -323.7088) (xy 461.108552 -323.709284)
			(xy 461.081903 -323.708831) (xy 461.029202 -323.700881) (xy 460.978274 -323.685166) (xy 460.930256 -323.662036)
			(xy 460.886222 -323.632009) (xy 460.847155 -323.595754) (xy 460.813927 -323.554083) (xy 460.78728 -323.507924)
			(xy 460.76781 -323.45831) (xy 460.755951 -323.406349) (xy 460.751968 -323.3532) (xy 460.287564 -323.3532)
			(xy 460.292824 -323.376246) (xy 460.296808 -323.4294) (xy 460.292824 -323.482554) (xy 460.280962 -323.534521)
			(xy 460.261487 -323.584139) (xy 460.234833 -323.6303) (xy 460.201597 -323.671972) (xy 460.16252 -323.708224)
			(xy 460.118476 -323.738248) (xy 460.070449 -323.76137) (xy 460.019513 -323.777076) (xy 459.966804 -323.785014)
			(xy 459.940152 -323.785484) (xy 459.913744 -323.784977) (xy 459.861507 -323.777182) (xy 459.810994 -323.761757)
			(xy 459.763314 -323.739038) (xy 459.719513 -323.709526) (xy 459.680552 -323.673867) (xy 459.663546 -323.653658)
			(xy 459.653609 -323.642265) (xy 459.628556 -323.625374) (xy 459.59966 -323.616543) (xy 459.569444 -323.616543)
			(xy 459.540548 -323.625374) (xy 459.515495 -323.642265) (xy 459.505558 -323.653658) (xy 459.488518 -323.673838)
			(xy 459.449566 -323.709504) (xy 459.405773 -323.739025) (xy 459.3581 -323.761754) (xy 459.307592 -323.777192)
			(xy 459.255359 -323.785) (xy 459.228952 -323.785484) (xy 459.202303 -323.785031) (xy 459.149602 -323.777081)
			(xy 459.098674 -323.761366) (xy 459.050656 -323.738236) (xy 459.006622 -323.708209) (xy 458.967555 -323.671954)
			(xy 458.934327 -323.630283) (xy 458.90768 -323.584124) (xy 458.88821 -323.53451) (xy 458.876351 -323.482549)
			(xy 458.872368 -323.4294) (xy 456.817008 -323.4294) (xy 456.813024 -323.482554) (xy 456.801162 -323.534521)
			(xy 456.781687 -323.584139) (xy 456.755033 -323.6303) (xy 456.721797 -323.671972) (xy 456.68272 -323.708224)
			(xy 456.638676 -323.738248) (xy 456.590649 -323.76137) (xy 456.539713 -323.777076) (xy 456.487004 -323.785014)
			(xy 456.460352 -323.785484) (xy 456.433944 -323.784977) (xy 456.381707 -323.777182) (xy 456.331194 -323.761757)
			(xy 456.283514 -323.739038) (xy 456.239713 -323.709526) (xy 456.200752 -323.673867) (xy 456.183746 -323.653658)
			(xy 456.173809 -323.642265) (xy 456.148756 -323.625374) (xy 456.11986 -323.616543) (xy 456.089644 -323.616543)
			(xy 456.060748 -323.625374) (xy 456.035695 -323.642265) (xy 456.025758 -323.653658) (xy 456.008718 -323.673838)
			(xy 455.969766 -323.709504) (xy 455.925973 -323.739025) (xy 455.8783 -323.761754) (xy 455.827792 -323.777192)
			(xy 455.775559 -323.785) (xy 455.749152 -323.785484) (xy 455.722503 -323.785031) (xy 455.669802 -323.777081)
			(xy 455.618874 -323.761366) (xy 455.570856 -323.738236) (xy 455.526822 -323.708209) (xy 455.487755 -323.671954)
			(xy 455.454527 -323.630283) (xy 455.42788 -323.584124) (xy 455.40841 -323.53451) (xy 455.396551 -323.482549)
			(xy 455.392568 -323.4294) (xy 452.753008 -323.4294) (xy 452.749024 -323.482554) (xy 452.737162 -323.534521)
			(xy 452.717687 -323.584139) (xy 452.691033 -323.6303) (xy 452.657797 -323.671972) (xy 452.61872 -323.708224)
			(xy 452.574676 -323.738248) (xy 452.526649 -323.76137) (xy 452.475713 -323.777076) (xy 452.423004 -323.785014)
			(xy 452.396352 -323.785484) (xy 452.369944 -323.784977) (xy 452.317707 -323.777182) (xy 452.267194 -323.761757)
			(xy 452.219514 -323.739038) (xy 452.175713 -323.709526) (xy 452.136752 -323.673867) (xy 452.119746 -323.653658)
			(xy 452.109809 -323.642265) (xy 452.084756 -323.625374) (xy 452.05586 -323.616543) (xy 452.025644 -323.616543)
			(xy 451.996748 -323.625374) (xy 451.971695 -323.642265) (xy 451.961758 -323.653658) (xy 451.944718 -323.673838)
			(xy 451.905766 -323.709504) (xy 451.861973 -323.739025) (xy 451.8143 -323.761754) (xy 451.763792 -323.777192)
			(xy 451.711559 -323.785) (xy 451.685152 -323.785484) (xy 451.658503 -323.785031) (xy 451.605802 -323.777081)
			(xy 451.554874 -323.761366) (xy 451.506856 -323.738236) (xy 451.462822 -323.708209) (xy 451.423755 -323.671954)
			(xy 451.390527 -323.630283) (xy 451.36388 -323.584124) (xy 451.34441 -323.53451) (xy 451.332551 -323.482549)
			(xy 451.328568 -323.4294) (xy 449.273208 -323.4294) (xy 449.269224 -323.482554) (xy 449.257362 -323.534521)
			(xy 449.237887 -323.584139) (xy 449.211233 -323.6303) (xy 449.177997 -323.671972) (xy 449.13892 -323.708224)
			(xy 449.094876 -323.738248) (xy 449.046849 -323.76137) (xy 448.995913 -323.777076) (xy 448.943204 -323.785014)
			(xy 448.916552 -323.785484) (xy 448.890144 -323.784977) (xy 448.837907 -323.777182) (xy 448.787394 -323.761757)
			(xy 448.739714 -323.739038) (xy 448.695913 -323.709526) (xy 448.656952 -323.673867) (xy 448.639946 -323.653658)
			(xy 448.630009 -323.642265) (xy 448.604956 -323.625374) (xy 448.57606 -323.616543) (xy 448.545844 -323.616543)
			(xy 448.516948 -323.625374) (xy 448.491895 -323.642265) (xy 448.481958 -323.653658) (xy 448.464918 -323.673838)
			(xy 448.425966 -323.709504) (xy 448.382173 -323.739025) (xy 448.3345 -323.761754) (xy 448.283992 -323.777192)
			(xy 448.231759 -323.785) (xy 448.205352 -323.785484) (xy 448.178703 -323.785031) (xy 448.126002 -323.777081)
			(xy 448.075074 -323.761366) (xy 448.027056 -323.738236) (xy 447.983022 -323.708209) (xy 447.943955 -323.671954)
			(xy 447.910727 -323.630283) (xy 447.88408 -323.584124) (xy 447.86461 -323.53451) (xy 447.852751 -323.482549)
			(xy 447.848768 -323.4294) (xy 445.209208 -323.4294) (xy 445.205224 -323.482554) (xy 445.193362 -323.534521)
			(xy 445.173887 -323.584139) (xy 445.147233 -323.6303) (xy 445.113997 -323.671972) (xy 445.07492 -323.708224)
			(xy 445.030876 -323.738248) (xy 444.982849 -323.76137) (xy 444.931913 -323.777076) (xy 444.879204 -323.785014)
			(xy 444.852552 -323.785484) (xy 444.826144 -323.784977) (xy 444.773907 -323.777182) (xy 444.723394 -323.761757)
			(xy 444.675714 -323.739038) (xy 444.631913 -323.709526) (xy 444.592952 -323.673867) (xy 444.575946 -323.653658)
			(xy 444.566009 -323.642265) (xy 444.540956 -323.625374) (xy 444.51206 -323.616543) (xy 444.481844 -323.616543)
			(xy 444.452948 -323.625374) (xy 444.427895 -323.642265) (xy 444.417958 -323.653658) (xy 444.400918 -323.673838)
			(xy 444.361966 -323.709504) (xy 444.318173 -323.739025) (xy 444.2705 -323.761754) (xy 444.219992 -323.777192)
			(xy 444.167759 -323.785) (xy 444.141352 -323.785484) (xy 444.114703 -323.785031) (xy 444.062002 -323.777081)
			(xy 444.011074 -323.761366) (xy 443.963056 -323.738236) (xy 443.919022 -323.708209) (xy 443.879955 -323.671954)
			(xy 443.846727 -323.630283) (xy 443.82008 -323.584124) (xy 443.80061 -323.53451) (xy 443.788751 -323.482549)
			(xy 443.784768 -323.4294) (xy 441.729408 -323.4294) (xy 441.725424 -323.482554) (xy 441.713562 -323.534521)
			(xy 441.694087 -323.584139) (xy 441.667433 -323.6303) (xy 441.634197 -323.671972) (xy 441.59512 -323.708224)
			(xy 441.551076 -323.738248) (xy 441.503049 -323.76137) (xy 441.452113 -323.777076) (xy 441.399404 -323.785014)
			(xy 441.372752 -323.785484) (xy 441.346344 -323.784977) (xy 441.294107 -323.777182) (xy 441.243594 -323.761757)
			(xy 441.195914 -323.739038) (xy 441.152113 -323.709526) (xy 441.113152 -323.673867) (xy 441.096146 -323.653658)
			(xy 441.086209 -323.642265) (xy 441.061156 -323.625374) (xy 441.03226 -323.616543) (xy 441.002044 -323.616543)
			(xy 440.973148 -323.625374) (xy 440.948095 -323.642265) (xy 440.938158 -323.653658) (xy 440.921118 -323.673838)
			(xy 440.882166 -323.709504) (xy 440.838373 -323.739025) (xy 440.7907 -323.761754) (xy 440.740192 -323.777192)
			(xy 440.687959 -323.785) (xy 440.661552 -323.785484) (xy 440.634903 -323.785031) (xy 440.582202 -323.777081)
			(xy 440.531274 -323.761366) (xy 440.483256 -323.738236) (xy 440.439222 -323.708209) (xy 440.400155 -323.671954)
			(xy 440.366927 -323.630283) (xy 440.34028 -323.584124) (xy 440.32081 -323.53451) (xy 440.308951 -323.482549)
			(xy 440.304968 -323.4294) (xy 438.173852 -323.4294) (xy 436.705756 -324.897496) (xy 436.705756 -327.10898)
			(xy 437.441721 -327.10898) (xy 437.441721 -327.02442) (xy 437.449524 -326.94022) (xy 437.465062 -326.857099)
			(xy 437.488204 -326.775767) (xy 437.518752 -326.696917) (xy 437.556445 -326.621222) (xy 437.600962 -326.549328)
			(xy 437.651923 -326.481848) (xy 437.708892 -326.419358) (xy 437.771385 -326.362392) (xy 437.838867 -326.311435)
			(xy 437.910764 -326.266922) (xy 437.986461 -326.229233) (xy 438.065312 -326.198689) (xy 438.146646 -326.175551)
			(xy 438.229767 -326.160017) (xy 438.313968 -326.152219) (xy 438.356248 -326.151748) (xy 439.600848 -326.151748)
			(xy 439.643121 -326.152326) (xy 439.727305 -326.160131) (xy 439.81041 -326.17567) (xy 439.891727 -326.198811)
			(xy 439.970562 -326.229355) (xy 440.046243 -326.267043) (xy 440.118123 -326.311553) (xy 440.185591 -326.362505)
			(xy 440.248069 -326.419465) (xy 440.305025 -326.481946) (xy 440.355974 -326.549416) (xy 440.40048 -326.621299)
			(xy 440.438164 -326.696982) (xy 440.468704 -326.775818) (xy 440.491841 -326.857136) (xy 440.507375 -326.940242)
			(xy 440.511557 -326.985376) (xy 441.073538 -326.985376) (xy 441.077609 -326.929754) (xy 441.089735 -326.875317)
			(xy 441.109658 -326.823226) (xy 441.136954 -326.774591) (xy 441.17104 -326.730448) (xy 441.211189 -326.691739)
			(xy 441.256547 -326.659288) (xy 441.306147 -326.633787) (xy 441.358931 -326.61578) (xy 441.413774 -326.60565)
			(xy 441.469508 -326.603613) (xy 441.524945 -326.609713) (xy 441.578902 -326.623819) (xy 441.630231 -326.645631)
			(xy 441.677837 -326.674685) (xy 441.720705 -326.71036) (xy 441.757922 -326.751897) (xy 441.788695 -326.79841)
			(xy 441.812367 -326.848907) (xy 441.828435 -326.902314) (xy 441.836555 -326.95749) (xy 441.8366 -326.959976)
			(xy 442.267338 -326.959976) (xy 442.271409 -326.904354) (xy 442.283535 -326.849917) (xy 442.303458 -326.797826)
			(xy 442.330754 -326.749191) (xy 442.36484 -326.705048) (xy 442.404989 -326.666339) (xy 442.450347 -326.633888)
			(xy 442.499947 -326.608387) (xy 442.552731 -326.59038) (xy 442.607574 -326.58025) (xy 442.663308 -326.578213)
			(xy 442.718745 -326.584313) (xy 442.772702 -326.598419) (xy 442.824031 -326.620231) (xy 442.871637 -326.649285)
			(xy 442.914505 -326.68496) (xy 442.951722 -326.726497) (xy 442.982495 -326.77301) (xy 443.006167 -326.823507)
			(xy 443.022235 -326.876914) (xy 443.030355 -326.93209) (xy 443.030864 -326.959976) (xy 443.030355 -326.987862)
			(xy 443.022235 -327.043038) (xy 443.006167 -327.096445) (xy 442.982495 -327.146942) (xy 442.951722 -327.193455)
			(xy 442.914505 -327.234992) (xy 442.871637 -327.270667) (xy 442.824031 -327.299721) (xy 442.772702 -327.321533)
			(xy 442.718745 -327.335639) (xy 442.663308 -327.341739) (xy 442.607574 -327.339702) (xy 442.552731 -327.329572)
			(xy 442.499947 -327.311565) (xy 442.450347 -327.286064) (xy 442.404989 -327.253613) (xy 442.36484 -327.214904)
			(xy 442.330754 -327.170761) (xy 442.303458 -327.122126) (xy 442.283535 -327.070035) (xy 442.271409 -327.015598)
			(xy 442.267338 -326.959976) (xy 441.8366 -326.959976) (xy 441.837064 -326.985376) (xy 441.836555 -327.013262)
			(xy 441.828435 -327.068438) (xy 441.812367 -327.121845) (xy 441.788695 -327.172342) (xy 441.757922 -327.218855)
			(xy 441.720705 -327.260392) (xy 441.677837 -327.296067) (xy 441.630231 -327.325121) (xy 441.578902 -327.346933)
			(xy 441.524945 -327.361039) (xy 441.469508 -327.367139) (xy 441.413774 -327.365102) (xy 441.358931 -327.354972)
			(xy 441.306147 -327.336965) (xy 441.256547 -327.311464) (xy 441.211189 -327.279013) (xy 441.17104 -327.240304)
			(xy 441.136954 -327.196161) (xy 441.109658 -327.147526) (xy 441.089735 -327.095435) (xy 441.077609 -327.040998)
			(xy 441.073538 -326.985376) (xy 440.511557 -326.985376) (xy 440.515176 -327.024427) (xy 440.515176 -327.108973)
			(xy 440.507375 -327.193158) (xy 440.491841 -327.276264) (xy 440.468704 -327.357582) (xy 440.438164 -327.436418)
			(xy 440.40048 -327.512101) (xy 440.355974 -327.583984) (xy 440.305025 -327.651454) (xy 440.248069 -327.713935)
			(xy 440.185591 -327.770895) (xy 440.118124 -327.821847) (xy 440.046243 -327.866357) (xy 439.970562 -327.904045)
			(xy 439.891727 -327.934589) (xy 439.81041 -327.95773) (xy 439.727305 -327.973269) (xy 439.643121 -327.981074)
			(xy 439.600848 -327.981564) (xy 438.356248 -327.981564) (xy 438.313968 -327.981181) (xy 438.229767 -327.973383)
			(xy 438.146646 -327.957849) (xy 438.065312 -327.934711) (xy 437.986461 -327.904167) (xy 437.910764 -327.866478)
			(xy 437.838867 -327.821965) (xy 437.771385 -327.771008) (xy 437.708892 -327.714042) (xy 437.651923 -327.651552)
			(xy 437.600962 -327.584072) (xy 437.556445 -327.512178) (xy 437.518752 -327.436483) (xy 437.488204 -327.357633)
			(xy 437.465062 -327.276301) (xy 437.449524 -327.19318) (xy 437.441721 -327.10898) (xy 436.705756 -327.10898)
			(xy 436.705756 -356.70236) (xy 440.2361 -356.70236) (xy 440.240171 -356.646738) (xy 440.252297 -356.592301)
			(xy 440.27222 -356.54021) (xy 440.299516 -356.491575) (xy 440.333602 -356.447432) (xy 440.373751 -356.408723)
			(xy 440.419109 -356.376272) (xy 440.468709 -356.350771) (xy 440.521493 -356.332764) (xy 440.576336 -356.322634)
			(xy 440.63207 -356.320597) (xy 440.687507 -356.326697) (xy 440.741464 -356.340803) (xy 440.792793 -356.362615)
			(xy 440.840399 -356.391669) (xy 440.883267 -356.427344) (xy 440.920484 -356.468881) (xy 440.951257 -356.515394)
			(xy 440.974929 -356.565891) (xy 440.990997 -356.619298) (xy 440.999117 -356.674474) (xy 440.999626 -356.70236)
			(xy 440.999117 -356.730246) (xy 440.990997 -356.785422) (xy 440.974929 -356.838829) (xy 440.951257 -356.889326)
			(xy 440.920484 -356.935839) (xy 440.883267 -356.977376) (xy 440.840399 -357.013051) (xy 440.792793 -357.042105)
			(xy 440.741464 -357.063917) (xy 440.687507 -357.078023) (xy 440.63207 -357.084123) (xy 440.576336 -357.082086)
			(xy 440.521493 -357.071956) (xy 440.468709 -357.053949) (xy 440.419109 -357.028448) (xy 440.373751 -356.995997)
			(xy 440.333602 -356.957288) (xy 440.299516 -356.913145) (xy 440.27222 -356.86451) (xy 440.252297 -356.812419)
			(xy 440.240171 -356.757982) (xy 440.2361 -356.70236) (xy 436.705756 -356.70236) (xy 436.705756 -368.742468)
			(xy 441.257942 -368.742468) (xy 441.262013 -368.686846) (xy 441.274139 -368.632409) (xy 441.294062 -368.580318)
			(xy 441.321358 -368.531683) (xy 441.355444 -368.48754) (xy 441.395593 -368.448831) (xy 441.440951 -368.41638)
			(xy 441.490551 -368.390879) (xy 441.543335 -368.372872) (xy 441.598178 -368.362742) (xy 441.653912 -368.360705)
			(xy 441.709349 -368.366805) (xy 441.763306 -368.380911) (xy 441.814635 -368.402723) (xy 441.862241 -368.431777)
			(xy 441.905109 -368.467452) (xy 441.942326 -368.508989) (xy 441.973099 -368.555502) (xy 441.996771 -368.605999)
			(xy 442.012839 -368.659406) (xy 442.020959 -368.714582) (xy 442.021468 -368.742468) (xy 442.020959 -368.770354)
			(xy 442.020203 -368.775488) (xy 443.357264 -368.775488) (xy 443.36124 -368.721162) (xy 443.373083 -368.667993)
			(xy 443.392542 -368.617116) (xy 443.419202 -368.569614) (xy 443.452493 -368.5265) (xy 443.491707 -368.488693)
			(xy 443.536009 -368.456998) (xy 443.584452 -368.432092) (xy 443.636006 -368.414504) (xy 443.689572 -368.40461)
			(xy 443.744007 -368.40262) (xy 443.798152 -368.408578) (xy 443.850852 -368.422356) (xy 443.900985 -368.44366)
			(xy 443.947481 -368.472036) (xy 443.989351 -368.50688) (xy 444.0257 -368.547449) (xy 444.055756 -368.592878)
			(xy 444.078877 -368.642199) (xy 444.09457 -368.694361) (xy 444.102501 -368.748252) (xy 444.102998 -368.775488)
			(xy 444.102501 -368.802724) (xy 444.09457 -368.856615) (xy 444.078877 -368.908777) (xy 444.055756 -368.958098)
			(xy 444.0257 -369.003527) (xy 443.989351 -369.044096) (xy 443.947481 -369.07894) (xy 443.900985 -369.107316)
			(xy 443.850852 -369.12862) (xy 443.798152 -369.142398) (xy 443.744007 -369.148356) (xy 443.689572 -369.146366)
			(xy 443.636006 -369.136472) (xy 443.584452 -369.118884) (xy 443.536009 -369.093978) (xy 443.491707 -369.062283)
			(xy 443.452493 -369.024476) (xy 443.419202 -368.981362) (xy 443.392542 -368.93386) (xy 443.373083 -368.882983)
			(xy 443.36124 -368.829814) (xy 443.357264 -368.775488) (xy 442.020203 -368.775488) (xy 442.012839 -368.82553)
			(xy 441.996771 -368.878937) (xy 441.973099 -368.929434) (xy 441.942326 -368.975947) (xy 441.905109 -369.017484)
			(xy 441.862241 -369.053159) (xy 441.814635 -369.082213) (xy 441.763306 -369.104025) (xy 441.709349 -369.118131)
			(xy 441.653912 -369.124231) (xy 441.598178 -369.122194) (xy 441.543335 -369.112064) (xy 441.490551 -369.094057)
			(xy 441.440951 -369.068556) (xy 441.395593 -369.036105) (xy 441.355444 -368.997396) (xy 441.321358 -368.953253)
			(xy 441.294062 -368.904618) (xy 441.274139 -368.852527) (xy 441.262013 -368.79809) (xy 441.257942 -368.742468)
			(xy 436.705756 -368.742468) (xy 436.705756 -369.682268) (xy 440.663582 -369.682268) (xy 440.667653 -369.626646)
			(xy 440.679779 -369.572209) (xy 440.699702 -369.520118) (xy 440.726998 -369.471483) (xy 440.761084 -369.42734)
			(xy 440.801233 -369.388631) (xy 440.846591 -369.35618) (xy 440.896191 -369.330679) (xy 440.948975 -369.312672)
			(xy 441.003818 -369.302542) (xy 441.059552 -369.300505) (xy 441.114989 -369.306605) (xy 441.168946 -369.320711)
			(xy 441.220275 -369.342523) (xy 441.267881 -369.371577) (xy 441.310749 -369.407252) (xy 441.347966 -369.448789)
			(xy 441.378739 -369.495302) (xy 441.402411 -369.545799) (xy 441.418479 -369.599206) (xy 441.426599 -369.654382)
			(xy 441.427108 -369.682268) (xy 441.426599 -369.710154) (xy 441.418479 -369.76533) (xy 441.402411 -369.818737)
			(xy 441.378739 -369.869234) (xy 441.347966 -369.915747) (xy 441.310749 -369.957284) (xy 441.267881 -369.992959)
			(xy 441.220275 -370.022013) (xy 441.168946 -370.043825) (xy 441.114989 -370.057931) (xy 441.059552 -370.064031)
			(xy 441.003818 -370.061994) (xy 440.948975 -370.051864) (xy 440.896191 -370.033857) (xy 440.846591 -370.008356)
			(xy 440.801233 -369.975905) (xy 440.761084 -369.937196) (xy 440.726998 -369.893053) (xy 440.699702 -369.844418)
			(xy 440.679779 -369.792327) (xy 440.667653 -369.73789) (xy 440.663582 -369.682268) (xy 436.705756 -369.682268)
			(xy 436.705756 -370.13642) (xy 439.444382 -370.13642) (xy 439.448453 -370.080798) (xy 439.460579 -370.026361)
			(xy 439.480502 -369.97427) (xy 439.507798 -369.925635) (xy 439.541884 -369.881492) (xy 439.582033 -369.842783)
			(xy 439.627391 -369.810332) (xy 439.676991 -369.784831) (xy 439.729775 -369.766824) (xy 439.784618 -369.756694)
			(xy 439.840352 -369.754657) (xy 439.895789 -369.760757) (xy 439.949746 -369.774863) (xy 440.001075 -369.796675)
			(xy 440.048681 -369.825729) (xy 440.091549 -369.861404) (xy 440.128766 -369.902941) (xy 440.159539 -369.949454)
			(xy 440.183211 -369.999951) (xy 440.199279 -370.053358) (xy 440.207399 -370.108534) (xy 440.207908 -370.13642)
			(xy 440.207399 -370.164306) (xy 440.199279 -370.219482) (xy 440.183211 -370.272889) (xy 440.159539 -370.323386)
			(xy 440.128766 -370.369899) (xy 440.091549 -370.411436) (xy 440.048681 -370.447111) (xy 440.001075 -370.476165)
			(xy 439.949746 -370.497977) (xy 439.895789 -370.512083) (xy 439.840352 -370.518183) (xy 439.784618 -370.516146)
			(xy 439.729775 -370.506016) (xy 439.676991 -370.488009) (xy 439.627391 -370.462508) (xy 439.582033 -370.430057)
			(xy 439.541884 -370.391348) (xy 439.507798 -370.347205) (xy 439.480502 -370.29857) (xy 439.460579 -370.246479)
			(xy 439.448453 -370.192042) (xy 439.444382 -370.13642) (xy 436.705756 -370.13642) (xy 436.705756 -370.571268)
			(xy 440.663582 -370.571268) (xy 440.667653 -370.515646) (xy 440.679779 -370.461209) (xy 440.699702 -370.409118)
			(xy 440.726998 -370.360483) (xy 440.761084 -370.31634) (xy 440.801233 -370.277631) (xy 440.846591 -370.24518)
			(xy 440.896191 -370.219679) (xy 440.948975 -370.201672) (xy 441.003818 -370.191542) (xy 441.059552 -370.189505)
			(xy 441.114989 -370.195605) (xy 441.168946 -370.209711) (xy 441.220275 -370.231523) (xy 441.267881 -370.260577)
			(xy 441.310749 -370.296252) (xy 441.347966 -370.337789) (xy 441.378739 -370.384302) (xy 441.402411 -370.434799)
			(xy 441.418479 -370.488206) (xy 441.426599 -370.543382) (xy 441.427108 -370.571268) (xy 441.426599 -370.599154)
			(xy 441.422105 -370.629688) (xy 444.373762 -370.629688) (xy 444.374307 -370.600688) (xy 444.383295 -370.543387)
			(xy 444.401053 -370.488172) (xy 444.427151 -370.436374) (xy 444.460959 -370.389246) (xy 444.501661 -370.347924)
			(xy 444.524638 -370.330222) (xy 444.535255 -370.321808) (xy 444.551957 -370.300491) (xy 444.562471 -370.275535)
			(xy 444.566058 -370.248693) (xy 444.562467 -370.221851) (xy 444.551949 -370.196896) (xy 444.535244 -370.175582)
			(xy 444.524638 -370.167154) (xy 444.501655 -370.14946) (xy 444.460954 -370.108136) (xy 444.427148 -370.061006)
			(xy 444.401053 -370.009206) (xy 444.383298 -369.95399) (xy 444.374314 -369.896689) (xy 444.373762 -369.867688)
			(xy 444.374283 -369.839803) (xy 444.382595 -369.784656) (xy 444.399033 -369.731364) (xy 444.423231 -369.681118)
			(xy 444.454647 -369.635039) (xy 444.49258 -369.594157) (xy 444.536182 -369.559385) (xy 444.58448 -369.5315)
			(xy 444.636395 -369.511125) (xy 444.690766 -369.498715) (xy 444.74638 -369.494548) (xy 444.801994 -369.498715)
			(xy 444.856365 -369.511125) (xy 444.90828 -369.5315) (xy 444.956578 -369.559385) (xy 445.00018 -369.594157)
			(xy 445.038113 -369.635039) (xy 445.069529 -369.681118) (xy 445.093727 -369.731364) (xy 445.110165 -369.784656)
			(xy 445.118477 -369.839803) (xy 445.118998 -369.867688) (xy 445.118452 -369.896689) (xy 445.109466 -369.953989)
			(xy 445.09171 -370.009206) (xy 445.065612 -370.061004) (xy 445.031804 -370.108132) (xy 444.9911 -370.149453)
			(xy 444.968122 -370.167154) (xy 444.957524 -370.175593) (xy 444.940813 -370.196901) (xy 444.93029 -370.221853)
			(xy 444.926697 -370.248693) (xy 444.930287 -370.275534) (xy 444.940805 -370.300487) (xy 444.957514 -370.321797)
			(xy 444.968122 -370.330222) (xy 444.991107 -370.347914) (xy 445.031804 -370.38924) (xy 445.065608 -370.436372)
			(xy 445.091703 -370.488171) (xy 445.109458 -370.543387) (xy 445.118445 -370.600688) (xy 445.118998 -370.629688)
			(xy 445.118477 -370.657573) (xy 445.110165 -370.71272) (xy 445.093727 -370.766012) (xy 445.069529 -370.816258)
			(xy 445.038113 -370.862337) (xy 445.00018 -370.903219) (xy 444.956578 -370.937991) (xy 444.90828 -370.965876)
			(xy 444.856365 -370.986251) (xy 444.801994 -370.998661) (xy 444.74638 -371.002829) (xy 444.690766 -370.998661)
			(xy 444.636395 -370.986251) (xy 444.58448 -370.965876) (xy 444.536182 -370.937991) (xy 444.49258 -370.903219)
			(xy 444.454647 -370.862337) (xy 444.423231 -370.816258) (xy 444.399033 -370.766012) (xy 444.382595 -370.71272)
			(xy 444.374283 -370.657573) (xy 444.373762 -370.629688) (xy 441.422105 -370.629688) (xy 441.418479 -370.65433)
			(xy 441.402411 -370.707737) (xy 441.378739 -370.758234) (xy 441.347966 -370.804747) (xy 441.310749 -370.846284)
			(xy 441.267881 -370.881959) (xy 441.220275 -370.911013) (xy 441.168946 -370.932825) (xy 441.114989 -370.946931)
			(xy 441.059552 -370.953031) (xy 441.003818 -370.950994) (xy 440.948975 -370.940864) (xy 440.896191 -370.922857)
			(xy 440.846591 -370.897356) (xy 440.801233 -370.864905) (xy 440.761084 -370.826196) (xy 440.726998 -370.782053)
			(xy 440.699702 -370.733418) (xy 440.679779 -370.681327) (xy 440.667653 -370.62689) (xy 440.663582 -370.571268)
			(xy 436.705756 -370.571268) (xy 436.705756 -371.584728) (xy 438.961782 -371.584728) (xy 438.965853 -371.529106)
			(xy 438.977979 -371.474669) (xy 438.997902 -371.422578) (xy 439.025198 -371.373943) (xy 439.059284 -371.3298)
			(xy 439.099433 -371.291091) (xy 439.144791 -371.25864) (xy 439.194391 -371.233139) (xy 439.247175 -371.215132)
			(xy 439.302018 -371.205002) (xy 439.357752 -371.202965) (xy 439.413189 -371.209065) (xy 439.467146 -371.223171)
			(xy 439.518475 -371.244983) (xy 439.566081 -371.274037) (xy 439.608949 -371.309712) (xy 439.646166 -371.351249)
			(xy 439.676939 -371.397762) (xy 439.700611 -371.448259) (xy 439.716679 -371.501666) (xy 439.724799 -371.556842)
			(xy 439.725308 -371.584728) (xy 439.850782 -371.584728) (xy 439.854853 -371.529106) (xy 439.866979 -371.474669)
			(xy 439.886902 -371.422578) (xy 439.914198 -371.373943) (xy 439.948284 -371.3298) (xy 439.988433 -371.291091)
			(xy 440.033791 -371.25864) (xy 440.083391 -371.233139) (xy 440.136175 -371.215132) (xy 440.191018 -371.205002)
			(xy 440.246752 -371.202965) (xy 440.302189 -371.209065) (xy 440.356146 -371.223171) (xy 440.407475 -371.244983)
			(xy 440.455081 -371.274037) (xy 440.497949 -371.309712) (xy 440.535166 -371.351249) (xy 440.565939 -371.397762)
			(xy 440.589611 -371.448259) (xy 440.605679 -371.501666) (xy 440.613799 -371.556842) (xy 440.614308 -371.584728)
			(xy 440.739782 -371.584728) (xy 440.743853 -371.529106) (xy 440.755979 -371.474669) (xy 440.775902 -371.422578)
			(xy 440.803198 -371.373943) (xy 440.837284 -371.3298) (xy 440.877433 -371.291091) (xy 440.922791 -371.25864)
			(xy 440.972391 -371.233139) (xy 441.025175 -371.215132) (xy 441.080018 -371.205002) (xy 441.135752 -371.202965)
			(xy 441.191189 -371.209065) (xy 441.245146 -371.223171) (xy 441.296475 -371.244983) (xy 441.344081 -371.274037)
			(xy 441.386949 -371.309712) (xy 441.424166 -371.351249) (xy 441.454939 -371.397762) (xy 441.478611 -371.448259)
			(xy 441.494679 -371.501666) (xy 441.502799 -371.556842) (xy 441.503308 -371.584728) (xy 441.628782 -371.584728)
			(xy 441.632853 -371.529106) (xy 441.644979 -371.474669) (xy 441.664902 -371.422578) (xy 441.692198 -371.373943)
			(xy 441.726284 -371.3298) (xy 441.766433 -371.291091) (xy 441.811791 -371.25864) (xy 441.861391 -371.233139)
			(xy 441.914175 -371.215132) (xy 441.969018 -371.205002) (xy 442.024752 -371.202965) (xy 442.080189 -371.209065)
			(xy 442.134146 -371.223171) (xy 442.185475 -371.244983) (xy 442.233081 -371.274037) (xy 442.275949 -371.309712)
			(xy 442.313166 -371.351249) (xy 442.343939 -371.397762) (xy 442.367611 -371.448259) (xy 442.383679 -371.501666)
			(xy 442.391799 -371.556842) (xy 442.392308 -371.584728) (xy 442.391799 -371.612614) (xy 442.383679 -371.66779)
			(xy 442.383451 -371.668548) (xy 442.876176 -371.668548) (xy 442.880247 -371.612926) (xy 442.892373 -371.558489)
			(xy 442.912296 -371.506398) (xy 442.939592 -371.457763) (xy 442.973678 -371.41362) (xy 443.013827 -371.374911)
			(xy 443.059185 -371.34246) (xy 443.108785 -371.316959) (xy 443.161569 -371.298952) (xy 443.216412 -371.288822)
			(xy 443.272146 -371.286785) (xy 443.327583 -371.292885) (xy 443.38154 -371.306991) (xy 443.432869 -371.328803)
			(xy 443.480475 -371.357857) (xy 443.523343 -371.393532) (xy 443.56056 -371.435069) (xy 443.591333 -371.481582)
			(xy 443.615005 -371.532079) (xy 443.631073 -371.585486) (xy 443.639193 -371.640662) (xy 443.639702 -371.668548)
			(xy 443.639193 -371.696434) (xy 443.631073 -371.75161) (xy 443.615005 -371.805017) (xy 443.591333 -371.855514)
			(xy 443.56056 -371.902027) (xy 443.523343 -371.943564) (xy 443.480475 -371.979239) (xy 443.432869 -372.008293)
			(xy 443.38154 -372.030105) (xy 443.327583 -372.044211) (xy 443.272146 -372.050311) (xy 443.216412 -372.048274)
			(xy 443.161569 -372.038144) (xy 443.108785 -372.020137) (xy 443.059185 -371.994636) (xy 443.013827 -371.962185)
			(xy 442.973678 -371.923476) (xy 442.939592 -371.879333) (xy 442.912296 -371.830698) (xy 442.892373 -371.778607)
			(xy 442.880247 -371.72417) (xy 442.876176 -371.668548) (xy 442.383451 -371.668548) (xy 442.367611 -371.721197)
			(xy 442.343939 -371.771694) (xy 442.313166 -371.818207) (xy 442.275949 -371.859744) (xy 442.233081 -371.895419)
			(xy 442.185475 -371.924473) (xy 442.134146 -371.946285) (xy 442.080189 -371.960391) (xy 442.024752 -371.966491)
			(xy 441.969018 -371.964454) (xy 441.914175 -371.954324) (xy 441.861391 -371.936317) (xy 441.811791 -371.910816)
			(xy 441.766433 -371.878365) (xy 441.726284 -371.839656) (xy 441.692198 -371.795513) (xy 441.664902 -371.746878)
			(xy 441.644979 -371.694787) (xy 441.632853 -371.64035) (xy 441.628782 -371.584728) (xy 441.503308 -371.584728)
			(xy 441.502799 -371.612614) (xy 441.494679 -371.66779) (xy 441.478611 -371.721197) (xy 441.454939 -371.771694)
			(xy 441.424166 -371.818207) (xy 441.386949 -371.859744) (xy 441.344081 -371.895419) (xy 441.296475 -371.924473)
			(xy 441.245146 -371.946285) (xy 441.191189 -371.960391) (xy 441.135752 -371.966491) (xy 441.080018 -371.964454)
			(xy 441.025175 -371.954324) (xy 440.972391 -371.936317) (xy 440.922791 -371.910816) (xy 440.877433 -371.878365)
			(xy 440.837284 -371.839656) (xy 440.803198 -371.795513) (xy 440.775902 -371.746878) (xy 440.755979 -371.694787)
			(xy 440.743853 -371.64035) (xy 440.739782 -371.584728) (xy 440.614308 -371.584728) (xy 440.613799 -371.612614)
			(xy 440.605679 -371.66779) (xy 440.589611 -371.721197) (xy 440.565939 -371.771694) (xy 440.535166 -371.818207)
			(xy 440.497949 -371.859744) (xy 440.455081 -371.895419) (xy 440.407475 -371.924473) (xy 440.356146 -371.946285)
			(xy 440.302189 -371.960391) (xy 440.246752 -371.966491) (xy 440.191018 -371.964454) (xy 440.136175 -371.954324)
			(xy 440.083391 -371.936317) (xy 440.033791 -371.910816) (xy 439.988433 -371.878365) (xy 439.948284 -371.839656)
			(xy 439.914198 -371.795513) (xy 439.886902 -371.746878) (xy 439.866979 -371.694787) (xy 439.854853 -371.64035)
			(xy 439.850782 -371.584728) (xy 439.725308 -371.584728) (xy 439.724799 -371.612614) (xy 439.716679 -371.66779)
			(xy 439.700611 -371.721197) (xy 439.676939 -371.771694) (xy 439.646166 -371.818207) (xy 439.608949 -371.859744)
			(xy 439.566081 -371.895419) (xy 439.518475 -371.924473) (xy 439.467146 -371.946285) (xy 439.413189 -371.960391)
			(xy 439.357752 -371.966491) (xy 439.302018 -371.964454) (xy 439.247175 -371.954324) (xy 439.194391 -371.936317)
			(xy 439.144791 -371.910816) (xy 439.099433 -371.878365) (xy 439.059284 -371.839656) (xy 439.025198 -371.795513)
			(xy 438.997902 -371.746878) (xy 438.977979 -371.694787) (xy 438.965853 -371.64035) (xy 438.961782 -371.584728)
			(xy 436.705756 -371.584728) (xy 436.705756 -374.868694) (xy 437.254396 -375.417334) (xy 447.035936 -375.417334)
		)
		(stroke
			(width 0)
			(type solid)
		)
		(fill yes)
		(layer "In15.Cu")
		(net "P3V3")
	)
	(gr_poly
		(pts
			(xy 84.500212 -332.086966) (xy 84.514944 -332.07198) (xy 84.514944 -331.036676) (xy 84.515373 -331.026609)
			(xy 84.523098 -331.008015) (xy 84.52993 -331.000608) (xy 86.314788 -329.21575) (xy 86.322183 -329.208896)
			(xy 86.340782 -329.20115) (xy 86.350856 -329.200764) (xy 91.901772 -329.200764) (xy 91.911733 -329.200276)
			(xy 91.930152 -329.192683) (xy 91.937586 -329.186032) (xy 95.153988 -325.96963) (xy 95.161385 -325.962779)
			(xy 95.179983 -325.955035) (xy 95.190056 -325.954644) (xy 124.029216 -325.954644) (xy 124.039284 -325.955071)
			(xy 124.05788 -325.962795) (xy 124.065284 -325.96963) (xy 124.136912 -326.041258) (xy 124.137166 -326.041258)
			(xy 124.22632 -326.130412) (xy 124.226066 -326.130412) (xy 127.457454 -329.3618) (xy 127.47244 -329.376532)
			(xy 132.058664 -329.376532) (xy 132.068728 -329.376967) (xy 132.087313 -329.384702) (xy 132.094732 -329.391518)
			(xy 133.834632 -331.131164) (xy 134.125208 -331.42174) (xy 134.140194 -331.436472) (xy 139.975844 -331.436472)
			(xy 140.46708 -330.945236) (xy 140.46708 -324.838568) (xy 137.31748 -310.352948) (xy 137.31748 -291.506148)
			(xy 136.09828 -290.286948) (xy 122.843036 -290.286948) (xy 122.542554 -289.986466) (xy 122.531513 -289.976188)
			(xy 122.504908 -289.962005) (xy 122.475324 -289.95619) (xy 122.445331 -289.959251) (xy 122.417531 -289.97092)
			(xy 122.394339 -289.990185) (xy 122.385582 -290.002468) (xy 122.371409 -290.023304) (xy 122.338123 -290.061137)
			(xy 122.299829 -290.093892) (xy 122.257295 -290.120913) (xy 122.211372 -290.14166) (xy 122.162981 -290.155716)
			(xy 122.11309 -290.162801) (xy 122.087894 -290.16325) (xy 122.05991 -290.162701) (xy 122.004631 -290.153945)
			(xy 121.951402 -290.136651) (xy 121.901534 -290.111243) (xy 121.856253 -290.078347) (xy 121.816676 -290.038774)
			(xy 121.783776 -289.993497) (xy 121.758363 -289.943631) (xy 121.741063 -289.890404) (xy 121.732302 -289.835126)
			(xy 121.731786 -289.807142) (xy 121.732226 -289.781948) (xy 121.739337 -289.732064) (xy 121.753409 -289.68368)
			(xy 121.77416 -289.637763) (xy 121.801177 -289.59523) (xy 121.83392 -289.556929) (xy 121.871734 -289.523627)
			(xy 121.892568 -289.509454) (xy 121.904915 -289.500749) (xy 121.924275 -289.477577) (xy 121.936001 -289.449752)
			(xy 121.939064 -289.419714) (xy 121.933197 -289.390095) (xy 121.918914 -289.363492) (xy 121.90857 -289.352482)
			(xy 121.788174 -289.232086) (xy 121.756678 -289.245294) (xy 121.734681 -289.25413) (xy 121.688938 -289.266572)
			(xy 121.64195 -289.272852) (xy 121.618248 -289.273234) (xy 121.590259 -289.272718) (xy 121.53497 -289.263968)
			(xy 121.481731 -289.246677) (xy 121.431852 -289.221269) (xy 121.386562 -289.188372) (xy 121.346976 -289.148794)
			(xy 121.314069 -289.103511) (xy 121.288652 -289.053638) (xy 121.271349 -289.000402) (xy 121.262588 -288.945114)
			(xy 121.26214 -288.917126) (xy 121.262514 -288.893881) (xy 121.268556 -288.847785) (xy 121.280542 -288.802866)
			(xy 121.289064 -288.781236) (xy 121.298716 -288.758122) (xy 121.277126 -288.721038) (xy 120.96369 -288.407602)
			(xy 120.958864 -288.404554) (xy 120.936575 -288.38996) (xy 120.896195 -288.355209) (xy 120.861443 -288.314829)
			(xy 120.84685 -288.29254) (xy 120.843802 -288.287714) (xy 120.71858 -288.162492) (xy 120.707584 -288.152244)
			(xy 120.681087 -288.138084) (xy 120.651618 -288.132242) (xy 120.621723 -288.135223) (xy 120.593987 -288.14677)
			(xy 120.570809 -288.165884) (xy 120.554192 -288.190914) (xy 120.549416 -288.205164) (xy 120.541723 -288.229304)
			(xy 120.52046 -288.27529) (xy 120.492896 -288.317799) (xy 120.459586 -288.355973) (xy 120.421203 -288.389042)
			(xy 120.378521 -288.416338) (xy 120.332402 -288.437311) (xy 120.283776 -288.451537) (xy 120.233626 -288.45873)
			(xy 120.208294 -288.459164) (xy 120.18031 -288.458643) (xy 120.125032 -288.449886) (xy 120.071804 -288.432589)
			(xy 120.021938 -288.407178) (xy 119.976661 -288.374278) (xy 119.937089 -288.334701) (xy 119.904196 -288.289419)
			(xy 119.878792 -288.239549) (xy 119.861502 -288.186319) (xy 119.852753 -288.13104) (xy 119.852186 -288.103056)
			(xy 119.852629 -288.077722) (xy 119.859805 -288.027565) (xy 119.874019 -287.978932) (xy 119.894985 -287.932806)
			(xy 119.922279 -287.890118) (xy 119.955349 -287.851731) (xy 119.993528 -287.81842) (xy 120.036044 -287.790859)
			(xy 120.082037 -287.769604) (xy 120.106186 -287.761934) (xy 120.120404 -287.757099) (xy 120.145397 -287.740474)
			(xy 120.164482 -287.717306) (xy 120.176016 -287.689593) (xy 120.179002 -287.659725) (xy 120.173184 -287.630278)
			(xy 120.159063 -287.60379) (xy 120.148858 -287.59277) (xy 120.115076 -287.558988) (xy 120.103799 -287.548471)
			(xy 120.0765 -287.534164) (xy 120.046179 -287.528636) (xy 120.015587 -287.53239) (xy 119.987502 -287.545084)
			(xy 119.97563 -287.554924) (xy 119.955962 -287.571853) (xy 119.912643 -287.600427) (xy 119.865636 -287.62241)
			(xy 119.815935 -287.637337) (xy 119.764595 -287.644891) (xy 119.738648 -287.645348) (xy 119.710659 -287.644832)
			(xy 119.655369 -287.636082) (xy 119.602129 -287.618791) (xy 119.552249 -287.593384) (xy 119.506958 -287.560487)
			(xy 119.467371 -287.520909) (xy 119.434462 -287.475626) (xy 119.409043 -287.425753) (xy 119.391739 -287.372517)
			(xy 119.382975 -287.317229) (xy 119.38254 -287.28924) (xy 119.383008 -287.263293) (xy 119.390544 -287.211948)
			(xy 119.405462 -287.162244) (xy 119.427445 -287.115235) (xy 119.456026 -287.07192) (xy 119.472964 -287.052258)
			(xy 119.482806 -287.040388) (xy 119.495498 -287.012303) (xy 119.499249 -286.981712) (xy 119.493718 -286.951393)
			(xy 119.479408 -286.924097) (xy 119.4689 -286.912812) (xy 119.373142 -286.817054) (xy 119.345964 -286.82315)
			(xy 119.326903 -286.827085) (xy 119.288209 -286.831281) (xy 119.268748 -286.831532) (xy 119.240759 -286.831016)
			(xy 119.185471 -286.822266) (xy 119.132231 -286.804975) (xy 119.082353 -286.779567) (xy 119.037063 -286.74667)
			(xy 118.997477 -286.707092) (xy 118.96457 -286.661809) (xy 118.939153 -286.611935) (xy 118.921851 -286.5587)
			(xy 118.91309 -286.503412) (xy 118.91264 -286.475424) (xy 118.91316 -286.448229) (xy 118.921439 -286.394472)
			(xy 118.937793 -286.342599) (xy 118.961841 -286.293814) (xy 118.993026 -286.249251) (xy 119.030622 -286.209947)
			(xy 119.073756 -286.176814) (xy 119.121424 -286.150622) (xy 119.17252 -286.13198) (xy 119.225856 -286.121322)
			(xy 119.253 -286.11957) (xy 119.268473 -286.118304) (xy 119.297615 -286.107642) (xy 119.322221 -286.088735)
			(xy 119.340027 -286.063321) (xy 119.349394 -286.033738) (xy 119.350028 -286.018224) (xy 119.350028 -285.383224)
			(xy 119.246396 -285.2039) (xy 119.221758 -285.200598) (xy 119.196414 -285.196776) (xy 119.147102 -285.182802)
			(xy 119.100303 -285.161901) (xy 119.056986 -285.134504) (xy 119.018045 -285.101179) (xy 118.984285 -285.062614)
			(xy 118.956405 -285.019606) (xy 118.934981 -284.973045) (xy 118.920455 -284.923893) (xy 118.913128 -284.873165)
			(xy 118.91264 -284.847538) (xy 118.913159 -284.820342) (xy 118.921436 -284.766584) (xy 118.937789 -284.714709)
			(xy 118.961837 -284.665922) (xy 118.993021 -284.621358) (xy 119.030617 -284.582051) (xy 119.073751 -284.548917)
			(xy 119.121421 -284.522724) (xy 119.172518 -284.504081) (xy 119.225855 -284.493422) (xy 119.253 -284.491684)
			(xy 119.268474 -284.490418) (xy 119.297618 -284.479757) (xy 119.322226 -284.460851) (xy 119.340035 -284.435437)
			(xy 119.349407 -284.405853) (xy 119.350028 -284.390338) (xy 119.350028 -283.937964) (xy 119.325644 -283.91358)
			(xy 119.315491 -283.904022) (xy 119.2912 -283.890351) (xy 119.264118 -283.883753) (xy 119.23626 -283.88472)
			(xy 119.2097 -283.89318) (xy 119.186415 -283.908502) (xy 119.168137 -283.929547) (xy 119.156227 -283.954749)
			(xy 119.15157 -283.982231) (xy 119.15267 -283.99613) (xy 119.153618 -284.005499) (xy 119.154635 -284.024305)
			(xy 119.154702 -284.033722) (xy 119.154195 -284.060801) (xy 119.14599 -284.114335) (xy 119.129774 -284.166009)
			(xy 119.105921 -284.214631) (xy 119.074979 -284.259081) (xy 119.037664 -284.298333) (xy 118.994835 -284.331482)
			(xy 118.947481 -284.357763) (xy 118.896693 -284.37657) (xy 118.843642 -284.38747) (xy 118.789553 -284.390211)
			(xy 118.735673 -284.38473) (xy 118.683243 -284.371154) (xy 118.633475 -284.349794) (xy 118.587514 -284.321145)
			(xy 118.546422 -284.285867) (xy 118.511145 -284.244773) (xy 118.482498 -284.198811) (xy 118.461141 -284.149041)
			(xy 118.447567 -284.096612) (xy 118.442088 -284.042731) (xy 118.444832 -283.988642) (xy 118.455734 -283.935592)
			(xy 118.474544 -283.884805) (xy 118.500827 -283.837451) (xy 118.533978 -283.794624) (xy 118.573232 -283.75731)
			(xy 118.617683 -283.726371) (xy 118.666306 -283.70252) (xy 118.717981 -283.686306) (xy 118.771515 -283.678104)
			(xy 118.798594 -283.677614) (xy 118.836186 -283.679646) (xy 118.850103 -283.680726) (xy 118.877627 -283.676126)
			(xy 118.902875 -283.664245) (xy 118.923963 -283.645969) (xy 118.939313 -283.622665) (xy 118.947777 -283.596075)
			(xy 118.948724 -283.568187) (xy 118.942083 -283.541084) (xy 118.928349 -283.516793) (xy 118.918736 -283.506672)
			(xy 118.794022 -283.381958) (xy 118.78271 -283.371453) (xy 118.755345 -283.357195) (xy 118.724974 -283.351745)
			(xy 118.694359 -283.3556) (xy 118.666287 -283.368409) (xy 118.643312 -283.389006) (xy 118.635018 -283.402024)
			(xy 118.621154 -283.424398) (xy 118.587874 -283.465173) (xy 118.548953 -283.500604) (xy 118.505239 -283.529918)
			(xy 118.457684 -283.552476) (xy 118.407327 -283.567785) (xy 118.355265 -283.575513) (xy 118.328948 -283.576014)
			(xy 118.30096 -283.575498) (xy 118.245672 -283.566748) (xy 118.192434 -283.549456) (xy 118.142557 -283.524049)
			(xy 118.097268 -283.491151) (xy 118.057684 -283.451573) (xy 118.02478 -283.40629) (xy 117.999364 -283.356416)
			(xy 117.982065 -283.30318) (xy 117.973307 -283.247894) (xy 117.97284 -283.219906) (xy 117.973319 -283.193592)
			(xy 117.981075 -283.141539) (xy 117.996405 -283.091193) (xy 118.018974 -283.043651) (xy 118.048292 -282.999946)
			(xy 118.08372 -282.961029) (xy 118.124488 -282.927748) (xy 118.14683 -282.913836) (xy 118.159836 -282.905504)
			(xy 118.180484 -282.882552) (xy 118.193332 -282.85448) (xy 118.197205 -282.823851) (xy 118.191749 -282.793464)
			(xy 118.177463 -282.766095) (xy 118.166896 -282.754832) (xy 118.091204 -282.67914) (xy 118.056406 -282.702254)
			(xy 118.034374 -282.716367) (xy 117.987048 -282.738676) (xy 117.936967 -282.753819) (xy 117.885208 -282.761469)
			(xy 117.859048 -282.761944) (xy 117.831059 -282.761428) (xy 117.77577 -282.752678) (xy 117.722529 -282.735387)
			(xy 117.67265 -282.70998) (xy 117.627359 -282.677082) (xy 117.587772 -282.637505) (xy 117.554864 -282.592222)
			(xy 117.529445 -282.542348) (xy 117.512142 -282.489112) (xy 117.503379 -282.433825) (xy 117.50294 -282.405836)
			(xy 117.503399 -282.379674) (xy 117.511049 -282.327913) (xy 117.52619 -282.277828) (xy 117.548496 -282.230497)
			(xy 117.56263 -282.208478) (xy 117.585744 -282.17368) (xy 117.35943 -281.947366) (xy 117.342412 -281.94508)
			(xy 117.316811 -281.941227) (xy 117.26701 -281.927081) (xy 117.219783 -281.905873) (xy 117.176123 -281.878052)
			(xy 117.136952 -281.844202) (xy 117.103094 -281.805038) (xy 117.075263 -281.761385) (xy 117.054046 -281.714161)
			(xy 117.039889 -281.664364) (xy 117.036088 -281.638756) (xy 117.033802 -281.621738) (xy 116.565172 -281.153108)
			(xy 116.565172 -280.816304) (xy 116.564918 -280.813764) (xy 116.56314 -280.778204) (xy 116.564918 -280.742644)
			(xy 116.565172 -280.740104) (xy 116.565172 -280.421588) (xy 116.564742 -280.408009) (xy 116.557582 -280.381811)
			(xy 116.543772 -280.358425) (xy 116.524288 -280.339506) (xy 116.500507 -280.326389) (xy 116.47411 -280.320002)
			(xy 116.460524 -280.319988) (xy 116.449348 -280.320242) (xy 116.422692 -280.319772) (xy 116.369975 -280.311833)
			(xy 116.319029 -280.296124) (xy 116.270995 -280.272998) (xy 116.226944 -280.24297) (xy 116.187861 -280.206711)
			(xy 116.154619 -280.165032) (xy 116.127961 -280.118864) (xy 116.108482 -280.069238) (xy 116.096618 -280.017263)
			(xy 116.092634 -279.9641) (xy 116.096618 -279.910937) (xy 116.108482 -279.858962) (xy 116.127961 -279.809336)
			(xy 116.154619 -279.763168) (xy 116.187861 -279.721489) (xy 116.226944 -279.68523) (xy 116.270995 -279.655202)
			(xy 116.319029 -279.632076) (xy 116.369975 -279.616367) (xy 116.422692 -279.608428) (xy 116.449348 -279.608026)
			(xy 116.460524 -279.60828) (xy 116.47411 -279.608261) (xy 116.500512 -279.601891) (xy 116.524296 -279.58878)
			(xy 116.543778 -279.569858) (xy 116.557576 -279.546465) (xy 116.564712 -279.52026) (xy 116.565172 -279.50668)
			(xy 116.565172 -279.367996) (xy 116.466874 -279.269698) (xy 116.456669 -279.26011) (xy 116.432246 -279.246432)
			(xy 116.405025 -279.23991) (xy 116.377056 -279.241035) (xy 116.350446 -279.249722) (xy 116.327202 -279.265317)
			(xy 116.309073 -279.286645) (xy 116.30279 -279.299162) (xy 116.29176 -279.32202) (xy 116.264191 -279.364633)
			(xy 116.230858 -279.402905) (xy 116.192435 -279.436064) (xy 116.149698 -279.463439) (xy 116.10351 -279.484476)
			(xy 116.054806 -279.498752) (xy 116.00457 -279.505976) (xy 115.979194 -279.506426) (xy 115.951211 -279.505877)
			(xy 115.895933 -279.497121) (xy 115.842706 -279.479826) (xy 115.792839 -279.454418) (xy 115.747561 -279.421522)
			(xy 115.707986 -279.381948) (xy 115.675088 -279.336671) (xy 115.649678 -279.286805) (xy 115.632382 -279.233578)
			(xy 115.623624 -279.178301) (xy 115.623086 -279.150318) (xy 115.623534 -279.124941) (xy 115.630738 -279.0747)
			(xy 115.645001 -279.025991) (xy 115.666037 -278.9798) (xy 115.693417 -278.937064) (xy 115.726587 -278.898649)
			(xy 115.764876 -278.865332) (xy 115.807507 -278.837789) (xy 115.83035 -278.826722) (xy 115.842869 -278.820468)
			(xy 115.864148 -278.802307) (xy 115.879704 -278.779055) (xy 115.88837 -278.752456) (xy 115.889498 -278.724503)
			(xy 115.883002 -278.697292) (xy 115.869369 -278.672863) (xy 115.859814 -278.662638) (xy 115.774978 -278.577802)
			(xy 115.739418 -278.608028) (xy 115.720041 -278.623881) (xy 115.67768 -278.650566) (xy 115.631999 -278.671053)
			(xy 115.583898 -278.68494) (xy 115.534327 -278.691952) (xy 115.509294 -278.692356) (xy 115.48131 -278.691807)
			(xy 115.426031 -278.683051) (xy 115.372801 -278.665757) (xy 115.322932 -278.640349) (xy 115.277652 -278.607454)
			(xy 115.238074 -278.56788) (xy 115.205173 -278.522603) (xy 115.179759 -278.472738) (xy 115.162459 -278.41951)
			(xy 115.153697 -278.364232) (xy 115.153186 -278.336248) (xy 115.153614 -278.311217) (xy 115.16063 -278.26165)
			(xy 115.174518 -278.213554) (xy 115.195002 -278.167876) (xy 115.22168 -278.125515) (xy 115.237514 -278.106124)
			(xy 115.26774 -278.070564) (xy 115.0747 -277.877524) (xy 115.052602 -277.878286) (xy 115.039394 -277.87854)
			(xy 115.01141 -277.877991) (xy 114.956132 -277.869235) (xy 114.902904 -277.85194) (xy 114.853036 -277.826532)
			(xy 114.807757 -277.793637) (xy 114.76818 -277.754063) (xy 114.735281 -277.708786) (xy 114.70987 -277.65892)
			(xy 114.692571 -277.605693) (xy 114.683811 -277.550416) (xy 114.683286 -277.522432) (xy 114.68354 -277.509224)
			(xy 114.684302 -277.487126) (xy 114.41811 -277.220934) (xy 114.386868 -277.220934) (xy 114.0079 -276.841966)
			(xy 114.0079 -276.240748) (xy 113.97488 -276.228302) (xy 113.949771 -276.218364) (xy 113.902642 -276.192005)
			(xy 113.860032 -276.158833) (xy 113.822919 -276.119609) (xy 113.792153 -276.075232) (xy 113.76844 -276.026718)
			(xy 113.752322 -275.97518) (xy 113.744169 -275.9218) (xy 113.744169 -275.8678) (xy 113.752322 -275.81442)
			(xy 113.76844 -275.762882) (xy 113.792153 -275.714368) (xy 113.822919 -275.669991) (xy 113.860032 -275.630767)
			(xy 113.902642 -275.597595) (xy 113.949771 -275.571236) (xy 113.97488 -275.561298) (xy 114.0079 -275.548852)
			(xy 114.0079 -275.445474) (xy 114.007438 -275.431345) (xy 113.999695 -275.404168) (xy 113.984806 -275.38015)
			(xy 113.963911 -275.361126) (xy 113.938606 -275.34855) (xy 113.910824 -275.343382) (xy 113.882689 -275.346017)
			(xy 113.856351 -275.356255) (xy 113.844832 -275.364448) (xy 113.821474 -275.381469) (xy 113.770398 -275.40851)
			(xy 113.715624 -275.426942) (xy 113.65859 -275.436281) (xy 113.629694 -275.436838) (xy 113.603043 -275.43634)
			(xy 113.550336 -275.428395) (xy 113.499401 -275.412683) (xy 113.451378 -275.389555) (xy 113.407337 -275.359528)
			(xy 113.368264 -275.323273) (xy 113.335031 -275.281599) (xy 113.30838 -275.235438) (xy 113.288907 -275.18582)
			(xy 113.277046 -275.133853) (xy 113.273062 -275.0807) (xy 113.277046 -275.027547) (xy 113.288907 -274.97558)
			(xy 113.30838 -274.925962) (xy 113.335031 -274.879801) (xy 113.368264 -274.838127) (xy 113.407337 -274.801872)
			(xy 113.451378 -274.771845) (xy 113.499401 -274.748717) (xy 113.550336 -274.733005) (xy 113.603043 -274.72506)
			(xy 113.629694 -274.724622) (xy 113.65859 -274.725185) (xy 113.715623 -274.734522) (xy 113.770398 -274.752952)
			(xy 113.821475 -274.77999) (xy 113.844832 -274.797012) (xy 113.856367 -274.805196) (xy 113.882705 -274.815472)
			(xy 113.910851 -274.818133) (xy 113.938648 -274.812977) (xy 113.963967 -274.800397) (xy 113.984868 -274.781358)
			(xy 113.999748 -274.75732) (xy 114.007468 -274.730122) (xy 114.0079 -274.715986) (xy 114.0079 -274.612862)
			(xy 113.97488 -274.600416) (xy 113.949761 -274.590484) (xy 113.902611 -274.564137) (xy 113.859979 -274.530972)
			(xy 113.822843 -274.491752) (xy 113.792054 -274.447374) (xy 113.768317 -274.398856) (xy 113.752178 -274.347311)
			(xy 113.744007 -274.29392) (xy 113.743486 -274.266914) (xy 113.744005 -274.238928) (xy 113.752759 -274.183644)
			(xy 113.770054 -274.13041) (xy 113.795463 -274.080538) (xy 113.828361 -274.035254) (xy 113.867939 -273.995674)
			(xy 113.913221 -273.962773) (xy 113.963092 -273.937361) (xy 114.016325 -273.920064) (xy 114.071608 -273.911307)
			(xy 114.099594 -273.910806) (xy 114.125683 -273.911258) (xy 114.177303 -273.918874) (xy 114.227253 -273.933958)
			(xy 114.27446 -273.956186) (xy 114.296444 -273.970242) (xy 114.331242 -273.993102) (xy 114.406426 -273.917918)
			(xy 114.417015 -273.906649) (xy 114.431438 -273.879315) (xy 114.437019 -273.848916) (xy 114.433244 -273.818241)
			(xy 114.42046 -273.790102) (xy 114.39984 -273.76708) (xy 114.386868 -273.75866) (xy 114.364561 -273.744795)
			(xy 114.323913 -273.711536) (xy 114.288595 -273.672664) (xy 114.259373 -273.629023) (xy 114.236882 -273.581561)
			(xy 114.221612 -273.531309) (xy 114.213893 -273.479358) (xy 114.213386 -273.453098) (xy 114.213935 -273.425115)
			(xy 114.22269 -273.369838) (xy 114.239985 -273.31661) (xy 114.265393 -273.266744) (xy 114.298289 -273.221466)
			(xy 114.337863 -273.181892) (xy 114.383141 -273.148995) (xy 114.433007 -273.123587) (xy 114.486234 -273.106291)
			(xy 114.541511 -273.097535) (xy 114.569494 -273.09699) (xy 114.597093 -273.097509) (xy 114.651631 -273.106027)
			(xy 114.7042 -273.122862) (xy 114.753541 -273.147608) (xy 114.798471 -273.179673) (xy 114.837914 -273.218288)
			(xy 114.870924 -273.262529) (xy 114.89671 -273.311334) (xy 114.914654 -273.363535) (xy 114.920014 -273.390614)
			(xy 114.927634 -273.432524) (xy 115.151154 -273.432524) (xy 115.158774 -273.390614) (xy 115.163816 -273.364958)
			(xy 115.180421 -273.315379) (xy 115.204099 -273.268761) (xy 115.23434 -273.226108) (xy 115.270494 -273.188337)
			(xy 115.311783 -273.156259) (xy 115.35732 -273.130564) (xy 115.406125 -273.111806) (xy 115.457149 -273.100387)
			(xy 115.509294 -273.096553) (xy 115.561439 -273.100387) (xy 115.612463 -273.111806) (xy 115.661268 -273.130564)
			(xy 115.706805 -273.156259) (xy 115.748094 -273.188337) (xy 115.784248 -273.226108) (xy 115.814489 -273.268761)
			(xy 115.838167 -273.315379) (xy 115.854772 -273.364958) (xy 115.859814 -273.390614) (xy 115.867434 -273.432524)
			(xy 116.091208 -273.432524) (xy 116.098828 -273.390614) (xy 116.10387 -273.364958) (xy 116.120475 -273.315379)
			(xy 116.144153 -273.268761) (xy 116.174394 -273.226108) (xy 116.210548 -273.188337) (xy 116.251837 -273.156259)
			(xy 116.297374 -273.130564) (xy 116.346179 -273.111806) (xy 116.397203 -273.100387) (xy 116.449348 -273.096553)
			(xy 116.501493 -273.100387) (xy 116.552517 -273.111806) (xy 116.601322 -273.130564) (xy 116.646859 -273.156259)
			(xy 116.688148 -273.188337) (xy 116.724302 -273.226108) (xy 116.754543 -273.268761) (xy 116.778221 -273.315379)
			(xy 116.794826 -273.364958) (xy 116.799868 -273.390614) (xy 116.807488 -273.432524) (xy 117.031008 -273.432524)
			(xy 117.038628 -273.390614) (xy 117.043987 -273.363537) (xy 117.061949 -273.311348) (xy 117.087747 -273.262554)
			(xy 117.120761 -273.218323) (xy 117.160203 -273.179713) (xy 117.205128 -273.14765) (xy 117.254461 -273.122899)
			(xy 117.307022 -273.106054) (xy 117.361551 -273.097517) (xy 117.389148 -273.09699) (xy 117.417477 -273.097533)
			(xy 117.473423 -273.106491) (xy 117.527246 -273.12419) (xy 117.57759 -273.150184) (xy 117.623186 -273.183818)
			(xy 117.643402 -273.20367) (xy 117.65308 -273.212927) (xy 117.676172 -273.226474) (xy 117.70199 -273.23356)
			(xy 117.728763 -273.233699) (xy 117.754653 -273.22688) (xy 117.777884 -273.213572) (xy 117.787674 -273.204432)
			(xy 117.833648 -273.158458) (xy 117.842978 -273.148512) (xy 117.856468 -273.124822) (xy 117.863208 -273.098407)
			(xy 117.862717 -273.071151) (xy 117.855031 -273.044995) (xy 117.840697 -273.021807) (xy 117.820738 -273.003238)
			(xy 117.796577 -272.990613) (xy 117.783356 -272.987262) (xy 117.757204 -272.981093) (xy 117.706998 -272.961951)
			(xy 117.660237 -272.935485) (xy 117.617982 -272.902295) (xy 117.581192 -272.863134) (xy 117.550703 -272.818891)
			(xy 117.527206 -272.77057) (xy 117.511235 -272.719267) (xy 117.503151 -272.666148) (xy 117.502686 -272.639282)
			(xy 117.503236 -272.6113) (xy 117.511994 -272.556024) (xy 117.52929 -272.502799) (xy 117.554699 -272.452935)
			(xy 117.587595 -272.407659) (xy 117.627169 -272.368087) (xy 117.672445 -272.335192) (xy 117.72231 -272.309785)
			(xy 117.775536 -272.292491) (xy 117.830812 -272.283735) (xy 117.858794 -272.283174) (xy 117.887849 -272.283749)
			(xy 117.945189 -272.293185) (xy 118.000235 -272.311808) (xy 118.051526 -272.339123) (xy 118.074948 -272.356326)
			(xy 118.086473 -272.364559) (xy 118.112818 -272.374928) (xy 118.140997 -272.377669) (xy 118.168846 -272.37257)
			(xy 118.194226 -272.360023) (xy 118.215188 -272.340992) (xy 118.230122 -272.316939) (xy 118.23788 -272.28971)
			(xy 118.23827 -272.275554) (xy 118.23827 -272.171414) (xy 118.204996 -272.159222) (xy 118.179755 -272.149356)
			(xy 118.132353 -272.12309) (xy 118.089479 -272.089944) (xy 118.052122 -272.050685) (xy 118.021146 -272.006218)
			(xy 117.997265 -271.957571) (xy 117.981031 -271.905867) (xy 117.972818 -271.8523) (xy 117.972818 -271.798108)
			(xy 117.981029 -271.744541) (xy 117.997262 -271.692837) (xy 118.021141 -271.644189) (xy 118.052117 -271.599722)
			(xy 118.089473 -271.560462) (xy 118.132346 -271.527315) (xy 118.179747 -271.501047) (xy 118.204996 -271.491202)
			(xy 118.23827 -271.47901) (xy 118.23827 -271.375124) (xy 118.237798 -271.360981) (xy 118.230024 -271.333783)
			(xy 118.215091 -271.309759) (xy 118.194144 -271.290749) (xy 118.168788 -271.278209) (xy 118.140966 -271.273101)
			(xy 118.11281 -271.275815) (xy 118.086476 -271.286144) (xy 118.074948 -271.294352) (xy 118.051517 -271.311542)
			(xy 118.000232 -271.338865) (xy 117.945188 -271.357489) (xy 117.887849 -271.366917) (xy 117.858794 -271.367504)
			(xy 117.832145 -271.367006) (xy 117.779443 -271.359062) (xy 117.728514 -271.343351) (xy 117.680495 -271.320226)
			(xy 117.636459 -271.290202) (xy 117.597389 -271.25395) (xy 117.564159 -271.21228) (xy 117.537511 -271.166123)
			(xy 117.518039 -271.11651) (xy 117.506179 -271.064548) (xy 117.502196 -271.0114) (xy 117.506179 -270.958252)
			(xy 117.518039 -270.90629) (xy 117.537511 -270.856677) (xy 117.564159 -270.81052) (xy 117.597389 -270.76885)
			(xy 117.636459 -270.732598) (xy 117.680495 -270.702574) (xy 117.728514 -270.679449) (xy 117.779443 -270.663738)
			(xy 117.832145 -270.655794) (xy 117.858794 -270.655288) (xy 117.887849 -270.655863) (xy 117.945189 -270.6653)
			(xy 118.000234 -270.683923) (xy 118.051525 -270.711239) (xy 118.074948 -270.72844) (xy 118.086474 -270.736672)
			(xy 118.112819 -270.74704) (xy 118.140999 -270.74978) (xy 118.168848 -270.744681) (xy 118.194229 -270.732134)
			(xy 118.215192 -270.713104) (xy 118.230128 -270.689052) (xy 118.237889 -270.661824) (xy 118.23827 -270.647668)
			(xy 118.23827 -270.543782) (xy 118.20525 -270.53159) (xy 118.180025 -270.521711) (xy 118.132657 -270.495427)
			(xy 118.089816 -270.462271) (xy 118.05249 -270.42301) (xy 118.021541 -270.378549) (xy 117.997682 -270.329914)
			(xy 117.981464 -270.278227) (xy 117.973261 -270.224679) (xy 117.973262 -270.170507) (xy 117.981468 -270.11696)
			(xy 117.997687 -270.065273) (xy 118.021548 -270.016639) (xy 118.052499 -269.972179) (xy 118.089826 -269.932919)
			(xy 118.132668 -269.899766) (xy 118.180037 -269.873483) (xy 118.20525 -269.86357) (xy 118.23827 -269.851378)
			(xy 118.23827 -269.747492) (xy 118.237807 -269.733342) (xy 118.230043 -269.706127) (xy 118.215112 -269.682085)
			(xy 118.194161 -269.66306) (xy 118.168794 -269.650511) (xy 118.140959 -269.645401) (xy 118.112789 -269.64812)
			(xy 118.086446 -269.658461) (xy 118.074948 -269.66672) (xy 118.05153 -269.683855) (xy 118.000292 -269.711085)
			(xy 117.945317 -269.729647) (xy 117.88806 -269.739048) (xy 117.859048 -269.739618) (xy 117.832394 -269.739148)
			(xy 117.77968 -269.731209) (xy 117.728738 -269.715502) (xy 117.680707 -269.692377) (xy 117.636659 -269.662351)
			(xy 117.597578 -269.626095) (xy 117.564339 -269.584419) (xy 117.537683 -269.538254) (xy 117.518205 -269.488631)
			(xy 117.506342 -269.436659) (xy 117.502358 -269.3835) (xy 117.506342 -269.330341) (xy 117.518205 -269.278369)
			(xy 117.537683 -269.228746) (xy 117.564339 -269.182581) (xy 117.597578 -269.140905) (xy 117.636659 -269.104649)
			(xy 117.680707 -269.074623) (xy 117.728738 -269.051498) (xy 117.77968 -269.035791) (xy 117.832394 -269.027852)
			(xy 117.859048 -269.027402) (xy 117.888059 -269.027977) (xy 117.945311 -269.037388) (xy 118.000282 -269.055954)
			(xy 118.051517 -269.083184) (xy 118.074948 -269.1003) (xy 118.086472 -269.108535) (xy 118.112815 -269.118906)
			(xy 118.140993 -269.121648) (xy 118.168842 -269.116549) (xy 118.194221 -269.104001) (xy 118.215181 -269.084969)
			(xy 118.23011 -269.060914) (xy 118.237863 -269.033684) (xy 118.23827 -269.019528) (xy 118.23827 -268.915896)
			(xy 118.20525 -268.903704) (xy 118.180023 -268.893825) (xy 118.132653 -268.86754) (xy 118.08981 -268.834384)
			(xy 118.052483 -268.795122) (xy 118.021532 -268.75066) (xy 117.997672 -268.702023) (xy 117.981453 -268.650334)
			(xy 117.973249 -268.596785) (xy 117.973249 -268.542611) (xy 117.981454 -268.489062) (xy 117.997673 -268.437373)
			(xy 118.021534 -268.388736) (xy 118.052486 -268.344275) (xy 118.089814 -268.305013) (xy 118.132657 -268.271857)
			(xy 118.180027 -268.245573) (xy 118.20525 -268.235684) (xy 118.23827 -268.223492) (xy 118.23827 -268.119606)
			(xy 118.237809 -268.105454) (xy 118.230047 -268.078236) (xy 118.215117 -268.05419) (xy 118.194164 -268.035163)
			(xy 118.168796 -268.022612) (xy 118.140957 -268.0175) (xy 118.112785 -268.020221) (xy 118.08644 -268.030565)
			(xy 118.074948 -268.038834) (xy 118.051517 -268.056024) (xy 118.000233 -268.083349) (xy 117.945189 -268.101974)
			(xy 117.887849 -268.111403) (xy 117.858794 -268.111986) (xy 117.832147 -268.111487) (xy 117.779447 -268.103544)
			(xy 117.728521 -268.087834) (xy 117.680504 -268.06471) (xy 117.63647 -268.034687) (xy 117.597403 -267.998437)
			(xy 117.564174 -267.95677) (xy 117.537527 -267.910615) (xy 117.518057 -267.861004) (xy 117.506198 -267.809046)
			(xy 117.502215 -267.7559) (xy 117.506198 -267.702754) (xy 117.518057 -267.650796) (xy 117.537527 -267.601185)
			(xy 117.564174 -267.55503) (xy 117.597403 -267.513363) (xy 117.63647 -267.477113) (xy 117.680504 -267.44709)
			(xy 117.728521 -267.423966) (xy 117.779447 -267.408256) (xy 117.832147 -267.400313) (xy 117.858794 -267.39977)
			(xy 117.887849 -267.400345) (xy 117.945189 -267.409781) (xy 118.000235 -267.428404) (xy 118.051526 -267.455719)
			(xy 118.074948 -267.472922) (xy 118.086473 -267.481155) (xy 118.112817 -267.491525) (xy 118.140996 -267.494266)
			(xy 118.168845 -267.489166) (xy 118.194225 -267.47662) (xy 118.215187 -267.457588) (xy 118.23012 -267.433535)
			(xy 118.237877 -267.406306) (xy 118.23827 -267.39215) (xy 118.23827 -267.28801) (xy 118.204996 -267.275818)
			(xy 118.179755 -267.265952) (xy 118.132354 -267.239686) (xy 118.08948 -267.20654) (xy 118.052124 -267.167281)
			(xy 118.021148 -267.122815) (xy 117.997268 -267.074168) (xy 117.981034 -267.022465) (xy 117.972822 -266.968899)
			(xy 117.972822 -266.914707) (xy 117.981033 -266.861141) (xy 117.997266 -266.809437) (xy 118.021145 -266.76079)
			(xy 118.052121 -266.716323) (xy 118.089476 -266.677063) (xy 118.132349 -266.643917) (xy 118.17975 -266.61765)
			(xy 118.204996 -266.607798) (xy 118.23827 -266.595606) (xy 118.23827 -266.491974) (xy 118.237805 -266.477826)
			(xy 118.230038 -266.450615) (xy 118.215107 -266.426578) (xy 118.194156 -266.407557) (xy 118.168793 -266.395011)
			(xy 118.140961 -266.389901) (xy 118.112795 -266.392619) (xy 118.086454 -266.402957) (xy 118.074948 -266.411202)
			(xy 118.051516 -266.428389) (xy 118.00023 -266.455709) (xy 117.945187 -266.47433) (xy 117.887848 -266.483757)
			(xy 117.858794 -266.484354) (xy 117.832142 -266.483856) (xy 117.779432 -266.47591) (xy 117.728496 -266.460198)
			(xy 117.68047 -266.437069) (xy 117.636427 -266.407041) (xy 117.597353 -266.370784) (xy 117.564118 -266.329108)
			(xy 117.537466 -266.282945) (xy 117.517991 -266.233324) (xy 117.50613 -266.181356) (xy 117.502146 -266.1282)
			(xy 117.50613 -266.075044) (xy 117.517991 -266.023076) (xy 117.537466 -265.973455) (xy 117.564118 -265.927292)
			(xy 117.597353 -265.885616) (xy 117.636427 -265.849359) (xy 117.68047 -265.819331) (xy 117.728496 -265.796202)
			(xy 117.779432 -265.78049) (xy 117.832142 -265.772544) (xy 117.858794 -265.772138) (xy 117.887849 -265.772713)
			(xy 117.945188 -265.782151) (xy 118.000232 -265.800777) (xy 118.05152 -265.828096) (xy 118.074948 -265.84529)
			(xy 118.086471 -265.853525) (xy 118.112814 -265.863898) (xy 118.140992 -265.86664) (xy 118.16884 -265.861541)
			(xy 118.194219 -265.848993) (xy 118.215178 -265.82996) (xy 118.230106 -265.805904) (xy 118.237856 -265.778674)
			(xy 118.23827 -265.764518) (xy 118.23827 -265.660378) (xy 118.204996 -265.648186) (xy 118.179774 -265.638305)
			(xy 118.132413 -265.612016) (xy 118.089579 -265.578858) (xy 118.05226 -265.539596) (xy 118.021316 -265.495137)
			(xy 117.997462 -265.446504) (xy 117.981247 -265.394819) (xy 117.973046 -265.341276) (xy 117.973047 -265.287108)
			(xy 117.981251 -265.233564) (xy 117.997468 -265.181881) (xy 118.021325 -265.133249) (xy 118.05227 -265.088791)
			(xy 118.089591 -265.049531) (xy 118.132427 -265.016375) (xy 118.179789 -264.990088) (xy 118.204996 -264.980166)
			(xy 118.23827 -264.967974) (xy 118.23827 -264.864088) (xy 118.237806 -264.849938) (xy 118.230042 -264.822724)
			(xy 118.215111 -264.798684) (xy 118.19416 -264.77966) (xy 118.168794 -264.767111) (xy 118.140959 -264.762001)
			(xy 118.11279 -264.76472) (xy 118.086447 -264.77506) (xy 118.074948 -264.783316) (xy 118.051517 -264.800507)
			(xy 118.000233 -264.827833) (xy 117.945189 -264.846459) (xy 117.887849 -264.855889) (xy 117.858794 -264.856468)
			(xy 117.832148 -264.85597) (xy 117.779451 -264.848026) (xy 117.728527 -264.832317) (xy 117.680513 -264.809194)
			(xy 117.636481 -264.779173) (xy 117.597416 -264.742925) (xy 117.564189 -264.701259) (xy 117.537543 -264.655107)
			(xy 117.518074 -264.605499) (xy 117.506215 -264.553543) (xy 117.502233 -264.5004) (xy 117.506215 -264.447257)
			(xy 117.518074 -264.395301) (xy 117.537543 -264.345693) (xy 117.564189 -264.299541) (xy 117.597416 -264.257875)
			(xy 117.636481 -264.221627) (xy 117.680513 -264.191606) (xy 117.728527 -264.168483) (xy 117.779451 -264.152774)
			(xy 117.832148 -264.14483) (xy 117.858794 -264.144252) (xy 117.884863 -264.1447) (xy 117.936445 -264.152293)
			(xy 117.986367 -264.167331) (xy 118.03356 -264.189492) (xy 118.077014 -264.218303) (xy 118.115799 -264.253146)
			(xy 118.149084 -264.293276) (xy 118.176158 -264.337833) (xy 118.186708 -264.361676) (xy 118.192656 -264.374643)
			(xy 118.21052 -264.396872) (xy 118.233841 -264.413285) (xy 118.260794 -264.422599) (xy 118.289272 -264.424087)
			(xy 118.317048 -264.417631) (xy 118.341952 -264.403737) (xy 118.352316 -264.393934) (xy 118.872 -263.87425)
			(xy 118.881918 -263.863624) (xy 118.895876 -263.838143) (xy 118.902096 -263.809764) (xy 118.900077 -263.780781)
			(xy 118.889982 -263.753538) (xy 118.872627 -263.730238) (xy 118.861332 -263.721088) (xy 118.83517 -263.70153)
			(xy 118.81104 -263.708388) (xy 118.787099 -263.71478) (xy 118.738026 -263.721661) (xy 118.71325 -263.722104)
			(xy 118.712488 -263.722104) (xy 118.68584 -263.721606) (xy 118.633138 -263.71366) (xy 118.58221 -263.697949)
			(xy 118.534191 -263.674824) (xy 118.490156 -263.6448) (xy 118.451087 -263.608548) (xy 118.417858 -263.566878)
			(xy 118.39121 -263.520721) (xy 118.371739 -263.471109) (xy 118.359879 -263.419148) (xy 118.355896 -263.366)
			(xy 118.359879 -263.312852) (xy 118.371739 -263.260891) (xy 118.39121 -263.211279) (xy 118.417858 -263.165122)
			(xy 118.451087 -263.123452) (xy 118.490156 -263.0872) (xy 118.534191 -263.057176) (xy 118.58221 -263.034051)
			(xy 118.633138 -263.01834) (xy 118.68584 -263.010394) (xy 118.712488 -263.009888) (xy 118.71325 -263.009888)
			(xy 118.738027 -263.010316) (xy 118.7871 -263.017203) (xy 118.81104 -263.023604) (xy 118.83517 -263.030462)
			(xy 118.940326 -262.951468) (xy 118.940326 -260.518148) (xy 120.070372 -259.388102) (xy 120.070372 -258.052824)
			(xy 120.0699 -258.0386) (xy 120.062049 -258.011256) (xy 120.046951 -257.987144) (xy 120.025781 -257.96814)
			(xy 120.000185 -257.955723) (xy 119.972156 -257.950858) (xy 119.943873 -257.953925) (xy 119.917537 -257.964683)
			(xy 119.906034 -257.973068) (xy 119.882321 -257.990948) (xy 119.830193 -258.019394) (xy 119.774071 -258.038808)
			(xy 119.715508 -258.048652) (xy 119.685816 -258.049268) (xy 119.661182 -258.048852) (xy 119.612383 -258.042064)
			(xy 119.564986 -258.028614) (xy 119.519895 -258.00876) (xy 119.477971 -257.982881) (xy 119.45874 -257.96748)
			(xy 119.447525 -257.958867) (xy 119.4216 -257.947599) (xy 119.393581 -257.943861) (xy 119.365609 -257.947938)
			(xy 119.339823 -257.959519) (xy 119.328692 -257.968242) (xy 119.309341 -257.983962) (xy 119.267079 -258.010408)
			(xy 119.221545 -258.030709) (xy 119.173626 -258.044469) (xy 119.124257 -258.051418) (xy 119.09933 -258.051808)
			(xy 119.070156 -258.051227) (xy 119.012586 -258.041725) (xy 118.957334 -258.02297) (xy 118.905876 -257.995464)
			(xy 118.859588 -257.959941) (xy 118.839234 -257.939032) (xy 118.829458 -257.929271) (xy 118.805871 -257.914912)
			(xy 118.779301 -257.907391) (xy 118.751687 -257.907256) (xy 118.725045 -257.914518) (xy 118.701319 -257.928646)
			(xy 118.691406 -257.93827) (xy 118.671089 -257.958857) (xy 118.625017 -257.993821) (xy 118.573901 -258.020881)
			(xy 118.519084 -258.039326) (xy 118.462007 -258.04867) (xy 118.433088 -258.049268) (xy 118.407149 -258.048826)
			(xy 118.355814 -258.041343) (xy 118.306111 -258.02648) (xy 118.259096 -258.004552) (xy 118.215766 -257.976024)
			(xy 118.196106 -257.959098) (xy 118.184712 -257.94961) (xy 118.157864 -257.937061) (xy 118.128542 -257.932757)
			(xy 118.09922 -257.937061) (xy 118.072372 -257.94961) (xy 118.060978 -257.959098) (xy 118.041291 -257.975987)
			(xy 117.997952 -258.004481) (xy 117.950941 -258.026396) (xy 117.901251 -258.041267) (xy 117.84993 -258.048782)
			(xy 117.823996 -258.049268) (xy 117.79735 -258.04877) (xy 117.744653 -258.040826) (xy 117.693729 -258.025118)
			(xy 117.645714 -258.001995) (xy 117.601682 -257.971974) (xy 117.562617 -257.935726) (xy 117.52939 -257.89406)
			(xy 117.502744 -257.847908) (xy 117.483274 -257.798299) (xy 117.471416 -257.746343) (xy 117.467433 -257.6932)
			(xy 117.471416 -257.640057) (xy 117.483274 -257.588101) (xy 117.502744 -257.538492) (xy 117.52939 -257.49234)
			(xy 117.562617 -257.450674) (xy 117.601682 -257.414426) (xy 117.645714 -257.384405) (xy 117.693729 -257.361282)
			(xy 117.744653 -257.345574) (xy 117.79735 -257.33763) (xy 117.823996 -257.337052) (xy 117.849933 -257.3375)
			(xy 117.901262 -257.344994) (xy 117.950957 -257.359867) (xy 117.997963 -257.381804) (xy 118.041282 -257.410339)
			(xy 118.060978 -257.427222) (xy 118.072372 -257.43671) (xy 118.09922 -257.449259) (xy 118.128542 -257.453563)
			(xy 118.157864 -257.449259) (xy 118.184712 -257.43671) (xy 118.196106 -257.427222) (xy 118.215792 -257.410332)
			(xy 118.259131 -257.381833) (xy 118.306141 -257.359916) (xy 118.355832 -257.345041) (xy 118.407153 -257.337523)
			(xy 118.433088 -257.337052) (xy 118.462261 -257.337635) (xy 118.519828 -257.347141) (xy 118.575076 -257.3659)
			(xy 118.626529 -257.393411) (xy 118.672811 -257.428939) (xy 118.693184 -257.449828) (xy 118.702963 -257.459595)
			(xy 118.726557 -257.473967) (xy 118.753136 -257.481503) (xy 118.780762 -257.481653) (xy 118.807422 -257.474406)
			(xy 118.831171 -257.460291) (xy 118.841012 -257.45059) (xy 118.861326 -257.429995) (xy 118.907393 -257.395014)
			(xy 118.958508 -257.367938) (xy 119.013327 -257.349478) (xy 119.070408 -257.340119) (xy 119.09933 -257.339592)
			(xy 119.123963 -257.340011) (xy 119.172758 -257.346806) (xy 119.22015 -257.360263) (xy 119.265235 -257.380124)
			(xy 119.307152 -257.40601) (xy 119.326406 -257.42138) (xy 119.33762 -257.430004) (xy 119.363549 -257.44129)
			(xy 119.391577 -257.445043) (xy 119.419562 -257.440974) (xy 119.445361 -257.429395) (xy 119.456454 -257.420618)
			(xy 119.475806 -257.404902) (xy 119.51807 -257.378464) (xy 119.563605 -257.358172) (xy 119.611523 -257.34442)
			(xy 119.66089 -257.337477) (xy 119.685816 -257.337052) (xy 119.715509 -257.337647) (xy 119.774072 -257.347497)
			(xy 119.830191 -257.366921) (xy 119.882312 -257.395382) (xy 119.906034 -257.413252) (xy 119.917507 -257.421668)
			(xy 119.943848 -257.432393) (xy 119.972127 -257.435435) (xy 120.000147 -257.430558) (xy 120.025734 -257.418139)
			(xy 120.046902 -257.399144) (xy 120.062008 -257.375046) (xy 120.06988 -257.347716) (xy 120.070372 -257.333496)
			(xy 120.070372 -247.053862) (xy 120.069849 -247.038563) (xy 120.06079 -247.009337) (xy 120.043493 -246.984097)
			(xy 120.019506 -246.965101) (xy 119.990974 -246.954049) (xy 119.960449 -246.951928) (xy 119.930663 -246.958928)
			(xy 119.91721 -246.966232) (xy 119.896607 -246.977926) (xy 119.852964 -246.996353) (xy 119.807259 -247.008819)
			(xy 119.760303 -247.015102) (xy 119.736616 -247.015508) (xy 119.709291 -247.015033) (xy 119.655277 -247.00672)
			(xy 119.603171 -246.990241) (xy 119.554199 -246.965985) (xy 119.509515 -246.934522) (xy 119.489474 -246.91594)
			(xy 119.477852 -246.905543) (xy 119.449918 -246.891719) (xy 119.419116 -246.886963) (xy 119.388314 -246.891719)
			(xy 119.36038 -246.905543) (xy 119.348758 -246.91594) (xy 119.328706 -246.934504) (xy 119.284007 -246.965932)
			(xy 119.235035 -246.990171) (xy 119.182939 -247.006654) (xy 119.128937 -247.014995) (xy 119.101616 -247.015508)
			(xy 119.072442 -247.014926) (xy 119.014874 -247.005422) (xy 118.959624 -246.986665) (xy 118.908167 -246.959158)
			(xy 118.86188 -246.923634) (xy 118.84152 -246.902732) (xy 118.831695 -246.892914) (xy 118.807969 -246.878497)
			(xy 118.781234 -246.871011) (xy 118.75347 -246.871011) (xy 118.726735 -246.878497) (xy 118.703009 -246.892914)
			(xy 118.693184 -246.902732) (xy 118.672818 -246.923629) (xy 118.626532 -246.959156) (xy 118.575078 -246.98667)
			(xy 118.519829 -247.005436) (xy 118.462262 -247.014954) (xy 118.433088 -247.015508) (xy 118.407752 -247.01506)
			(xy 118.357593 -247.007874) (xy 118.308959 -246.993648) (xy 118.262834 -246.972669) (xy 118.22015 -246.945363)
			(xy 118.200678 -246.929148) (xy 118.189094 -246.919861) (xy 118.161984 -246.907785) (xy 118.13255 -246.903988)
			(xy 118.103263 -246.908788) (xy 118.076581 -246.921784) (xy 118.065296 -246.931434) (xy 118.045459 -246.949052)
			(xy 118.001545 -246.978821) (xy 117.953702 -247.001749) (xy 117.902987 -247.017326) (xy 117.850523 -247.025209)
			(xy 117.823996 -247.025668) (xy 117.79735 -247.02517) (xy 117.744653 -247.017226) (xy 117.693729 -247.001518)
			(xy 117.645714 -246.978395) (xy 117.601682 -246.948374) (xy 117.562617 -246.912126) (xy 117.52939 -246.87046)
			(xy 117.502744 -246.824308) (xy 117.483274 -246.774699) (xy 117.471416 -246.722743) (xy 117.467433 -246.6696)
			(xy 117.471416 -246.616457) (xy 117.483274 -246.564501) (xy 117.502744 -246.514892) (xy 117.52939 -246.46874)
			(xy 117.562617 -246.427074) (xy 117.601682 -246.390826) (xy 117.645714 -246.360805) (xy 117.693729 -246.337682)
			(xy 117.744653 -246.321974) (xy 117.79735 -246.31403) (xy 117.823996 -246.313452) (xy 117.849332 -246.313899)
			(xy 117.899491 -246.321084) (xy 117.948125 -246.335311) (xy 117.994249 -246.35629) (xy 118.036933 -246.383599)
			(xy 118.056406 -246.399812) (xy 118.067992 -246.409097) (xy 118.095104 -246.421171) (xy 118.124538 -246.424969)
			(xy 118.153827 -246.420174) (xy 118.180514 -246.407188) (xy 118.191788 -246.397526) (xy 118.211628 -246.379915)
			(xy 118.255544 -246.350159) (xy 118.303389 -246.327246) (xy 118.354103 -246.311682) (xy 118.406564 -246.303812)
			(xy 118.433088 -246.303292) (xy 118.462262 -246.303875) (xy 118.519829 -246.313379) (xy 118.575079 -246.332136)
			(xy 118.626535 -246.359644) (xy 118.672822 -246.395168) (xy 118.693184 -246.416068) (xy 118.703009 -246.425886)
			(xy 118.726735 -246.440303) (xy 118.75347 -246.447789) (xy 118.781234 -246.447789) (xy 118.807969 -246.440303)
			(xy 118.831695 -246.425886) (xy 118.84152 -246.416068) (xy 118.861886 -246.395171) (xy 118.908172 -246.359645)
			(xy 118.959627 -246.332131) (xy 119.014875 -246.313366) (xy 119.072442 -246.303849) (xy 119.101616 -246.303292)
			(xy 119.128943 -246.303762) (xy 119.182962 -246.312066) (xy 119.235075 -246.328537) (xy 119.284054 -246.352787)
			(xy 119.328746 -246.384246) (xy 119.348758 -246.40286) (xy 119.36038 -246.413257) (xy 119.388314 -246.427081)
			(xy 119.419116 -246.431837) (xy 119.449918 -246.427081) (xy 119.477852 -246.413257) (xy 119.489474 -246.40286)
			(xy 119.509527 -246.384298) (xy 119.554227 -246.352874) (xy 119.603199 -246.328639) (xy 119.655295 -246.312161)
			(xy 119.709296 -246.303825) (xy 119.736616 -246.303292) (xy 119.760302 -246.303699) (xy 119.807253 -246.310008)
			(xy 119.852956 -246.322472) (xy 119.896609 -246.340873) (xy 119.91721 -246.352568) (xy 119.930665 -246.359892)
			(xy 119.960466 -246.366928) (xy 119.991014 -246.364827) (xy 120.019571 -246.353776) (xy 120.043577 -246.334766)
			(xy 120.060878 -246.309502) (xy 120.069925 -246.280249) (xy 120.070372 -246.264938) (xy 120.070372 -239.716818)
			(xy 120.04675 -239.701832) (xy 119.990362 -239.666018) (xy 119.956326 -239.674654) (xy 119.950992 -239.677194)
			(xy 119.92344 -239.690642) (xy 119.865154 -239.709651) (xy 119.804608 -239.71928) (xy 119.773954 -239.719866)
			(xy 119.745695 -239.719365) (xy 119.689769 -239.711199) (xy 119.635613 -239.695031) (xy 119.584363 -239.671202)
			(xy 119.537099 -239.640211) (xy 119.515636 -239.621822) (xy 119.508439 -239.615977) (xy 119.491117 -239.609403)
			(xy 119.472591 -239.609403) (xy 119.455269 -239.615977) (xy 119.448072 -239.621822) (xy 119.426593 -239.640191)
			(xy 119.37933 -239.671178) (xy 119.328084 -239.695008) (xy 119.273932 -239.711181) (xy 119.218012 -239.719357)
			(xy 119.189754 -239.719866) (xy 119.163748 -239.719437) (xy 119.112199 -239.712522) (xy 119.062029 -239.698807)
			(xy 119.01413 -239.678536) (xy 118.969356 -239.652071) (xy 118.928503 -239.619881) (xy 118.9101 -239.601502)
			(xy 118.903041 -239.594808) (xy 118.885306 -239.586853) (xy 118.865883 -239.586082) (xy 118.847573 -239.592605)
			(xy 118.839996 -239.598708) (xy 118.818576 -239.61695) (xy 118.77147 -239.647712) (xy 118.720422 -239.671364)
			(xy 118.666498 -239.687411) (xy 118.610825 -239.695519) (xy 118.582694 -239.69599) (xy 118.554436 -239.695484)
			(xy 118.498515 -239.687311) (xy 118.444362 -239.671138) (xy 118.393118 -239.647304) (xy 118.345859 -239.61631)
			(xy 118.324376 -239.597946) (xy 118.317179 -239.592101) (xy 118.299857 -239.585527) (xy 118.281331 -239.585527)
			(xy 118.264009 -239.592101) (xy 118.256812 -239.597946) (xy 118.235329 -239.616305) (xy 118.18806 -239.647271)
			(xy 118.136814 -239.671084) (xy 118.082664 -239.687242) (xy 118.026748 -239.695406) (xy 117.97024 -239.695406)
			(xy 117.914324 -239.687242) (xy 117.860174 -239.671084) (xy 117.808928 -239.647271) (xy 117.761659 -239.616305)
			(xy 117.740176 -239.597946) (xy 117.732979 -239.592101) (xy 117.715657 -239.585527) (xy 117.697131 -239.585527)
			(xy 117.679809 -239.592101) (xy 117.672612 -239.597946) (xy 117.651134 -239.616316) (xy 117.603871 -239.647306)
			(xy 117.552625 -239.67114) (xy 117.498474 -239.687317) (xy 117.442552 -239.695498) (xy 117.414294 -239.69599)
			(xy 117.38648 -239.695494) (xy 117.331418 -239.687576) (xy 117.278044 -239.671903) (xy 117.227443 -239.648794)
			(xy 117.180646 -239.618719) (xy 117.138606 -239.58229) (xy 117.102178 -239.540249) (xy 117.072103 -239.493452)
			(xy 117.048995 -239.44285) (xy 117.033322 -239.389476) (xy 117.025406 -239.334414) (xy 117.025406 -239.278786)
			(xy 117.033322 -239.223724) (xy 117.048995 -239.17035) (xy 117.072103 -239.119748) (xy 117.102178 -239.072951)
			(xy 117.138606 -239.03091) (xy 117.180646 -238.994481) (xy 117.227443 -238.964406) (xy 117.278044 -238.941297)
			(xy 117.331418 -238.925624) (xy 117.38648 -238.917706) (xy 117.414294 -238.917226) (xy 117.442552 -238.917731)
			(xy 117.498474 -238.925903) (xy 117.552627 -238.942075) (xy 117.603872 -238.965909) (xy 117.651131 -238.996902)
			(xy 117.672612 -239.01527) (xy 117.679809 -239.021115) (xy 117.697131 -239.027689) (xy 117.715657 -239.027689)
			(xy 117.732979 -239.021115) (xy 117.740176 -239.01527) (xy 117.761659 -238.996911) (xy 117.808928 -238.965945)
			(xy 117.860174 -238.942132) (xy 117.914324 -238.925974) (xy 117.97024 -238.91781) (xy 118.026748 -238.91781)
			(xy 118.082664 -238.925974) (xy 118.136814 -238.942132) (xy 118.18806 -238.965945) (xy 118.235329 -238.996911)
			(xy 118.256812 -239.01527) (xy 118.264009 -239.021115) (xy 118.281331 -239.027689) (xy 118.299857 -239.027689)
			(xy 118.317179 -239.021115) (xy 118.324376 -239.01527) (xy 118.345854 -238.996898) (xy 118.393116 -238.965906)
			(xy 118.444361 -238.94207) (xy 118.498513 -238.92589) (xy 118.554435 -238.917706) (xy 118.582694 -238.917226)
			(xy 118.608698 -238.917658) (xy 118.660245 -238.924579) (xy 118.710411 -238.938299) (xy 118.758306 -238.958573)
			(xy 118.803075 -238.985041) (xy 118.843925 -239.017232) (xy 118.862348 -239.03559) (xy 118.869407 -239.042295)
			(xy 118.887149 -239.05027) (xy 118.906585 -239.051056) (xy 118.924913 -239.04454) (xy 118.932452 -239.038384)
			(xy 118.953873 -239.020145) (xy 119.00098 -238.989389) (xy 119.052029 -238.965744) (xy 119.105952 -238.949704)
			(xy 119.161625 -238.941603) (xy 119.189754 -238.941102) (xy 119.218013 -238.941604) (xy 119.273939 -238.94977)
			(xy 119.328095 -238.965938) (xy 119.379345 -238.989766) (xy 119.42661 -239.020756) (xy 119.448072 -239.039146)
			(xy 119.455269 -239.044991) (xy 119.472591 -239.051565) (xy 119.491117 -239.051565) (xy 119.508439 -239.044991)
			(xy 119.515636 -239.039146) (xy 119.537115 -239.020779) (xy 119.58438 -238.989796) (xy 119.635626 -238.965969)
			(xy 119.689777 -238.949798) (xy 119.745697 -238.941624) (xy 119.773954 -238.941102) (xy 119.801283 -238.941566)
			(xy 119.855405 -238.949209) (xy 119.907928 -238.964338) (xy 119.957823 -238.986657) (xy 119.981218 -239.000792)
			(xy 120.047766 -238.958374) (xy 120.070372 -238.942372) (xy 120.070372 -237.978696) (xy 120.055386 -237.96371)
			(xy 119.638318 -237.546642) (xy 119.623332 -237.531656) (xy 113.855754 -237.531656) (xy 113.846431 -237.556299)
			(xy 113.821565 -237.602749) (xy 113.790131 -237.645032) (xy 113.752812 -237.682224) (xy 113.710423 -237.713514)
			(xy 113.663888 -237.738221) (xy 113.614223 -237.755806) (xy 113.562509 -237.765884) (xy 113.509874 -237.768238)
			(xy 113.457467 -237.762814) (xy 113.40643 -237.749731) (xy 113.357876 -237.729275) (xy 113.312864 -237.701892)
			(xy 113.272376 -237.668179) (xy 113.237293 -237.62887) (xy 113.208383 -237.584824) (xy 113.196878 -237.56112)
			(xy 113.183162 -237.531656) (xy 112.915954 -237.531656) (xy 112.906631 -237.556299) (xy 112.881765 -237.602749)
			(xy 112.850331 -237.645032) (xy 112.813012 -237.682224) (xy 112.770623 -237.713514) (xy 112.724088 -237.738221)
			(xy 112.674423 -237.755806) (xy 112.622709 -237.765884) (xy 112.570074 -237.768238) (xy 112.517667 -237.762814)
			(xy 112.46663 -237.749731) (xy 112.418076 -237.729275) (xy 112.373064 -237.701892) (xy 112.332576 -237.668179)
			(xy 112.297493 -237.62887) (xy 112.268583 -237.584824) (xy 112.257078 -237.56112) (xy 112.243362 -237.531656)
			(xy 111.976154 -237.531656) (xy 111.966831 -237.556299) (xy 111.941965 -237.602749) (xy 111.910531 -237.645032)
			(xy 111.873212 -237.682224) (xy 111.830823 -237.713514) (xy 111.784288 -237.738221) (xy 111.734623 -237.755806)
			(xy 111.682909 -237.765884) (xy 111.630274 -237.768238) (xy 111.577867 -237.762814) (xy 111.52683 -237.749731)
			(xy 111.478276 -237.729275) (xy 111.433264 -237.701892) (xy 111.392776 -237.668179) (xy 111.357693 -237.62887)
			(xy 111.328783 -237.584824) (xy 111.317278 -237.56112) (xy 111.303562 -237.531656) (xy 111.036354 -237.531656)
			(xy 111.027031 -237.556299) (xy 111.002165 -237.602749) (xy 110.970731 -237.645032) (xy 110.933412 -237.682224)
			(xy 110.891023 -237.713514) (xy 110.844488 -237.738221) (xy 110.794823 -237.755806) (xy 110.743109 -237.765884)
			(xy 110.690474 -237.768238) (xy 110.638067 -237.762814) (xy 110.58703 -237.749731) (xy 110.538476 -237.729275)
			(xy 110.493464 -237.701892) (xy 110.452976 -237.668179) (xy 110.417893 -237.62887) (xy 110.388983 -237.584824)
			(xy 110.377478 -237.56112) (xy 110.363762 -237.531656) (xy 110.096554 -237.531656) (xy 110.087231 -237.556299)
			(xy 110.062365 -237.602749) (xy 110.030931 -237.645032) (xy 109.993612 -237.682224) (xy 109.951223 -237.713514)
			(xy 109.904688 -237.738221) (xy 109.855023 -237.755806) (xy 109.803309 -237.765884) (xy 109.750674 -237.768238)
			(xy 109.698267 -237.762814) (xy 109.64723 -237.749731) (xy 109.598676 -237.729275) (xy 109.553664 -237.701892)
			(xy 109.513176 -237.668179) (xy 109.478093 -237.62887) (xy 109.449183 -237.584824) (xy 109.437678 -237.56112)
			(xy 109.423962 -237.531656) (xy 109.075474 -237.531656) (xy 109.062774 -237.534958) (xy 109.041438 -237.540038)
			(xy 108.973366 -237.659164) (xy 108.988098 -237.68431) (xy 108.998598 -237.70305) (xy 109.015528 -237.74253)
			(xy 109.02188 -237.76305) (xy 109.024559 -237.772398) (xy 109.029006 -237.791332) (xy 109.03077 -237.800896)
			(xy 109.032802 -237.81131) (xy 109.056932 -237.847124) (xy 109.145324 -237.899956) (xy 109.168184 -237.891574)
			(xy 109.19783 -237.881401) (xy 109.259531 -237.87042) (xy 109.290866 -237.86973) (xy 109.29493 -237.86973)
			(xy 109.322705 -237.870578) (xy 109.377494 -237.879829) (xy 109.430182 -237.897479) (xy 109.479489 -237.923098)
			(xy 109.524218 -237.956065) (xy 109.563283 -237.995579) (xy 109.595737 -238.040682) (xy 109.620791 -238.090278)
			(xy 109.637838 -238.143164) (xy 109.646462 -238.198055) (xy 109.646974 -238.225838) (xy 109.646448 -238.252487)
			(xy 109.875056 -238.252487) (xy 109.875056 -238.199189) (xy 109.882999 -238.146485) (xy 109.898709 -238.095555)
			(xy 109.921835 -238.047534) (xy 109.951859 -238.003497) (xy 109.988111 -237.964426) (xy 110.029782 -237.931195)
			(xy 110.07594 -237.904546) (xy 110.125554 -237.885074) (xy 110.177516 -237.873214) (xy 110.230666 -237.869231)
			(xy 110.283816 -237.873214) (xy 110.335778 -237.885074) (xy 110.385392 -237.904546) (xy 110.43155 -237.931195)
			(xy 110.473221 -237.964426) (xy 110.509473 -238.003497) (xy 110.539497 -238.047534) (xy 110.562623 -238.095555)
			(xy 110.578333 -238.146485) (xy 110.586276 -238.199189) (xy 110.586774 -238.225838) (xy 110.586276 -238.252487)
			(xy 110.814856 -238.252487) (xy 110.814856 -238.199189) (xy 110.822799 -238.146485) (xy 110.838509 -238.095555)
			(xy 110.861635 -238.047534) (xy 110.891659 -238.003497) (xy 110.927911 -237.964426) (xy 110.969582 -237.931195)
			(xy 111.01574 -237.904546) (xy 111.065354 -237.885074) (xy 111.117316 -237.873214) (xy 111.170466 -237.869231)
			(xy 111.223616 -237.873214) (xy 111.275578 -237.885074) (xy 111.325192 -237.904546) (xy 111.37135 -237.931195)
			(xy 111.413021 -237.964426) (xy 111.449273 -238.003497) (xy 111.479297 -238.047534) (xy 111.502423 -238.095555)
			(xy 111.518133 -238.146485) (xy 111.526076 -238.199189) (xy 111.526574 -238.225838) (xy 111.526076 -238.252487)
			(xy 111.754656 -238.252487) (xy 111.754656 -238.199189) (xy 111.762599 -238.146485) (xy 111.778309 -238.095555)
			(xy 111.801435 -238.047534) (xy 111.831459 -238.003497) (xy 111.867711 -237.964426) (xy 111.909382 -237.931195)
			(xy 111.95554 -237.904546) (xy 112.005154 -237.885074) (xy 112.057116 -237.873214) (xy 112.110266 -237.869231)
			(xy 112.163416 -237.873214) (xy 112.215378 -237.885074) (xy 112.264992 -237.904546) (xy 112.31115 -237.931195)
			(xy 112.352821 -237.964426) (xy 112.389073 -238.003497) (xy 112.419097 -238.047534) (xy 112.442223 -238.095555)
			(xy 112.457933 -238.146485) (xy 112.465876 -238.199189) (xy 112.466374 -238.225838) (xy 112.465876 -238.252487)
			(xy 112.694456 -238.252487) (xy 112.694456 -238.199189) (xy 112.702399 -238.146485) (xy 112.718109 -238.095555)
			(xy 112.741235 -238.047534) (xy 112.771259 -238.003497) (xy 112.807511 -237.964426) (xy 112.849182 -237.931195)
			(xy 112.89534 -237.904546) (xy 112.944954 -237.885074) (xy 112.996916 -237.873214) (xy 113.050066 -237.869231)
			(xy 113.103216 -237.873214) (xy 113.155178 -237.885074) (xy 113.204792 -237.904546) (xy 113.25095 -237.931195)
			(xy 113.292621 -237.964426) (xy 113.328873 -238.003497) (xy 113.358897 -238.047534) (xy 113.382023 -238.095555)
			(xy 113.397733 -238.146485) (xy 113.405676 -238.199189) (xy 113.406174 -238.225838) (xy 113.405676 -238.252487)
			(xy 113.634256 -238.252487) (xy 113.634256 -238.199189) (xy 113.642199 -238.146485) (xy 113.657909 -238.095555)
			(xy 113.681035 -238.047534) (xy 113.711059 -238.003497) (xy 113.747311 -237.964426) (xy 113.788982 -237.931195)
			(xy 113.83514 -237.904546) (xy 113.884754 -237.885074) (xy 113.936716 -237.873214) (xy 113.989866 -237.869231)
			(xy 114.043016 -237.873214) (xy 114.094978 -237.885074) (xy 114.144592 -237.904546) (xy 114.19075 -237.931195)
			(xy 114.232421 -237.964426) (xy 114.268673 -238.003497) (xy 114.298697 -238.047534) (xy 114.321823 -238.095555)
			(xy 114.337533 -238.146485) (xy 114.345476 -238.199189) (xy 114.345974 -238.225838) (xy 114.345476 -238.252487)
			(xy 114.337533 -238.305191) (xy 114.321823 -238.356121) (xy 114.298697 -238.404142) (xy 114.268673 -238.448179)
			(xy 114.232421 -238.48725) (xy 114.19075 -238.520481) (xy 114.144592 -238.54713) (xy 114.094978 -238.566602)
			(xy 114.043016 -238.578462) (xy 113.989866 -238.582446) (xy 113.936716 -238.578462) (xy 113.884754 -238.566602)
			(xy 113.83514 -238.54713) (xy 113.788982 -238.520481) (xy 113.747311 -238.48725) (xy 113.711059 -238.448179)
			(xy 113.681035 -238.404142) (xy 113.657909 -238.356121) (xy 113.642199 -238.305191) (xy 113.634256 -238.252487)
			(xy 113.405676 -238.252487) (xy 113.397733 -238.305191) (xy 113.382023 -238.356121) (xy 113.358897 -238.404142)
			(xy 113.328873 -238.448179) (xy 113.292621 -238.48725) (xy 113.25095 -238.520481) (xy 113.204792 -238.54713)
			(xy 113.155178 -238.566602) (xy 113.103216 -238.578462) (xy 113.050066 -238.582446) (xy 112.996916 -238.578462)
			(xy 112.944954 -238.566602) (xy 112.89534 -238.54713) (xy 112.849182 -238.520481) (xy 112.807511 -238.48725)
			(xy 112.771259 -238.448179) (xy 112.741235 -238.404142) (xy 112.718109 -238.356121) (xy 112.702399 -238.305191)
			(xy 112.694456 -238.252487) (xy 112.465876 -238.252487) (xy 112.457933 -238.305191) (xy 112.442223 -238.356121)
			(xy 112.419097 -238.404142) (xy 112.389073 -238.448179) (xy 112.352821 -238.48725) (xy 112.31115 -238.520481)
			(xy 112.264992 -238.54713) (xy 112.215378 -238.566602) (xy 112.163416 -238.578462) (xy 112.110266 -238.582446)
			(xy 112.057116 -238.578462) (xy 112.005154 -238.566602) (xy 111.95554 -238.54713) (xy 111.909382 -238.520481)
			(xy 111.867711 -238.48725) (xy 111.831459 -238.448179) (xy 111.801435 -238.404142) (xy 111.778309 -238.356121)
			(xy 111.762599 -238.305191) (xy 111.754656 -238.252487) (xy 111.526076 -238.252487) (xy 111.518133 -238.305191)
			(xy 111.502423 -238.356121) (xy 111.479297 -238.404142) (xy 111.449273 -238.448179) (xy 111.413021 -238.48725)
			(xy 111.37135 -238.520481) (xy 111.325192 -238.54713) (xy 111.275578 -238.566602) (xy 111.223616 -238.578462)
			(xy 111.170466 -238.582446) (xy 111.117316 -238.578462) (xy 111.065354 -238.566602) (xy 111.01574 -238.54713)
			(xy 110.969582 -238.520481) (xy 110.927911 -238.48725) (xy 110.891659 -238.448179) (xy 110.861635 -238.404142)
			(xy 110.838509 -238.356121) (xy 110.822799 -238.305191) (xy 110.814856 -238.252487) (xy 110.586276 -238.252487)
			(xy 110.578333 -238.305191) (xy 110.562623 -238.356121) (xy 110.539497 -238.404142) (xy 110.509473 -238.448179)
			(xy 110.473221 -238.48725) (xy 110.43155 -238.520481) (xy 110.385392 -238.54713) (xy 110.335778 -238.566602)
			(xy 110.283816 -238.578462) (xy 110.230666 -238.582446) (xy 110.177516 -238.578462) (xy 110.125554 -238.566602)
			(xy 110.07594 -238.54713) (xy 110.029782 -238.520481) (xy 109.988111 -238.48725) (xy 109.951859 -238.448179)
			(xy 109.921835 -238.404142) (xy 109.898709 -238.356121) (xy 109.882999 -238.305191) (xy 109.875056 -238.252487)
			(xy 109.646448 -238.252487) (xy 109.646422 -238.253818) (xy 109.637662 -238.309089) (xy 109.620364 -238.362309)
			(xy 109.594953 -238.412167) (xy 109.562056 -238.457437) (xy 109.522482 -238.497003) (xy 109.477206 -238.529891)
			(xy 109.427342 -238.555291) (xy 109.374119 -238.572579) (xy 109.318846 -238.581328) (xy 109.290866 -238.581946)
			(xy 109.278123 -238.581851) (xy 109.252698 -238.580074) (xy 109.240066 -238.57839) (xy 109.21499 -238.574314)
			(xy 109.16625 -238.559985) (xy 109.120039 -238.538879) (xy 109.077294 -238.511425) (xy 109.038881 -238.478178)
			(xy 109.00558 -238.439813) (xy 108.978064 -238.397107) (xy 108.956893 -238.350926) (xy 108.942495 -238.302206)
			(xy 108.938314 -238.277146) (xy 108.935936 -238.266301) (xy 108.923431 -238.247984) (xy 108.914184 -238.24184)
			(xy 108.825792 -238.189262) (xy 108.802932 -238.197644) (xy 108.773287 -238.207818) (xy 108.711585 -238.218801)
			(xy 108.68025 -238.219488) (xy 108.676186 -238.219488) (xy 108.64841 -238.218642) (xy 108.593617 -238.209392)
			(xy 108.540926 -238.191744) (xy 108.491616 -238.166126) (xy 108.446883 -238.13316) (xy 108.407814 -238.093646)
			(xy 108.375357 -238.048543) (xy 108.350299 -237.998945) (xy 108.333249 -237.946058) (xy 108.324621 -237.891164)
			(xy 108.324142 -237.86338) (xy 108.324142 -237.848902) (xy 108.325873 -237.820072) (xy 108.337504 -237.763504)
			(xy 108.358122 -237.709558) (xy 108.372148 -237.68431) (xy 108.38688 -237.65891) (xy 108.32084 -237.54334)
			(xy 108.295948 -237.531656) (xy 104.192578 -237.531656) (xy 104.177592 -237.546642) (xy 103.661464 -238.06277)
			(xy 103.646478 -238.077756) (xy 103.646478 -238.972344) (xy 103.676196 -238.98606) (xy 103.697247 -238.996128)
			(xy 103.736747 -239.020973) (xy 103.754936 -239.03559) (xy 103.76916 -239.047274) (xy 103.802434 -239.047274)
			(xy 103.83774 -239.032542) (xy 103.844598 -239.026192) (xy 103.866404 -239.006427) (xy 103.914849 -238.973013)
			(xy 103.967765 -238.947257) (xy 104.023949 -238.929741) (xy 104.082127 -238.920863) (xy 104.111552 -238.920274)
			(xy 104.111806 -238.920274) (xy 104.139623 -238.92077) (xy 104.194689 -238.928689) (xy 104.248069 -238.944363)
			(xy 104.298674 -238.967474) (xy 104.345475 -238.997552) (xy 104.38752 -239.033985) (xy 104.423951 -239.07603)
			(xy 104.454029 -239.122831) (xy 104.477139 -239.173437) (xy 104.492813 -239.226817) (xy 104.50073 -239.281883)
			(xy 104.50073 -239.2929) (xy 104.82296 -239.2929) (xy 104.826944 -239.239743) (xy 104.838806 -239.187775)
			(xy 104.858281 -239.138154) (xy 104.884935 -239.091991) (xy 104.918172 -239.050316) (xy 104.957248 -239.01406)
			(xy 105.001293 -238.984033) (xy 105.04932 -238.960907) (xy 105.100259 -238.945198) (xy 105.152969 -238.937256)
			(xy 105.179622 -238.936784) (xy 105.204293 -238.937167) (xy 105.253162 -238.943977) (xy 105.30062 -238.957477)
			(xy 105.345757 -238.977408) (xy 105.387705 -239.003386) (xy 105.406952 -239.018826) (xy 105.418082 -239.027453)
			(xy 105.443842 -239.0388) (xy 105.471722 -239.042681) (xy 105.499602 -239.0388) (xy 105.525362 -239.027453)
			(xy 105.536492 -239.018826) (xy 105.557908 -239.001703) (xy 105.604965 -238.973564) (xy 105.655782 -238.952975)
			(xy 105.709155 -238.940423) (xy 105.763822 -238.936206) (xy 105.818489 -238.940423) (xy 105.871862 -238.952975)
			(xy 105.922679 -238.973564) (xy 105.969736 -239.001703) (xy 105.991152 -239.018826) (xy 106.002282 -239.027453)
			(xy 106.028042 -239.0388) (xy 106.055922 -239.042681) (xy 106.083802 -239.0388) (xy 106.109562 -239.027453)
			(xy 106.120692 -239.018826) (xy 106.139955 -239.003411) (xy 106.181907 -238.97745) (xy 106.227041 -238.957529)
			(xy 106.274493 -238.944029) (xy 106.323355 -238.937209) (xy 106.348022 -238.936784) (xy 106.37467 -238.937299)
			(xy 106.427369 -238.945245) (xy 106.478296 -238.960957) (xy 106.526312 -238.984083) (xy 106.570346 -239.014107)
			(xy 106.609413 -239.050358) (xy 106.622128 -239.066303) (xy 113.164356 -239.066303) (xy 113.164356 -239.013005)
			(xy 113.172299 -238.960301) (xy 113.188009 -238.909371) (xy 113.211135 -238.86135) (xy 113.241159 -238.817313)
			(xy 113.277411 -238.778242) (xy 113.319082 -238.745011) (xy 113.36524 -238.718362) (xy 113.414854 -238.69889)
			(xy 113.466816 -238.68703) (xy 113.519966 -238.683047) (xy 113.573116 -238.68703) (xy 113.625078 -238.69889)
			(xy 113.674692 -238.718362) (xy 113.72085 -238.745011) (xy 113.762521 -238.778242) (xy 113.798773 -238.817313)
			(xy 113.828797 -238.86135) (xy 113.851923 -238.909371) (xy 113.867633 -238.960301) (xy 113.875576 -239.013005)
			(xy 113.876074 -239.039654) (xy 113.875576 -239.066303) (xy 113.867633 -239.119007) (xy 113.851923 -239.169937)
			(xy 113.828797 -239.217958) (xy 113.798773 -239.261995) (xy 113.762521 -239.301066) (xy 113.72085 -239.334297)
			(xy 113.674692 -239.360946) (xy 113.625078 -239.380418) (xy 113.573116 -239.392278) (xy 113.519966 -239.396262)
			(xy 113.466816 -239.392278) (xy 113.414854 -239.380418) (xy 113.36524 -239.360946) (xy 113.319082 -239.334297)
			(xy 113.277411 -239.301066) (xy 113.241159 -239.261995) (xy 113.211135 -239.217958) (xy 113.188009 -239.169937)
			(xy 113.172299 -239.119007) (xy 113.164356 -239.066303) (xy 106.622128 -239.066303) (xy 106.642641 -239.092027)
			(xy 106.669288 -239.138183) (xy 106.688758 -239.187794) (xy 106.700617 -239.239754) (xy 106.7046 -239.2929)
			(xy 106.700617 -239.346046) (xy 106.688758 -239.398006) (xy 106.669288 -239.447617) (xy 106.642641 -239.493773)
			(xy 106.609413 -239.535442) (xy 106.570346 -239.571693) (xy 106.526312 -239.601717) (xy 106.478296 -239.624843)
			(xy 106.427369 -239.640555) (xy 106.37467 -239.648501) (xy 106.348022 -239.649) (xy 106.323353 -239.648573)
			(xy 106.274487 -239.641771) (xy 106.227029 -239.62828) (xy 106.181892 -239.60836) (xy 106.139941 -239.582392)
			(xy 106.120692 -239.566958) (xy 106.109562 -239.558331) (xy 106.083802 -239.546984) (xy 106.055922 -239.543103)
			(xy 106.028042 -239.546984) (xy 106.002282 -239.558331) (xy 105.991152 -239.566958) (xy 105.969736 -239.584081)
			(xy 105.922679 -239.61222) (xy 105.871862 -239.632809) (xy 105.818489 -239.645361) (xy 105.763822 -239.649578)
			(xy 105.709155 -239.645361) (xy 105.655782 -239.632809) (xy 105.604965 -239.61222) (xy 105.557908 -239.584081)
			(xy 105.536492 -239.566958) (xy 105.525362 -239.558331) (xy 105.499602 -239.546984) (xy 105.471722 -239.543103)
			(xy 105.443842 -239.546984) (xy 105.418082 -239.558331) (xy 105.406952 -239.566958) (xy 105.387708 -239.582397)
			(xy 105.34575 -239.608354) (xy 105.300611 -239.628271) (xy 105.253155 -239.641765) (xy 105.204291 -239.648579)
			(xy 105.179622 -239.649) (xy 105.152969 -239.648544) (xy 105.100259 -239.640602) (xy 105.04932 -239.624893)
			(xy 105.001293 -239.601767) (xy 104.957248 -239.57174) (xy 104.918172 -239.535484) (xy 104.884935 -239.493809)
			(xy 104.858281 -239.447646) (xy 104.838806 -239.398025) (xy 104.826944 -239.346057) (xy 104.82296 -239.2929)
			(xy 104.50073 -239.2929) (xy 104.50073 -239.337517) (xy 104.492813 -239.392583) (xy 104.477139 -239.445963)
			(xy 104.454029 -239.496569) (xy 104.423951 -239.54337) (xy 104.38752 -239.585415) (xy 104.345475 -239.621848)
			(xy 104.298674 -239.651926) (xy 104.248069 -239.675037) (xy 104.194689 -239.690711) (xy 104.139623 -239.69863)
			(xy 104.111806 -239.699038) (xy 104.111552 -239.699038) (xy 104.082123 -239.698502) (xy 104.023934 -239.689645)
			(xy 103.967743 -239.672127) (xy 103.914831 -239.646346) (xy 103.866405 -239.61289) (xy 103.844598 -239.59312)
			(xy 103.83774 -239.58677) (xy 103.802434 -239.572038) (xy 103.787194 -239.572038) (xy 103.764334 -239.576102)
			(xy 103.75392 -239.584484) (xy 103.735934 -239.598843) (xy 103.696949 -239.623303) (xy 103.676196 -239.633252)
			(xy 103.646478 -239.646968) (xy 103.646478 -239.880119) (xy 109.87531 -239.880119) (xy 109.87531 -239.826821)
			(xy 109.883253 -239.774117) (xy 109.898963 -239.723187) (xy 109.922089 -239.675166) (xy 109.952113 -239.631129)
			(xy 109.988365 -239.592058) (xy 110.030036 -239.558827) (xy 110.076194 -239.532178) (xy 110.125808 -239.512706)
			(xy 110.17777 -239.500846) (xy 110.23092 -239.496863) (xy 110.28407 -239.500846) (xy 110.336032 -239.512706)
			(xy 110.385646 -239.532178) (xy 110.431804 -239.558827) (xy 110.473475 -239.592058) (xy 110.509727 -239.631129)
			(xy 110.539751 -239.675166) (xy 110.562877 -239.723187) (xy 110.578587 -239.774117) (xy 110.58653 -239.826821)
			(xy 110.587028 -239.85347) (xy 110.58653 -239.880119) (xy 110.578587 -239.932823) (xy 110.562877 -239.983753)
			(xy 110.539751 -240.031774) (xy 110.509727 -240.075811) (xy 110.473475 -240.114882) (xy 110.431804 -240.148113)
			(xy 110.385646 -240.174762) (xy 110.336032 -240.194234) (xy 110.28407 -240.206094) (xy 110.23092 -240.210078)
			(xy 110.17777 -240.206094) (xy 110.125808 -240.194234) (xy 110.076194 -240.174762) (xy 110.030036 -240.148113)
			(xy 109.988365 -240.114882) (xy 109.952113 -240.075811) (xy 109.922089 -240.031774) (xy 109.898963 -239.983753)
			(xy 109.883253 -239.932823) (xy 109.87531 -239.880119) (xy 103.646478 -239.880119) (xy 103.646478 -241.172746)
			(xy 108.070142 -241.172746) (xy 108.070574 -241.148077) (xy 108.077373 -241.09921) (xy 108.090862 -241.051753)
			(xy 108.110782 -241.006615) (xy 108.13675 -240.964665) (xy 108.152184 -240.945416) (xy 108.160771 -240.934257)
			(xy 108.172129 -240.908508) (xy 108.17602 -240.880636) (xy 108.172149 -240.852761) (xy 108.160808 -240.827004)
			(xy 108.152184 -240.815876) (xy 108.136763 -240.796618) (xy 108.110802 -240.754665) (xy 108.090881 -240.70953)
			(xy 108.077383 -240.662076) (xy 108.070565 -240.613214) (xy 108.070142 -240.588546) (xy 108.07064 -240.561897)
			(xy 108.078583 -240.509193) (xy 108.094293 -240.458263) (xy 108.117419 -240.410242) (xy 108.147443 -240.366205)
			(xy 108.183695 -240.327134) (xy 108.225366 -240.293903) (xy 108.271524 -240.267254) (xy 108.321138 -240.247782)
			(xy 108.3731 -240.235922) (xy 108.42625 -240.231939) (xy 108.4794 -240.235922) (xy 108.531362 -240.247782)
			(xy 108.580976 -240.267254) (xy 108.627134 -240.293903) (xy 108.668805 -240.327134) (xy 108.705057 -240.366205)
			(xy 108.735081 -240.410242) (xy 108.758207 -240.458263) (xy 108.773917 -240.509193) (xy 108.78186 -240.561897)
			(xy 108.782358 -240.588546) (xy 108.781922 -240.613215) (xy 108.775123 -240.662081) (xy 108.765998 -240.694189)
			(xy 113.16461 -240.694189) (xy 113.16461 -240.640891) (xy 113.172553 -240.588187) (xy 113.188263 -240.537257)
			(xy 113.211389 -240.489236) (xy 113.241413 -240.445199) (xy 113.277665 -240.406128) (xy 113.319336 -240.372897)
			(xy 113.365494 -240.346248) (xy 113.415108 -240.326776) (xy 113.46707 -240.314916) (xy 113.52022 -240.310933)
			(xy 113.57337 -240.314916) (xy 113.625332 -240.326776) (xy 113.674946 -240.346248) (xy 113.721104 -240.372897)
			(xy 113.762775 -240.406128) (xy 113.799027 -240.445199) (xy 113.829051 -240.489236) (xy 113.852177 -240.537257)
			(xy 113.867887 -240.588187) (xy 113.87583 -240.640891) (xy 113.876328 -240.66754) (xy 113.87583 -240.694189)
			(xy 113.867887 -240.746893) (xy 113.852177 -240.797823) (xy 113.829051 -240.845844) (xy 113.799027 -240.889881)
			(xy 113.762775 -240.928952) (xy 113.721104 -240.962183) (xy 113.674946 -240.988832) (xy 113.625332 -241.008304)
			(xy 113.57337 -241.020164) (xy 113.52022 -241.024148) (xy 113.46707 -241.020164) (xy 113.415108 -241.008304)
			(xy 113.365494 -240.988832) (xy 113.319336 -240.962183) (xy 113.277665 -240.928952) (xy 113.241413 -240.889881)
			(xy 113.211389 -240.845844) (xy 113.188263 -240.797823) (xy 113.172553 -240.746893) (xy 113.16461 -240.694189)
			(xy 108.765998 -240.694189) (xy 108.761635 -240.709539) (xy 108.741716 -240.754676) (xy 108.71575 -240.796627)
			(xy 108.700316 -240.815876) (xy 108.691642 -240.826973) (xy 108.680295 -240.852745) (xy 108.676421 -240.880636)
			(xy 108.680314 -240.908524) (xy 108.691679 -240.934287) (xy 108.700316 -240.945416) (xy 108.715733 -240.964677)
			(xy 108.741695 -241.006629) (xy 108.761616 -241.051764) (xy 108.775116 -241.099216) (xy 108.781934 -241.148078)
			(xy 108.782358 -241.172746) (xy 108.78186 -241.199395) (xy 108.773917 -241.252099) (xy 108.758207 -241.303029)
			(xy 108.735081 -241.35105) (xy 108.705057 -241.395087) (xy 108.668805 -241.434158) (xy 108.627134 -241.467389)
			(xy 108.580976 -241.494038) (xy 108.545389 -241.508005) (xy 109.87531 -241.508005) (xy 109.87531 -241.454707)
			(xy 109.883253 -241.402003) (xy 109.898963 -241.351073) (xy 109.922089 -241.303052) (xy 109.952113 -241.259015)
			(xy 109.988365 -241.219944) (xy 110.030036 -241.186713) (xy 110.076194 -241.160064) (xy 110.125808 -241.140592)
			(xy 110.17777 -241.128732) (xy 110.23092 -241.124749) (xy 110.28407 -241.128732) (xy 110.336032 -241.140592)
			(xy 110.385646 -241.160064) (xy 110.431804 -241.186713) (xy 110.473475 -241.219944) (xy 110.509727 -241.259015)
			(xy 110.539751 -241.303052) (xy 110.562877 -241.351073) (xy 110.578587 -241.402003) (xy 110.58653 -241.454707)
			(xy 110.587028 -241.481356) (xy 110.58653 -241.508005) (xy 110.578587 -241.560709) (xy 110.562877 -241.611639)
			(xy 110.539751 -241.65966) (xy 110.535765 -241.665506) (xy 115.067334 -241.665506) (xy 115.067744 -241.640836)
			(xy 115.074549 -241.591969) (xy 115.088043 -241.544511) (xy 115.107968 -241.499374) (xy 115.133939 -241.457424)
			(xy 115.149376 -241.438176) (xy 115.157994 -241.427041) (xy 115.169337 -241.401282) (xy 115.173217 -241.373405)
			(xy 115.16934 -241.345527) (xy 115.157999 -241.319767) (xy 115.149376 -241.308636) (xy 115.133935 -241.289393)
			(xy 115.107977 -241.247436) (xy 115.088061 -241.202297) (xy 115.074567 -241.15484) (xy 115.067754 -241.105975)
			(xy 115.067334 -241.081306) (xy 115.067832 -241.054657) (xy 115.075775 -241.001953) (xy 115.091485 -240.951023)
			(xy 115.114611 -240.903002) (xy 115.144635 -240.858965) (xy 115.180887 -240.819894) (xy 115.222558 -240.786663)
			(xy 115.268716 -240.760014) (xy 115.31833 -240.740542) (xy 115.370292 -240.728682) (xy 115.423442 -240.724699)
			(xy 115.476592 -240.728682) (xy 115.528554 -240.740542) (xy 115.578168 -240.760014) (xy 115.624326 -240.786663)
			(xy 115.665997 -240.819894) (xy 115.702249 -240.858965) (xy 115.732273 -240.903002) (xy 115.755399 -240.951023)
			(xy 115.771109 -241.001953) (xy 115.779052 -241.054657) (xy 115.77955 -241.081306) (xy 115.77915 -241.105976)
			(xy 115.772343 -241.154844) (xy 115.758846 -241.202302) (xy 115.73892 -241.247439) (xy 115.712945 -241.289388)
			(xy 115.697508 -241.308636) (xy 115.688873 -241.31976) (xy 115.677522 -241.345522) (xy 115.67364 -241.373405)
			(xy 115.677524 -241.401287) (xy 115.688877 -241.427047) (xy 115.697508 -241.438176) (xy 115.712952 -241.457417)
			(xy 115.73891 -241.499374) (xy 115.758826 -241.544514) (xy 115.772319 -241.591971) (xy 115.77913 -241.640837)
			(xy 115.77955 -241.665506) (xy 115.779052 -241.692155) (xy 115.771109 -241.744859) (xy 115.755399 -241.795789)
			(xy 115.732273 -241.84381) (xy 115.702249 -241.887847) (xy 115.665997 -241.926918) (xy 115.624326 -241.960149)
			(xy 115.578168 -241.986798) (xy 115.528554 -242.00627) (xy 115.476592 -242.01813) (xy 115.423442 -242.022114)
			(xy 115.370292 -242.01813) (xy 115.31833 -242.00627) (xy 115.268716 -241.986798) (xy 115.222558 -241.960149)
			(xy 115.180887 -241.926918) (xy 115.144635 -241.887847) (xy 115.114611 -241.84381) (xy 115.091485 -241.795789)
			(xy 115.075775 -241.744859) (xy 115.067832 -241.692155) (xy 115.067334 -241.665506) (xy 110.535765 -241.665506)
			(xy 110.509727 -241.703697) (xy 110.473475 -241.742768) (xy 110.431804 -241.775999) (xy 110.385646 -241.802648)
			(xy 110.336032 -241.82212) (xy 110.28407 -241.83398) (xy 110.23092 -241.837964) (xy 110.17777 -241.83398)
			(xy 110.125808 -241.82212) (xy 110.076194 -241.802648) (xy 110.030036 -241.775999) (xy 109.988365 -241.742768)
			(xy 109.952113 -241.703697) (xy 109.922089 -241.65966) (xy 109.898963 -241.611639) (xy 109.883253 -241.560709)
			(xy 109.87531 -241.508005) (xy 108.545389 -241.508005) (xy 108.531362 -241.51351) (xy 108.4794 -241.52537)
			(xy 108.42625 -241.529354) (xy 108.3731 -241.52537) (xy 108.321138 -241.51351) (xy 108.271524 -241.494038)
			(xy 108.225366 -241.467389) (xy 108.183695 -241.434158) (xy 108.147443 -241.395087) (xy 108.117419 -241.35105)
			(xy 108.094293 -241.303029) (xy 108.078583 -241.252099) (xy 108.07064 -241.199395) (xy 108.070142 -241.172746)
			(xy 103.646478 -241.172746) (xy 103.646478 -242.321821) (xy 113.16461 -242.321821) (xy 113.16461 -242.268523)
			(xy 113.172553 -242.215819) (xy 113.188263 -242.164889) (xy 113.211389 -242.116868) (xy 113.241413 -242.072831)
			(xy 113.277665 -242.03376) (xy 113.319336 -242.000529) (xy 113.365494 -241.97388) (xy 113.415108 -241.954408)
			(xy 113.46707 -241.942548) (xy 113.52022 -241.938565) (xy 113.57337 -241.942548) (xy 113.625332 -241.954408)
			(xy 113.674946 -241.97388) (xy 113.721104 -242.000529) (xy 113.762775 -242.03376) (xy 113.799027 -242.072831)
			(xy 113.829051 -242.116868) (xy 113.852177 -242.164889) (xy 113.867887 -242.215819) (xy 113.87583 -242.268523)
			(xy 113.876328 -242.295172) (xy 113.87583 -242.321821) (xy 113.867887 -242.374525) (xy 113.852177 -242.425455)
			(xy 113.829051 -242.473476) (xy 113.799027 -242.517513) (xy 113.762775 -242.556584) (xy 113.721104 -242.589815)
			(xy 113.674946 -242.616464) (xy 113.625332 -242.635936) (xy 113.57337 -242.647796) (xy 113.52022 -242.65178)
			(xy 113.46707 -242.647796) (xy 113.415108 -242.635936) (xy 113.365494 -242.616464) (xy 113.319336 -242.589815)
			(xy 113.277665 -242.556584) (xy 113.241413 -242.517513) (xy 113.211389 -242.473476) (xy 113.188263 -242.425455)
			(xy 113.172553 -242.374525) (xy 113.16461 -242.321821) (xy 103.646478 -242.321821) (xy 103.646478 -243.060982)
			(xy 103.721387 -243.135891) (xy 109.87531 -243.135891) (xy 109.87531 -243.082593) (xy 109.883253 -243.029889)
			(xy 109.898963 -242.978959) (xy 109.922089 -242.930938) (xy 109.952113 -242.886901) (xy 109.988365 -242.84783)
			(xy 110.030036 -242.814599) (xy 110.076194 -242.78795) (xy 110.125808 -242.768478) (xy 110.17777 -242.756618)
			(xy 110.23092 -242.752635) (xy 110.28407 -242.756618) (xy 110.336032 -242.768478) (xy 110.385646 -242.78795)
			(xy 110.431804 -242.814599) (xy 110.473475 -242.84783) (xy 110.509727 -242.886901) (xy 110.539751 -242.930938)
			(xy 110.554325 -242.9612) (xy 117.467352 -242.9612) (xy 117.471336 -242.908045) (xy 117.483197 -242.856077)
			(xy 117.502671 -242.806457) (xy 117.529323 -242.760295) (xy 117.562558 -242.718619) (xy 117.601632 -242.682363)
			(xy 117.645674 -242.652336) (xy 117.693699 -242.629207) (xy 117.744635 -242.613495) (xy 117.797344 -242.60555)
			(xy 117.823996 -242.605052) (xy 117.84993 -242.605533) (xy 117.901251 -242.613048) (xy 117.950942 -242.627921)
			(xy 117.997953 -242.649836) (xy 118.041292 -242.678333) (xy 118.060978 -242.695222) (xy 118.072372 -242.70471)
			(xy 118.09922 -242.717259) (xy 118.128542 -242.721563) (xy 118.157864 -242.717259) (xy 118.184712 -242.70471)
			(xy 118.196106 -242.695222) (xy 118.215769 -242.678299) (xy 118.259097 -242.64977) (xy 118.306112 -242.627841)
			(xy 118.355814 -242.612977) (xy 118.407149 -242.605494) (xy 118.433088 -242.605052) (xy 118.459737 -242.605604)
			(xy 118.512439 -242.613546) (xy 118.563369 -242.629255) (xy 118.611389 -242.652378) (xy 118.655426 -242.682401)
			(xy 118.694497 -242.718652) (xy 118.727728 -242.760321) (xy 118.754377 -242.806477) (xy 118.773849 -242.85609)
			(xy 118.785709 -242.908052) (xy 118.789692 -242.9612) (xy 118.785709 -243.014348) (xy 118.773849 -243.06631)
			(xy 118.754377 -243.115923) (xy 118.727728 -243.162079) (xy 118.694497 -243.203748) (xy 118.655426 -243.239999)
			(xy 118.611389 -243.270022) (xy 118.563369 -243.293145) (xy 118.512439 -243.308854) (xy 118.459737 -243.316796)
			(xy 118.433088 -243.317268) (xy 118.407154 -243.316792) (xy 118.355833 -243.309275) (xy 118.306142 -243.294401)
			(xy 118.259132 -243.272484) (xy 118.215792 -243.243987) (xy 118.196106 -243.227098) (xy 118.184712 -243.21761)
			(xy 118.157864 -243.205061) (xy 118.128542 -243.200757) (xy 118.09922 -243.205061) (xy 118.072372 -243.21761)
			(xy 118.060978 -243.227098) (xy 118.041285 -243.243984) (xy 117.997964 -243.272518) (xy 117.950958 -243.294454)
			(xy 117.901262 -243.309326) (xy 117.849933 -243.31682) (xy 117.823996 -243.317268) (xy 117.797344 -243.31685)
			(xy 117.744635 -243.308905) (xy 117.693699 -243.293193) (xy 117.645674 -243.270064) (xy 117.601632 -243.240037)
			(xy 117.562558 -243.203781) (xy 117.529323 -243.162105) (xy 117.502671 -243.115943) (xy 117.483197 -243.066323)
			(xy 117.471336 -243.014355) (xy 117.467352 -242.9612) (xy 110.554325 -242.9612) (xy 110.562877 -242.978959)
			(xy 110.578587 -243.029889) (xy 110.58653 -243.082593) (xy 110.587028 -243.109242) (xy 110.58653 -243.135891)
			(xy 110.578587 -243.188595) (xy 110.562877 -243.239525) (xy 110.539751 -243.287546) (xy 110.509727 -243.331583)
			(xy 110.473475 -243.370654) (xy 110.431804 -243.403885) (xy 110.385646 -243.430534) (xy 110.336032 -243.450006)
			(xy 110.28407 -243.461866) (xy 110.23092 -243.46585) (xy 110.17777 -243.461866) (xy 110.125808 -243.450006)
			(xy 110.076194 -243.430534) (xy 110.030036 -243.403885) (xy 109.988365 -243.370654) (xy 109.952113 -243.331583)
			(xy 109.922089 -243.287546) (xy 109.898963 -243.239525) (xy 109.883253 -243.188595) (xy 109.87531 -243.135891)
			(xy 103.721387 -243.135891) (xy 104.535203 -243.949707) (xy 113.16461 -243.949707) (xy 113.16461 -243.896409)
			(xy 113.172553 -243.843705) (xy 113.188263 -243.792775) (xy 113.211389 -243.744754) (xy 113.241413 -243.700717)
			(xy 113.277665 -243.661646) (xy 113.319336 -243.628415) (xy 113.365494 -243.601766) (xy 113.415108 -243.582294)
			(xy 113.46707 -243.570434) (xy 113.52022 -243.566451) (xy 113.57337 -243.570434) (xy 113.625332 -243.582294)
			(xy 113.674946 -243.601766) (xy 113.721104 -243.628415) (xy 113.762775 -243.661646) (xy 113.799027 -243.700717)
			(xy 113.829051 -243.744754) (xy 113.852177 -243.792775) (xy 113.867887 -243.843705) (xy 113.87583 -243.896409)
			(xy 113.876328 -243.923058) (xy 113.87583 -243.949707) (xy 113.867887 -244.002411) (xy 113.852177 -244.053341)
			(xy 113.829051 -244.101362) (xy 113.799027 -244.145399) (xy 113.762775 -244.18447) (xy 113.721104 -244.217701)
			(xy 113.674946 -244.24435) (xy 113.625332 -244.263822) (xy 113.57337 -244.275682) (xy 113.52022 -244.279666)
			(xy 113.46707 -244.275682) (xy 113.415108 -244.263822) (xy 113.365494 -244.24435) (xy 113.319336 -244.217701)
			(xy 113.277665 -244.18447) (xy 113.241413 -244.145399) (xy 113.211389 -244.101362) (xy 113.188263 -244.053341)
			(xy 113.172553 -244.002411) (xy 113.16461 -243.949707) (xy 104.535203 -243.949707) (xy 105.294176 -244.70868)
			(xy 105.294176 -245.34749) (xy 108.077762 -245.34749) (xy 108.078157 -245.32282) (xy 108.084965 -245.273951)
			(xy 108.098462 -245.226493) (xy 108.11839 -245.181356) (xy 108.144366 -245.139407) (xy 108.159804 -245.12016)
			(xy 108.168442 -245.109038) (xy 108.179792 -245.083275) (xy 108.183672 -245.055392) (xy 108.179787 -245.02751)
			(xy 108.168434 -245.001749) (xy 108.159804 -244.99062) (xy 108.144406 -244.971344) (xy 108.118441 -244.929396)
			(xy 108.098515 -244.884266) (xy 108.085012 -244.836816) (xy 108.078188 -244.787957) (xy 108.077762 -244.76329)
			(xy 108.07826 -244.736641) (xy 108.086203 -244.683937) (xy 108.101913 -244.633007) (xy 108.125039 -244.584986)
			(xy 108.155063 -244.540949) (xy 108.191315 -244.501878) (xy 108.232986 -244.468647) (xy 108.279144 -244.441998)
			(xy 108.328758 -244.422526) (xy 108.38072 -244.410666) (xy 108.43387 -244.406683) (xy 108.48702 -244.410666)
			(xy 108.538982 -244.422526) (xy 108.588596 -244.441998) (xy 108.634754 -244.468647) (xy 108.676425 -244.501878)
			(xy 108.712677 -244.540949) (xy 108.742701 -244.584986) (xy 108.765827 -244.633007) (xy 108.781537 -244.683937)
			(xy 108.78948 -244.736641) (xy 108.789978 -244.76329) (xy 108.789974 -244.763523) (xy 109.87531 -244.763523)
			(xy 109.87531 -244.710225) (xy 109.883253 -244.657521) (xy 109.898963 -244.606591) (xy 109.922089 -244.55857)
			(xy 109.952113 -244.514533) (xy 109.988365 -244.475462) (xy 110.030036 -244.442231) (xy 110.076194 -244.415582)
			(xy 110.125808 -244.39611) (xy 110.17777 -244.38425) (xy 110.23092 -244.380267) (xy 110.28407 -244.38425)
			(xy 110.336032 -244.39611) (xy 110.385646 -244.415582) (xy 110.431804 -244.442231) (xy 110.473475 -244.475462)
			(xy 110.509727 -244.514533) (xy 110.539751 -244.55857) (xy 110.562877 -244.606591) (xy 110.578587 -244.657521)
			(xy 110.58653 -244.710225) (xy 110.587028 -244.736874) (xy 110.58653 -244.763523) (xy 110.578587 -244.816227)
			(xy 110.562877 -244.867157) (xy 110.539751 -244.915178) (xy 110.509727 -244.959215) (xy 110.473475 -244.998286)
			(xy 110.431804 -245.031517) (xy 110.385646 -245.058166) (xy 110.336032 -245.077638) (xy 110.28407 -245.089498)
			(xy 110.23092 -245.093482) (xy 110.17777 -245.089498) (xy 110.125808 -245.077638) (xy 110.076194 -245.058166)
			(xy 110.030036 -245.031517) (xy 109.988365 -244.998286) (xy 109.952113 -244.959215) (xy 109.922089 -244.915178)
			(xy 109.898963 -244.867157) (xy 109.883253 -244.816227) (xy 109.87531 -244.763523) (xy 108.789974 -244.763523)
			(xy 108.789563 -244.787959) (xy 108.782759 -244.836827) (xy 108.769265 -244.884284) (xy 108.749342 -244.929422)
			(xy 108.723372 -244.971372) (xy 108.707936 -244.99062) (xy 108.699321 -245.001757) (xy 108.687976 -245.027515)
			(xy 108.684094 -245.055392) (xy 108.687972 -245.08327) (xy 108.699313 -245.10903) (xy 108.707936 -245.12016)
			(xy 108.723377 -245.139403) (xy 108.749335 -245.18136) (xy 108.769251 -245.226499) (xy 108.782745 -245.273956)
			(xy 108.789558 -245.322821) (xy 108.789978 -245.34749) (xy 108.78948 -245.374139) (xy 108.781537 -245.426843)
			(xy 108.765827 -245.477773) (xy 108.742701 -245.525794) (xy 108.712677 -245.569831) (xy 108.705475 -245.577593)
			(xy 113.16461 -245.577593) (xy 113.16461 -245.524295) (xy 113.172553 -245.471591) (xy 113.188263 -245.420661)
			(xy 113.211389 -245.37264) (xy 113.241413 -245.328603) (xy 113.277665 -245.289532) (xy 113.319336 -245.256301)
			(xy 113.365494 -245.229652) (xy 113.415108 -245.21018) (xy 113.46707 -245.19832) (xy 113.52022 -245.194337)
			(xy 113.57337 -245.19832) (xy 113.625332 -245.21018) (xy 113.674946 -245.229652) (xy 113.721104 -245.256301)
			(xy 113.762775 -245.289532) (xy 113.799027 -245.328603) (xy 113.829051 -245.37264) (xy 113.84067 -245.396766)
			(xy 115.059714 -245.396766) (xy 115.060163 -245.372098) (xy 115.06696 -245.323232) (xy 115.080445 -245.275775)
			(xy 115.100361 -245.230637) (xy 115.126324 -245.188685) (xy 115.141756 -245.169436) (xy 115.150414 -245.158329)
			(xy 115.161754 -245.13256) (xy 115.165627 -245.104674) (xy 115.16174 -245.07679) (xy 115.150386 -245.051027)
			(xy 115.141756 -245.039896) (xy 115.12634 -245.020634) (xy 115.100378 -244.978682) (xy 115.080457 -244.933548)
			(xy 115.066958 -244.886095) (xy 115.060138 -244.837234) (xy 115.059714 -244.812566) (xy 115.060212 -244.785917)
			(xy 115.068155 -244.733213) (xy 115.083865 -244.682283) (xy 115.106991 -244.634262) (xy 115.137015 -244.590225)
			(xy 115.173267 -244.551154) (xy 115.214938 -244.517923) (xy 115.261096 -244.491274) (xy 115.31071 -244.471802)
			(xy 115.362672 -244.459942) (xy 115.415822 -244.455959) (xy 115.468972 -244.459942) (xy 115.520934 -244.471802)
			(xy 115.570548 -244.491274) (xy 115.616706 -244.517923) (xy 115.658377 -244.551154) (xy 115.694629 -244.590225)
			(xy 115.724653 -244.634262) (xy 115.747779 -244.682283) (xy 115.763489 -244.733213) (xy 115.771432 -244.785917)
			(xy 115.77193 -244.812566) (xy 115.771512 -244.837235) (xy 115.76471 -244.886103) (xy 115.751218 -244.933561)
			(xy 115.731295 -244.978698) (xy 115.705324 -245.020648) (xy 115.689888 -245.039896) (xy 115.681292 -245.051048)
			(xy 115.669938 -245.0768) (xy 115.66605 -245.104674) (xy 115.669924 -245.132549) (xy 115.681264 -245.158307)
			(xy 115.689888 -245.169436) (xy 115.705326 -245.188681) (xy 115.731282 -245.230639) (xy 115.751198 -245.275777)
			(xy 115.764693 -245.323233) (xy 115.771508 -245.372097) (xy 115.77193 -245.396766) (xy 115.771432 -245.423415)
			(xy 115.763489 -245.476119) (xy 115.747779 -245.527049) (xy 115.724653 -245.57507) (xy 115.694629 -245.619107)
			(xy 115.658377 -245.658178) (xy 115.616706 -245.691409) (xy 115.570548 -245.718058) (xy 115.520934 -245.73753)
			(xy 115.468972 -245.74939) (xy 115.415822 -245.753374) (xy 115.362672 -245.74939) (xy 115.31071 -245.73753)
			(xy 115.261096 -245.718058) (xy 115.214938 -245.691409) (xy 115.173267 -245.658178) (xy 115.137015 -245.619107)
			(xy 115.106991 -245.57507) (xy 115.083865 -245.527049) (xy 115.068155 -245.476119) (xy 115.060212 -245.423415)
			(xy 115.059714 -245.396766) (xy 113.84067 -245.396766) (xy 113.852177 -245.420661) (xy 113.867887 -245.471591)
			(xy 113.87583 -245.524295) (xy 113.876328 -245.550944) (xy 113.87583 -245.577593) (xy 113.867887 -245.630297)
			(xy 113.852177 -245.681227) (xy 113.829051 -245.729248) (xy 113.799027 -245.773285) (xy 113.762775 -245.812356)
			(xy 113.721104 -245.845587) (xy 113.674946 -245.872236) (xy 113.625332 -245.891708) (xy 113.57337 -245.903568)
			(xy 113.52022 -245.907552) (xy 113.46707 -245.903568) (xy 113.415108 -245.891708) (xy 113.365494 -245.872236)
			(xy 113.319336 -245.845587) (xy 113.277665 -245.812356) (xy 113.241413 -245.773285) (xy 113.211389 -245.729248)
			(xy 113.188263 -245.681227) (xy 113.172553 -245.630297) (xy 113.16461 -245.577593) (xy 108.705475 -245.577593)
			(xy 108.676425 -245.608902) (xy 108.634754 -245.642133) (xy 108.588596 -245.668782) (xy 108.538982 -245.688254)
			(xy 108.48702 -245.700114) (xy 108.43387 -245.704098) (xy 108.38072 -245.700114) (xy 108.328758 -245.688254)
			(xy 108.279144 -245.668782) (xy 108.232986 -245.642133) (xy 108.191315 -245.608902) (xy 108.155063 -245.569831)
			(xy 108.125039 -245.525794) (xy 108.101913 -245.477773) (xy 108.086203 -245.426843) (xy 108.07826 -245.374139)
			(xy 108.077762 -245.34749) (xy 105.294176 -245.34749) (xy 105.294176 -246.314214) (xy 105.333038 -246.323612)
			(xy 105.360958 -246.330995) (xy 105.414123 -246.353545) (xy 105.462952 -246.384378) (xy 105.48493 -246.403114)
			(xy 105.496308 -246.412504) (xy 105.52306 -246.424907) (xy 105.55224 -246.429159) (xy 105.58142 -246.424907)
			(xy 105.608172 -246.412504) (xy 105.61955 -246.403114) (xy 105.639192 -246.386316) (xy 105.682412 -246.357977)
			(xy 105.729273 -246.336181) (xy 105.778792 -246.321385) (xy 105.829929 -246.313899) (xy 105.85577 -246.313452)
			(xy 105.882426 -246.313923) (xy 105.935142 -246.321865) (xy 105.986086 -246.337575) (xy 106.034119 -246.360703)
			(xy 106.078168 -246.390732) (xy 106.078898 -246.391409) (xy 109.87531 -246.391409) (xy 109.87531 -246.338111)
			(xy 109.883253 -246.285407) (xy 109.898963 -246.234477) (xy 109.922089 -246.186456) (xy 109.952113 -246.142419)
			(xy 109.988365 -246.103348) (xy 110.030036 -246.070117) (xy 110.076194 -246.043468) (xy 110.125808 -246.023996)
			(xy 110.17777 -246.012136) (xy 110.23092 -246.008153) (xy 110.28407 -246.012136) (xy 110.336032 -246.023996)
			(xy 110.385646 -246.043468) (xy 110.431804 -246.070117) (xy 110.473475 -246.103348) (xy 110.509727 -246.142419)
			(xy 110.539751 -246.186456) (xy 110.562877 -246.234477) (xy 110.578587 -246.285407) (xy 110.58653 -246.338111)
			(xy 110.587028 -246.36476) (xy 110.58653 -246.391409) (xy 110.578587 -246.444113) (xy 110.562877 -246.495043)
			(xy 110.539751 -246.543064) (xy 110.509727 -246.587101) (xy 110.473475 -246.626172) (xy 110.431804 -246.659403)
			(xy 110.385646 -246.686052) (xy 110.336032 -246.705524) (xy 110.28407 -246.717384) (xy 110.23092 -246.721368)
			(xy 110.17777 -246.717384) (xy 110.125808 -246.705524) (xy 110.076194 -246.686052) (xy 110.030036 -246.659403)
			(xy 109.988365 -246.626172) (xy 109.952113 -246.587101) (xy 109.922089 -246.543064) (xy 109.898963 -246.495043)
			(xy 109.883253 -246.444113) (xy 109.87531 -246.391409) (xy 106.078898 -246.391409) (xy 106.117249 -246.426991)
			(xy 106.15049 -246.46867) (xy 106.177147 -246.514838) (xy 106.196624 -246.564464) (xy 106.208488 -246.616438)
			(xy 106.212472 -246.6696) (xy 106.208488 -246.722762) (xy 106.196624 -246.774736) (xy 106.177147 -246.824362)
			(xy 106.15049 -246.87053) (xy 106.117249 -246.912209) (xy 106.078168 -246.948468) (xy 106.034119 -246.978497)
			(xy 105.986086 -247.001625) (xy 105.935142 -247.017335) (xy 105.882426 -247.025277) (xy 105.85577 -247.025668)
			(xy 105.829928 -247.025211) (xy 105.778786 -247.017744) (xy 105.729262 -247.002958) (xy 105.682398 -246.981164)
			(xy 105.63918 -246.952819) (xy 105.61955 -246.936006) (xy 105.608172 -246.926616) (xy 105.58142 -246.914213)
			(xy 105.55224 -246.909961) (xy 105.52306 -246.914213) (xy 105.496308 -246.926616) (xy 105.48493 -246.936006)
			(xy 105.462953 -246.954744) (xy 105.414126 -246.985584) (xy 105.360963 -247.008139) (xy 105.333038 -247.015508)
			(xy 105.294176 -247.024906) (xy 105.294176 -247.205225) (xy 113.16461 -247.205225) (xy 113.16461 -247.151927)
			(xy 113.172553 -247.099223) (xy 113.188263 -247.048293) (xy 113.211389 -247.000272) (xy 113.241413 -246.956235)
			(xy 113.277665 -246.917164) (xy 113.319336 -246.883933) (xy 113.365494 -246.857284) (xy 113.415108 -246.837812)
			(xy 113.46707 -246.825952) (xy 113.52022 -246.821969) (xy 113.57337 -246.825952) (xy 113.625332 -246.837812)
			(xy 113.674946 -246.857284) (xy 113.721104 -246.883933) (xy 113.762775 -246.917164) (xy 113.799027 -246.956235)
			(xy 113.829051 -247.000272) (xy 113.852177 -247.048293) (xy 113.867887 -247.099223) (xy 113.87583 -247.151927)
			(xy 113.876328 -247.178576) (xy 113.87583 -247.205225) (xy 113.867887 -247.257929) (xy 113.852177 -247.308859)
			(xy 113.829051 -247.35688) (xy 113.799027 -247.400917) (xy 113.762775 -247.439988) (xy 113.721104 -247.473219)
			(xy 113.674946 -247.499868) (xy 113.625332 -247.51934) (xy 113.57337 -247.5312) (xy 113.52022 -247.535184)
			(xy 113.46707 -247.5312) (xy 113.415108 -247.51934) (xy 113.365494 -247.499868) (xy 113.319336 -247.473219)
			(xy 113.277665 -247.439988) (xy 113.241413 -247.400917) (xy 113.211389 -247.35688) (xy 113.188263 -247.308859)
			(xy 113.172553 -247.257929) (xy 113.16461 -247.205225) (xy 105.294176 -247.205225) (xy 105.294176 -248.019041)
			(xy 109.87531 -248.019041) (xy 109.87531 -247.965743) (xy 109.883253 -247.913039) (xy 109.898963 -247.862109)
			(xy 109.922089 -247.814088) (xy 109.952113 -247.770051) (xy 109.988365 -247.73098) (xy 110.030036 -247.697749)
			(xy 110.076194 -247.6711) (xy 110.125808 -247.651628) (xy 110.17777 -247.639768) (xy 110.23092 -247.635785)
			(xy 110.28407 -247.639768) (xy 110.336032 -247.651628) (xy 110.385646 -247.6711) (xy 110.431804 -247.697749)
			(xy 110.473475 -247.73098) (xy 110.509727 -247.770051) (xy 110.539751 -247.814088) (xy 110.562877 -247.862109)
			(xy 110.578587 -247.913039) (xy 110.58653 -247.965743) (xy 110.587028 -247.992392) (xy 110.58653 -248.019041)
			(xy 110.578587 -248.071745) (xy 110.562877 -248.122675) (xy 110.539751 -248.170696) (xy 110.509727 -248.214733)
			(xy 110.473475 -248.253804) (xy 110.431804 -248.287035) (xy 110.385646 -248.313684) (xy 110.336032 -248.333156)
			(xy 110.28407 -248.345016) (xy 110.23092 -248.349) (xy 110.17777 -248.345016) (xy 110.125808 -248.333156)
			(xy 110.076194 -248.313684) (xy 110.030036 -248.287035) (xy 109.988365 -248.253804) (xy 109.952113 -248.214733)
			(xy 109.922089 -248.170696) (xy 109.898963 -248.122675) (xy 109.883253 -248.071745) (xy 109.87531 -248.019041)
			(xy 105.294176 -248.019041) (xy 105.294176 -248.964704) (xy 105.253536 -249.005344) (xy 108.077762 -249.005344)
			(xy 108.078188 -248.980675) (xy 108.084988 -248.931808) (xy 108.098479 -248.88435) (xy 108.1184 -248.839213)
			(xy 108.144369 -248.797262) (xy 108.159804 -248.778014) (xy 108.168391 -248.766855) (xy 108.179747 -248.741106)
			(xy 108.183637 -248.713234) (xy 108.179766 -248.685359) (xy 108.168427 -248.659603) (xy 108.159804 -248.648474)
			(xy 108.144385 -248.629214) (xy 108.118423 -248.587262) (xy 108.098502 -248.542127) (xy 108.085003 -248.494674)
			(xy 108.078185 -248.445812) (xy 108.077762 -248.421144) (xy 108.07826 -248.394495) (xy 108.086203 -248.341791)
			(xy 108.101913 -248.290861) (xy 108.125039 -248.24284) (xy 108.155063 -248.198803) (xy 108.191315 -248.159732)
			(xy 108.232986 -248.126501) (xy 108.279144 -248.099852) (xy 108.328758 -248.08038) (xy 108.38072 -248.06852)
			(xy 108.43387 -248.064537) (xy 108.48702 -248.06852) (xy 108.538982 -248.08038) (xy 108.588596 -248.099852)
			(xy 108.634754 -248.126501) (xy 108.676425 -248.159732) (xy 108.712677 -248.198803) (xy 108.742701 -248.24284)
			(xy 108.765827 -248.290861) (xy 108.781537 -248.341791) (xy 108.78948 -248.394495) (xy 108.789978 -248.421144)
			(xy 108.789536 -248.445812) (xy 108.782738 -248.494679) (xy 108.769251 -248.542136) (xy 108.749334 -248.587274)
			(xy 108.723369 -248.629225) (xy 108.707936 -248.648474) (xy 108.699269 -248.659575) (xy 108.687931 -248.685346)
			(xy 108.68406 -248.713234) (xy 108.68795 -248.741119) (xy 108.699305 -248.766883) (xy 108.707936 -248.778014)
			(xy 108.723356 -248.797273) (xy 108.745533 -248.833111) (xy 113.16461 -248.833111) (xy 113.16461 -248.779813)
			(xy 113.172553 -248.727109) (xy 113.188263 -248.676179) (xy 113.211389 -248.628158) (xy 113.241413 -248.584121)
			(xy 113.277665 -248.54505) (xy 113.319336 -248.511819) (xy 113.365494 -248.48517) (xy 113.415108 -248.465698)
			(xy 113.46707 -248.453838) (xy 113.52022 -248.449855) (xy 113.57337 -248.453838) (xy 113.625332 -248.465698)
			(xy 113.674946 -248.48517) (xy 113.721104 -248.511819) (xy 113.762775 -248.54505) (xy 113.799027 -248.584121)
			(xy 113.829051 -248.628158) (xy 113.852177 -248.676179) (xy 113.867887 -248.727109) (xy 113.87583 -248.779813)
			(xy 113.876328 -248.806462) (xy 113.87583 -248.833111) (xy 113.867887 -248.885815) (xy 113.852177 -248.936745)
			(xy 113.829051 -248.984766) (xy 113.799027 -249.028803) (xy 113.762775 -249.067874) (xy 113.721104 -249.101105)
			(xy 113.674946 -249.127754) (xy 113.625332 -249.147226) (xy 113.57337 -249.159086) (xy 113.52022 -249.16307)
			(xy 113.46707 -249.159086) (xy 113.415108 -249.147226) (xy 113.365494 -249.127754) (xy 113.319336 -249.101105)
			(xy 113.277665 -249.067874) (xy 113.241413 -249.028803) (xy 113.211389 -248.984766) (xy 113.188263 -248.936745)
			(xy 113.172553 -248.885815) (xy 113.16461 -248.833111) (xy 108.745533 -248.833111) (xy 108.749317 -248.839226)
			(xy 108.769237 -248.884361) (xy 108.782736 -248.931814) (xy 108.789555 -248.980676) (xy 108.789978 -249.005344)
			(xy 108.78948 -249.031993) (xy 108.781537 -249.084697) (xy 108.765827 -249.135627) (xy 108.742701 -249.183648)
			(xy 108.713085 -249.227086) (xy 115.026694 -249.227086) (xy 115.02708 -249.202415) (xy 115.033889 -249.153546)
			(xy 115.047388 -249.106088) (xy 115.067318 -249.060951) (xy 115.093296 -249.019003) (xy 115.108736 -248.999756)
			(xy 115.117376 -248.988636) (xy 115.128721 -248.962872) (xy 115.132599 -248.934989) (xy 115.128715 -248.907107)
			(xy 115.117365 -248.881346) (xy 115.108736 -248.870216) (xy 115.093326 -248.850949) (xy 115.067364 -248.808998)
			(xy 115.047442 -248.763865) (xy 115.033941 -248.716414) (xy 115.027119 -248.667553) (xy 115.026694 -248.642886)
			(xy 115.027192 -248.616237) (xy 115.035135 -248.563533) (xy 115.050845 -248.512603) (xy 115.073971 -248.464582)
			(xy 115.103995 -248.420545) (xy 115.140247 -248.381474) (xy 115.181918 -248.348243) (xy 115.228076 -248.321594)
			(xy 115.27769 -248.302122) (xy 115.329652 -248.290262) (xy 115.382802 -248.286279) (xy 115.435952 -248.290262)
			(xy 115.487914 -248.302122) (xy 115.537528 -248.321594) (xy 115.583686 -248.348243) (xy 115.625357 -248.381474)
			(xy 115.661609 -248.420545) (xy 115.691633 -248.464582) (xy 115.714759 -248.512603) (xy 115.730469 -248.563533)
			(xy 115.738412 -248.616237) (xy 115.73891 -248.642886) (xy 115.738508 -248.667556) (xy 115.731702 -248.716424)
			(xy 115.718207 -248.763883) (xy 115.698281 -248.80902) (xy 115.672306 -248.850969) (xy 115.656868 -248.870216)
			(xy 115.648255 -248.881355) (xy 115.636906 -248.907112) (xy 115.633022 -248.934989) (xy 115.6369 -248.962867)
			(xy 115.648243 -248.988626) (xy 115.656868 -248.999756) (xy 115.672312 -249.018996) (xy 115.698268 -249.060955)
			(xy 115.718183 -249.106095) (xy 115.731677 -249.153552) (xy 115.73849 -249.202417) (xy 115.73891 -249.227086)
			(xy 115.738412 -249.253735) (xy 115.730469 -249.306439) (xy 115.714759 -249.357369) (xy 115.691633 -249.40539)
			(xy 115.661609 -249.449427) (xy 115.625357 -249.488498) (xy 115.583686 -249.521729) (xy 115.537528 -249.548378)
			(xy 115.487914 -249.56785) (xy 115.435952 -249.57971) (xy 115.382802 -249.583694) (xy 115.329652 -249.57971)
			(xy 115.27769 -249.56785) (xy 115.228076 -249.548378) (xy 115.181918 -249.521729) (xy 115.140247 -249.488498)
			(xy 115.103995 -249.449427) (xy 115.073971 -249.40539) (xy 115.050845 -249.357369) (xy 115.035135 -249.306439)
			(xy 115.027192 -249.253735) (xy 115.026694 -249.227086) (xy 108.713085 -249.227086) (xy 108.712677 -249.227685)
			(xy 108.676425 -249.266756) (xy 108.634754 -249.299987) (xy 108.588596 -249.326636) (xy 108.538982 -249.346108)
			(xy 108.48702 -249.357968) (xy 108.43387 -249.361952) (xy 108.38072 -249.357968) (xy 108.328758 -249.346108)
			(xy 108.279144 -249.326636) (xy 108.232986 -249.299987) (xy 108.191315 -249.266756) (xy 108.155063 -249.227685)
			(xy 108.125039 -249.183648) (xy 108.101913 -249.135627) (xy 108.086203 -249.084697) (xy 108.07826 -249.031993)
			(xy 108.077762 -249.005344) (xy 105.253536 -249.005344) (xy 104.611953 -249.646927) (xy 109.87531 -249.646927)
			(xy 109.87531 -249.593629) (xy 109.883253 -249.540925) (xy 109.898963 -249.489995) (xy 109.922089 -249.441974)
			(xy 109.952113 -249.397937) (xy 109.988365 -249.358866) (xy 110.030036 -249.325635) (xy 110.076194 -249.298986)
			(xy 110.125808 -249.279514) (xy 110.17777 -249.267654) (xy 110.23092 -249.263671) (xy 110.28407 -249.267654)
			(xy 110.336032 -249.279514) (xy 110.385646 -249.298986) (xy 110.431804 -249.325635) (xy 110.473475 -249.358866)
			(xy 110.509727 -249.397937) (xy 110.539751 -249.441974) (xy 110.562877 -249.489995) (xy 110.578587 -249.540925)
			(xy 110.58653 -249.593629) (xy 110.587028 -249.620278) (xy 110.58653 -249.646927) (xy 110.578587 -249.699631)
			(xy 110.562877 -249.750561) (xy 110.539751 -249.798582) (xy 110.509727 -249.842619) (xy 110.473475 -249.88169)
			(xy 110.431804 -249.914921) (xy 110.385646 -249.94157) (xy 110.336032 -249.961042) (xy 110.28407 -249.972902)
			(xy 110.23092 -249.976886) (xy 110.17777 -249.972902) (xy 110.125808 -249.961042) (xy 110.076194 -249.94157)
			(xy 110.030036 -249.914921) (xy 109.988365 -249.88169) (xy 109.952113 -249.842619) (xy 109.922089 -249.798582)
			(xy 109.898963 -249.750561) (xy 109.883253 -249.699631) (xy 109.87531 -249.646927) (xy 104.611953 -249.646927)
			(xy 103.92158 -250.3373) (xy 105.100413 -250.3373) (xy 105.104396 -250.284154) (xy 105.116255 -250.232196)
			(xy 105.135725 -250.182585) (xy 105.162372 -250.136431) (xy 105.1956 -250.094763) (xy 105.234667 -250.058513)
			(xy 105.278701 -250.02849) (xy 105.326717 -250.005365) (xy 105.377644 -249.989655) (xy 105.430343 -249.981711)
			(xy 105.45699 -249.981212) (xy 105.48283 -249.981692) (xy 105.533965 -249.989172) (xy 105.583483 -250.003961)
			(xy 105.630345 -250.025749) (xy 105.673567 -250.05408) (xy 105.69321 -250.070874) (xy 105.704588 -250.080264)
			(xy 105.73134 -250.092667) (xy 105.76052 -250.096919) (xy 105.7897 -250.092667) (xy 105.816452 -250.080264)
			(xy 105.82783 -250.070874) (xy 105.847465 -250.054067) (xy 105.890682 -250.025722) (xy 105.937545 -250.003927)
			(xy 105.987067 -249.989139) (xy 106.038208 -249.981671) (xy 106.06405 -249.981212) (xy 106.090705 -249.981642)
			(xy 106.143421 -249.98958) (xy 106.194364 -250.005288) (xy 106.242397 -250.028414) (xy 106.286447 -250.05844)
			(xy 106.325528 -250.094698) (xy 106.358769 -250.136375) (xy 106.385426 -250.182542) (xy 106.404904 -250.232166)
			(xy 106.416768 -250.284139) (xy 106.420752 -250.3373) (xy 117.467413 -250.3373) (xy 117.471396 -250.284154)
			(xy 117.483255 -250.232195) (xy 117.502726 -250.182584) (xy 117.529373 -250.136429) (xy 117.562602 -250.094761)
			(xy 117.60167 -250.05851) (xy 117.645704 -250.028488) (xy 117.693721 -250.005364) (xy 117.744649 -249.989654)
			(xy 117.797348 -249.98171) (xy 117.823996 -249.981212) (xy 117.84993 -249.981703) (xy 117.90125 -249.989217)
			(xy 117.95094 -250.004088) (xy 117.997951 -250.026001) (xy 118.041291 -250.054494) (xy 118.060978 -250.071382)
			(xy 118.072372 -250.08087) (xy 118.09922 -250.093419) (xy 118.128542 -250.097723) (xy 118.157864 -250.093419)
			(xy 118.184712 -250.08087) (xy 118.196106 -250.071382) (xy 118.215764 -250.054453) (xy 118.259094 -250.025926)
			(xy 118.30611 -250.003999) (xy 118.355813 -249.989137) (xy 118.407149 -249.981654) (xy 118.433088 -249.981212)
			(xy 118.459741 -249.981644) (xy 118.512452 -249.989588) (xy 118.563391 -250.005299) (xy 118.611419 -250.028426)
			(xy 118.655464 -250.058454) (xy 118.694541 -250.094711) (xy 118.727777 -250.136387) (xy 118.754431 -250.182551)
			(xy 118.773906 -250.232173) (xy 118.785768 -250.284143) (xy 118.789752 -250.3373) (xy 118.785768 -250.390457)
			(xy 118.773906 -250.442427) (xy 118.754431 -250.492049) (xy 118.727777 -250.538213) (xy 118.694541 -250.579889)
			(xy 118.655464 -250.616146) (xy 118.611419 -250.646174) (xy 118.563391 -250.669301) (xy 118.512452 -250.685012)
			(xy 118.459741 -250.692956) (xy 118.433088 -250.693428) (xy 118.407153 -250.692962) (xy 118.355831 -250.685444)
			(xy 118.306141 -250.670568) (xy 118.25913 -250.648649) (xy 118.215791 -250.620149) (xy 118.196106 -250.603258)
			(xy 118.184712 -250.59377) (xy 118.157864 -250.581221) (xy 118.128542 -250.576917) (xy 118.09922 -250.581221)
			(xy 118.072372 -250.59377) (xy 118.060978 -250.603258) (xy 118.04128 -250.620138) (xy 117.997961 -250.648674)
			(xy 117.950956 -250.670611) (xy 117.901261 -250.685485) (xy 117.849933 -250.69298) (xy 117.823996 -250.693428)
			(xy 117.797348 -250.69289) (xy 117.744649 -250.684946) (xy 117.693721 -250.669236) (xy 117.645704 -250.646112)
			(xy 117.60167 -250.61609) (xy 117.562602 -250.579839) (xy 117.529373 -250.538171) (xy 117.502726 -250.492016)
			(xy 117.483255 -250.442405) (xy 117.471396 -250.390446) (xy 117.467413 -250.3373) (xy 106.420752 -250.3373)
			(xy 106.416768 -250.390461) (xy 106.404904 -250.442434) (xy 106.385426 -250.492058) (xy 106.358769 -250.538225)
			(xy 106.325528 -250.579902) (xy 106.286447 -250.61616) (xy 106.242397 -250.646186) (xy 106.194364 -250.669312)
			(xy 106.143421 -250.68502) (xy 106.090705 -250.692958) (xy 106.06405 -250.693428) (xy 106.03821 -250.692973)
			(xy 105.987074 -250.685486) (xy 105.937556 -250.67069) (xy 105.890694 -250.648897) (xy 105.847473 -250.620562)
			(xy 105.82783 -250.603766) (xy 105.816452 -250.594376) (xy 105.7897 -250.581973) (xy 105.76052 -250.577721)
			(xy 105.73134 -250.581973) (xy 105.704588 -250.594376) (xy 105.69321 -250.603766) (xy 105.673565 -250.620561)
			(xy 105.63035 -250.648906) (xy 105.58349 -250.670703) (xy 105.53397 -250.685494) (xy 105.482831 -250.692967)
			(xy 105.45699 -250.693428) (xy 105.430343 -250.692889) (xy 105.377644 -250.684945) (xy 105.326717 -250.669235)
			(xy 105.278701 -250.64611) (xy 105.234667 -250.616087) (xy 105.1956 -250.579837) (xy 105.162372 -250.538169)
			(xy 105.135725 -250.492015) (xy 105.116255 -250.442404) (xy 105.104396 -250.390446) (xy 105.100413 -250.3373)
			(xy 103.92158 -250.3373) (xy 103.881428 -250.377452) (xy 103.881428 -252.659388) (xy 108.077762 -252.659388)
			(xy 108.078156 -252.634718) (xy 108.084964 -252.585849) (xy 108.098462 -252.538391) (xy 108.11839 -252.493254)
			(xy 108.144366 -252.451305) (xy 108.159804 -252.432058) (xy 108.168444 -252.420937) (xy 108.179793 -252.395174)
			(xy 108.183673 -252.367291) (xy 108.179788 -252.339408) (xy 108.168434 -252.313647) (xy 108.159804 -252.302518)
			(xy 108.144405 -252.283243) (xy 108.11844 -252.241295) (xy 108.098515 -252.196164) (xy 108.085011 -252.148714)
			(xy 108.078188 -252.099855) (xy 108.077762 -252.075188) (xy 108.07826 -252.048539) (xy 108.086203 -251.995835)
			(xy 108.101913 -251.944905) (xy 108.125039 -251.896884) (xy 108.155063 -251.852847) (xy 108.191315 -251.813776)
			(xy 108.232986 -251.780545) (xy 108.279144 -251.753896) (xy 108.328758 -251.734424) (xy 108.38072 -251.722564)
			(xy 108.43387 -251.718581) (xy 108.48702 -251.722564) (xy 108.538982 -251.734424) (xy 108.588596 -251.753896)
			(xy 108.634754 -251.780545) (xy 108.676425 -251.813776) (xy 108.712677 -251.852847) (xy 108.742701 -251.896884)
			(xy 108.765827 -251.944905) (xy 108.781537 -251.995835) (xy 108.78948 -252.048539) (xy 108.789978 -252.075188)
			(xy 108.789562 -252.099857) (xy 108.782758 -252.148725) (xy 108.769265 -252.196182) (xy 108.749342 -252.24132)
			(xy 108.723372 -252.28327) (xy 108.707936 -252.302518) (xy 108.699323 -252.313657) (xy 108.687977 -252.339414)
			(xy 108.684096 -252.367291) (xy 108.687972 -252.395168) (xy 108.699313 -252.420928) (xy 108.707936 -252.432058)
			(xy 108.723376 -252.451301) (xy 108.749334 -252.493259) (xy 108.769251 -252.538398) (xy 108.782745 -252.585854)
			(xy 108.789558 -252.634719) (xy 108.789978 -252.659388) (xy 108.78948 -252.686037) (xy 108.781537 -252.738741)
			(xy 108.765827 -252.789671) (xy 108.757989 -252.805946) (xy 115.077494 -252.805946) (xy 115.077914 -252.781277)
			(xy 115.084715 -252.732409) (xy 115.098206 -252.684951) (xy 115.118128 -252.639813) (xy 115.1441 -252.597864)
			(xy 115.159536 -252.578616) (xy 115.168119 -252.567455) (xy 115.179471 -252.541706) (xy 115.18336 -252.513836)
			(xy 115.179491 -252.485962) (xy 115.168156 -252.460206) (xy 115.159536 -252.449076) (xy 115.144107 -252.429824)
			(xy 115.118149 -252.387869) (xy 115.09823 -252.342732) (xy 115.084733 -252.295277) (xy 115.077917 -252.246414)
			(xy 115.077494 -252.221746) (xy 115.077992 -252.195097) (xy 115.085935 -252.142393) (xy 115.101645 -252.091463)
			(xy 115.124771 -252.043442) (xy 115.154795 -251.999405) (xy 115.191047 -251.960334) (xy 115.232718 -251.927103)
			(xy 115.278876 -251.900454) (xy 115.32849 -251.880982) (xy 115.380452 -251.869122) (xy 115.433602 -251.865139)
			(xy 115.486752 -251.869122) (xy 115.538714 -251.880982) (xy 115.588328 -251.900454) (xy 115.634486 -251.927103)
			(xy 115.676157 -251.960334) (xy 115.712409 -251.999405) (xy 115.742433 -252.043442) (xy 115.765559 -252.091463)
			(xy 115.781269 -252.142393) (xy 115.789212 -252.195097) (xy 115.78971 -252.221746) (xy 115.789285 -252.246415)
			(xy 115.782485 -252.295283) (xy 115.768995 -252.342741) (xy 115.749074 -252.387878) (xy 115.723104 -252.429828)
			(xy 115.707668 -252.449076) (xy 115.698997 -252.460174) (xy 115.687656 -252.485946) (xy 115.683783 -252.513836)
			(xy 115.687675 -252.541722) (xy 115.699035 -252.567486) (xy 115.707668 -252.578616) (xy 115.723094 -252.597871)
			(xy 115.749053 -252.639825) (xy 115.768971 -252.684961) (xy 115.782469 -252.732415) (xy 115.789287 -252.781278)
			(xy 115.78971 -252.805946) (xy 115.789212 -252.832595) (xy 115.781269 -252.885299) (xy 115.765559 -252.936229)
			(xy 115.742433 -252.98425) (xy 115.712409 -253.028287) (xy 115.676157 -253.067358) (xy 115.634486 -253.100589)
			(xy 115.588328 -253.127238) (xy 115.538714 -253.14671) (xy 115.486752 -253.15857) (xy 115.433602 -253.162554)
			(xy 115.380452 -253.15857) (xy 115.32849 -253.14671) (xy 115.278876 -253.127238) (xy 115.232718 -253.100589)
			(xy 115.191047 -253.067358) (xy 115.154795 -253.028287) (xy 115.124771 -252.98425) (xy 115.101645 -252.936229)
			(xy 115.085935 -252.885299) (xy 115.077992 -252.832595) (xy 115.077494 -252.805946) (xy 108.757989 -252.805946)
			(xy 108.742701 -252.837692) (xy 108.712677 -252.881729) (xy 108.676425 -252.9208) (xy 108.634754 -252.954031)
			(xy 108.588596 -252.98068) (xy 108.538982 -253.000152) (xy 108.48702 -253.012012) (xy 108.43387 -253.015996)
			(xy 108.38072 -253.012012) (xy 108.328758 -253.000152) (xy 108.279144 -252.98068) (xy 108.232986 -252.954031)
			(xy 108.191315 -252.9208) (xy 108.155063 -252.881729) (xy 108.125039 -252.837692) (xy 108.101913 -252.789671)
			(xy 108.086203 -252.738741) (xy 108.07826 -252.686037) (xy 108.077762 -252.659388) (xy 103.881428 -252.659388)
			(xy 103.881428 -254.0152) (xy 105.100433 -254.0152) (xy 105.104415 -253.962057) (xy 105.116274 -253.910102)
			(xy 105.135743 -253.860494) (xy 105.162388 -253.814342) (xy 105.195615 -253.772676) (xy 105.23468 -253.736428)
			(xy 105.278711 -253.706407) (xy 105.326724 -253.683284) (xy 105.377648 -253.667575) (xy 105.430344 -253.659631)
			(xy 105.45699 -253.659132) (xy 105.48283 -253.659607) (xy 105.533966 -253.667087) (xy 105.583484 -253.681877)
			(xy 105.630346 -253.703667) (xy 105.673567 -253.731999) (xy 105.69321 -253.748794) (xy 105.704588 -253.758184)
			(xy 105.73134 -253.770587) (xy 105.76052 -253.774839) (xy 105.7897 -253.770587) (xy 105.816452 -253.758184)
			(xy 105.82783 -253.748794) (xy 105.847467 -253.73199) (xy 105.890684 -253.703644) (xy 105.937546 -253.681848)
			(xy 105.987068 -253.66706) (xy 106.038208 -253.659591) (xy 106.06405 -253.659132) (xy 106.090707 -253.659522)
			(xy 106.143425 -253.667461) (xy 106.194371 -253.683169) (xy 106.242407 -253.706296) (xy 106.286459 -253.736325)
			(xy 106.325543 -253.772584) (xy 106.358785 -253.814264) (xy 106.385444 -253.860433) (xy 106.404923 -253.91006)
			(xy 106.413273 -253.946639) (xy 113.274338 -253.946639) (xy 113.274338 -253.893341) (xy 113.282281 -253.840637)
			(xy 113.297991 -253.789707) (xy 113.321117 -253.741686) (xy 113.351141 -253.697649) (xy 113.387393 -253.658578)
			(xy 113.429064 -253.625347) (xy 113.475222 -253.598698) (xy 113.524836 -253.579226) (xy 113.576798 -253.567366)
			(xy 113.629948 -253.563383) (xy 113.683098 -253.567366) (xy 113.73506 -253.579226) (xy 113.784674 -253.598698)
			(xy 113.830832 -253.625347) (xy 113.872503 -253.658578) (xy 113.908755 -253.697649) (xy 113.938779 -253.741686)
			(xy 113.961905 -253.789707) (xy 113.977615 -253.840637) (xy 113.985558 -253.893341) (xy 113.986056 -253.91999)
			(xy 113.985558 -253.946639) (xy 113.977615 -253.999343) (xy 113.972724 -254.0152) (xy 117.467433 -254.0152)
			(xy 117.471416 -253.962057) (xy 117.483274 -253.910101) (xy 117.502744 -253.860492) (xy 117.52939 -253.81434)
			(xy 117.562617 -253.772674) (xy 117.601682 -253.736426) (xy 117.645714 -253.706405) (xy 117.693729 -253.683282)
			(xy 117.744653 -253.667574) (xy 117.79735 -253.65963) (xy 117.823996 -253.659132) (xy 117.84993 -253.659618)
			(xy 117.901251 -253.667133) (xy 117.950941 -253.682004) (xy 117.997952 -253.703919) (xy 118.041291 -253.732413)
			(xy 118.060978 -253.749302) (xy 118.072372 -253.75879) (xy 118.09922 -253.771339) (xy 118.128542 -253.775643)
			(xy 118.157864 -253.771339) (xy 118.184712 -253.75879) (xy 118.196106 -253.749302) (xy 118.215766 -253.732376)
			(xy 118.259096 -253.703848) (xy 118.306111 -253.68192) (xy 118.355814 -253.667057) (xy 118.407149 -253.659574)
			(xy 118.433088 -253.659132) (xy 118.459743 -253.659524) (xy 118.512457 -253.667468) (xy 118.563398 -253.68318)
			(xy 118.611429 -253.706309) (xy 118.655476 -253.736338) (xy 118.694555 -253.772597) (xy 118.727794 -253.814276)
			(xy 118.754449 -253.860443) (xy 118.773925 -253.910067) (xy 118.785788 -253.96204) (xy 118.789772 -254.0152)
			(xy 118.785788 -254.06836) (xy 118.773925 -254.120333) (xy 118.754449 -254.169957) (xy 118.727794 -254.216124)
			(xy 118.694555 -254.257803) (xy 118.655476 -254.294062) (xy 118.611429 -254.324091) (xy 118.563398 -254.34722)
			(xy 118.512457 -254.362932) (xy 118.459743 -254.370876) (xy 118.433088 -254.371348) (xy 118.407153 -254.370877)
			(xy 118.355832 -254.363359) (xy 118.306141 -254.348484) (xy 118.259131 -254.326567) (xy 118.215792 -254.298068)
			(xy 118.196106 -254.281178) (xy 118.184712 -254.27169) (xy 118.157864 -254.259141) (xy 118.128542 -254.254837)
			(xy 118.09922 -254.259141) (xy 118.072372 -254.27169) (xy 118.060978 -254.281178) (xy 118.041282 -254.298061)
			(xy 117.997963 -254.326596) (xy 117.950957 -254.348533) (xy 117.901262 -254.363406) (xy 117.849933 -254.3709)
			(xy 117.823996 -254.371348) (xy 117.79735 -254.37077) (xy 117.744653 -254.362826) (xy 117.693729 -254.347118)
			(xy 117.645714 -254.323995) (xy 117.601682 -254.293974) (xy 117.562617 -254.257726) (xy 117.52939 -254.21606)
			(xy 117.502744 -254.169908) (xy 117.483274 -254.120299) (xy 117.471416 -254.068343) (xy 117.467433 -254.0152)
			(xy 113.972724 -254.0152) (xy 113.961905 -254.050273) (xy 113.938779 -254.098294) (xy 113.908755 -254.142331)
			(xy 113.872503 -254.181402) (xy 113.830832 -254.214633) (xy 113.784674 -254.241282) (xy 113.73506 -254.260754)
			(xy 113.683098 -254.272614) (xy 113.629948 -254.276598) (xy 113.576798 -254.272614) (xy 113.524836 -254.260754)
			(xy 113.475222 -254.241282) (xy 113.429064 -254.214633) (xy 113.387393 -254.181402) (xy 113.351141 -254.142331)
			(xy 113.321117 -254.098294) (xy 113.297991 -254.050273) (xy 113.282281 -253.999343) (xy 113.274338 -253.946639)
			(xy 106.413273 -253.946639) (xy 106.416788 -253.962036) (xy 106.420772 -254.0152) (xy 106.416788 -254.068364)
			(xy 106.404923 -254.12034) (xy 106.385444 -254.169967) (xy 106.358785 -254.216136) (xy 106.325543 -254.257816)
			(xy 106.286459 -254.294075) (xy 106.242407 -254.324104) (xy 106.194371 -254.347231) (xy 106.143425 -254.362939)
			(xy 106.090707 -254.370878) (xy 106.06405 -254.371348) (xy 106.038209 -254.370913) (xy 105.987071 -254.363424)
			(xy 105.937552 -254.348625) (xy 105.890691 -254.326826) (xy 105.847471 -254.298485) (xy 105.82783 -254.281686)
			(xy 105.816452 -254.272296) (xy 105.7897 -254.259893) (xy 105.76052 -254.255641) (xy 105.73134 -254.259893)
			(xy 105.704588 -254.272296) (xy 105.69321 -254.281686) (xy 105.673568 -254.298484) (xy 105.630352 -254.326828)
			(xy 105.583491 -254.348624) (xy 105.53397 -254.363414) (xy 105.482831 -254.370887) (xy 105.45699 -254.371348)
			(xy 105.430344 -254.370769) (xy 105.377648 -254.362825) (xy 105.326724 -254.347116) (xy 105.278711 -254.323993)
			(xy 105.23468 -254.293972) (xy 105.195615 -254.257724) (xy 105.162388 -254.216058) (xy 105.135743 -254.169906)
			(xy 105.116274 -254.120298) (xy 105.104415 -254.068343) (xy 105.100433 -254.0152) (xy 103.881428 -254.0152)
			(xy 103.881428 -254.760455) (xy 109.985038 -254.760455) (xy 109.985038 -254.707157) (xy 109.992981 -254.654453)
			(xy 110.008691 -254.603523) (xy 110.031817 -254.555502) (xy 110.061841 -254.511465) (xy 110.098093 -254.472394)
			(xy 110.139764 -254.439163) (xy 110.185922 -254.412514) (xy 110.235536 -254.393042) (xy 110.287498 -254.381182)
			(xy 110.340648 -254.377199) (xy 110.393798 -254.381182) (xy 110.44576 -254.393042) (xy 110.495374 -254.412514)
			(xy 110.541532 -254.439163) (xy 110.583203 -254.472394) (xy 110.619455 -254.511465) (xy 110.649479 -254.555502)
			(xy 110.672605 -254.603523) (xy 110.688315 -254.654453) (xy 110.696258 -254.707157) (xy 110.696756 -254.733806)
			(xy 110.696258 -254.760455) (xy 110.688315 -254.813159) (xy 110.672605 -254.864089) (xy 110.649479 -254.91211)
			(xy 110.619455 -254.956147) (xy 110.583203 -254.995218) (xy 110.541532 -255.028449) (xy 110.495374 -255.055098)
			(xy 110.44576 -255.07457) (xy 110.393798 -255.08643) (xy 110.340648 -255.090414) (xy 110.287498 -255.08643)
			(xy 110.235536 -255.07457) (xy 110.185922 -255.055098) (xy 110.139764 -255.028449) (xy 110.098093 -254.995218)
			(xy 110.061841 -254.956147) (xy 110.031817 -254.91211) (xy 110.008691 -254.864089) (xy 109.992981 -254.813159)
			(xy 109.985038 -254.760455) (xy 103.881428 -254.760455) (xy 103.881428 -256.33045) (xy 108.077762 -256.33045)
			(xy 108.078191 -256.305781) (xy 108.084991 -256.256914) (xy 108.09848 -256.209456) (xy 108.118401 -256.164319)
			(xy 108.144369 -256.122368) (xy 108.159804 -256.10312) (xy 108.168385 -256.091957) (xy 108.179742 -256.066209)
			(xy 108.183633 -256.038339) (xy 108.179763 -256.010465) (xy 108.168426 -255.984709) (xy 108.159804 -255.97358)
			(xy 108.144388 -255.954318) (xy 108.118425 -255.912367) (xy 108.098503 -255.867232) (xy 108.085004 -255.81978)
			(xy 108.078185 -255.770918) (xy 108.077762 -255.74625) (xy 108.07826 -255.719601) (xy 108.086203 -255.666897)
			(xy 108.101913 -255.615967) (xy 108.125039 -255.567946) (xy 108.155063 -255.523909) (xy 108.191315 -255.484838)
			(xy 108.232986 -255.451607) (xy 108.279144 -255.424958) (xy 108.328758 -255.405486) (xy 108.38072 -255.393626)
			(xy 108.43387 -255.389643) (xy 108.48702 -255.393626) (xy 108.538982 -255.405486) (xy 108.588596 -255.424958)
			(xy 108.634754 -255.451607) (xy 108.676425 -255.484838) (xy 108.712677 -255.523909) (xy 108.742701 -255.567946)
			(xy 108.745869 -255.574525) (xy 113.274338 -255.574525) (xy 113.274338 -255.521227) (xy 113.282281 -255.468523)
			(xy 113.297991 -255.417593) (xy 113.321117 -255.369572) (xy 113.351141 -255.325535) (xy 113.387393 -255.286464)
			(xy 113.429064 -255.253233) (xy 113.475222 -255.226584) (xy 113.524836 -255.207112) (xy 113.576798 -255.195252)
			(xy 113.629948 -255.191269) (xy 113.683098 -255.195252) (xy 113.73506 -255.207112) (xy 113.784674 -255.226584)
			(xy 113.830832 -255.253233) (xy 113.872503 -255.286464) (xy 113.908755 -255.325535) (xy 113.938779 -255.369572)
			(xy 113.961905 -255.417593) (xy 113.977615 -255.468523) (xy 113.985558 -255.521227) (xy 113.986056 -255.547876)
			(xy 113.985558 -255.574525) (xy 113.977615 -255.627229) (xy 113.961905 -255.678159) (xy 113.938779 -255.72618)
			(xy 113.908755 -255.770217) (xy 113.872503 -255.809288) (xy 113.830832 -255.842519) (xy 113.784674 -255.869168)
			(xy 113.73506 -255.88864) (xy 113.683098 -255.9005) (xy 113.629948 -255.904484) (xy 113.576798 -255.9005)
			(xy 113.524836 -255.88864) (xy 113.475222 -255.869168) (xy 113.429064 -255.842519) (xy 113.387393 -255.809288)
			(xy 113.351141 -255.770217) (xy 113.321117 -255.72618) (xy 113.297991 -255.678159) (xy 113.282281 -255.627229)
			(xy 113.274338 -255.574525) (xy 108.745869 -255.574525) (xy 108.765827 -255.615967) (xy 108.781537 -255.666897)
			(xy 108.78948 -255.719601) (xy 108.789978 -255.74625) (xy 108.78954 -255.770919) (xy 108.782741 -255.819785)
			(xy 108.769253 -255.867242) (xy 108.749335 -255.91238) (xy 108.723369 -255.954331) (xy 108.707936 -255.97358)
			(xy 108.699264 -255.984677) (xy 108.687926 -256.01045) (xy 108.684056 -256.038339) (xy 108.687947 -256.066225)
			(xy 108.699304 -256.091989) (xy 108.707936 -256.10312) (xy 108.723359 -256.122377) (xy 108.749319 -256.16433)
			(xy 108.769239 -256.209466) (xy 108.782737 -256.25692) (xy 108.789555 -256.305782) (xy 108.789978 -256.33045)
			(xy 108.78948 -256.357099) (xy 108.784772 -256.388341) (xy 109.984784 -256.388341) (xy 109.984784 -256.335043)
			(xy 109.992727 -256.282339) (xy 110.008437 -256.231409) (xy 110.031563 -256.183388) (xy 110.061587 -256.139351)
			(xy 110.097839 -256.10028) (xy 110.13951 -256.067049) (xy 110.185668 -256.0404) (xy 110.235282 -256.020928)
			(xy 110.287244 -256.009068) (xy 110.340394 -256.005085) (xy 110.393544 -256.009068) (xy 110.445506 -256.020928)
			(xy 110.49512 -256.0404) (xy 110.541278 -256.067049) (xy 110.582949 -256.10028) (xy 110.619201 -256.139351)
			(xy 110.649225 -256.183388) (xy 110.672351 -256.231409) (xy 110.688061 -256.282339) (xy 110.696004 -256.335043)
			(xy 110.696502 -256.361692) (xy 110.696004 -256.388341) (xy 110.695771 -256.389886) (xy 115.072414 -256.389886)
			(xy 115.072817 -256.365216) (xy 115.079625 -256.316349) (xy 115.093121 -256.268891) (xy 115.113046 -256.223754)
			(xy 115.139019 -256.181804) (xy 115.154456 -256.162556) (xy 115.163095 -256.151435) (xy 115.174437 -256.125671)
			(xy 115.178315 -256.097789) (xy 115.174432 -256.069908) (xy 115.163083 -256.044146) (xy 115.154456 -256.033016)
			(xy 115.139049 -256.013747) (xy 115.113086 -255.971797) (xy 115.093163 -255.926664) (xy 115.079662 -255.879213)
			(xy 115.072839 -255.830353) (xy 115.072414 -255.805686) (xy 115.072912 -255.779037) (xy 115.080855 -255.726333)
			(xy 115.096565 -255.675403) (xy 115.119691 -255.627382) (xy 115.149715 -255.583345) (xy 115.185967 -255.544274)
			(xy 115.227638 -255.511043) (xy 115.273796 -255.484394) (xy 115.32341 -255.464922) (xy 115.375372 -255.453062)
			(xy 115.428522 -255.449079) (xy 115.481672 -255.453062) (xy 115.533634 -255.464922) (xy 115.583248 -255.484394)
			(xy 115.629406 -255.511043) (xy 115.671077 -255.544274) (xy 115.707329 -255.583345) (xy 115.737353 -255.627382)
			(xy 115.760479 -255.675403) (xy 115.776189 -255.726333) (xy 115.784132 -255.779037) (xy 115.78463 -255.805686)
			(xy 115.784223 -255.830356) (xy 115.777418 -255.879224) (xy 115.763924 -255.926682) (xy 115.743999 -255.971819)
			(xy 115.718025 -256.013768) (xy 115.702588 -256.033016) (xy 115.693973 -256.044155) (xy 115.682622 -256.069911)
			(xy 115.678738 -256.097789) (xy 115.682616 -256.125668) (xy 115.693962 -256.151427) (xy 115.702588 -256.162556)
			(xy 115.718035 -256.181794) (xy 115.74399 -256.223754) (xy 115.763904 -256.268894) (xy 115.777397 -256.316351)
			(xy 115.78421 -256.365217) (xy 115.78463 -256.389886) (xy 115.784132 -256.416535) (xy 115.776189 -256.469239)
			(xy 115.760479 -256.520169) (xy 115.737353 -256.56819) (xy 115.707329 -256.612227) (xy 115.671077 -256.651298)
			(xy 115.629406 -256.684529) (xy 115.583248 -256.711178) (xy 115.533634 -256.73065) (xy 115.481672 -256.74251)
			(xy 115.428522 -256.746494) (xy 115.375372 -256.74251) (xy 115.32341 -256.73065) (xy 115.273796 -256.711178)
			(xy 115.227638 -256.684529) (xy 115.185967 -256.651298) (xy 115.149715 -256.612227) (xy 115.119691 -256.56819)
			(xy 115.096565 -256.520169) (xy 115.080855 -256.469239) (xy 115.072912 -256.416535) (xy 115.072414 -256.389886)
			(xy 110.695771 -256.389886) (xy 110.688061 -256.441045) (xy 110.672351 -256.491975) (xy 110.649225 -256.539996)
			(xy 110.619201 -256.584033) (xy 110.582949 -256.623104) (xy 110.541278 -256.656335) (xy 110.49512 -256.682984)
			(xy 110.445506 -256.702456) (xy 110.393544 -256.714316) (xy 110.340394 -256.7183) (xy 110.287244 -256.714316)
			(xy 110.235282 -256.702456) (xy 110.185668 -256.682984) (xy 110.13951 -256.656335) (xy 110.097839 -256.623104)
			(xy 110.061587 -256.584033) (xy 110.031563 -256.539996) (xy 110.008437 -256.491975) (xy 109.992727 -256.441045)
			(xy 109.984784 -256.388341) (xy 108.784772 -256.388341) (xy 108.781537 -256.409803) (xy 108.765827 -256.460733)
			(xy 108.742701 -256.508754) (xy 108.712677 -256.552791) (xy 108.676425 -256.591862) (xy 108.634754 -256.625093)
			(xy 108.588596 -256.651742) (xy 108.538982 -256.671214) (xy 108.48702 -256.683074) (xy 108.43387 -256.687058)
			(xy 108.38072 -256.683074) (xy 108.328758 -256.671214) (xy 108.279144 -256.651742) (xy 108.232986 -256.625093)
			(xy 108.191315 -256.591862) (xy 108.155063 -256.552791) (xy 108.125039 -256.508754) (xy 108.101913 -256.460733)
			(xy 108.086203 -256.409803) (xy 108.07826 -256.357099) (xy 108.077762 -256.33045) (xy 103.881428 -256.33045)
			(xy 103.881428 -257.202157) (xy 113.274338 -257.202157) (xy 113.274338 -257.148859) (xy 113.282281 -257.096155)
			(xy 113.297991 -257.045225) (xy 113.321117 -256.997204) (xy 113.351141 -256.953167) (xy 113.387393 -256.914096)
			(xy 113.429064 -256.880865) (xy 113.475222 -256.854216) (xy 113.524836 -256.834744) (xy 113.576798 -256.822884)
			(xy 113.629948 -256.818901) (xy 113.683098 -256.822884) (xy 113.73506 -256.834744) (xy 113.784674 -256.854216)
			(xy 113.830832 -256.880865) (xy 113.872503 -256.914096) (xy 113.908755 -256.953167) (xy 113.938779 -256.997204)
			(xy 113.961905 -257.045225) (xy 113.977615 -257.096155) (xy 113.985558 -257.148859) (xy 113.986056 -257.175508)
			(xy 113.985558 -257.202157) (xy 113.977615 -257.254861) (xy 113.961905 -257.305791) (xy 113.938779 -257.353812)
			(xy 113.908755 -257.397849) (xy 113.872503 -257.43692) (xy 113.830832 -257.470151) (xy 113.784674 -257.4968)
			(xy 113.73506 -257.516272) (xy 113.683098 -257.528132) (xy 113.629948 -257.532116) (xy 113.576798 -257.528132)
			(xy 113.524836 -257.516272) (xy 113.475222 -257.4968) (xy 113.429064 -257.470151) (xy 113.387393 -257.43692)
			(xy 113.351141 -257.397849) (xy 113.321117 -257.353812) (xy 113.297991 -257.305791) (xy 113.282281 -257.254861)
			(xy 113.274338 -257.202157) (xy 103.881428 -257.202157) (xy 103.881428 -257.235452) (xy 103.881818 -257.248779)
			(xy 103.888707 -257.274526) (xy 103.902029 -257.297611) (xy 103.920873 -257.316459) (xy 103.943956 -257.329785)
			(xy 103.969701 -257.336679) (xy 103.983028 -257.337052) (xy 103.983282 -257.337052) (xy 104.008001 -257.33744)
			(xy 104.056973 -257.344212) (xy 104.104536 -257.357698) (xy 104.149774 -257.377638) (xy 104.191816 -257.403648)
			(xy 104.21112 -257.419094) (xy 104.22225 -257.427721) (xy 104.24801 -257.439068) (xy 104.27589 -257.442949)
			(xy 104.30377 -257.439068) (xy 104.32953 -257.427721) (xy 104.34066 -257.419094) (xy 104.359907 -257.403656)
			(xy 104.401857 -257.377681) (xy 104.446994 -257.357754) (xy 104.494452 -257.344257) (xy 104.54332 -257.337449)
			(xy 104.56799 -257.337052) (xy 104.594645 -257.337525) (xy 104.647359 -257.345469) (xy 104.6983 -257.361181)
			(xy 104.74633 -257.38431) (xy 104.790377 -257.414339) (xy 104.829456 -257.450598) (xy 104.862694 -257.492276)
			(xy 104.889349 -257.538443) (xy 104.908826 -257.588067) (xy 104.920688 -257.64004) (xy 104.924672 -257.6932)
			(xy 105.100352 -257.6932) (xy 105.104336 -257.640045) (xy 105.116197 -257.588078) (xy 105.13567 -257.538459)
			(xy 105.162322 -257.492296) (xy 105.195556 -257.450622) (xy 105.234629 -257.414365) (xy 105.27867 -257.384338)
			(xy 105.326695 -257.361209) (xy 105.37763 -257.345496) (xy 105.430338 -257.33755) (xy 105.45699 -257.337052)
			(xy 105.48283 -257.337522) (xy 105.533966 -257.345003) (xy 105.583485 -257.359794) (xy 105.630346 -257.381584)
			(xy 105.673568 -257.409918) (xy 105.69321 -257.426714) (xy 105.704588 -257.436104) (xy 105.73134 -257.448507)
			(xy 105.76052 -257.452759) (xy 105.7897 -257.448507) (xy 105.816452 -257.436104) (xy 105.82783 -257.426714)
			(xy 105.847457 -257.409897) (xy 105.890677 -257.381556) (xy 105.937542 -257.359764) (xy 105.987066 -257.344978)
			(xy 106.038208 -257.33751) (xy 106.06405 -257.337052) (xy 106.090701 -257.337602) (xy 106.143407 -257.345539)
			(xy 106.194342 -257.361244) (xy 106.242367 -257.384366) (xy 106.286409 -257.414387) (xy 106.325484 -257.450638)
			(xy 106.358719 -257.492309) (xy 106.385372 -257.538468) (xy 106.404847 -257.588084) (xy 106.416708 -257.640048)
			(xy 106.420692 -257.6932) (xy 106.416708 -257.746352) (xy 106.404847 -257.798316) (xy 106.385372 -257.847932)
			(xy 106.358719 -257.894091) (xy 106.325484 -257.935762) (xy 106.286409 -257.972013) (xy 106.242367 -258.002034)
			(xy 106.213415 -258.015973) (xy 109.985038 -258.015973) (xy 109.985038 -257.962675) (xy 109.992981 -257.909971)
			(xy 110.008691 -257.859041) (xy 110.031817 -257.81102) (xy 110.061841 -257.766983) (xy 110.098093 -257.727912)
			(xy 110.139764 -257.694681) (xy 110.185922 -257.668032) (xy 110.235536 -257.64856) (xy 110.287498 -257.6367)
			(xy 110.340648 -257.632717) (xy 110.393798 -257.6367) (xy 110.44576 -257.64856) (xy 110.495374 -257.668032)
			(xy 110.541532 -257.694681) (xy 110.583203 -257.727912) (xy 110.619455 -257.766983) (xy 110.649479 -257.81102)
			(xy 110.672605 -257.859041) (xy 110.688315 -257.909971) (xy 110.696258 -257.962675) (xy 110.696756 -257.989324)
			(xy 110.696258 -258.015973) (xy 110.688315 -258.068677) (xy 110.672605 -258.119607) (xy 110.649479 -258.167628)
			(xy 110.619455 -258.211665) (xy 110.583203 -258.250736) (xy 110.541532 -258.283967) (xy 110.495374 -258.310616)
			(xy 110.44576 -258.330088) (xy 110.393798 -258.341948) (xy 110.340648 -258.345932) (xy 110.287498 -258.341948)
			(xy 110.235536 -258.330088) (xy 110.185922 -258.310616) (xy 110.139764 -258.283967) (xy 110.098093 -258.250736)
			(xy 110.061841 -258.211665) (xy 110.031817 -258.167628) (xy 110.008691 -258.119607) (xy 109.992981 -258.068677)
			(xy 109.985038 -258.015973) (xy 106.213415 -258.015973) (xy 106.194342 -258.025156) (xy 106.143407 -258.040861)
			(xy 106.090701 -258.048798) (xy 106.06405 -258.049268) (xy 106.038209 -258.048828) (xy 105.987072 -258.04134)
			(xy 105.937553 -258.026541) (xy 105.890692 -258.004744) (xy 105.847472 -257.976405) (xy 105.82783 -257.959606)
			(xy 105.816452 -257.950216) (xy 105.7897 -257.937813) (xy 105.76052 -257.933561) (xy 105.73134 -257.937813)
			(xy 105.704588 -257.950216) (xy 105.69321 -257.959606) (xy 105.673557 -257.976391) (xy 105.630345 -258.00474)
			(xy 105.583487 -258.02654) (xy 105.533968 -258.041332) (xy 105.482831 -258.048807) (xy 105.45699 -258.049268)
			(xy 105.430338 -258.04885) (xy 105.37763 -258.040904) (xy 105.326695 -258.025191) (xy 105.27867 -258.002062)
			(xy 105.234629 -257.972035) (xy 105.195556 -257.935778) (xy 105.162322 -257.894104) (xy 105.13567 -257.847941)
			(xy 105.116197 -257.798322) (xy 105.104336 -257.746355) (xy 105.100352 -257.6932) (xy 104.924672 -257.6932)
			(xy 104.920688 -257.74636) (xy 104.908826 -257.798333) (xy 104.889349 -257.847957) (xy 104.862694 -257.894124)
			(xy 104.829456 -257.935802) (xy 104.790377 -257.972061) (xy 104.74633 -258.00209) (xy 104.6983 -258.025219)
			(xy 104.647359 -258.040931) (xy 104.594645 -258.048875) (xy 104.56799 -258.049268) (xy 104.543321 -258.048847)
			(xy 104.494456 -258.042034) (xy 104.447 -258.02854) (xy 104.401861 -258.008623) (xy 104.359904 -257.982665)
			(xy 104.34066 -257.967226) (xy 104.32953 -257.958599) (xy 104.30377 -257.947252) (xy 104.27589 -257.943371)
			(xy 104.24801 -257.947252) (xy 104.22225 -257.958599) (xy 104.21112 -257.967226) (xy 104.191822 -257.982676)
			(xy 104.149769 -258.008662) (xy 104.104528 -258.028586) (xy 104.056967 -258.042066) (xy 104.008 -258.048841)
			(xy 103.983282 -258.049268) (xy 103.983028 -258.049268) (xy 103.969705 -258.049699) (xy 103.943966 -258.056588)
			(xy 103.920887 -258.069904) (xy 103.902041 -258.088739) (xy 103.888711 -258.111811) (xy 103.881807 -258.137546)
			(xy 103.881428 -258.150868) (xy 103.881428 -259.578602) (xy 108.077762 -259.578602) (xy 108.078164 -259.553932)
			(xy 108.08497 -259.505064) (xy 108.098466 -259.457606) (xy 108.118392 -259.412469) (xy 108.144367 -259.370519)
			(xy 108.159804 -259.351272) (xy 108.168431 -259.340142) (xy 108.179782 -259.314382) (xy 108.183664 -259.286502)
			(xy 108.179782 -259.258621) (xy 108.168433 -259.232861) (xy 108.159804 -259.221732) (xy 108.144365 -259.202487)
			(xy 108.118406 -259.160531) (xy 108.098489 -259.115392) (xy 108.084995 -259.067936) (xy 108.078182 -259.019071)
			(xy 108.077762 -258.994402) (xy 108.07826 -258.967753) (xy 108.086203 -258.915049) (xy 108.101913 -258.864119)
			(xy 108.125039 -258.816098) (xy 108.155063 -258.772061) (xy 108.191315 -258.73299) (xy 108.232986 -258.699759)
			(xy 108.279144 -258.67311) (xy 108.328758 -258.653638) (xy 108.38072 -258.641778) (xy 108.43387 -258.637795)
			(xy 108.48702 -258.641778) (xy 108.538982 -258.653638) (xy 108.588596 -258.67311) (xy 108.634754 -258.699759)
			(xy 108.676425 -258.73299) (xy 108.712677 -258.772061) (xy 108.742701 -258.816098) (xy 108.749417 -258.830043)
			(xy 113.274338 -258.830043) (xy 113.274338 -258.776745) (xy 113.282281 -258.724041) (xy 113.297991 -258.673111)
			(xy 113.321117 -258.62509) (xy 113.351141 -258.581053) (xy 113.387393 -258.541982) (xy 113.429064 -258.508751)
			(xy 113.475222 -258.482102) (xy 113.524836 -258.46263) (xy 113.576798 -258.45077) (xy 113.629948 -258.446787)
			(xy 113.683098 -258.45077) (xy 113.73506 -258.46263) (xy 113.784674 -258.482102) (xy 113.830832 -258.508751)
			(xy 113.872503 -258.541982) (xy 113.908755 -258.581053) (xy 113.938779 -258.62509) (xy 113.961905 -258.673111)
			(xy 113.977615 -258.724041) (xy 113.985558 -258.776745) (xy 113.986056 -258.803394) (xy 113.985558 -258.830043)
			(xy 113.977615 -258.882747) (xy 113.961905 -258.933677) (xy 113.938779 -258.981698) (xy 113.908755 -259.025735)
			(xy 113.872503 -259.064806) (xy 113.830832 -259.098037) (xy 113.784674 -259.124686) (xy 113.73506 -259.144158)
			(xy 113.683098 -259.156018) (xy 113.629948 -259.160002) (xy 113.576798 -259.156018) (xy 113.524836 -259.144158)
			(xy 113.475222 -259.124686) (xy 113.429064 -259.098037) (xy 113.387393 -259.064806) (xy 113.351141 -259.025735)
			(xy 113.321117 -258.981698) (xy 113.297991 -258.933677) (xy 113.282281 -258.882747) (xy 113.274338 -258.830043)
			(xy 108.749417 -258.830043) (xy 108.765827 -258.864119) (xy 108.781537 -258.915049) (xy 108.78948 -258.967753)
			(xy 108.789978 -258.994402) (xy 108.78957 -259.019072) (xy 108.782764 -259.067939) (xy 108.769269 -259.115397)
			(xy 108.749344 -259.160534) (xy 108.723372 -259.202484) (xy 108.707936 -259.221732) (xy 108.699309 -259.232861)
			(xy 108.687966 -259.258622) (xy 108.684087 -259.286502) (xy 108.687967 -259.314381) (xy 108.699311 -259.340141)
			(xy 108.707936 -259.351272) (xy 108.723383 -259.370511) (xy 108.749339 -259.412469) (xy 108.769255 -259.457609)
			(xy 108.782747 -259.505067) (xy 108.789559 -259.553933) (xy 108.789978 -259.578602) (xy 108.78948 -259.605251)
			(xy 108.783661 -259.643859) (xy 109.984784 -259.643859) (xy 109.984784 -259.590561) (xy 109.992727 -259.537857)
			(xy 110.008437 -259.486927) (xy 110.031563 -259.438906) (xy 110.061587 -259.394869) (xy 110.097839 -259.355798)
			(xy 110.13951 -259.322567) (xy 110.185668 -259.295918) (xy 110.235282 -259.276446) (xy 110.287244 -259.264586)
			(xy 110.340394 -259.260603) (xy 110.393544 -259.264586) (xy 110.445506 -259.276446) (xy 110.49512 -259.295918)
			(xy 110.541278 -259.322567) (xy 110.582949 -259.355798) (xy 110.619201 -259.394869) (xy 110.649225 -259.438906)
			(xy 110.672351 -259.486927) (xy 110.688061 -259.537857) (xy 110.696004 -259.590561) (xy 110.696502 -259.61721)
			(xy 110.696165 -259.635244) (xy 115.070128 -259.635244) (xy 115.070562 -259.610575) (xy 115.077361 -259.561709)
			(xy 115.09085 -259.514251) (xy 115.110769 -259.469114) (xy 115.136736 -259.427163) (xy 115.15217 -259.407914)
			(xy 115.160752 -259.396753) (xy 115.172101 -259.371004) (xy 115.175988 -259.343134) (xy 115.172119 -259.315262)
			(xy 115.160788 -259.289505) (xy 115.15217 -259.278374) (xy 115.136746 -259.259118) (xy 115.110786 -259.217164)
			(xy 115.090866 -259.172029) (xy 115.077368 -259.124575) (xy 115.070551 -259.075712) (xy 115.070128 -259.051044)
			(xy 115.070626 -259.024395) (xy 115.078569 -258.971691) (xy 115.094279 -258.920761) (xy 115.117405 -258.87274)
			(xy 115.147429 -258.828703) (xy 115.183681 -258.789632) (xy 115.225352 -258.756401) (xy 115.27151 -258.729752)
			(xy 115.321124 -258.71028) (xy 115.373086 -258.69842) (xy 115.426236 -258.694437) (xy 115.479386 -258.69842)
			(xy 115.531348 -258.71028) (xy 115.580962 -258.729752) (xy 115.62712 -258.756401) (xy 115.668791 -258.789632)
			(xy 115.705043 -258.828703) (xy 115.735067 -258.87274) (xy 115.758193 -258.920761) (xy 115.773903 -258.971691)
			(xy 115.781846 -259.024395) (xy 115.782344 -259.051044) (xy 115.78191 -259.075713) (xy 115.775111 -259.12458)
			(xy 115.761623 -259.172037) (xy 115.741704 -259.217175) (xy 115.715736 -259.259125) (xy 115.700302 -259.278374)
			(xy 115.691631 -259.289473) (xy 115.680285 -259.315244) (xy 115.676411 -259.343134) (xy 115.680304 -259.371022)
			(xy 115.691667 -259.396785) (xy 115.700302 -259.407914) (xy 115.715716 -259.427177) (xy 115.741679 -259.469129)
			(xy 115.761601 -259.514263) (xy 115.775101 -259.561715) (xy 115.78192 -259.610576) (xy 115.782344 -259.635244)
			(xy 115.781846 -259.661893) (xy 115.773903 -259.714597) (xy 115.758193 -259.765527) (xy 115.735067 -259.813548)
			(xy 115.705043 -259.857585) (xy 115.668791 -259.896656) (xy 115.62712 -259.929887) (xy 115.580962 -259.956536)
			(xy 115.531348 -259.976008) (xy 115.479386 -259.987868) (xy 115.426236 -259.991852) (xy 115.373086 -259.987868)
			(xy 115.321124 -259.976008) (xy 115.27151 -259.956536) (xy 115.225352 -259.929887) (xy 115.183681 -259.896656)
			(xy 115.147429 -259.857585) (xy 115.117405 -259.813548) (xy 115.094279 -259.765527) (xy 115.078569 -259.714597)
			(xy 115.070626 -259.661893) (xy 115.070128 -259.635244) (xy 110.696165 -259.635244) (xy 110.696004 -259.643859)
			(xy 110.688061 -259.696563) (xy 110.672351 -259.747493) (xy 110.649225 -259.795514) (xy 110.619201 -259.839551)
			(xy 110.582949 -259.878622) (xy 110.541278 -259.911853) (xy 110.49512 -259.938502) (xy 110.445506 -259.957974)
			(xy 110.393544 -259.969834) (xy 110.340394 -259.973818) (xy 110.287244 -259.969834) (xy 110.235282 -259.957974)
			(xy 110.185668 -259.938502) (xy 110.13951 -259.911853) (xy 110.097839 -259.878622) (xy 110.061587 -259.839551)
			(xy 110.031563 -259.795514) (xy 110.008437 -259.747493) (xy 109.992727 -259.696563) (xy 109.984784 -259.643859)
			(xy 108.783661 -259.643859) (xy 108.781537 -259.657955) (xy 108.765827 -259.708885) (xy 108.742701 -259.756906)
			(xy 108.712677 -259.800943) (xy 108.676425 -259.840014) (xy 108.634754 -259.873245) (xy 108.588596 -259.899894)
			(xy 108.538982 -259.919366) (xy 108.48702 -259.931226) (xy 108.43387 -259.93521) (xy 108.38072 -259.931226)
			(xy 108.328758 -259.919366) (xy 108.279144 -259.899894) (xy 108.232986 -259.873245) (xy 108.191315 -259.840014)
			(xy 108.155063 -259.800943) (xy 108.125039 -259.756906) (xy 108.101913 -259.708885) (xy 108.086203 -259.657955)
			(xy 108.07826 -259.605251) (xy 108.077762 -259.578602) (xy 103.881428 -259.578602) (xy 103.881428 -260.457675)
			(xy 113.274338 -260.457675) (xy 113.274338 -260.404377) (xy 113.282281 -260.351673) (xy 113.297991 -260.300743)
			(xy 113.321117 -260.252722) (xy 113.351141 -260.208685) (xy 113.387393 -260.169614) (xy 113.429064 -260.136383)
			(xy 113.475222 -260.109734) (xy 113.524836 -260.090262) (xy 113.576798 -260.078402) (xy 113.629948 -260.074419)
			(xy 113.683098 -260.078402) (xy 113.73506 -260.090262) (xy 113.784674 -260.109734) (xy 113.830832 -260.136383)
			(xy 113.872503 -260.169614) (xy 113.908755 -260.208685) (xy 113.938779 -260.252722) (xy 113.961905 -260.300743)
			(xy 113.977615 -260.351673) (xy 113.985558 -260.404377) (xy 113.986056 -260.431026) (xy 113.985558 -260.457675)
			(xy 113.977615 -260.510379) (xy 113.961905 -260.561309) (xy 113.938779 -260.60933) (xy 113.908755 -260.653367)
			(xy 113.872503 -260.692438) (xy 113.830832 -260.725669) (xy 113.784674 -260.752318) (xy 113.73506 -260.77179)
			(xy 113.683098 -260.78365) (xy 113.629948 -260.787634) (xy 113.576798 -260.78365) (xy 113.524836 -260.77179)
			(xy 113.475222 -260.752318) (xy 113.429064 -260.725669) (xy 113.387393 -260.692438) (xy 113.351141 -260.653367)
			(xy 113.321117 -260.60933) (xy 113.297991 -260.561309) (xy 113.282281 -260.510379) (xy 113.274338 -260.457675)
			(xy 103.881428 -260.457675) (xy 103.881428 -261.3292) (xy 104.281462 -261.3292) (xy 104.285446 -261.276047)
			(xy 104.297307 -261.22408) (xy 104.31678 -261.174462) (xy 104.343431 -261.128301) (xy 104.376664 -261.086627)
			(xy 104.415737 -261.050372) (xy 104.459778 -261.020345) (xy 104.507801 -260.997217) (xy 104.558736 -260.981505)
			(xy 104.611443 -260.97356) (xy 104.638094 -260.973062) (xy 104.665414 -260.973597) (xy 104.719414 -260.981933)
			(xy 104.77151 -260.998412) (xy 104.820482 -261.022646) (xy 104.865183 -261.054069) (xy 104.885236 -261.07263)
			(xy 104.896858 -261.083027) (xy 104.924792 -261.096851) (xy 104.955594 -261.101607) (xy 104.986396 -261.096851)
			(xy 105.01433 -261.083027) (xy 105.025952 -261.07263) (xy 105.045998 -261.054054) (xy 105.090681 -261.022591)
			(xy 105.139652 -260.998334) (xy 105.191757 -260.981854) (xy 105.245769 -260.973539) (xy 105.273094 -260.973062)
			(xy 105.300414 -260.973597) (xy 105.354414 -260.981933) (xy 105.40651 -260.998412) (xy 105.455482 -261.022646)
			(xy 105.500183 -261.054069) (xy 105.520236 -261.07263) (xy 105.531858 -261.083027) (xy 105.559792 -261.096851)
			(xy 105.590594 -261.101607) (xy 105.621396 -261.096851) (xy 105.64933 -261.083027) (xy 105.660952 -261.07263)
			(xy 105.680998 -261.054054) (xy 105.725681 -261.022591) (xy 105.774652 -260.998334) (xy 105.826757 -260.981854)
			(xy 105.880769 -260.973539) (xy 105.908094 -260.973062) (xy 105.935414 -260.973597) (xy 105.989414 -260.981933)
			(xy 106.04151 -260.998412) (xy 106.090482 -261.022646) (xy 106.135183 -261.054069) (xy 106.155236 -261.07263)
			(xy 106.166858 -261.083027) (xy 106.194792 -261.096851) (xy 106.225594 -261.101607) (xy 106.256396 -261.096851)
			(xy 106.28433 -261.083027) (xy 106.295952 -261.07263) (xy 106.315998 -261.054054) (xy 106.360681 -261.022591)
			(xy 106.409652 -260.998334) (xy 106.461757 -260.981854) (xy 106.515769 -260.973539) (xy 106.543094 -260.973062)
			(xy 106.570414 -260.973597) (xy 106.624414 -260.981933) (xy 106.67651 -260.998412) (xy 106.725482 -261.022646)
			(xy 106.770183 -261.054069) (xy 106.790236 -261.07263) (xy 106.801858 -261.083027) (xy 106.829792 -261.096851)
			(xy 106.860594 -261.101607) (xy 106.891396 -261.096851) (xy 106.91933 -261.083027) (xy 106.930952 -261.07263)
			(xy 106.950998 -261.054054) (xy 106.995681 -261.022591) (xy 107.044652 -260.998334) (xy 107.096757 -260.981854)
			(xy 107.150769 -260.973539) (xy 107.178094 -260.973062) (xy 107.204743 -260.973595) (xy 107.257446 -260.981538)
			(xy 107.308377 -260.997247) (xy 107.356398 -261.020372) (xy 107.400435 -261.050395) (xy 107.439506 -261.086647)
			(xy 107.472737 -261.128317) (xy 107.499387 -261.174475) (xy 107.518859 -261.224089) (xy 107.529736 -261.271745)
			(xy 109.984784 -261.271745) (xy 109.984784 -261.218447) (xy 109.992727 -261.165743) (xy 110.008437 -261.114813)
			(xy 110.031563 -261.066792) (xy 110.061587 -261.022755) (xy 110.097839 -260.983684) (xy 110.13951 -260.950453)
			(xy 110.185668 -260.923804) (xy 110.235282 -260.904332) (xy 110.287244 -260.892472) (xy 110.340394 -260.888489)
			(xy 110.393544 -260.892472) (xy 110.445506 -260.904332) (xy 110.49512 -260.923804) (xy 110.541278 -260.950453)
			(xy 110.582949 -260.983684) (xy 110.619201 -261.022755) (xy 110.649225 -261.066792) (xy 110.672351 -261.114813)
			(xy 110.688061 -261.165743) (xy 110.696004 -261.218447) (xy 110.696502 -261.245096) (xy 110.696004 -261.271745)
			(xy 110.688061 -261.324449) (xy 110.672351 -261.375379) (xy 110.649225 -261.4234) (xy 110.619201 -261.467437)
			(xy 110.582949 -261.506508) (xy 110.541278 -261.539739) (xy 110.49512 -261.566388) (xy 110.445506 -261.58586)
			(xy 110.393544 -261.59772) (xy 110.340394 -261.601704) (xy 110.287244 -261.59772) (xy 110.235282 -261.58586)
			(xy 110.185668 -261.566388) (xy 110.13951 -261.539739) (xy 110.097839 -261.506508) (xy 110.061587 -261.467437)
			(xy 110.031563 -261.4234) (xy 110.008437 -261.375379) (xy 109.992727 -261.324449) (xy 109.984784 -261.271745)
			(xy 107.529736 -261.271745) (xy 107.530719 -261.276051) (xy 107.534702 -261.3292) (xy 107.530719 -261.382349)
			(xy 107.518859 -261.434311) (xy 107.499387 -261.483925) (xy 107.472737 -261.530083) (xy 107.439506 -261.571753)
			(xy 107.400435 -261.608005) (xy 107.356398 -261.638028) (xy 107.308377 -261.661153) (xy 107.257446 -261.676862)
			(xy 107.204743 -261.684805) (xy 107.178094 -261.685278) (xy 107.150773 -261.684767) (xy 107.096771 -261.676427)
			(xy 107.044674 -261.659944) (xy 106.995702 -261.635704) (xy 106.951004 -261.604275) (xy 106.930952 -261.58571)
			(xy 106.91933 -261.575313) (xy 106.891396 -261.561489) (xy 106.860594 -261.556733) (xy 106.829792 -261.561489)
			(xy 106.801858 -261.575313) (xy 106.790236 -261.58571) (xy 106.770202 -261.604299) (xy 106.725514 -261.635758)
			(xy 106.676541 -261.660012) (xy 106.624434 -261.676489) (xy 106.57042 -261.684802) (xy 106.543094 -261.685278)
			(xy 106.515773 -261.684767) (xy 106.461771 -261.676427) (xy 106.409674 -261.659944) (xy 106.360702 -261.635704)
			(xy 106.316004 -261.604275) (xy 106.295952 -261.58571) (xy 106.28433 -261.575313) (xy 106.256396 -261.561489)
			(xy 106.225594 -261.556733) (xy 106.194792 -261.561489) (xy 106.166858 -261.575313) (xy 106.155236 -261.58571)
			(xy 106.135202 -261.604299) (xy 106.090514 -261.635758) (xy 106.041541 -261.660012) (xy 105.989434 -261.676489)
			(xy 105.93542 -261.684802) (xy 105.908094 -261.685278) (xy 105.880773 -261.684767) (xy 105.826771 -261.676427)
			(xy 105.774674 -261.659944) (xy 105.725702 -261.635704) (xy 105.681004 -261.604275) (xy 105.660952 -261.58571)
			(xy 105.64933 -261.575313) (xy 105.621396 -261.561489) (xy 105.590594 -261.556733) (xy 105.559792 -261.561489)
			(xy 105.531858 -261.575313) (xy 105.520236 -261.58571) (xy 105.500202 -261.604299) (xy 105.455514 -261.635758)
			(xy 105.406541 -261.660012) (xy 105.354434 -261.676489) (xy 105.30042 -261.684802) (xy 105.273094 -261.685278)
			(xy 105.245773 -261.684767) (xy 105.191771 -261.676427) (xy 105.139674 -261.659944) (xy 105.090702 -261.635704)
			(xy 105.046004 -261.604275) (xy 105.025952 -261.58571) (xy 105.01433 -261.575313) (xy 104.986396 -261.561489)
			(xy 104.955594 -261.556733) (xy 104.924792 -261.561489) (xy 104.896858 -261.575313) (xy 104.885236 -261.58571)
			(xy 104.865202 -261.604299) (xy 104.820514 -261.635758) (xy 104.771541 -261.660012) (xy 104.719434 -261.676489)
			(xy 104.66542 -261.684802) (xy 104.638094 -261.685278) (xy 104.611443 -261.68484) (xy 104.558736 -261.676895)
			(xy 104.507801 -261.661183) (xy 104.459778 -261.638055) (xy 104.415737 -261.608028) (xy 104.376664 -261.571773)
			(xy 104.343431 -261.530099) (xy 104.31678 -261.483938) (xy 104.297307 -261.43432) (xy 104.285446 -261.382353)
			(xy 104.281462 -261.3292) (xy 103.881428 -261.3292) (xy 103.881428 -261.805928) (xy 103.905533 -261.819318)
			(xy 103.949662 -261.852377) (xy 103.988173 -261.891837) (xy 104.020149 -261.936757) (xy 104.044826 -261.986065)
			(xy 104.061615 -262.038586) (xy 104.068945 -262.085561) (xy 113.274338 -262.085561) (xy 113.274338 -262.032263)
			(xy 113.282281 -261.979559) (xy 113.297991 -261.928629) (xy 113.321117 -261.880608) (xy 113.351141 -261.836571)
			(xy 113.387393 -261.7975) (xy 113.429064 -261.764269) (xy 113.475222 -261.73762) (xy 113.524836 -261.718148)
			(xy 113.576798 -261.706288) (xy 113.629948 -261.702305) (xy 113.683098 -261.706288) (xy 113.73506 -261.718148)
			(xy 113.784674 -261.73762) (xy 113.830832 -261.764269) (xy 113.872503 -261.7975) (xy 113.908755 -261.836571)
			(xy 113.938779 -261.880608) (xy 113.961905 -261.928629) (xy 113.977615 -261.979559) (xy 113.985558 -262.032263)
			(xy 113.986056 -262.058912) (xy 113.985558 -262.085561) (xy 113.977615 -262.138265) (xy 113.961905 -262.189195)
			(xy 113.938779 -262.237216) (xy 113.908755 -262.281253) (xy 113.872503 -262.320324) (xy 113.830832 -262.353555)
			(xy 113.784674 -262.380204) (xy 113.73506 -262.399676) (xy 113.683098 -262.411536) (xy 113.629948 -262.41552)
			(xy 113.576798 -262.411536) (xy 113.524836 -262.399676) (xy 113.475222 -262.380204) (xy 113.429064 -262.353555)
			(xy 113.387393 -262.320324) (xy 113.351141 -262.281253) (xy 113.321117 -262.237216) (xy 113.297991 -262.189195)
			(xy 113.282281 -262.138265) (xy 113.274338 -262.085561) (xy 104.068945 -262.085561) (xy 104.070116 -262.093065)
			(xy 104.070658 -262.120634) (xy 104.070236 -262.145302) (xy 104.063419 -262.194165) (xy 104.049922 -262.24162)
			(xy 104.030003 -262.286756) (xy 104.004043 -262.32871) (xy 103.988616 -262.347964) (xy 103.97999 -262.359092)
			(xy 103.968647 -262.38485) (xy 103.964772 -262.412726) (xy 103.968661 -262.440601) (xy 103.980018 -262.466353)
			(xy 103.988616 -262.477504) (xy 104.004051 -262.496752) (xy 104.03002 -262.538703) (xy 104.049941 -262.58384)
			(xy 104.063432 -262.631298) (xy 104.070233 -262.680165) (xy 104.070658 -262.704834) (xy 104.070147 -262.732407)
			(xy 104.06166 -262.786896) (xy 104.044877 -262.839427) (xy 104.020201 -262.888744) (xy 104.012632 -262.899377)
			(xy 109.985038 -262.899377) (xy 109.985038 -262.846079) (xy 109.992981 -262.793375) (xy 110.008691 -262.742445)
			(xy 110.031817 -262.694424) (xy 110.061841 -262.650387) (xy 110.098093 -262.611316) (xy 110.139764 -262.578085)
			(xy 110.185922 -262.551436) (xy 110.235536 -262.531964) (xy 110.287498 -262.520104) (xy 110.340648 -262.516121)
			(xy 110.393798 -262.520104) (xy 110.44576 -262.531964) (xy 110.495374 -262.551436) (xy 110.541532 -262.578085)
			(xy 110.583203 -262.611316) (xy 110.619455 -262.650387) (xy 110.649479 -262.694424) (xy 110.671373 -262.739886)
			(xy 115.96116 -262.739886) (xy 115.961683 -262.712566) (xy 115.970023 -262.658565) (xy 115.986504 -262.606469)
			(xy 116.010741 -262.557497) (xy 116.042166 -262.512797) (xy 116.060728 -262.492744) (xy 116.071141 -262.481134)
			(xy 116.084967 -262.453197) (xy 116.089721 -262.42239) (xy 116.084961 -262.391584) (xy 116.071129 -262.363649)
			(xy 116.060728 -262.352028) (xy 116.042142 -262.331991) (xy 116.010681 -262.287305) (xy 115.986426 -262.238332)
			(xy 115.969948 -262.186226) (xy 115.961636 -262.132211) (xy 115.96116 -262.104886) (xy 115.961726 -262.07706)
			(xy 115.970365 -262.022083) (xy 115.98746 -261.969122) (xy 116.012595 -261.919469) (xy 116.045155 -261.874337)
			(xy 116.084348 -261.834827) (xy 116.129215 -261.801902) (xy 116.153692 -261.788656) (xy 116.166621 -261.781447)
			(xy 116.187964 -261.760957) (xy 116.202529 -261.735203) (xy 116.209089 -261.706352) (xy 116.207093 -261.676832)
			(xy 116.196709 -261.649127) (xy 116.17881 -261.625568) (xy 116.167154 -261.616444) (xy 116.145015 -261.599521)
			(xy 116.105761 -261.559975) (xy 116.073143 -261.514798) (xy 116.047958 -261.465093) (xy 116.030821 -261.412073)
			(xy 116.022149 -261.357031) (xy 116.021612 -261.32917) (xy 116.022113 -261.301185) (xy 116.030873 -261.245905)
			(xy 116.048173 -261.192676) (xy 116.073587 -261.142808) (xy 116.106489 -261.09753) (xy 116.146068 -261.057956)
			(xy 116.191351 -261.025061) (xy 116.241222 -260.999654) (xy 116.294454 -260.982362) (xy 116.349735 -260.973609)
			(xy 116.37772 -260.973062) (xy 116.405041 -260.973581) (xy 116.459042 -260.981921) (xy 116.511138 -260.998403)
			(xy 116.560109 -261.022641) (xy 116.604809 -261.054067) (xy 116.624862 -261.07263) (xy 116.636484 -261.083027)
			(xy 116.664418 -261.096851) (xy 116.69522 -261.101607) (xy 116.726022 -261.096851) (xy 116.753956 -261.083027)
			(xy 116.765578 -261.07263) (xy 116.785613 -261.054041) (xy 116.830299 -261.02258) (xy 116.879272 -260.998326)
			(xy 116.93138 -260.981849) (xy 116.985394 -260.973537) (xy 117.01272 -260.973062) (xy 117.040041 -260.973581)
			(xy 117.094042 -260.981921) (xy 117.146138 -260.998403) (xy 117.195109 -261.022641) (xy 117.239809 -261.054067)
			(xy 117.259862 -261.07263) (xy 117.271484 -261.083027) (xy 117.299418 -261.096851) (xy 117.33022 -261.101607)
			(xy 117.361022 -261.096851) (xy 117.388956 -261.083027) (xy 117.400578 -261.07263) (xy 117.420613 -261.054041)
			(xy 117.465299 -261.02258) (xy 117.514272 -260.998326) (xy 117.56638 -260.981849) (xy 117.620394 -260.973537)
			(xy 117.64772 -260.973062) (xy 117.675041 -260.973581) (xy 117.729042 -260.981921) (xy 117.781138 -260.998403)
			(xy 117.830109 -261.022641) (xy 117.874809 -261.054067) (xy 117.894862 -261.07263) (xy 117.906484 -261.083027)
			(xy 117.934418 -261.096851) (xy 117.96522 -261.101607) (xy 117.996022 -261.096851) (xy 118.023956 -261.083027)
			(xy 118.035578 -261.07263) (xy 118.055613 -261.054041) (xy 118.100299 -261.02258) (xy 118.149272 -260.998326)
			(xy 118.20138 -260.981849) (xy 118.255394 -260.973537) (xy 118.28272 -260.973062) (xy 118.309366 -260.973621)
			(xy 118.362063 -260.981567) (xy 118.412986 -260.997277) (xy 118.461 -261.020402) (xy 118.505031 -261.050424)
			(xy 118.544096 -261.086673) (xy 118.577322 -261.128339) (xy 118.603967 -261.174492) (xy 118.623436 -261.224101)
			(xy 118.635295 -261.276057) (xy 118.639277 -261.3292) (xy 118.635295 -261.382343) (xy 118.623436 -261.434299)
			(xy 118.603967 -261.483908) (xy 118.577322 -261.530061) (xy 118.544096 -261.571727) (xy 118.505031 -261.607976)
			(xy 118.461 -261.637998) (xy 118.412986 -261.661123) (xy 118.362063 -261.676833) (xy 118.309366 -261.684779)
			(xy 118.28272 -261.685278) (xy 118.255399 -261.684751) (xy 118.201398 -261.676415) (xy 118.149301 -261.659936)
			(xy 118.10033 -261.635699) (xy 118.05563 -261.604273) (xy 118.035578 -261.58571) (xy 118.023956 -261.575313)
			(xy 117.996022 -261.561489) (xy 117.96522 -261.556733) (xy 117.934418 -261.561489) (xy 117.906484 -261.575313)
			(xy 117.894862 -261.58571) (xy 117.874859 -261.604334) (xy 117.830163 -261.635789) (xy 117.781182 -261.660036)
			(xy 117.729068 -261.676505) (xy 117.675048 -261.684807) (xy 117.64772 -261.685278) (xy 117.620399 -261.684751)
			(xy 117.566398 -261.676415) (xy 117.514301 -261.659936) (xy 117.46533 -261.635699) (xy 117.42063 -261.604273)
			(xy 117.400578 -261.58571) (xy 117.388956 -261.575313) (xy 117.361022 -261.561489) (xy 117.33022 -261.556733)
			(xy 117.299418 -261.561489) (xy 117.271484 -261.575313) (xy 117.259862 -261.58571) (xy 117.239859 -261.604334)
			(xy 117.195163 -261.635789) (xy 117.146182 -261.660036) (xy 117.094068 -261.676505) (xy 117.040048 -261.684807)
			(xy 117.01272 -261.685278) (xy 116.985399 -261.684751) (xy 116.931398 -261.676415) (xy 116.879301 -261.659936)
			(xy 116.83033 -261.635699) (xy 116.78563 -261.604273) (xy 116.765578 -261.58571) (xy 116.753956 -261.575313)
			(xy 116.726022 -261.561489) (xy 116.69522 -261.556733) (xy 116.664418 -261.561489) (xy 116.636484 -261.575313)
			(xy 116.624862 -261.58571) (xy 116.605945 -261.603223) (xy 116.563998 -261.633186) (xy 116.541296 -261.6454)
			(xy 116.528406 -261.65267) (xy 116.507068 -261.673149) (xy 116.492505 -261.69889) (xy 116.485942 -261.727728)
			(xy 116.48793 -261.757236) (xy 116.498302 -261.784933) (xy 116.516186 -261.808488) (xy 116.527834 -261.817612)
			(xy 116.54995 -261.834564) (xy 116.589206 -261.874104) (xy 116.621826 -261.919275) (xy 116.647015 -261.968974)
			(xy 116.664158 -262.021989) (xy 116.672836 -262.077027) (xy 116.673376 -262.104886) (xy 116.672853 -262.132207)
			(xy 116.664516 -262.186208) (xy 116.648036 -262.238305) (xy 116.623799 -262.287277) (xy 116.592372 -262.331976)
			(xy 116.573808 -262.352028) (xy 116.563429 -262.363663) (xy 116.549609 -262.391593) (xy 116.544852 -262.42239)
			(xy 116.549602 -262.453188) (xy 116.563417 -262.48112) (xy 116.573808 -262.492744) (xy 116.592435 -262.512745)
			(xy 116.623889 -262.557441) (xy 116.648136 -262.606423) (xy 116.664604 -262.658538) (xy 116.672906 -262.712558)
			(xy 116.673376 -262.739886) (xy 116.672879 -262.766778) (xy 116.664797 -262.819952) (xy 116.648802 -262.871303)
			(xy 116.625257 -262.91966) (xy 116.610384 -262.94207) (xy 116.602317 -262.954509) (xy 116.593128 -262.982686)
			(xy 116.592423 -263.012314) (xy 116.600263 -263.040896) (xy 116.615986 -263.066018) (xy 116.638265 -263.085563)
			(xy 116.651532 -263.092184) (xy 116.672434 -263.102231) (xy 116.711678 -263.126944) (xy 116.729764 -263.14146)
			(xy 116.740894 -263.150087) (xy 116.766654 -263.161434) (xy 116.794534 -263.165315) (xy 116.822414 -263.161434)
			(xy 116.848174 -263.150087) (xy 116.859304 -263.14146) (xy 116.88072 -263.124337) (xy 116.927777 -263.096198)
			(xy 116.978594 -263.075609) (xy 117.031967 -263.063057) (xy 117.086634 -263.05884) (xy 117.141301 -263.063057)
			(xy 117.194674 -263.075609) (xy 117.245491 -263.096198) (xy 117.292548 -263.124337) (xy 117.313964 -263.14146)
			(xy 117.325094 -263.150087) (xy 117.350854 -263.161434) (xy 117.378734 -263.165315) (xy 117.406614 -263.161434)
			(xy 117.432374 -263.150087) (xy 117.443504 -263.14146) (xy 117.462766 -263.126044) (xy 117.504718 -263.100083)
			(xy 117.549853 -263.080162) (xy 117.597305 -263.066662) (xy 117.646166 -263.059842) (xy 117.670834 -263.059418)
			(xy 117.697484 -263.059866) (xy 117.750187 -263.067815) (xy 117.801117 -263.083529) (xy 117.849136 -263.106658)
			(xy 117.893173 -263.136685) (xy 117.932242 -263.17294) (xy 117.965472 -263.214612) (xy 117.99212 -263.260771)
			(xy 118.011591 -263.310387) (xy 118.023451 -263.36235) (xy 118.027434 -263.4155) (xy 118.023451 -263.46865)
			(xy 118.011591 -263.520613) (xy 117.99212 -263.570229) (xy 117.965472 -263.616388) (xy 117.932242 -263.658061)
			(xy 117.893173 -263.694315) (xy 117.849136 -263.724342) (xy 117.801117 -263.747471) (xy 117.750187 -263.763185)
			(xy 117.697484 -263.771134) (xy 117.670834 -263.771634) (xy 117.646165 -263.771215) (xy 117.597297 -263.764413)
			(xy 117.549839 -263.750921) (xy 117.504702 -263.730999) (xy 117.462752 -263.705028) (xy 117.443504 -263.689592)
			(xy 117.432374 -263.680965) (xy 117.406614 -263.669618) (xy 117.378734 -263.665737) (xy 117.350854 -263.669618)
			(xy 117.325094 -263.680965) (xy 117.313964 -263.689592) (xy 117.292548 -263.706715) (xy 117.245491 -263.734854)
			(xy 117.194674 -263.755443) (xy 117.141301 -263.767995) (xy 117.086634 -263.772212) (xy 117.031967 -263.767995)
			(xy 116.978594 -263.755443) (xy 116.927777 -263.734854) (xy 116.88072 -263.706715) (xy 116.859304 -263.689592)
			(xy 116.848174 -263.680965) (xy 116.822414 -263.669618) (xy 116.794534 -263.665737) (xy 116.766654 -263.669618)
			(xy 116.740894 -263.680965) (xy 116.729764 -263.689592) (xy 116.710519 -263.70503) (xy 116.668562 -263.730987)
			(xy 116.623423 -263.750903) (xy 116.575967 -263.764397) (xy 116.527103 -263.771212) (xy 116.502434 -263.771634)
			(xy 116.474451 -263.771056) (xy 116.419173 -263.762306) (xy 116.365944 -263.745017) (xy 116.316076 -263.719613)
			(xy 116.270796 -263.686721) (xy 116.231218 -263.64715) (xy 116.198318 -263.601875) (xy 116.172906 -263.552011)
			(xy 116.155608 -263.498785) (xy 116.146849 -263.443509) (xy 116.146326 -263.415526) (xy 116.146829 -263.388634)
			(xy 116.154909 -263.33546) (xy 116.170902 -263.28411) (xy 116.194446 -263.235753) (xy 116.209318 -263.213342)
			(xy 116.21737 -263.200894) (xy 116.226561 -263.172721) (xy 116.227268 -263.143095) (xy 116.219431 -263.114515)
			(xy 116.203711 -263.089394) (xy 116.181435 -263.06985) (xy 116.16817 -263.063228) (xy 116.145346 -263.052178)
			(xy 116.102766 -263.024642) (xy 116.064526 -262.991343) (xy 116.031398 -262.952953) (xy 116.004054 -262.91025)
			(xy 115.983047 -262.864099) (xy 115.968802 -262.815434) (xy 115.961607 -262.76524) (xy 115.96116 -262.739886)
			(xy 110.671373 -262.739886) (xy 110.672605 -262.742445) (xy 110.688315 -262.793375) (xy 110.696258 -262.846079)
			(xy 110.696756 -262.872728) (xy 110.696258 -262.899377) (xy 110.688315 -262.952081) (xy 110.672605 -263.003011)
			(xy 110.649479 -263.051032) (xy 110.619455 -263.095069) (xy 110.583203 -263.13414) (xy 110.541532 -263.167371)
			(xy 110.495374 -263.19402) (xy 110.44576 -263.213492) (xy 110.393798 -263.225352) (xy 110.340648 -263.229336)
			(xy 110.287498 -263.225352) (xy 110.235536 -263.213492) (xy 110.185922 -263.19402) (xy 110.139764 -263.167371)
			(xy 110.098093 -263.13414) (xy 110.061841 -263.095069) (xy 110.031817 -263.051032) (xy 110.008691 -263.003011)
			(xy 109.992981 -262.952081) (xy 109.985038 -262.899377) (xy 104.012632 -262.899377) (xy 103.98822 -262.933669)
			(xy 103.949698 -262.97313) (xy 103.905555 -263.006184) (xy 103.881428 -263.01954) (xy 103.881428 -263.274556)
			(xy 104.320065 -263.713193) (xy 113.27383 -263.713193) (xy 113.27383 -263.659895) (xy 113.281773 -263.607191)
			(xy 113.297483 -263.556261) (xy 113.320609 -263.50824) (xy 113.350633 -263.464203) (xy 113.386885 -263.425132)
			(xy 113.428556 -263.391901) (xy 113.474714 -263.365252) (xy 113.524328 -263.34578) (xy 113.57629 -263.33392)
			(xy 113.62944 -263.329937) (xy 113.68259 -263.33392) (xy 113.734552 -263.34578) (xy 113.784166 -263.365252)
			(xy 113.830324 -263.391901) (xy 113.871995 -263.425132) (xy 113.908247 -263.464203) (xy 113.938271 -263.50824)
			(xy 113.961397 -263.556261) (xy 113.977107 -263.607191) (xy 113.98505 -263.659895) (xy 113.985548 -263.686544)
			(xy 113.98505 -263.713193) (xy 115.153938 -263.713193) (xy 115.153938 -263.659895) (xy 115.161881 -263.607191)
			(xy 115.177591 -263.556261) (xy 115.200717 -263.50824) (xy 115.230741 -263.464203) (xy 115.266993 -263.425132)
			(xy 115.308664 -263.391901) (xy 115.354822 -263.365252) (xy 115.404436 -263.34578) (xy 115.456398 -263.33392)
			(xy 115.509548 -263.329937) (xy 115.562698 -263.33392) (xy 115.61466 -263.34578) (xy 115.664274 -263.365252)
			(xy 115.710432 -263.391901) (xy 115.752103 -263.425132) (xy 115.788355 -263.464203) (xy 115.818379 -263.50824)
			(xy 115.841505 -263.556261) (xy 115.857215 -263.607191) (xy 115.865158 -263.659895) (xy 115.865656 -263.686544)
			(xy 115.865158 -263.713193) (xy 115.857215 -263.765897) (xy 115.841505 -263.816827) (xy 115.818379 -263.864848)
			(xy 115.788355 -263.908885) (xy 115.752103 -263.947956) (xy 115.710432 -263.981187) (xy 115.664274 -264.007836)
			(xy 115.61466 -264.027308) (xy 115.562698 -264.039168) (xy 115.509548 -264.043152) (xy 115.456398 -264.039168)
			(xy 115.404436 -264.027308) (xy 115.354822 -264.007836) (xy 115.308664 -263.981187) (xy 115.266993 -263.947956)
			(xy 115.230741 -263.908885) (xy 115.200717 -263.864848) (xy 115.177591 -263.816827) (xy 115.161881 -263.765897)
			(xy 115.153938 -263.713193) (xy 113.98505 -263.713193) (xy 113.977107 -263.765897) (xy 113.961397 -263.816827)
			(xy 113.938271 -263.864848) (xy 113.908247 -263.908885) (xy 113.871995 -263.947956) (xy 113.830324 -263.981187)
			(xy 113.784166 -264.007836) (xy 113.734552 -264.027308) (xy 113.68259 -264.039168) (xy 113.62944 -264.043152)
			(xy 113.57629 -264.039168) (xy 113.524328 -264.027308) (xy 113.474714 -264.007836) (xy 113.428556 -263.981187)
			(xy 113.386885 -263.947956) (xy 113.350633 -263.908885) (xy 113.320609 -263.864848) (xy 113.297483 -263.816827)
			(xy 113.281773 -263.765897) (xy 113.27383 -263.713193) (xy 104.320065 -263.713193) (xy 104.362758 -263.755886)
			(xy 108.088176 -263.755886) (xy 108.476288 -264.143998) (xy 108.494576 -264.145776) (xy 108.521772 -264.148854)
			(xy 108.574828 -264.162286) (xy 108.625205 -264.183675) (xy 108.671717 -264.212518) (xy 108.713271 -264.248135)
			(xy 108.748888 -264.28969) (xy 108.777729 -264.336203) (xy 108.799117 -264.386581) (xy 108.812548 -264.439637)
			(xy 108.815632 -264.466832) (xy 108.81741 -264.48512) (xy 108.859299 -264.527009) (xy 114.683784 -264.527009)
			(xy 114.683784 -264.473711) (xy 114.691727 -264.421007) (xy 114.707437 -264.370077) (xy 114.730563 -264.322056)
			(xy 114.760587 -264.278019) (xy 114.796839 -264.238948) (xy 114.83851 -264.205717) (xy 114.884668 -264.179068)
			(xy 114.934282 -264.159596) (xy 114.986244 -264.147736) (xy 115.039394 -264.143753) (xy 115.092544 -264.147736)
			(xy 115.144506 -264.159596) (xy 115.19412 -264.179068) (xy 115.240278 -264.205717) (xy 115.281949 -264.238948)
			(xy 115.318201 -264.278019) (xy 115.348225 -264.322056) (xy 115.371351 -264.370077) (xy 115.387061 -264.421007)
			(xy 115.395004 -264.473711) (xy 115.395502 -264.50036) (xy 115.395004 -264.527009) (xy 115.623584 -264.527009)
			(xy 115.623584 -264.473711) (xy 115.631527 -264.421007) (xy 115.647237 -264.370077) (xy 115.670363 -264.322056)
			(xy 115.700387 -264.278019) (xy 115.736639 -264.238948) (xy 115.77831 -264.205717) (xy 115.824468 -264.179068)
			(xy 115.874082 -264.159596) (xy 115.926044 -264.147736) (xy 115.979194 -264.143753) (xy 116.032344 -264.147736)
			(xy 116.084306 -264.159596) (xy 116.13392 -264.179068) (xy 116.180078 -264.205717) (xy 116.221749 -264.238948)
			(xy 116.258001 -264.278019) (xy 116.288025 -264.322056) (xy 116.311151 -264.370077) (xy 116.326861 -264.421007)
			(xy 116.334804 -264.473711) (xy 116.335302 -264.50036) (xy 116.334804 -264.527009) (xy 116.563384 -264.527009)
			(xy 116.563384 -264.473711) (xy 116.571327 -264.421007) (xy 116.587037 -264.370077) (xy 116.610163 -264.322056)
			(xy 116.640187 -264.278019) (xy 116.676439 -264.238948) (xy 116.71811 -264.205717) (xy 116.764268 -264.179068)
			(xy 116.813882 -264.159596) (xy 116.865844 -264.147736) (xy 116.918994 -264.143753) (xy 116.972144 -264.147736)
			(xy 117.024106 -264.159596) (xy 117.07372 -264.179068) (xy 117.119878 -264.205717) (xy 117.161549 -264.238948)
			(xy 117.197801 -264.278019) (xy 117.227825 -264.322056) (xy 117.250951 -264.370077) (xy 117.266661 -264.421007)
			(xy 117.274604 -264.473711) (xy 117.275102 -264.50036) (xy 117.274604 -264.527009) (xy 117.266661 -264.579713)
			(xy 117.250951 -264.630643) (xy 117.227825 -264.678664) (xy 117.197801 -264.722701) (xy 117.161549 -264.761772)
			(xy 117.119878 -264.795003) (xy 117.07372 -264.821652) (xy 117.024106 -264.841124) (xy 116.972144 -264.852984)
			(xy 116.918994 -264.856968) (xy 116.865844 -264.852984) (xy 116.813882 -264.841124) (xy 116.764268 -264.821652)
			(xy 116.71811 -264.795003) (xy 116.676439 -264.761772) (xy 116.640187 -264.722701) (xy 116.610163 -264.678664)
			(xy 116.587037 -264.630643) (xy 116.571327 -264.579713) (xy 116.563384 -264.527009) (xy 116.334804 -264.527009)
			(xy 116.326861 -264.579713) (xy 116.311151 -264.630643) (xy 116.288025 -264.678664) (xy 116.258001 -264.722701)
			(xy 116.221749 -264.761772) (xy 116.180078 -264.795003) (xy 116.13392 -264.821652) (xy 116.084306 -264.841124)
			(xy 116.032344 -264.852984) (xy 115.979194 -264.856968) (xy 115.926044 -264.852984) (xy 115.874082 -264.841124)
			(xy 115.824468 -264.821652) (xy 115.77831 -264.795003) (xy 115.736639 -264.761772) (xy 115.700387 -264.722701)
			(xy 115.670363 -264.678664) (xy 115.647237 -264.630643) (xy 115.631527 -264.579713) (xy 115.623584 -264.527009)
			(xy 115.395004 -264.527009) (xy 115.387061 -264.579713) (xy 115.371351 -264.630643) (xy 115.348225 -264.678664)
			(xy 115.318201 -264.722701) (xy 115.281949 -264.761772) (xy 115.240278 -264.795003) (xy 115.19412 -264.821652)
			(xy 115.144506 -264.841124) (xy 115.092544 -264.852984) (xy 115.039394 -264.856968) (xy 114.986244 -264.852984)
			(xy 114.934282 -264.841124) (xy 114.884668 -264.821652) (xy 114.83851 -264.795003) (xy 114.796839 -264.761772)
			(xy 114.760587 -264.722701) (xy 114.730563 -264.678664) (xy 114.707437 -264.630643) (xy 114.691727 -264.579713)
			(xy 114.683784 -264.527009) (xy 108.859299 -264.527009) (xy 109.335316 -265.003026) (xy 109.335316 -265.340825)
			(xy 114.213884 -265.340825) (xy 114.213884 -265.287527) (xy 114.221827 -265.234823) (xy 114.237537 -265.183893)
			(xy 114.260663 -265.135872) (xy 114.290687 -265.091835) (xy 114.326939 -265.052764) (xy 114.36861 -265.019533)
			(xy 114.414768 -264.992884) (xy 114.464382 -264.973412) (xy 114.516344 -264.961552) (xy 114.569494 -264.957569)
			(xy 114.622644 -264.961552) (xy 114.674606 -264.973412) (xy 114.72422 -264.992884) (xy 114.770378 -265.019533)
			(xy 114.812049 -265.052764) (xy 114.848301 -265.091835) (xy 114.878325 -265.135872) (xy 114.901451 -265.183893)
			(xy 114.917161 -265.234823) (xy 114.925104 -265.287527) (xy 114.925602 -265.314176) (xy 114.925104 -265.340825)
			(xy 115.153938 -265.340825) (xy 115.153938 -265.287527) (xy 115.161881 -265.234823) (xy 115.177591 -265.183893)
			(xy 115.200717 -265.135872) (xy 115.230741 -265.091835) (xy 115.266993 -265.052764) (xy 115.308664 -265.019533)
			(xy 115.354822 -264.992884) (xy 115.404436 -264.973412) (xy 115.456398 -264.961552) (xy 115.509548 -264.957569)
			(xy 115.562698 -264.961552) (xy 115.61466 -264.973412) (xy 115.664274 -264.992884) (xy 115.710432 -265.019533)
			(xy 115.752103 -265.052764) (xy 115.788355 -265.091835) (xy 115.818379 -265.135872) (xy 115.841505 -265.183893)
			(xy 115.857215 -265.234823) (xy 115.865158 -265.287527) (xy 115.865656 -265.314176) (xy 115.865158 -265.340825)
			(xy 116.093738 -265.340825) (xy 116.093738 -265.287527) (xy 116.101681 -265.234823) (xy 116.117391 -265.183893)
			(xy 116.140517 -265.135872) (xy 116.170541 -265.091835) (xy 116.206793 -265.052764) (xy 116.248464 -265.019533)
			(xy 116.294622 -264.992884) (xy 116.344236 -264.973412) (xy 116.396198 -264.961552) (xy 116.449348 -264.957569)
			(xy 116.502498 -264.961552) (xy 116.55446 -264.973412) (xy 116.604074 -264.992884) (xy 116.650232 -265.019533)
			(xy 116.691903 -265.052764) (xy 116.728155 -265.091835) (xy 116.758179 -265.135872) (xy 116.781305 -265.183893)
			(xy 116.797015 -265.234823) (xy 116.804958 -265.287527) (xy 116.805456 -265.314176) (xy 116.804958 -265.340825)
			(xy 117.033538 -265.340825) (xy 117.033538 -265.287527) (xy 117.041481 -265.234823) (xy 117.057191 -265.183893)
			(xy 117.080317 -265.135872) (xy 117.110341 -265.091835) (xy 117.146593 -265.052764) (xy 117.188264 -265.019533)
			(xy 117.234422 -264.992884) (xy 117.284036 -264.973412) (xy 117.335998 -264.961552) (xy 117.389148 -264.957569)
			(xy 117.442298 -264.961552) (xy 117.49426 -264.973412) (xy 117.543874 -264.992884) (xy 117.590032 -265.019533)
			(xy 117.631703 -265.052764) (xy 117.667955 -265.091835) (xy 117.697979 -265.135872) (xy 117.721105 -265.183893)
			(xy 117.736815 -265.234823) (xy 117.744758 -265.287527) (xy 117.745256 -265.314176) (xy 117.744758 -265.340825)
			(xy 117.736815 -265.393529) (xy 117.721105 -265.444459) (xy 117.697979 -265.49248) (xy 117.667955 -265.536517)
			(xy 117.631703 -265.575588) (xy 117.590032 -265.608819) (xy 117.543874 -265.635468) (xy 117.49426 -265.65494)
			(xy 117.442298 -265.6668) (xy 117.389148 -265.670784) (xy 117.335998 -265.6668) (xy 117.284036 -265.65494)
			(xy 117.234422 -265.635468) (xy 117.188264 -265.608819) (xy 117.146593 -265.575588) (xy 117.110341 -265.536517)
			(xy 117.080317 -265.49248) (xy 117.057191 -265.444459) (xy 117.041481 -265.393529) (xy 117.033538 -265.340825)
			(xy 116.804958 -265.340825) (xy 116.797015 -265.393529) (xy 116.781305 -265.444459) (xy 116.758179 -265.49248)
			(xy 116.728155 -265.536517) (xy 116.691903 -265.575588) (xy 116.650232 -265.608819) (xy 116.604074 -265.635468)
			(xy 116.55446 -265.65494) (xy 116.502498 -265.6668) (xy 116.449348 -265.670784) (xy 116.396198 -265.6668)
			(xy 116.344236 -265.65494) (xy 116.294622 -265.635468) (xy 116.248464 -265.608819) (xy 116.206793 -265.575588)
			(xy 116.170541 -265.536517) (xy 116.140517 -265.49248) (xy 116.117391 -265.444459) (xy 116.101681 -265.393529)
			(xy 116.093738 -265.340825) (xy 115.865158 -265.340825) (xy 115.857215 -265.393529) (xy 115.841505 -265.444459)
			(xy 115.818379 -265.49248) (xy 115.788355 -265.536517) (xy 115.752103 -265.575588) (xy 115.710432 -265.608819)
			(xy 115.664274 -265.635468) (xy 115.61466 -265.65494) (xy 115.562698 -265.6668) (xy 115.509548 -265.670784)
			(xy 115.456398 -265.6668) (xy 115.404436 -265.65494) (xy 115.354822 -265.635468) (xy 115.308664 -265.608819)
			(xy 115.266993 -265.575588) (xy 115.230741 -265.536517) (xy 115.200717 -265.49248) (xy 115.177591 -265.444459)
			(xy 115.161881 -265.393529) (xy 115.153938 -265.340825) (xy 114.925104 -265.340825) (xy 114.917161 -265.393529)
			(xy 114.901451 -265.444459) (xy 114.878325 -265.49248) (xy 114.848301 -265.536517) (xy 114.812049 -265.575588)
			(xy 114.770378 -265.608819) (xy 114.72422 -265.635468) (xy 114.674606 -265.65494) (xy 114.622644 -265.6668)
			(xy 114.569494 -265.670784) (xy 114.516344 -265.6668) (xy 114.464382 -265.65494) (xy 114.414768 -265.635468)
			(xy 114.36861 -265.608819) (xy 114.326939 -265.575588) (xy 114.290687 -265.536517) (xy 114.260663 -265.49248)
			(xy 114.237537 -265.444459) (xy 114.221827 -265.393529) (xy 114.213884 -265.340825) (xy 109.335316 -265.340825)
			(xy 109.335316 -265.672062) (xy 109.33591 -265.687214) (xy 109.344868 -265.716167) (xy 109.361918 -265.741224)
			(xy 109.385565 -265.760181) (xy 109.413729 -265.771376) (xy 109.428788 -265.773154) (xy 109.455251 -265.775734)
			(xy 109.507044 -265.787745) (xy 109.556475 -265.807323) (xy 109.602447 -265.834031) (xy 109.643938 -265.867277)
			(xy 109.680026 -265.906321) (xy 109.709908 -265.950297) (xy 109.73292 -265.998226) (xy 109.748552 -266.049043)
			(xy 109.756455 -266.10162) (xy 109.756455 -266.154787) (xy 109.756439 -266.154895) (xy 113.743984 -266.154895)
			(xy 113.743984 -266.101597) (xy 113.751927 -266.048893) (xy 113.767637 -265.997963) (xy 113.790763 -265.949942)
			(xy 113.820787 -265.905905) (xy 113.857039 -265.866834) (xy 113.89871 -265.833603) (xy 113.944868 -265.806954)
			(xy 113.994482 -265.787482) (xy 114.046444 -265.775622) (xy 114.099594 -265.771639) (xy 114.152744 -265.775622)
			(xy 114.204706 -265.787482) (xy 114.25432 -265.806954) (xy 114.300478 -265.833603) (xy 114.342149 -265.866834)
			(xy 114.378401 -265.905905) (xy 114.408425 -265.949942) (xy 114.431551 -265.997963) (xy 114.447261 -266.048893)
			(xy 114.455204 -266.101597) (xy 114.455702 -266.128246) (xy 114.455204 -266.154895) (xy 114.683784 -266.154895)
			(xy 114.683784 -266.101597) (xy 114.691727 -266.048893) (xy 114.707437 -265.997963) (xy 114.730563 -265.949942)
			(xy 114.760587 -265.905905) (xy 114.796839 -265.866834) (xy 114.83851 -265.833603) (xy 114.884668 -265.806954)
			(xy 114.934282 -265.787482) (xy 114.986244 -265.775622) (xy 115.039394 -265.771639) (xy 115.092544 -265.775622)
			(xy 115.144506 -265.787482) (xy 115.19412 -265.806954) (xy 115.240278 -265.833603) (xy 115.281949 -265.866834)
			(xy 115.318201 -265.905905) (xy 115.348225 -265.949942) (xy 115.371351 -265.997963) (xy 115.387061 -266.048893)
			(xy 115.395004 -266.101597) (xy 115.395502 -266.128246) (xy 115.395004 -266.154895) (xy 115.623584 -266.154895)
			(xy 115.623584 -266.101597) (xy 115.631527 -266.048893) (xy 115.647237 -265.997963) (xy 115.670363 -265.949942)
			(xy 115.700387 -265.905905) (xy 115.736639 -265.866834) (xy 115.77831 -265.833603) (xy 115.824468 -265.806954)
			(xy 115.874082 -265.787482) (xy 115.926044 -265.775622) (xy 115.979194 -265.771639) (xy 116.032344 -265.775622)
			(xy 116.084306 -265.787482) (xy 116.13392 -265.806954) (xy 116.180078 -265.833603) (xy 116.221749 -265.866834)
			(xy 116.258001 -265.905905) (xy 116.288025 -265.949942) (xy 116.311151 -265.997963) (xy 116.326861 -266.048893)
			(xy 116.334804 -266.101597) (xy 116.335302 -266.128246) (xy 116.334804 -266.154895) (xy 116.334766 -266.155149)
			(xy 116.563384 -266.155149) (xy 116.563384 -266.101851) (xy 116.571327 -266.049147) (xy 116.587037 -265.998217)
			(xy 116.610163 -265.950196) (xy 116.640187 -265.906159) (xy 116.676439 -265.867088) (xy 116.71811 -265.833857)
			(xy 116.764268 -265.807208) (xy 116.813882 -265.787736) (xy 116.865844 -265.775876) (xy 116.918994 -265.771893)
			(xy 116.972144 -265.775876) (xy 117.024106 -265.787736) (xy 117.07372 -265.807208) (xy 117.119878 -265.833857)
			(xy 117.161549 -265.867088) (xy 117.197801 -265.906159) (xy 117.227825 -265.950196) (xy 117.250951 -265.998217)
			(xy 117.266661 -266.049147) (xy 117.274604 -266.101851) (xy 117.275102 -266.1285) (xy 117.274604 -266.155149)
			(xy 117.266661 -266.207853) (xy 117.250951 -266.258783) (xy 117.227825 -266.306804) (xy 117.197801 -266.350841)
			(xy 117.161549 -266.389912) (xy 117.119878 -266.423143) (xy 117.07372 -266.449792) (xy 117.024106 -266.469264)
			(xy 116.972144 -266.481124) (xy 116.918994 -266.485108) (xy 116.865844 -266.481124) (xy 116.813882 -266.469264)
			(xy 116.764268 -266.449792) (xy 116.71811 -266.423143) (xy 116.676439 -266.389912) (xy 116.640187 -266.350841)
			(xy 116.610163 -266.306804) (xy 116.587037 -266.258783) (xy 116.571327 -266.207853) (xy 116.563384 -266.155149)
			(xy 116.334766 -266.155149) (xy 116.326861 -266.207599) (xy 116.311151 -266.258529) (xy 116.288025 -266.30655)
			(xy 116.258001 -266.350587) (xy 116.221749 -266.389658) (xy 116.180078 -266.422889) (xy 116.13392 -266.449538)
			(xy 116.084306 -266.46901) (xy 116.032344 -266.48087) (xy 115.979194 -266.484854) (xy 115.926044 -266.48087)
			(xy 115.874082 -266.46901) (xy 115.824468 -266.449538) (xy 115.77831 -266.422889) (xy 115.736639 -266.389658)
			(xy 115.700387 -266.350587) (xy 115.670363 -266.30655) (xy 115.647237 -266.258529) (xy 115.631527 -266.207599)
			(xy 115.623584 -266.154895) (xy 115.395004 -266.154895) (xy 115.387061 -266.207599) (xy 115.371351 -266.258529)
			(xy 115.348225 -266.30655) (xy 115.318201 -266.350587) (xy 115.281949 -266.389658) (xy 115.240278 -266.422889)
			(xy 115.19412 -266.449538) (xy 115.144506 -266.46901) (xy 115.092544 -266.48087) (xy 115.039394 -266.484854)
			(xy 114.986244 -266.48087) (xy 114.934282 -266.46901) (xy 114.884668 -266.449538) (xy 114.83851 -266.422889)
			(xy 114.796839 -266.389658) (xy 114.760587 -266.350587) (xy 114.730563 -266.30655) (xy 114.707437 -266.258529)
			(xy 114.691727 -266.207599) (xy 114.683784 -266.154895) (xy 114.455204 -266.154895) (xy 114.447261 -266.207599)
			(xy 114.431551 -266.258529) (xy 114.408425 -266.30655) (xy 114.378401 -266.350587) (xy 114.342149 -266.389658)
			(xy 114.300478 -266.422889) (xy 114.25432 -266.449538) (xy 114.204706 -266.46901) (xy 114.152744 -266.48087)
			(xy 114.099594 -266.484854) (xy 114.046444 -266.48087) (xy 113.994482 -266.46901) (xy 113.944868 -266.449538)
			(xy 113.89871 -266.422889) (xy 113.857039 -266.389658) (xy 113.820787 -266.350587) (xy 113.790763 -266.30655)
			(xy 113.767637 -266.258529) (xy 113.751927 -266.207599) (xy 113.743984 -266.154895) (xy 109.756439 -266.154895)
			(xy 109.74855 -266.207364) (xy 109.732917 -266.258181) (xy 109.709904 -266.30611) (xy 109.680021 -266.350084)
			(xy 109.643933 -266.389128) (xy 109.602441 -266.422373) (xy 109.556469 -266.44908) (xy 109.507037 -266.468657)
			(xy 109.455244 -266.480667) (xy 109.428788 -266.483338) (xy 109.413724 -266.485104) (xy 109.385546 -266.496285)
			(xy 109.361891 -266.515243) (xy 109.344841 -266.540309) (xy 109.335896 -266.569274) (xy 109.335316 -266.58443)
			(xy 109.335316 -266.968457) (xy 109.514884 -266.968457) (xy 109.514884 -266.915159) (xy 109.522827 -266.862455)
			(xy 109.538537 -266.811525) (xy 109.561663 -266.763504) (xy 109.591687 -266.719467) (xy 109.627939 -266.680396)
			(xy 109.66961 -266.647165) (xy 109.715768 -266.620516) (xy 109.765382 -266.601044) (xy 109.817344 -266.589184)
			(xy 109.870494 -266.585201) (xy 109.923644 -266.589184) (xy 109.975606 -266.601044) (xy 110.02522 -266.620516)
			(xy 110.071378 -266.647165) (xy 110.113049 -266.680396) (xy 110.149301 -266.719467) (xy 110.179325 -266.763504)
			(xy 110.202451 -266.811525) (xy 110.218161 -266.862455) (xy 110.226104 -266.915159) (xy 110.226602 -266.941808)
			(xy 110.226104 -266.968457) (xy 113.274084 -266.968457) (xy 113.274084 -266.915159) (xy 113.282027 -266.862455)
			(xy 113.297737 -266.811525) (xy 113.320863 -266.763504) (xy 113.350887 -266.719467) (xy 113.387139 -266.680396)
			(xy 113.42881 -266.647165) (xy 113.474968 -266.620516) (xy 113.524582 -266.601044) (xy 113.576544 -266.589184)
			(xy 113.629694 -266.585201) (xy 113.682844 -266.589184) (xy 113.734806 -266.601044) (xy 113.78442 -266.620516)
			(xy 113.830578 -266.647165) (xy 113.872249 -266.680396) (xy 113.908501 -266.719467) (xy 113.938525 -266.763504)
			(xy 113.961651 -266.811525) (xy 113.977361 -266.862455) (xy 113.985304 -266.915159) (xy 113.985802 -266.941808)
			(xy 113.985304 -266.968457) (xy 114.214138 -266.968457) (xy 114.214138 -266.915159) (xy 114.222081 -266.862455)
			(xy 114.237791 -266.811525) (xy 114.260917 -266.763504) (xy 114.290941 -266.719467) (xy 114.327193 -266.680396)
			(xy 114.368864 -266.647165) (xy 114.415022 -266.620516) (xy 114.464636 -266.601044) (xy 114.516598 -266.589184)
			(xy 114.569748 -266.585201) (xy 114.622898 -266.589184) (xy 114.67486 -266.601044) (xy 114.724474 -266.620516)
			(xy 114.770632 -266.647165) (xy 114.812303 -266.680396) (xy 114.848555 -266.719467) (xy 114.878579 -266.763504)
			(xy 114.901705 -266.811525) (xy 114.917415 -266.862455) (xy 114.925358 -266.915159) (xy 114.925856 -266.941808)
			(xy 114.925358 -266.968457) (xy 115.153938 -266.968457) (xy 115.153938 -266.915159) (xy 115.161881 -266.862455)
			(xy 115.177591 -266.811525) (xy 115.200717 -266.763504) (xy 115.230741 -266.719467) (xy 115.266993 -266.680396)
			(xy 115.308664 -266.647165) (xy 115.354822 -266.620516) (xy 115.404436 -266.601044) (xy 115.456398 -266.589184)
			(xy 115.509548 -266.585201) (xy 115.562698 -266.589184) (xy 115.61466 -266.601044) (xy 115.664274 -266.620516)
			(xy 115.710432 -266.647165) (xy 115.752103 -266.680396) (xy 115.788355 -266.719467) (xy 115.818379 -266.763504)
			(xy 115.841505 -266.811525) (xy 115.857215 -266.862455) (xy 115.865158 -266.915159) (xy 115.865656 -266.941808)
			(xy 115.865158 -266.968457) (xy 116.09323 -266.968457) (xy 116.09323 -266.915159) (xy 116.101173 -266.862455)
			(xy 116.116883 -266.811525) (xy 116.140009 -266.763504) (xy 116.170033 -266.719467) (xy 116.206285 -266.680396)
			(xy 116.247956 -266.647165) (xy 116.294114 -266.620516) (xy 116.343728 -266.601044) (xy 116.39569 -266.589184)
			(xy 116.44884 -266.585201) (xy 116.50199 -266.589184) (xy 116.553952 -266.601044) (xy 116.603566 -266.620516)
			(xy 116.649724 -266.647165) (xy 116.691395 -266.680396) (xy 116.727647 -266.719467) (xy 116.757671 -266.763504)
			(xy 116.780797 -266.811525) (xy 116.796507 -266.862455) (xy 116.80445 -266.915159) (xy 116.804948 -266.941808)
			(xy 116.80445 -266.968457) (xy 117.033538 -266.968457) (xy 117.033538 -266.915159) (xy 117.041481 -266.862455)
			(xy 117.057191 -266.811525) (xy 117.080317 -266.763504) (xy 117.110341 -266.719467) (xy 117.146593 -266.680396)
			(xy 117.188264 -266.647165) (xy 117.234422 -266.620516) (xy 117.284036 -266.601044) (xy 117.335998 -266.589184)
			(xy 117.389148 -266.585201) (xy 117.442298 -266.589184) (xy 117.49426 -266.601044) (xy 117.543874 -266.620516)
			(xy 117.590032 -266.647165) (xy 117.631703 -266.680396) (xy 117.667955 -266.719467) (xy 117.697979 -266.763504)
			(xy 117.721105 -266.811525) (xy 117.736815 -266.862455) (xy 117.744758 -266.915159) (xy 117.745256 -266.941808)
			(xy 117.744758 -266.968457) (xy 117.736815 -267.021161) (xy 117.721105 -267.072091) (xy 117.697979 -267.120112)
			(xy 117.667955 -267.164149) (xy 117.631703 -267.20322) (xy 117.590032 -267.236451) (xy 117.543874 -267.2631)
			(xy 117.49426 -267.282572) (xy 117.442298 -267.294432) (xy 117.389148 -267.298416) (xy 117.335998 -267.294432)
			(xy 117.284036 -267.282572) (xy 117.234422 -267.2631) (xy 117.188264 -267.236451) (xy 117.146593 -267.20322)
			(xy 117.110341 -267.164149) (xy 117.080317 -267.120112) (xy 117.057191 -267.072091) (xy 117.041481 -267.021161)
			(xy 117.033538 -266.968457) (xy 116.80445 -266.968457) (xy 116.796507 -267.021161) (xy 116.780797 -267.072091)
			(xy 116.757671 -267.120112) (xy 116.727647 -267.164149) (xy 116.691395 -267.20322) (xy 116.649724 -267.236451)
			(xy 116.603566 -267.2631) (xy 116.553952 -267.282572) (xy 116.50199 -267.294432) (xy 116.44884 -267.298416)
			(xy 116.39569 -267.294432) (xy 116.343728 -267.282572) (xy 116.294114 -267.2631) (xy 116.247956 -267.236451)
			(xy 116.206285 -267.20322) (xy 116.170033 -267.164149) (xy 116.140009 -267.120112) (xy 116.116883 -267.072091)
			(xy 116.101173 -267.021161) (xy 116.09323 -266.968457) (xy 115.865158 -266.968457) (xy 115.857215 -267.021161)
			(xy 115.841505 -267.072091) (xy 115.818379 -267.120112) (xy 115.788355 -267.164149) (xy 115.752103 -267.20322)
			(xy 115.710432 -267.236451) (xy 115.664274 -267.2631) (xy 115.61466 -267.282572) (xy 115.562698 -267.294432)
			(xy 115.509548 -267.298416) (xy 115.456398 -267.294432) (xy 115.404436 -267.282572) (xy 115.354822 -267.2631)
			(xy 115.308664 -267.236451) (xy 115.266993 -267.20322) (xy 115.230741 -267.164149) (xy 115.200717 -267.120112)
			(xy 115.177591 -267.072091) (xy 115.161881 -267.021161) (xy 115.153938 -266.968457) (xy 114.925358 -266.968457)
			(xy 114.917415 -267.021161) (xy 114.901705 -267.072091) (xy 114.878579 -267.120112) (xy 114.848555 -267.164149)
			(xy 114.812303 -267.20322) (xy 114.770632 -267.236451) (xy 114.724474 -267.2631) (xy 114.67486 -267.282572)
			(xy 114.622898 -267.294432) (xy 114.569748 -267.298416) (xy 114.516598 -267.294432) (xy 114.464636 -267.282572)
			(xy 114.415022 -267.2631) (xy 114.368864 -267.236451) (xy 114.327193 -267.20322) (xy 114.290941 -267.164149)
			(xy 114.260917 -267.120112) (xy 114.237791 -267.072091) (xy 114.222081 -267.021161) (xy 114.214138 -266.968457)
			(xy 113.985304 -266.968457) (xy 113.977361 -267.021161) (xy 113.961651 -267.072091) (xy 113.938525 -267.120112)
			(xy 113.908501 -267.164149) (xy 113.872249 -267.20322) (xy 113.830578 -267.236451) (xy 113.78442 -267.2631)
			(xy 113.734806 -267.282572) (xy 113.682844 -267.294432) (xy 113.629694 -267.298416) (xy 113.576544 -267.294432)
			(xy 113.524582 -267.282572) (xy 113.474968 -267.2631) (xy 113.42881 -267.236451) (xy 113.387139 -267.20322)
			(xy 113.350887 -267.164149) (xy 113.320863 -267.120112) (xy 113.297737 -267.072091) (xy 113.282027 -267.021161)
			(xy 113.274084 -266.968457) (xy 110.226104 -266.968457) (xy 110.218161 -267.021161) (xy 110.202451 -267.072091)
			(xy 110.179325 -267.120112) (xy 110.149301 -267.164149) (xy 110.113049 -267.20322) (xy 110.071378 -267.236451)
			(xy 110.02522 -267.2631) (xy 109.975606 -267.282572) (xy 109.923644 -267.294432) (xy 109.870494 -267.298416)
			(xy 109.817344 -267.294432) (xy 109.765382 -267.282572) (xy 109.715768 -267.2631) (xy 109.66961 -267.236451)
			(xy 109.627939 -267.20322) (xy 109.591687 -267.164149) (xy 109.561663 -267.120112) (xy 109.538537 -267.072091)
			(xy 109.522827 -267.021161) (xy 109.514884 -266.968457) (xy 109.335316 -266.968457) (xy 109.335316 -267.299694)
			(xy 109.335914 -267.314843) (xy 109.344878 -267.343789) (xy 109.36193 -267.368836) (xy 109.385574 -267.387787)
			(xy 109.413734 -267.398977) (xy 109.428788 -267.400786) (xy 109.455246 -267.40338) (xy 109.507025 -267.415415)
			(xy 109.556442 -267.435011) (xy 109.602397 -267.461733) (xy 109.643872 -267.494987) (xy 109.679944 -267.534036)
			(xy 109.709812 -267.578011) (xy 109.732814 -267.625937) (xy 109.748439 -267.676749) (xy 109.756339 -267.729318)
			(xy 109.756339 -267.782478) (xy 109.756332 -267.782527) (xy 109.984784 -267.782527) (xy 109.984784 -267.729229)
			(xy 109.992727 -267.676525) (xy 110.008437 -267.625595) (xy 110.031563 -267.577574) (xy 110.061587 -267.533537)
			(xy 110.097839 -267.494466) (xy 110.13951 -267.461235) (xy 110.185668 -267.434586) (xy 110.235282 -267.415114)
			(xy 110.287244 -267.403254) (xy 110.340394 -267.399271) (xy 110.393544 -267.403254) (xy 110.445506 -267.415114)
			(xy 110.49512 -267.434586) (xy 110.541278 -267.461235) (xy 110.582949 -267.494466) (xy 110.619201 -267.533537)
			(xy 110.649225 -267.577574) (xy 110.672351 -267.625595) (xy 110.688061 -267.676525) (xy 110.696004 -267.729229)
			(xy 110.696502 -267.755878) (xy 110.696004 -267.782527) (xy 113.743984 -267.782527) (xy 113.743984 -267.729229)
			(xy 113.751927 -267.676525) (xy 113.767637 -267.625595) (xy 113.790763 -267.577574) (xy 113.820787 -267.533537)
			(xy 113.857039 -267.494466) (xy 113.89871 -267.461235) (xy 113.944868 -267.434586) (xy 113.994482 -267.415114)
			(xy 114.046444 -267.403254) (xy 114.099594 -267.399271) (xy 114.152744 -267.403254) (xy 114.204706 -267.415114)
			(xy 114.25432 -267.434586) (xy 114.300478 -267.461235) (xy 114.342149 -267.494466) (xy 114.378401 -267.533537)
			(xy 114.408425 -267.577574) (xy 114.431551 -267.625595) (xy 114.447261 -267.676525) (xy 114.455204 -267.729229)
			(xy 114.455702 -267.755878) (xy 114.455204 -267.782527) (xy 114.683784 -267.782527) (xy 114.683784 -267.729229)
			(xy 114.691727 -267.676525) (xy 114.707437 -267.625595) (xy 114.730563 -267.577574) (xy 114.760587 -267.533537)
			(xy 114.796839 -267.494466) (xy 114.83851 -267.461235) (xy 114.884668 -267.434586) (xy 114.934282 -267.415114)
			(xy 114.986244 -267.403254) (xy 115.039394 -267.399271) (xy 115.092544 -267.403254) (xy 115.144506 -267.415114)
			(xy 115.19412 -267.434586) (xy 115.240278 -267.461235) (xy 115.281949 -267.494466) (xy 115.318201 -267.533537)
			(xy 115.348225 -267.577574) (xy 115.371351 -267.625595) (xy 115.387061 -267.676525) (xy 115.395004 -267.729229)
			(xy 115.395502 -267.755878) (xy 115.395004 -267.782527) (xy 115.623584 -267.782527) (xy 115.623584 -267.729229)
			(xy 115.631527 -267.676525) (xy 115.647237 -267.625595) (xy 115.670363 -267.577574) (xy 115.700387 -267.533537)
			(xy 115.736639 -267.494466) (xy 115.77831 -267.461235) (xy 115.824468 -267.434586) (xy 115.874082 -267.415114)
			(xy 115.926044 -267.403254) (xy 115.979194 -267.399271) (xy 116.032344 -267.403254) (xy 116.084306 -267.415114)
			(xy 116.13392 -267.434586) (xy 116.180078 -267.461235) (xy 116.221749 -267.494466) (xy 116.258001 -267.533537)
			(xy 116.288025 -267.577574) (xy 116.311151 -267.625595) (xy 116.326861 -267.676525) (xy 116.334804 -267.729229)
			(xy 116.335302 -267.755878) (xy 116.334804 -267.782527) (xy 116.563638 -267.782527) (xy 116.563638 -267.729229)
			(xy 116.571581 -267.676525) (xy 116.587291 -267.625595) (xy 116.610417 -267.577574) (xy 116.640441 -267.533537)
			(xy 116.676693 -267.494466) (xy 116.718364 -267.461235) (xy 116.764522 -267.434586) (xy 116.814136 -267.415114)
			(xy 116.866098 -267.403254) (xy 116.919248 -267.399271) (xy 116.972398 -267.403254) (xy 117.02436 -267.415114)
			(xy 117.073974 -267.434586) (xy 117.120132 -267.461235) (xy 117.161803 -267.494466) (xy 117.198055 -267.533537)
			(xy 117.228079 -267.577574) (xy 117.251205 -267.625595) (xy 117.266915 -267.676525) (xy 117.274858 -267.729229)
			(xy 117.275356 -267.755878) (xy 117.274858 -267.782527) (xy 117.266915 -267.835231) (xy 117.251205 -267.886161)
			(xy 117.228079 -267.934182) (xy 117.198055 -267.978219) (xy 117.161803 -268.01729) (xy 117.120132 -268.050521)
			(xy 117.073974 -268.07717) (xy 117.02436 -268.096642) (xy 116.972398 -268.108502) (xy 116.919248 -268.112486)
			(xy 116.866098 -268.108502) (xy 116.814136 -268.096642) (xy 116.764522 -268.07717) (xy 116.718364 -268.050521)
			(xy 116.676693 -268.01729) (xy 116.640441 -267.978219) (xy 116.610417 -267.934182) (xy 116.587291 -267.886161)
			(xy 116.571581 -267.835231) (xy 116.563638 -267.782527) (xy 116.334804 -267.782527) (xy 116.326861 -267.835231)
			(xy 116.311151 -267.886161) (xy 116.288025 -267.934182) (xy 116.258001 -267.978219) (xy 116.221749 -268.01729)
			(xy 116.180078 -268.050521) (xy 116.13392 -268.07717) (xy 116.084306 -268.096642) (xy 116.032344 -268.108502)
			(xy 115.979194 -268.112486) (xy 115.926044 -268.108502) (xy 115.874082 -268.096642) (xy 115.824468 -268.07717)
			(xy 115.77831 -268.050521) (xy 115.736639 -268.01729) (xy 115.700387 -267.978219) (xy 115.670363 -267.934182)
			(xy 115.647237 -267.886161) (xy 115.631527 -267.835231) (xy 115.623584 -267.782527) (xy 115.395004 -267.782527)
			(xy 115.387061 -267.835231) (xy 115.371351 -267.886161) (xy 115.348225 -267.934182) (xy 115.318201 -267.978219)
			(xy 115.281949 -268.01729) (xy 115.240278 -268.050521) (xy 115.19412 -268.07717) (xy 115.144506 -268.096642)
			(xy 115.092544 -268.108502) (xy 115.039394 -268.112486) (xy 114.986244 -268.108502) (xy 114.934282 -268.096642)
			(xy 114.884668 -268.07717) (xy 114.83851 -268.050521) (xy 114.796839 -268.01729) (xy 114.760587 -267.978219)
			(xy 114.730563 -267.934182) (xy 114.707437 -267.886161) (xy 114.691727 -267.835231) (xy 114.683784 -267.782527)
			(xy 114.455204 -267.782527) (xy 114.447261 -267.835231) (xy 114.431551 -267.886161) (xy 114.408425 -267.934182)
			(xy 114.378401 -267.978219) (xy 114.342149 -268.01729) (xy 114.300478 -268.050521) (xy 114.25432 -268.07717)
			(xy 114.204706 -268.096642) (xy 114.152744 -268.108502) (xy 114.099594 -268.112486) (xy 114.046444 -268.108502)
			(xy 113.994482 -268.096642) (xy 113.944868 -268.07717) (xy 113.89871 -268.050521) (xy 113.857039 -268.01729)
			(xy 113.820787 -267.978219) (xy 113.790763 -267.934182) (xy 113.767637 -267.886161) (xy 113.751927 -267.835231)
			(xy 113.743984 -267.782527) (xy 110.696004 -267.782527) (xy 110.688061 -267.835231) (xy 110.672351 -267.886161)
			(xy 110.649225 -267.934182) (xy 110.619201 -267.978219) (xy 110.582949 -268.01729) (xy 110.541278 -268.050521)
			(xy 110.49512 -268.07717) (xy 110.445506 -268.096642) (xy 110.393544 -268.108502) (xy 110.340394 -268.112486)
			(xy 110.287244 -268.108502) (xy 110.235282 -268.096642) (xy 110.185668 -268.07717) (xy 110.13951 -268.050521)
			(xy 110.097839 -268.01729) (xy 110.061587 -267.978219) (xy 110.031563 -267.934182) (xy 110.008437 -267.886161)
			(xy 109.992727 -267.835231) (xy 109.984784 -267.782527) (xy 109.756332 -267.782527) (xy 109.748439 -267.835048)
			(xy 109.732815 -267.88586) (xy 109.709814 -267.933786) (xy 109.679946 -267.977762) (xy 109.643874 -268.016811)
			(xy 109.6024 -268.050066) (xy 109.556445 -268.076788) (xy 109.507029 -268.096384) (xy 109.455249 -268.10842)
			(xy 109.428788 -268.11097) (xy 109.413725 -268.112736) (xy 109.385553 -268.123919) (xy 109.361903 -268.142878)
			(xy 109.344859 -268.167943) (xy 109.335923 -268.196907) (xy 109.335316 -268.212062) (xy 109.335316 -268.596343)
			(xy 109.514884 -268.596343) (xy 109.514884 -268.543045) (xy 109.522827 -268.490341) (xy 109.538537 -268.439411)
			(xy 109.561663 -268.39139) (xy 109.591687 -268.347353) (xy 109.627939 -268.308282) (xy 109.66961 -268.275051)
			(xy 109.715768 -268.248402) (xy 109.765382 -268.22893) (xy 109.817344 -268.21707) (xy 109.870494 -268.213087)
			(xy 109.923644 -268.21707) (xy 109.975606 -268.22893) (xy 110.02522 -268.248402) (xy 110.071378 -268.275051)
			(xy 110.113049 -268.308282) (xy 110.149301 -268.347353) (xy 110.179325 -268.39139) (xy 110.202451 -268.439411)
			(xy 110.218161 -268.490341) (xy 110.226104 -268.543045) (xy 110.226602 -268.569694) (xy 110.226104 -268.596343)
			(xy 113.274084 -268.596343) (xy 113.274084 -268.543045) (xy 113.282027 -268.490341) (xy 113.297737 -268.439411)
			(xy 113.320863 -268.39139) (xy 113.350887 -268.347353) (xy 113.387139 -268.308282) (xy 113.42881 -268.275051)
			(xy 113.474968 -268.248402) (xy 113.524582 -268.22893) (xy 113.576544 -268.21707) (xy 113.629694 -268.213087)
			(xy 113.682844 -268.21707) (xy 113.734806 -268.22893) (xy 113.78442 -268.248402) (xy 113.830578 -268.275051)
			(xy 113.872249 -268.308282) (xy 113.908501 -268.347353) (xy 113.938525 -268.39139) (xy 113.961651 -268.439411)
			(xy 113.977361 -268.490341) (xy 113.985304 -268.543045) (xy 113.985802 -268.569694) (xy 113.985304 -268.596343)
			(xy 114.214138 -268.596343) (xy 114.214138 -268.543045) (xy 114.222081 -268.490341) (xy 114.237791 -268.439411)
			(xy 114.260917 -268.39139) (xy 114.290941 -268.347353) (xy 114.327193 -268.308282) (xy 114.368864 -268.275051)
			(xy 114.415022 -268.248402) (xy 114.464636 -268.22893) (xy 114.516598 -268.21707) (xy 114.569748 -268.213087)
			(xy 114.622898 -268.21707) (xy 114.67486 -268.22893) (xy 114.724474 -268.248402) (xy 114.770632 -268.275051)
			(xy 114.812303 -268.308282) (xy 114.848555 -268.347353) (xy 114.878579 -268.39139) (xy 114.901705 -268.439411)
			(xy 114.917415 -268.490341) (xy 114.925358 -268.543045) (xy 114.925856 -268.569694) (xy 114.925358 -268.596343)
			(xy 115.153938 -268.596343) (xy 115.153938 -268.543045) (xy 115.161881 -268.490341) (xy 115.177591 -268.439411)
			(xy 115.200717 -268.39139) (xy 115.230741 -268.347353) (xy 115.266993 -268.308282) (xy 115.308664 -268.275051)
			(xy 115.354822 -268.248402) (xy 115.404436 -268.22893) (xy 115.456398 -268.21707) (xy 115.509548 -268.213087)
			(xy 115.562698 -268.21707) (xy 115.61466 -268.22893) (xy 115.664274 -268.248402) (xy 115.710432 -268.275051)
			(xy 115.752103 -268.308282) (xy 115.788355 -268.347353) (xy 115.818379 -268.39139) (xy 115.841505 -268.439411)
			(xy 115.857215 -268.490341) (xy 115.865158 -268.543045) (xy 115.865656 -268.569694) (xy 115.865158 -268.596343)
			(xy 116.093738 -268.596343) (xy 116.093738 -268.543045) (xy 116.101681 -268.490341) (xy 116.117391 -268.439411)
			(xy 116.140517 -268.39139) (xy 116.170541 -268.347353) (xy 116.206793 -268.308282) (xy 116.248464 -268.275051)
			(xy 116.294622 -268.248402) (xy 116.344236 -268.22893) (xy 116.396198 -268.21707) (xy 116.449348 -268.213087)
			(xy 116.502498 -268.21707) (xy 116.55446 -268.22893) (xy 116.604074 -268.248402) (xy 116.650232 -268.275051)
			(xy 116.691903 -268.308282) (xy 116.728155 -268.347353) (xy 116.758179 -268.39139) (xy 116.781305 -268.439411)
			(xy 116.797015 -268.490341) (xy 116.804958 -268.543045) (xy 116.805456 -268.569694) (xy 116.804958 -268.596343)
			(xy 117.033284 -268.596343) (xy 117.033284 -268.543045) (xy 117.041227 -268.490341) (xy 117.056937 -268.439411)
			(xy 117.080063 -268.39139) (xy 117.110087 -268.347353) (xy 117.146339 -268.308282) (xy 117.18801 -268.275051)
			(xy 117.234168 -268.248402) (xy 117.283782 -268.22893) (xy 117.335744 -268.21707) (xy 117.388894 -268.213087)
			(xy 117.442044 -268.21707) (xy 117.494006 -268.22893) (xy 117.54362 -268.248402) (xy 117.589778 -268.275051)
			(xy 117.631449 -268.308282) (xy 117.667701 -268.347353) (xy 117.697725 -268.39139) (xy 117.720851 -268.439411)
			(xy 117.736561 -268.490341) (xy 117.744504 -268.543045) (xy 117.745002 -268.569694) (xy 117.744504 -268.596343)
			(xy 117.736561 -268.649047) (xy 117.720851 -268.699977) (xy 117.697725 -268.747998) (xy 117.667701 -268.792035)
			(xy 117.631449 -268.831106) (xy 117.589778 -268.864337) (xy 117.54362 -268.890986) (xy 117.494006 -268.910458)
			(xy 117.442044 -268.922318) (xy 117.388894 -268.926302) (xy 117.335744 -268.922318) (xy 117.283782 -268.910458)
			(xy 117.234168 -268.890986) (xy 117.18801 -268.864337) (xy 117.146339 -268.831106) (xy 117.110087 -268.792035)
			(xy 117.080063 -268.747998) (xy 117.056937 -268.699977) (xy 117.041227 -268.649047) (xy 117.033284 -268.596343)
			(xy 116.804958 -268.596343) (xy 116.797015 -268.649047) (xy 116.781305 -268.699977) (xy 116.758179 -268.747998)
			(xy 116.728155 -268.792035) (xy 116.691903 -268.831106) (xy 116.650232 -268.864337) (xy 116.604074 -268.890986)
			(xy 116.55446 -268.910458) (xy 116.502498 -268.922318) (xy 116.449348 -268.926302) (xy 116.396198 -268.922318)
			(xy 116.344236 -268.910458) (xy 116.294622 -268.890986) (xy 116.248464 -268.864337) (xy 116.206793 -268.831106)
			(xy 116.170541 -268.792035) (xy 116.140517 -268.747998) (xy 116.117391 -268.699977) (xy 116.101681 -268.649047)
			(xy 116.093738 -268.596343) (xy 115.865158 -268.596343) (xy 115.857215 -268.649047) (xy 115.841505 -268.699977)
			(xy 115.818379 -268.747998) (xy 115.788355 -268.792035) (xy 115.752103 -268.831106) (xy 115.710432 -268.864337)
			(xy 115.664274 -268.890986) (xy 115.61466 -268.910458) (xy 115.562698 -268.922318) (xy 115.509548 -268.926302)
			(xy 115.456398 -268.922318) (xy 115.404436 -268.910458) (xy 115.354822 -268.890986) (xy 115.308664 -268.864337)
			(xy 115.266993 -268.831106) (xy 115.230741 -268.792035) (xy 115.200717 -268.747998) (xy 115.177591 -268.699977)
			(xy 115.161881 -268.649047) (xy 115.153938 -268.596343) (xy 114.925358 -268.596343) (xy 114.917415 -268.649047)
			(xy 114.901705 -268.699977) (xy 114.878579 -268.747998) (xy 114.848555 -268.792035) (xy 114.812303 -268.831106)
			(xy 114.770632 -268.864337) (xy 114.724474 -268.890986) (xy 114.67486 -268.910458) (xy 114.622898 -268.922318)
			(xy 114.569748 -268.926302) (xy 114.516598 -268.922318) (xy 114.464636 -268.910458) (xy 114.415022 -268.890986)
			(xy 114.368864 -268.864337) (xy 114.327193 -268.831106) (xy 114.290941 -268.792035) (xy 114.260917 -268.747998)
			(xy 114.237791 -268.699977) (xy 114.222081 -268.649047) (xy 114.214138 -268.596343) (xy 113.985304 -268.596343)
			(xy 113.977361 -268.649047) (xy 113.961651 -268.699977) (xy 113.938525 -268.747998) (xy 113.908501 -268.792035)
			(xy 113.872249 -268.831106) (xy 113.830578 -268.864337) (xy 113.78442 -268.890986) (xy 113.734806 -268.910458)
			(xy 113.682844 -268.922318) (xy 113.629694 -268.926302) (xy 113.576544 -268.922318) (xy 113.524582 -268.910458)
			(xy 113.474968 -268.890986) (xy 113.42881 -268.864337) (xy 113.387139 -268.831106) (xy 113.350887 -268.792035)
			(xy 113.320863 -268.747998) (xy 113.297737 -268.699977) (xy 113.282027 -268.649047) (xy 113.274084 -268.596343)
			(xy 110.226104 -268.596343) (xy 110.218161 -268.649047) (xy 110.202451 -268.699977) (xy 110.179325 -268.747998)
			(xy 110.149301 -268.792035) (xy 110.113049 -268.831106) (xy 110.071378 -268.864337) (xy 110.02522 -268.890986)
			(xy 109.975606 -268.910458) (xy 109.923644 -268.922318) (xy 109.870494 -268.926302) (xy 109.817344 -268.922318)
			(xy 109.765382 -268.910458) (xy 109.715768 -268.890986) (xy 109.66961 -268.864337) (xy 109.627939 -268.831106)
			(xy 109.591687 -268.792035) (xy 109.561663 -268.747998) (xy 109.538537 -268.699977) (xy 109.522827 -268.649047)
			(xy 109.514884 -268.596343) (xy 109.335316 -268.596343) (xy 109.335316 -268.927326) (xy 109.335918 -268.942472)
			(xy 109.344888 -268.97141) (xy 109.361942 -268.996449) (xy 109.385584 -269.015393) (xy 109.41374 -269.026578)
			(xy 109.428788 -269.028418) (xy 109.455243 -269.031012) (xy 109.507018 -269.043046) (xy 109.55643 -269.06264)
			(xy 109.602381 -269.08936) (xy 109.643852 -269.122612) (xy 109.67992 -269.161657) (xy 109.709786 -269.205629)
			(xy 109.732785 -269.253551) (xy 109.748408 -269.304358) (xy 109.756307 -269.356923) (xy 109.756307 -269.410078)
			(xy 109.756295 -269.410159) (xy 109.984784 -269.410159) (xy 109.984784 -269.356861) (xy 109.992727 -269.304157)
			(xy 110.008437 -269.253227) (xy 110.031563 -269.205206) (xy 110.061587 -269.161169) (xy 110.097839 -269.122098)
			(xy 110.13951 -269.088867) (xy 110.185668 -269.062218) (xy 110.235282 -269.042746) (xy 110.287244 -269.030886)
			(xy 110.340394 -269.026903) (xy 110.393544 -269.030886) (xy 110.445506 -269.042746) (xy 110.49512 -269.062218)
			(xy 110.541278 -269.088867) (xy 110.582949 -269.122098) (xy 110.619201 -269.161169) (xy 110.649225 -269.205206)
			(xy 110.672351 -269.253227) (xy 110.688061 -269.304157) (xy 110.696004 -269.356861) (xy 110.696502 -269.38351)
			(xy 110.696004 -269.410159) (xy 113.744492 -269.410159) (xy 113.744492 -269.356861) (xy 113.752435 -269.304157)
			(xy 113.768145 -269.253227) (xy 113.791271 -269.205206) (xy 113.821295 -269.161169) (xy 113.857547 -269.122098)
			(xy 113.899218 -269.088867) (xy 113.945376 -269.062218) (xy 113.99499 -269.042746) (xy 114.046952 -269.030886)
			(xy 114.100102 -269.026903) (xy 114.153252 -269.030886) (xy 114.205214 -269.042746) (xy 114.254828 -269.062218)
			(xy 114.300986 -269.088867) (xy 114.342657 -269.122098) (xy 114.378909 -269.161169) (xy 114.408933 -269.205206)
			(xy 114.432059 -269.253227) (xy 114.447769 -269.304157) (xy 114.455712 -269.356861) (xy 114.45621 -269.38351)
			(xy 114.455712 -269.410159) (xy 114.683784 -269.410159) (xy 114.683784 -269.356861) (xy 114.691727 -269.304157)
			(xy 114.707437 -269.253227) (xy 114.730563 -269.205206) (xy 114.760587 -269.161169) (xy 114.796839 -269.122098)
			(xy 114.83851 -269.088867) (xy 114.884668 -269.062218) (xy 114.934282 -269.042746) (xy 114.986244 -269.030886)
			(xy 115.039394 -269.026903) (xy 115.092544 -269.030886) (xy 115.144506 -269.042746) (xy 115.19412 -269.062218)
			(xy 115.240278 -269.088867) (xy 115.281949 -269.122098) (xy 115.318201 -269.161169) (xy 115.348225 -269.205206)
			(xy 115.371351 -269.253227) (xy 115.387061 -269.304157) (xy 115.395004 -269.356861) (xy 115.395502 -269.38351)
			(xy 115.395004 -269.410159) (xy 115.623584 -269.410159) (xy 115.623584 -269.356861) (xy 115.631527 -269.304157)
			(xy 115.647237 -269.253227) (xy 115.670363 -269.205206) (xy 115.700387 -269.161169) (xy 115.736639 -269.122098)
			(xy 115.77831 -269.088867) (xy 115.824468 -269.062218) (xy 115.874082 -269.042746) (xy 115.926044 -269.030886)
			(xy 115.979194 -269.026903) (xy 116.032344 -269.030886) (xy 116.084306 -269.042746) (xy 116.13392 -269.062218)
			(xy 116.180078 -269.088867) (xy 116.221749 -269.122098) (xy 116.258001 -269.161169) (xy 116.288025 -269.205206)
			(xy 116.311151 -269.253227) (xy 116.326861 -269.304157) (xy 116.334804 -269.356861) (xy 116.335302 -269.38351)
			(xy 116.334804 -269.410159) (xy 116.563384 -269.410159) (xy 116.563384 -269.356861) (xy 116.571327 -269.304157)
			(xy 116.587037 -269.253227) (xy 116.610163 -269.205206) (xy 116.640187 -269.161169) (xy 116.676439 -269.122098)
			(xy 116.71811 -269.088867) (xy 116.764268 -269.062218) (xy 116.813882 -269.042746) (xy 116.865844 -269.030886)
			(xy 116.918994 -269.026903) (xy 116.972144 -269.030886) (xy 117.024106 -269.042746) (xy 117.07372 -269.062218)
			(xy 117.119878 -269.088867) (xy 117.161549 -269.122098) (xy 117.197801 -269.161169) (xy 117.227825 -269.205206)
			(xy 117.250951 -269.253227) (xy 117.266661 -269.304157) (xy 117.274604 -269.356861) (xy 117.275102 -269.38351)
			(xy 117.274604 -269.410159) (xy 117.266661 -269.462863) (xy 117.250951 -269.513793) (xy 117.227825 -269.561814)
			(xy 117.197801 -269.605851) (xy 117.161549 -269.644922) (xy 117.119878 -269.678153) (xy 117.07372 -269.704802)
			(xy 117.024106 -269.724274) (xy 116.972144 -269.736134) (xy 116.918994 -269.740118) (xy 116.865844 -269.736134)
			(xy 116.813882 -269.724274) (xy 116.764268 -269.704802) (xy 116.71811 -269.678153) (xy 116.676439 -269.644922)
			(xy 116.640187 -269.605851) (xy 116.610163 -269.561814) (xy 116.587037 -269.513793) (xy 116.571327 -269.462863)
			(xy 116.563384 -269.410159) (xy 116.334804 -269.410159) (xy 116.326861 -269.462863) (xy 116.311151 -269.513793)
			(xy 116.288025 -269.561814) (xy 116.258001 -269.605851) (xy 116.221749 -269.644922) (xy 116.180078 -269.678153)
			(xy 116.13392 -269.704802) (xy 116.084306 -269.724274) (xy 116.032344 -269.736134) (xy 115.979194 -269.740118)
			(xy 115.926044 -269.736134) (xy 115.874082 -269.724274) (xy 115.824468 -269.704802) (xy 115.77831 -269.678153)
			(xy 115.736639 -269.644922) (xy 115.700387 -269.605851) (xy 115.670363 -269.561814) (xy 115.647237 -269.513793)
			(xy 115.631527 -269.462863) (xy 115.623584 -269.410159) (xy 115.395004 -269.410159) (xy 115.387061 -269.462863)
			(xy 115.371351 -269.513793) (xy 115.348225 -269.561814) (xy 115.318201 -269.605851) (xy 115.281949 -269.644922)
			(xy 115.240278 -269.678153) (xy 115.19412 -269.704802) (xy 115.144506 -269.724274) (xy 115.092544 -269.736134)
			(xy 115.039394 -269.740118) (xy 114.986244 -269.736134) (xy 114.934282 -269.724274) (xy 114.884668 -269.704802)
			(xy 114.83851 -269.678153) (xy 114.796839 -269.644922) (xy 114.760587 -269.605851) (xy 114.730563 -269.561814)
			(xy 114.707437 -269.513793) (xy 114.691727 -269.462863) (xy 114.683784 -269.410159) (xy 114.455712 -269.410159)
			(xy 114.447769 -269.462863) (xy 114.432059 -269.513793) (xy 114.408933 -269.561814) (xy 114.378909 -269.605851)
			(xy 114.342657 -269.644922) (xy 114.300986 -269.678153) (xy 114.254828 -269.704802) (xy 114.205214 -269.724274)
			(xy 114.153252 -269.736134) (xy 114.100102 -269.740118) (xy 114.046952 -269.736134) (xy 113.99499 -269.724274)
			(xy 113.945376 -269.704802) (xy 113.899218 -269.678153) (xy 113.857547 -269.644922) (xy 113.821295 -269.605851)
			(xy 113.791271 -269.561814) (xy 113.768145 -269.513793) (xy 113.752435 -269.462863) (xy 113.744492 -269.410159)
			(xy 110.696004 -269.410159) (xy 110.688061 -269.462863) (xy 110.672351 -269.513793) (xy 110.649225 -269.561814)
			(xy 110.619201 -269.605851) (xy 110.582949 -269.644922) (xy 110.541278 -269.678153) (xy 110.49512 -269.704802)
			(xy 110.445506 -269.724274) (xy 110.393544 -269.736134) (xy 110.340394 -269.740118) (xy 110.287244 -269.736134)
			(xy 110.235282 -269.724274) (xy 110.185668 -269.704802) (xy 110.13951 -269.678153) (xy 110.097839 -269.644922)
			(xy 110.061587 -269.605851) (xy 110.031563 -269.561814) (xy 110.008437 -269.513793) (xy 109.992727 -269.462863)
			(xy 109.984784 -269.410159) (xy 109.756295 -269.410159) (xy 109.748408 -269.462643) (xy 109.732785 -269.513451)
			(xy 109.709785 -269.561372) (xy 109.679919 -269.605344) (xy 109.64385 -269.644389) (xy 109.60238 -269.677641)
			(xy 109.556429 -269.70436) (xy 109.507017 -269.723955) (xy 109.455242 -269.735989) (xy 109.428788 -269.738602)
			(xy 109.413727 -269.740368) (xy 109.385559 -269.751552) (xy 109.361914 -269.770512) (xy 109.344878 -269.795578)
			(xy 109.335951 -269.824541) (xy 109.335316 -269.839694) (xy 109.335316 -269.975584) (xy 109.367066 -270.007334)
			(xy 109.367066 -270.224229) (xy 113.274084 -270.224229) (xy 113.274084 -270.170931) (xy 113.282027 -270.118227)
			(xy 113.297737 -270.067297) (xy 113.320863 -270.019276) (xy 113.350887 -269.975239) (xy 113.387139 -269.936168)
			(xy 113.42881 -269.902937) (xy 113.474968 -269.876288) (xy 113.524582 -269.856816) (xy 113.576544 -269.844956)
			(xy 113.629694 -269.840973) (xy 113.682844 -269.844956) (xy 113.734806 -269.856816) (xy 113.78442 -269.876288)
			(xy 113.830578 -269.902937) (xy 113.872249 -269.936168) (xy 113.908501 -269.975239) (xy 113.938525 -270.019276)
			(xy 113.961651 -270.067297) (xy 113.977361 -270.118227) (xy 113.985304 -270.170931) (xy 113.985802 -270.19758)
			(xy 113.985304 -270.224229) (xy 114.213884 -270.224229) (xy 114.213884 -270.170931) (xy 114.221827 -270.118227)
			(xy 114.237537 -270.067297) (xy 114.260663 -270.019276) (xy 114.290687 -269.975239) (xy 114.326939 -269.936168)
			(xy 114.36861 -269.902937) (xy 114.414768 -269.876288) (xy 114.464382 -269.856816) (xy 114.516344 -269.844956)
			(xy 114.569494 -269.840973) (xy 114.622644 -269.844956) (xy 114.674606 -269.856816) (xy 114.72422 -269.876288)
			(xy 114.770378 -269.902937) (xy 114.812049 -269.936168) (xy 114.848301 -269.975239) (xy 114.878325 -270.019276)
			(xy 114.901451 -270.067297) (xy 114.917161 -270.118227) (xy 114.925104 -270.170931) (xy 114.925602 -270.19758)
			(xy 114.925104 -270.224229) (xy 115.153684 -270.224229) (xy 115.153684 -270.170931) (xy 115.161627 -270.118227)
			(xy 115.177337 -270.067297) (xy 115.200463 -270.019276) (xy 115.230487 -269.975239) (xy 115.266739 -269.936168)
			(xy 115.30841 -269.902937) (xy 115.354568 -269.876288) (xy 115.404182 -269.856816) (xy 115.456144 -269.844956)
			(xy 115.509294 -269.840973) (xy 115.562444 -269.844956) (xy 115.614406 -269.856816) (xy 115.66402 -269.876288)
			(xy 115.710178 -269.902937) (xy 115.751849 -269.936168) (xy 115.788101 -269.975239) (xy 115.818125 -270.019276)
			(xy 115.841251 -270.067297) (xy 115.856961 -270.118227) (xy 115.864904 -270.170931) (xy 115.865402 -270.19758)
			(xy 115.864904 -270.224229) (xy 116.093738 -270.224229) (xy 116.093738 -270.170931) (xy 116.101681 -270.118227)
			(xy 116.117391 -270.067297) (xy 116.140517 -270.019276) (xy 116.170541 -269.975239) (xy 116.206793 -269.936168)
			(xy 116.248464 -269.902937) (xy 116.294622 -269.876288) (xy 116.344236 -269.856816) (xy 116.396198 -269.844956)
			(xy 116.449348 -269.840973) (xy 116.502498 -269.844956) (xy 116.55446 -269.856816) (xy 116.604074 -269.876288)
			(xy 116.650232 -269.902937) (xy 116.691903 -269.936168) (xy 116.728155 -269.975239) (xy 116.758179 -270.019276)
			(xy 116.781305 -270.067297) (xy 116.797015 -270.118227) (xy 116.804958 -270.170931) (xy 116.805456 -270.19758)
			(xy 116.804958 -270.224229) (xy 117.033284 -270.224229) (xy 117.033284 -270.170931) (xy 117.041227 -270.118227)
			(xy 117.056937 -270.067297) (xy 117.080063 -270.019276) (xy 117.110087 -269.975239) (xy 117.146339 -269.936168)
			(xy 117.18801 -269.902937) (xy 117.234168 -269.876288) (xy 117.283782 -269.856816) (xy 117.335744 -269.844956)
			(xy 117.388894 -269.840973) (xy 117.442044 -269.844956) (xy 117.494006 -269.856816) (xy 117.54362 -269.876288)
			(xy 117.589778 -269.902937) (xy 117.631449 -269.936168) (xy 117.667701 -269.975239) (xy 117.697725 -270.019276)
			(xy 117.720851 -270.067297) (xy 117.736561 -270.118227) (xy 117.744504 -270.170931) (xy 117.745002 -270.19758)
			(xy 117.744504 -270.224229) (xy 117.736561 -270.276933) (xy 117.720851 -270.327863) (xy 117.697725 -270.375884)
			(xy 117.667701 -270.419921) (xy 117.631449 -270.458992) (xy 117.589778 -270.492223) (xy 117.54362 -270.518872)
			(xy 117.494006 -270.538344) (xy 117.442044 -270.550204) (xy 117.388894 -270.554188) (xy 117.335744 -270.550204)
			(xy 117.283782 -270.538344) (xy 117.234168 -270.518872) (xy 117.18801 -270.492223) (xy 117.146339 -270.458992)
			(xy 117.110087 -270.419921) (xy 117.080063 -270.375884) (xy 117.056937 -270.327863) (xy 117.041227 -270.276933)
			(xy 117.033284 -270.224229) (xy 116.804958 -270.224229) (xy 116.797015 -270.276933) (xy 116.781305 -270.327863)
			(xy 116.758179 -270.375884) (xy 116.728155 -270.419921) (xy 116.691903 -270.458992) (xy 116.650232 -270.492223)
			(xy 116.604074 -270.518872) (xy 116.55446 -270.538344) (xy 116.502498 -270.550204) (xy 116.449348 -270.554188)
			(xy 116.396198 -270.550204) (xy 116.344236 -270.538344) (xy 116.294622 -270.518872) (xy 116.248464 -270.492223)
			(xy 116.206793 -270.458992) (xy 116.170541 -270.419921) (xy 116.140517 -270.375884) (xy 116.117391 -270.327863)
			(xy 116.101681 -270.276933) (xy 116.093738 -270.224229) (xy 115.864904 -270.224229) (xy 115.856961 -270.276933)
			(xy 115.841251 -270.327863) (xy 115.818125 -270.375884) (xy 115.788101 -270.419921) (xy 115.751849 -270.458992)
			(xy 115.710178 -270.492223) (xy 115.66402 -270.518872) (xy 115.614406 -270.538344) (xy 115.562444 -270.550204)
			(xy 115.509294 -270.554188) (xy 115.456144 -270.550204) (xy 115.404182 -270.538344) (xy 115.354568 -270.518872)
			(xy 115.30841 -270.492223) (xy 115.266739 -270.458992) (xy 115.230487 -270.419921) (xy 115.200463 -270.375884)
			(xy 115.177337 -270.327863) (xy 115.161627 -270.276933) (xy 115.153684 -270.224229) (xy 114.925104 -270.224229)
			(xy 114.917161 -270.276933) (xy 114.901451 -270.327863) (xy 114.878325 -270.375884) (xy 114.848301 -270.419921)
			(xy 114.812049 -270.458992) (xy 114.770378 -270.492223) (xy 114.72422 -270.518872) (xy 114.674606 -270.538344)
			(xy 114.622644 -270.550204) (xy 114.569494 -270.554188) (xy 114.516344 -270.550204) (xy 114.464382 -270.538344)
			(xy 114.414768 -270.518872) (xy 114.36861 -270.492223) (xy 114.326939 -270.458992) (xy 114.290687 -270.419921)
			(xy 114.260663 -270.375884) (xy 114.237537 -270.327863) (xy 114.221827 -270.276933) (xy 114.213884 -270.224229)
			(xy 113.985304 -270.224229) (xy 113.977361 -270.276933) (xy 113.961651 -270.327863) (xy 113.938525 -270.375884)
			(xy 113.908501 -270.419921) (xy 113.872249 -270.458992) (xy 113.830578 -270.492223) (xy 113.78442 -270.518872)
			(xy 113.734806 -270.538344) (xy 113.682844 -270.550204) (xy 113.629694 -270.554188) (xy 113.576544 -270.550204)
			(xy 113.524582 -270.538344) (xy 113.474968 -270.518872) (xy 113.42881 -270.492223) (xy 113.387139 -270.458992)
			(xy 113.350887 -270.419921) (xy 113.320863 -270.375884) (xy 113.297737 -270.327863) (xy 113.282027 -270.276933)
			(xy 113.274084 -270.224229) (xy 109.367066 -270.224229) (xy 109.367066 -270.604742) (xy 109.367504 -270.61447)
			(xy 109.374747 -270.63253) (xy 109.38818 -270.646606) (xy 109.405881 -270.654685) (xy 109.41558 -270.655542)
			(xy 109.442772 -270.657205) (xy 109.496216 -270.667757) (xy 109.547431 -270.686325) (xy 109.59522 -270.712475)
			(xy 109.63847 -270.745598) (xy 109.676171 -270.78492) (xy 109.707445 -270.829524) (xy 109.731563 -270.878371)
			(xy 109.74796 -270.930321) (xy 109.756256 -270.984162) (xy 109.756256 -271.038045) (xy 109.984784 -271.038045)
			(xy 109.984784 -270.984747) (xy 109.992727 -270.932043) (xy 110.008437 -270.881113) (xy 110.031563 -270.833092)
			(xy 110.061587 -270.789055) (xy 110.097839 -270.749984) (xy 110.13951 -270.716753) (xy 110.185668 -270.690104)
			(xy 110.235282 -270.670632) (xy 110.287244 -270.658772) (xy 110.340394 -270.654789) (xy 110.393544 -270.658772)
			(xy 110.445506 -270.670632) (xy 110.49512 -270.690104) (xy 110.541278 -270.716753) (xy 110.582949 -270.749984)
			(xy 110.619201 -270.789055) (xy 110.649225 -270.833092) (xy 110.672351 -270.881113) (xy 110.688061 -270.932043)
			(xy 110.696004 -270.984747) (xy 110.696502 -271.011396) (xy 110.696004 -271.038045) (xy 113.743984 -271.038045)
			(xy 113.743984 -270.984747) (xy 113.751927 -270.932043) (xy 113.767637 -270.881113) (xy 113.790763 -270.833092)
			(xy 113.820787 -270.789055) (xy 113.857039 -270.749984) (xy 113.89871 -270.716753) (xy 113.944868 -270.690104)
			(xy 113.994482 -270.670632) (xy 114.046444 -270.658772) (xy 114.099594 -270.654789) (xy 114.152744 -270.658772)
			(xy 114.204706 -270.670632) (xy 114.25432 -270.690104) (xy 114.300478 -270.716753) (xy 114.342149 -270.749984)
			(xy 114.378401 -270.789055) (xy 114.408425 -270.833092) (xy 114.431551 -270.881113) (xy 114.447261 -270.932043)
			(xy 114.455204 -270.984747) (xy 114.455702 -271.011396) (xy 114.455204 -271.038045) (xy 114.683784 -271.038045)
			(xy 114.683784 -270.984747) (xy 114.691727 -270.932043) (xy 114.707437 -270.881113) (xy 114.730563 -270.833092)
			(xy 114.760587 -270.789055) (xy 114.796839 -270.749984) (xy 114.83851 -270.716753) (xy 114.884668 -270.690104)
			(xy 114.934282 -270.670632) (xy 114.986244 -270.658772) (xy 115.039394 -270.654789) (xy 115.092544 -270.658772)
			(xy 115.144506 -270.670632) (xy 115.19412 -270.690104) (xy 115.240278 -270.716753) (xy 115.281949 -270.749984)
			(xy 115.318201 -270.789055) (xy 115.348225 -270.833092) (xy 115.371351 -270.881113) (xy 115.387061 -270.932043)
			(xy 115.395004 -270.984747) (xy 115.395502 -271.011396) (xy 115.395004 -271.038045) (xy 115.623584 -271.038045)
			(xy 115.623584 -270.984747) (xy 115.631527 -270.932043) (xy 115.647237 -270.881113) (xy 115.670363 -270.833092)
			(xy 115.700387 -270.789055) (xy 115.736639 -270.749984) (xy 115.77831 -270.716753) (xy 115.824468 -270.690104)
			(xy 115.874082 -270.670632) (xy 115.926044 -270.658772) (xy 115.979194 -270.654789) (xy 116.032344 -270.658772)
			(xy 116.084306 -270.670632) (xy 116.13392 -270.690104) (xy 116.180078 -270.716753) (xy 116.221749 -270.749984)
			(xy 116.258001 -270.789055) (xy 116.288025 -270.833092) (xy 116.311151 -270.881113) (xy 116.326861 -270.932043)
			(xy 116.334804 -270.984747) (xy 116.335302 -271.011396) (xy 116.334804 -271.038045) (xy 116.563384 -271.038045)
			(xy 116.563384 -270.984747) (xy 116.571327 -270.932043) (xy 116.587037 -270.881113) (xy 116.610163 -270.833092)
			(xy 116.640187 -270.789055) (xy 116.676439 -270.749984) (xy 116.71811 -270.716753) (xy 116.764268 -270.690104)
			(xy 116.813882 -270.670632) (xy 116.865844 -270.658772) (xy 116.918994 -270.654789) (xy 116.972144 -270.658772)
			(xy 117.024106 -270.670632) (xy 117.07372 -270.690104) (xy 117.119878 -270.716753) (xy 117.161549 -270.749984)
			(xy 117.197801 -270.789055) (xy 117.227825 -270.833092) (xy 117.250951 -270.881113) (xy 117.266661 -270.932043)
			(xy 117.274604 -270.984747) (xy 117.275102 -271.011396) (xy 117.274604 -271.038045) (xy 117.266661 -271.090749)
			(xy 117.250951 -271.141679) (xy 117.227825 -271.1897) (xy 117.197801 -271.233737) (xy 117.161549 -271.272808)
			(xy 117.119878 -271.306039) (xy 117.07372 -271.332688) (xy 117.024106 -271.35216) (xy 116.972144 -271.36402)
			(xy 116.918994 -271.368004) (xy 116.865844 -271.36402) (xy 116.813882 -271.35216) (xy 116.764268 -271.332688)
			(xy 116.71811 -271.306039) (xy 116.676439 -271.272808) (xy 116.640187 -271.233737) (xy 116.610163 -271.1897)
			(xy 116.587037 -271.141679) (xy 116.571327 -271.090749) (xy 116.563384 -271.038045) (xy 116.334804 -271.038045)
			(xy 116.326861 -271.090749) (xy 116.311151 -271.141679) (xy 116.288025 -271.1897) (xy 116.258001 -271.233737)
			(xy 116.221749 -271.272808) (xy 116.180078 -271.306039) (xy 116.13392 -271.332688) (xy 116.084306 -271.35216)
			(xy 116.032344 -271.36402) (xy 115.979194 -271.368004) (xy 115.926044 -271.36402) (xy 115.874082 -271.35216)
			(xy 115.824468 -271.332688) (xy 115.77831 -271.306039) (xy 115.736639 -271.272808) (xy 115.700387 -271.233737)
			(xy 115.670363 -271.1897) (xy 115.647237 -271.141679) (xy 115.631527 -271.090749) (xy 115.623584 -271.038045)
			(xy 115.395004 -271.038045) (xy 115.387061 -271.090749) (xy 115.371351 -271.141679) (xy 115.348225 -271.1897)
			(xy 115.318201 -271.233737) (xy 115.281949 -271.272808) (xy 115.240278 -271.306039) (xy 115.19412 -271.332688)
			(xy 115.144506 -271.35216) (xy 115.092544 -271.36402) (xy 115.039394 -271.368004) (xy 114.986244 -271.36402)
			(xy 114.934282 -271.35216) (xy 114.884668 -271.332688) (xy 114.83851 -271.306039) (xy 114.796839 -271.272808)
			(xy 114.760587 -271.233737) (xy 114.730563 -271.1897) (xy 114.707437 -271.141679) (xy 114.691727 -271.090749)
			(xy 114.683784 -271.038045) (xy 114.455204 -271.038045) (xy 114.447261 -271.090749) (xy 114.431551 -271.141679)
			(xy 114.408425 -271.1897) (xy 114.378401 -271.233737) (xy 114.342149 -271.272808) (xy 114.300478 -271.306039)
			(xy 114.25432 -271.332688) (xy 114.204706 -271.35216) (xy 114.152744 -271.36402) (xy 114.099594 -271.368004)
			(xy 114.046444 -271.36402) (xy 113.994482 -271.35216) (xy 113.944868 -271.332688) (xy 113.89871 -271.306039)
			(xy 113.857039 -271.272808) (xy 113.820787 -271.233737) (xy 113.790763 -271.1897) (xy 113.767637 -271.141679)
			(xy 113.751927 -271.090749) (xy 113.743984 -271.038045) (xy 110.696004 -271.038045) (xy 110.688061 -271.090749)
			(xy 110.672351 -271.141679) (xy 110.649225 -271.1897) (xy 110.619201 -271.233737) (xy 110.582949 -271.272808)
			(xy 110.541278 -271.306039) (xy 110.49512 -271.332688) (xy 110.445506 -271.35216) (xy 110.393544 -271.36402)
			(xy 110.340394 -271.368004) (xy 110.287244 -271.36402) (xy 110.235282 -271.35216) (xy 110.185668 -271.332688)
			(xy 110.13951 -271.306039) (xy 110.097839 -271.272808) (xy 110.061587 -271.233737) (xy 110.031563 -271.1897)
			(xy 110.008437 -271.141679) (xy 109.992727 -271.090749) (xy 109.984784 -271.038045) (xy 109.756256 -271.038045)
			(xy 109.756256 -271.038638) (xy 109.74796 -271.092479) (xy 109.731563 -271.144428) (xy 109.707446 -271.193275)
			(xy 109.676172 -271.23788) (xy 109.63847 -271.277202) (xy 109.59522 -271.310325) (xy 109.547431 -271.336475)
			(xy 109.496217 -271.355043) (xy 109.442773 -271.365595) (xy 109.41558 -271.36725) (xy 109.40587 -271.368111)
			(xy 109.388131 -271.376154) (xy 109.37467 -271.390231) (xy 109.367427 -271.408311) (xy 109.367066 -271.41805)
			(xy 109.367066 -271.851861) (xy 109.51463 -271.851861) (xy 109.51463 -271.798563) (xy 109.522573 -271.745859)
			(xy 109.538283 -271.694929) (xy 109.561409 -271.646908) (xy 109.591433 -271.602871) (xy 109.627685 -271.5638)
			(xy 109.669356 -271.530569) (xy 109.715514 -271.50392) (xy 109.765128 -271.484448) (xy 109.81709 -271.472588)
			(xy 109.87024 -271.468605) (xy 109.92339 -271.472588) (xy 109.975352 -271.484448) (xy 110.024966 -271.50392)
			(xy 110.071124 -271.530569) (xy 110.112795 -271.5638) (xy 110.149047 -271.602871) (xy 110.179071 -271.646908)
			(xy 110.202197 -271.694929) (xy 110.217907 -271.745859) (xy 110.22585 -271.798563) (xy 110.226348 -271.825212)
			(xy 110.22585 -271.851861) (xy 113.274084 -271.851861) (xy 113.274084 -271.798563) (xy 113.282027 -271.745859)
			(xy 113.297737 -271.694929) (xy 113.320863 -271.646908) (xy 113.350887 -271.602871) (xy 113.387139 -271.5638)
			(xy 113.42881 -271.530569) (xy 113.474968 -271.50392) (xy 113.524582 -271.484448) (xy 113.576544 -271.472588)
			(xy 113.629694 -271.468605) (xy 113.682844 -271.472588) (xy 113.734806 -271.484448) (xy 113.78442 -271.50392)
			(xy 113.830578 -271.530569) (xy 113.872249 -271.5638) (xy 113.908501 -271.602871) (xy 113.938525 -271.646908)
			(xy 113.961651 -271.694929) (xy 113.977361 -271.745859) (xy 113.985304 -271.798563) (xy 113.985802 -271.825212)
			(xy 113.985304 -271.851861) (xy 114.214138 -271.851861) (xy 114.214138 -271.798563) (xy 114.222081 -271.745859)
			(xy 114.237791 -271.694929) (xy 114.260917 -271.646908) (xy 114.290941 -271.602871) (xy 114.327193 -271.5638)
			(xy 114.368864 -271.530569) (xy 114.415022 -271.50392) (xy 114.464636 -271.484448) (xy 114.516598 -271.472588)
			(xy 114.569748 -271.468605) (xy 114.622898 -271.472588) (xy 114.67486 -271.484448) (xy 114.724474 -271.50392)
			(xy 114.770632 -271.530569) (xy 114.812303 -271.5638) (xy 114.848555 -271.602871) (xy 114.878579 -271.646908)
			(xy 114.901705 -271.694929) (xy 114.917415 -271.745859) (xy 114.925358 -271.798563) (xy 114.925856 -271.825212)
			(xy 114.925358 -271.851861) (xy 115.153938 -271.851861) (xy 115.153938 -271.798563) (xy 115.161881 -271.745859)
			(xy 115.177591 -271.694929) (xy 115.200717 -271.646908) (xy 115.230741 -271.602871) (xy 115.266993 -271.5638)
			(xy 115.308664 -271.530569) (xy 115.354822 -271.50392) (xy 115.404436 -271.484448) (xy 115.456398 -271.472588)
			(xy 115.509548 -271.468605) (xy 115.562698 -271.472588) (xy 115.61466 -271.484448) (xy 115.664274 -271.50392)
			(xy 115.710432 -271.530569) (xy 115.752103 -271.5638) (xy 115.788355 -271.602871) (xy 115.818379 -271.646908)
			(xy 115.841505 -271.694929) (xy 115.857215 -271.745859) (xy 115.865158 -271.798563) (xy 115.865656 -271.825212)
			(xy 115.865158 -271.851861) (xy 116.09323 -271.851861) (xy 116.09323 -271.798563) (xy 116.101173 -271.745859)
			(xy 116.116883 -271.694929) (xy 116.140009 -271.646908) (xy 116.170033 -271.602871) (xy 116.206285 -271.5638)
			(xy 116.247956 -271.530569) (xy 116.294114 -271.50392) (xy 116.343728 -271.484448) (xy 116.39569 -271.472588)
			(xy 116.44884 -271.468605) (xy 116.50199 -271.472588) (xy 116.553952 -271.484448) (xy 116.603566 -271.50392)
			(xy 116.649724 -271.530569) (xy 116.691395 -271.5638) (xy 116.727647 -271.602871) (xy 116.757671 -271.646908)
			(xy 116.780797 -271.694929) (xy 116.796507 -271.745859) (xy 116.80445 -271.798563) (xy 116.804948 -271.825212)
			(xy 116.80445 -271.851861) (xy 117.033538 -271.851861) (xy 117.033538 -271.798563) (xy 117.041481 -271.745859)
			(xy 117.057191 -271.694929) (xy 117.080317 -271.646908) (xy 117.110341 -271.602871) (xy 117.146593 -271.5638)
			(xy 117.188264 -271.530569) (xy 117.234422 -271.50392) (xy 117.284036 -271.484448) (xy 117.335998 -271.472588)
			(xy 117.389148 -271.468605) (xy 117.442298 -271.472588) (xy 117.49426 -271.484448) (xy 117.543874 -271.50392)
			(xy 117.590032 -271.530569) (xy 117.631703 -271.5638) (xy 117.667955 -271.602871) (xy 117.697979 -271.646908)
			(xy 117.721105 -271.694929) (xy 117.736815 -271.745859) (xy 117.744758 -271.798563) (xy 117.745256 -271.825212)
			(xy 117.744758 -271.851861) (xy 117.736815 -271.904565) (xy 117.721105 -271.955495) (xy 117.697979 -272.003516)
			(xy 117.667955 -272.047553) (xy 117.631703 -272.086624) (xy 117.590032 -272.119855) (xy 117.543874 -272.146504)
			(xy 117.49426 -272.165976) (xy 117.442298 -272.177836) (xy 117.389148 -272.18182) (xy 117.335998 -272.177836)
			(xy 117.284036 -272.165976) (xy 117.234422 -272.146504) (xy 117.188264 -272.119855) (xy 117.146593 -272.086624)
			(xy 117.110341 -272.047553) (xy 117.080317 -272.003516) (xy 117.057191 -271.955495) (xy 117.041481 -271.904565)
			(xy 117.033538 -271.851861) (xy 116.80445 -271.851861) (xy 116.796507 -271.904565) (xy 116.780797 -271.955495)
			(xy 116.757671 -272.003516) (xy 116.727647 -272.047553) (xy 116.691395 -272.086624) (xy 116.649724 -272.119855)
			(xy 116.603566 -272.146504) (xy 116.553952 -272.165976) (xy 116.50199 -272.177836) (xy 116.44884 -272.18182)
			(xy 116.39569 -272.177836) (xy 116.343728 -272.165976) (xy 116.294114 -272.146504) (xy 116.247956 -272.119855)
			(xy 116.206285 -272.086624) (xy 116.170033 -272.047553) (xy 116.140009 -272.003516) (xy 116.116883 -271.955495)
			(xy 116.101173 -271.904565) (xy 116.09323 -271.851861) (xy 115.865158 -271.851861) (xy 115.857215 -271.904565)
			(xy 115.841505 -271.955495) (xy 115.818379 -272.003516) (xy 115.788355 -272.047553) (xy 115.752103 -272.086624)
			(xy 115.710432 -272.119855) (xy 115.664274 -272.146504) (xy 115.61466 -272.165976) (xy 115.562698 -272.177836)
			(xy 115.509548 -272.18182) (xy 115.456398 -272.177836) (xy 115.404436 -272.165976) (xy 115.354822 -272.146504)
			(xy 115.308664 -272.119855) (xy 115.266993 -272.086624) (xy 115.230741 -272.047553) (xy 115.200717 -272.003516)
			(xy 115.177591 -271.955495) (xy 115.161881 -271.904565) (xy 115.153938 -271.851861) (xy 114.925358 -271.851861)
			(xy 114.917415 -271.904565) (xy 114.901705 -271.955495) (xy 114.878579 -272.003516) (xy 114.848555 -272.047553)
			(xy 114.812303 -272.086624) (xy 114.770632 -272.119855) (xy 114.724474 -272.146504) (xy 114.67486 -272.165976)
			(xy 114.622898 -272.177836) (xy 114.569748 -272.18182) (xy 114.516598 -272.177836) (xy 114.464636 -272.165976)
			(xy 114.415022 -272.146504) (xy 114.368864 -272.119855) (xy 114.327193 -272.086624) (xy 114.290941 -272.047553)
			(xy 114.260917 -272.003516) (xy 114.237791 -271.955495) (xy 114.222081 -271.904565) (xy 114.214138 -271.851861)
			(xy 113.985304 -271.851861) (xy 113.977361 -271.904565) (xy 113.961651 -271.955495) (xy 113.938525 -272.003516)
			(xy 113.908501 -272.047553) (xy 113.872249 -272.086624) (xy 113.830578 -272.119855) (xy 113.78442 -272.146504)
			(xy 113.734806 -272.165976) (xy 113.682844 -272.177836) (xy 113.629694 -272.18182) (xy 113.576544 -272.177836)
			(xy 113.524582 -272.165976) (xy 113.474968 -272.146504) (xy 113.42881 -272.119855) (xy 113.387139 -272.086624)
			(xy 113.350887 -272.047553) (xy 113.320863 -272.003516) (xy 113.297737 -271.955495) (xy 113.282027 -271.904565)
			(xy 113.274084 -271.851861) (xy 110.22585 -271.851861) (xy 110.217907 -271.904565) (xy 110.202197 -271.955495)
			(xy 110.179071 -272.003516) (xy 110.149047 -272.047553) (xy 110.112795 -272.086624) (xy 110.071124 -272.119855)
			(xy 110.024966 -272.146504) (xy 109.975352 -272.165976) (xy 109.92339 -272.177836) (xy 109.87024 -272.18182)
			(xy 109.81709 -272.177836) (xy 109.765128 -272.165976) (xy 109.715514 -272.146504) (xy 109.669356 -272.119855)
			(xy 109.627685 -272.086624) (xy 109.591433 -272.047553) (xy 109.561409 -272.003516) (xy 109.538283 -271.955495)
			(xy 109.522573 -271.904565) (xy 109.51463 -271.851861) (xy 109.367066 -271.851861) (xy 109.367066 -272.232628)
			(xy 109.367501 -272.242358) (xy 109.374742 -272.260422) (xy 109.388175 -272.274503) (xy 109.405879 -272.282584)
			(xy 109.41558 -272.283428) (xy 109.44277 -272.285091) (xy 109.496208 -272.295644) (xy 109.547416 -272.314213)
			(xy 109.595199 -272.340364) (xy 109.638441 -272.373488) (xy 109.676135 -272.412811) (xy 109.707399 -272.457415)
			(xy 109.731506 -272.506261) (xy 109.747892 -272.558209) (xy 109.756176 -272.612046) (xy 109.756702 -272.639282)
			(xy 109.756208 -272.665931) (xy 109.984784 -272.665931) (xy 109.984784 -272.612633) (xy 109.992727 -272.559929)
			(xy 110.008437 -272.508999) (xy 110.031563 -272.460978) (xy 110.061587 -272.416941) (xy 110.097839 -272.37787)
			(xy 110.13951 -272.344639) (xy 110.185668 -272.31799) (xy 110.235282 -272.298518) (xy 110.287244 -272.286658)
			(xy 110.340394 -272.282675) (xy 110.393544 -272.286658) (xy 110.445506 -272.298518) (xy 110.49512 -272.31799)
			(xy 110.541278 -272.344639) (xy 110.582949 -272.37787) (xy 110.619201 -272.416941) (xy 110.649225 -272.460978)
			(xy 110.672351 -272.508999) (xy 110.688061 -272.559929) (xy 110.696004 -272.612633) (xy 110.696502 -272.639282)
			(xy 110.696004 -272.665931) (xy 113.743984 -272.665931) (xy 113.743984 -272.612633) (xy 113.751927 -272.559929)
			(xy 113.767637 -272.508999) (xy 113.790763 -272.460978) (xy 113.820787 -272.416941) (xy 113.857039 -272.37787)
			(xy 113.89871 -272.344639) (xy 113.944868 -272.31799) (xy 113.994482 -272.298518) (xy 114.046444 -272.286658)
			(xy 114.099594 -272.282675) (xy 114.152744 -272.286658) (xy 114.204706 -272.298518) (xy 114.25432 -272.31799)
			(xy 114.300478 -272.344639) (xy 114.342149 -272.37787) (xy 114.378401 -272.416941) (xy 114.408425 -272.460978)
			(xy 114.431551 -272.508999) (xy 114.447261 -272.559929) (xy 114.455204 -272.612633) (xy 114.455702 -272.639282)
			(xy 114.455204 -272.665931) (xy 114.683784 -272.665931) (xy 114.683784 -272.612633) (xy 114.691727 -272.559929)
			(xy 114.707437 -272.508999) (xy 114.730563 -272.460978) (xy 114.760587 -272.416941) (xy 114.796839 -272.37787)
			(xy 114.83851 -272.344639) (xy 114.884668 -272.31799) (xy 114.934282 -272.298518) (xy 114.986244 -272.286658)
			(xy 115.039394 -272.282675) (xy 115.092544 -272.286658) (xy 115.144506 -272.298518) (xy 115.19412 -272.31799)
			(xy 115.240278 -272.344639) (xy 115.281949 -272.37787) (xy 115.318201 -272.416941) (xy 115.348225 -272.460978)
			(xy 115.371351 -272.508999) (xy 115.387061 -272.559929) (xy 115.395004 -272.612633) (xy 115.395502 -272.639282)
			(xy 115.395004 -272.665931) (xy 115.623584 -272.665931) (xy 115.623584 -272.612633) (xy 115.631527 -272.559929)
			(xy 115.647237 -272.508999) (xy 115.670363 -272.460978) (xy 115.700387 -272.416941) (xy 115.736639 -272.37787)
			(xy 115.77831 -272.344639) (xy 115.824468 -272.31799) (xy 115.874082 -272.298518) (xy 115.926044 -272.286658)
			(xy 115.979194 -272.282675) (xy 116.032344 -272.286658) (xy 116.084306 -272.298518) (xy 116.13392 -272.31799)
			(xy 116.180078 -272.344639) (xy 116.221749 -272.37787) (xy 116.258001 -272.416941) (xy 116.288025 -272.460978)
			(xy 116.311151 -272.508999) (xy 116.326861 -272.559929) (xy 116.334804 -272.612633) (xy 116.335302 -272.639282)
			(xy 116.334804 -272.665931) (xy 116.563384 -272.665931) (xy 116.563384 -272.612633) (xy 116.571327 -272.559929)
			(xy 116.587037 -272.508999) (xy 116.610163 -272.460978) (xy 116.640187 -272.416941) (xy 116.676439 -272.37787)
			(xy 116.71811 -272.344639) (xy 116.764268 -272.31799) (xy 116.813882 -272.298518) (xy 116.865844 -272.286658)
			(xy 116.918994 -272.282675) (xy 116.972144 -272.286658) (xy 117.024106 -272.298518) (xy 117.07372 -272.31799)
			(xy 117.119878 -272.344639) (xy 117.161549 -272.37787) (xy 117.197801 -272.416941) (xy 117.227825 -272.460978)
			(xy 117.250951 -272.508999) (xy 117.266661 -272.559929) (xy 117.274604 -272.612633) (xy 117.275102 -272.639282)
			(xy 117.274604 -272.665931) (xy 117.266661 -272.718635) (xy 117.250951 -272.769565) (xy 117.227825 -272.817586)
			(xy 117.197801 -272.861623) (xy 117.161549 -272.900694) (xy 117.119878 -272.933925) (xy 117.07372 -272.960574)
			(xy 117.024106 -272.980046) (xy 116.972144 -272.991906) (xy 116.918994 -272.99589) (xy 116.865844 -272.991906)
			(xy 116.813882 -272.980046) (xy 116.764268 -272.960574) (xy 116.71811 -272.933925) (xy 116.676439 -272.900694)
			(xy 116.640187 -272.861623) (xy 116.610163 -272.817586) (xy 116.587037 -272.769565) (xy 116.571327 -272.718635)
			(xy 116.563384 -272.665931) (xy 116.334804 -272.665931) (xy 116.326861 -272.718635) (xy 116.311151 -272.769565)
			(xy 116.288025 -272.817586) (xy 116.258001 -272.861623) (xy 116.221749 -272.900694) (xy 116.180078 -272.933925)
			(xy 116.13392 -272.960574) (xy 116.084306 -272.980046) (xy 116.032344 -272.991906) (xy 115.979194 -272.99589)
			(xy 115.926044 -272.991906) (xy 115.874082 -272.980046) (xy 115.824468 -272.960574) (xy 115.77831 -272.933925)
			(xy 115.736639 -272.900694) (xy 115.700387 -272.861623) (xy 115.670363 -272.817586) (xy 115.647237 -272.769565)
			(xy 115.631527 -272.718635) (xy 115.623584 -272.665931) (xy 115.395004 -272.665931) (xy 115.387061 -272.718635)
			(xy 115.371351 -272.769565) (xy 115.348225 -272.817586) (xy 115.318201 -272.861623) (xy 115.281949 -272.900694)
			(xy 115.240278 -272.933925) (xy 115.19412 -272.960574) (xy 115.144506 -272.980046) (xy 115.092544 -272.991906)
			(xy 115.039394 -272.99589) (xy 114.986244 -272.991906) (xy 114.934282 -272.980046) (xy 114.884668 -272.960574)
			(xy 114.83851 -272.933925) (xy 114.796839 -272.900694) (xy 114.760587 -272.861623) (xy 114.730563 -272.817586)
			(xy 114.707437 -272.769565) (xy 114.691727 -272.718635) (xy 114.683784 -272.665931) (xy 114.455204 -272.665931)
			(xy 114.447261 -272.718635) (xy 114.431551 -272.769565) (xy 114.408425 -272.817586) (xy 114.378401 -272.861623)
			(xy 114.342149 -272.900694) (xy 114.300478 -272.933925) (xy 114.25432 -272.960574) (xy 114.204706 -272.980046)
			(xy 114.152744 -272.991906) (xy 114.099594 -272.99589) (xy 114.046444 -272.991906) (xy 113.994482 -272.980046)
			(xy 113.944868 -272.960574) (xy 113.89871 -272.933925) (xy 113.857039 -272.900694) (xy 113.820787 -272.861623)
			(xy 113.790763 -272.817586) (xy 113.767637 -272.769565) (xy 113.751927 -272.718635) (xy 113.743984 -272.665931)
			(xy 110.696004 -272.665931) (xy 110.688061 -272.718635) (xy 110.672351 -272.769565) (xy 110.649225 -272.817586)
			(xy 110.619201 -272.861623) (xy 110.582949 -272.900694) (xy 110.541278 -272.933925) (xy 110.49512 -272.960574)
			(xy 110.445506 -272.980046) (xy 110.393544 -272.991906) (xy 110.340394 -272.99589) (xy 110.287244 -272.991906)
			(xy 110.235282 -272.980046) (xy 110.185668 -272.960574) (xy 110.13951 -272.933925) (xy 110.097839 -272.900694)
			(xy 110.061587 -272.861623) (xy 110.031563 -272.817586) (xy 110.008437 -272.769565) (xy 109.992727 -272.718635)
			(xy 109.984784 -272.665931) (xy 109.756208 -272.665931) (xy 109.756183 -272.667268) (xy 109.747429 -272.722552)
			(xy 109.730135 -272.775785) (xy 109.704726 -272.825657) (xy 109.671827 -272.87094) (xy 109.632249 -272.910519)
			(xy 109.586967 -272.943419) (xy 109.537096 -272.96883) (xy 109.483863 -272.986126) (xy 109.42858 -272.994882)
			(xy 109.400594 -272.99539) (xy 109.375106 -272.994961) (xy 109.324649 -272.987708) (xy 109.275741 -272.973335)
			(xy 109.229382 -272.952137) (xy 109.186518 -272.924547) (xy 109.148025 -272.891127) (xy 109.11469 -272.852562)
			(xy 109.10062 -272.831306) (xy 109.091996 -272.818848) (xy 109.068912 -272.799248) (xy 109.041088 -272.787293)
			(xy 109.010981 -272.784039) (xy 108.981246 -272.789772) (xy 108.954507 -272.803987) (xy 108.943394 -272.814288)
			(xy 108.833412 -272.92427) (xy 108.824072 -272.934211) (xy 108.810567 -272.9579) (xy 108.803823 -272.98432)
			(xy 108.804323 -273.011583) (xy 108.81203 -273.037739) (xy 108.826394 -273.060916) (xy 108.846387 -273.079458)
			(xy 108.87058 -273.092038) (xy 108.897241 -273.097756) (xy 108.910882 -273.097498) (xy 108.930694 -273.09699)
			(xy 108.95868 -273.09751) (xy 109.013962 -273.106265) (xy 109.067195 -273.12356) (xy 109.117066 -273.14897)
			(xy 109.162348 -273.181868) (xy 109.201926 -273.221446) (xy 109.234826 -273.266727) (xy 109.260237 -273.316598)
			(xy 109.277534 -273.36983) (xy 109.28629 -273.425112) (xy 109.286802 -273.453098) (xy 109.28641 -273.4763)
			(xy 109.285956 -273.479747) (xy 109.514884 -273.479747) (xy 109.514884 -273.426449) (xy 109.522827 -273.373745)
			(xy 109.538537 -273.322815) (xy 109.561663 -273.274794) (xy 109.591687 -273.230757) (xy 109.627939 -273.191686)
			(xy 109.66961 -273.158455) (xy 109.715768 -273.131806) (xy 109.765382 -273.112334) (xy 109.817344 -273.100474)
			(xy 109.870494 -273.096491) (xy 109.923644 -273.100474) (xy 109.975606 -273.112334) (xy 110.02522 -273.131806)
			(xy 110.071378 -273.158455) (xy 110.113049 -273.191686) (xy 110.149301 -273.230757) (xy 110.179325 -273.274794)
			(xy 110.202451 -273.322815) (xy 110.218161 -273.373745) (xy 110.226104 -273.426449) (xy 110.226602 -273.453098)
			(xy 110.226104 -273.479747) (xy 113.274084 -273.479747) (xy 113.274084 -273.426449) (xy 113.282027 -273.373745)
			(xy 113.297737 -273.322815) (xy 113.320863 -273.274794) (xy 113.350887 -273.230757) (xy 113.387139 -273.191686)
			(xy 113.42881 -273.158455) (xy 113.474968 -273.131806) (xy 113.524582 -273.112334) (xy 113.576544 -273.100474)
			(xy 113.629694 -273.096491) (xy 113.682844 -273.100474) (xy 113.734806 -273.112334) (xy 113.78442 -273.131806)
			(xy 113.830578 -273.158455) (xy 113.872249 -273.191686) (xy 113.908501 -273.230757) (xy 113.938525 -273.274794)
			(xy 113.961651 -273.322815) (xy 113.977361 -273.373745) (xy 113.985304 -273.426449) (xy 113.985802 -273.453098)
			(xy 113.985304 -273.479747) (xy 113.977361 -273.532451) (xy 113.961651 -273.583381) (xy 113.938525 -273.631402)
			(xy 113.908501 -273.675439) (xy 113.872249 -273.71451) (xy 113.830578 -273.747741) (xy 113.78442 -273.77439)
			(xy 113.734806 -273.793862) (xy 113.682844 -273.805722) (xy 113.629694 -273.809706) (xy 113.576544 -273.805722)
			(xy 113.524582 -273.793862) (xy 113.474968 -273.77439) (xy 113.42881 -273.747741) (xy 113.387139 -273.71451)
			(xy 113.350887 -273.675439) (xy 113.320863 -273.631402) (xy 113.297737 -273.583381) (xy 113.282027 -273.532451)
			(xy 113.274084 -273.479747) (xy 110.226104 -273.479747) (xy 110.218161 -273.532451) (xy 110.202451 -273.583381)
			(xy 110.179325 -273.631402) (xy 110.149301 -273.675439) (xy 110.113049 -273.71451) (xy 110.071378 -273.747741)
			(xy 110.02522 -273.77439) (xy 109.975606 -273.793862) (xy 109.923644 -273.805722) (xy 109.870494 -273.809706)
			(xy 109.817344 -273.805722) (xy 109.765382 -273.793862) (xy 109.715768 -273.77439) (xy 109.66961 -273.747741)
			(xy 109.627939 -273.71451) (xy 109.591687 -273.675439) (xy 109.561663 -273.631402) (xy 109.538537 -273.583381)
			(xy 109.522827 -273.532451) (xy 109.514884 -273.479747) (xy 109.285956 -273.479747) (xy 109.280354 -273.522309)
			(xy 109.268383 -273.567143) (xy 109.259878 -273.588734) (xy 109.25048 -273.611848) (xy 109.422946 -273.910552)
			(xy 109.447584 -273.913854) (xy 109.472933 -273.917672) (xy 109.522254 -273.931639) (xy 109.569063 -273.952536)
			(xy 109.612391 -273.979929) (xy 109.651343 -274.013252) (xy 109.685113 -274.051818) (xy 109.713004 -274.094827)
			(xy 109.734438 -274.141392) (xy 109.748973 -274.19055) (xy 109.756308 -274.241283) (xy 109.756702 -274.266914)
			(xy 109.756204 -274.293563) (xy 109.984784 -274.293563) (xy 109.984784 -274.240265) (xy 109.992727 -274.187561)
			(xy 110.008437 -274.136631) (xy 110.031563 -274.08861) (xy 110.061587 -274.044573) (xy 110.097839 -274.005502)
			(xy 110.13951 -273.972271) (xy 110.185668 -273.945622) (xy 110.235282 -273.92615) (xy 110.287244 -273.91429)
			(xy 110.340394 -273.910307) (xy 110.393544 -273.91429) (xy 110.445506 -273.92615) (xy 110.49512 -273.945622)
			(xy 110.541278 -273.972271) (xy 110.582949 -274.005502) (xy 110.619201 -274.044573) (xy 110.649225 -274.08861)
			(xy 110.672351 -274.136631) (xy 110.688061 -274.187561) (xy 110.696004 -274.240265) (xy 110.696502 -274.266914)
			(xy 110.696004 -274.293563) (xy 110.688061 -274.346267) (xy 110.672351 -274.397197) (xy 110.649225 -274.445218)
			(xy 110.619201 -274.489255) (xy 110.582949 -274.528326) (xy 110.541278 -274.561557) (xy 110.49512 -274.588206)
			(xy 110.445506 -274.607678) (xy 110.393544 -274.619538) (xy 110.340394 -274.623522) (xy 110.287244 -274.619538)
			(xy 110.235282 -274.607678) (xy 110.185668 -274.588206) (xy 110.13951 -274.561557) (xy 110.097839 -274.528326)
			(xy 110.061587 -274.489255) (xy 110.031563 -274.445218) (xy 110.008437 -274.397197) (xy 109.992727 -274.346267)
			(xy 109.984784 -274.293563) (xy 109.756204 -274.293563) (xy 109.748261 -274.346267) (xy 109.732551 -274.397197)
			(xy 109.709425 -274.445218) (xy 109.679401 -274.489255) (xy 109.643149 -274.528326) (xy 109.601478 -274.561557)
			(xy 109.55532 -274.588206) (xy 109.505706 -274.607678) (xy 109.453744 -274.619538) (xy 109.400594 -274.623522)
			(xy 109.347444 -274.619538) (xy 109.295482 -274.607678) (xy 109.245868 -274.588206) (xy 109.19971 -274.561557)
			(xy 109.158039 -274.528326) (xy 109.121787 -274.489255) (xy 109.091763 -274.445218) (xy 109.068637 -274.397197)
			(xy 109.052927 -274.346267) (xy 109.044984 -274.293563) (xy 109.044486 -274.266914) (xy 109.044861 -274.243669)
			(xy 109.050904 -274.197573) (xy 109.062889 -274.152654) (xy 109.07141 -274.131024) (xy 109.081062 -274.10791)
			(xy 108.908596 -273.80946) (xy 108.883704 -273.806158) (xy 108.858154 -273.802277) (xy 108.80846 -273.788095)
			(xy 108.761338 -273.76688) (xy 108.717778 -273.739076) (xy 108.678694 -273.705268) (xy 108.661454 -273.686016)
			(xy 108.652136 -273.675893) (xy 108.629273 -273.660604) (xy 108.603158 -273.651978) (xy 108.575687 -273.650639)
			(xy 108.548857 -273.656685) (xy 108.524616 -273.669677) (xy 108.504725 -273.688671) (xy 108.490629 -273.712288)
			(xy 108.483353 -273.738811) (xy 108.482892 -273.752564) (xy 108.482892 -273.909028) (xy 108.524548 -273.916648)
			(xy 108.550143 -273.921735) (xy 108.599591 -273.938407) (xy 108.646075 -273.962121) (xy 108.688598 -273.992368)
			(xy 108.726248 -274.0285) (xy 108.758219 -274.069742) (xy 108.783826 -274.115211) (xy 108.802518 -274.163932)
			(xy 108.813896 -274.214859) (xy 108.817716 -274.266902) (xy 108.813895 -274.318946) (xy 108.802517 -274.369873)
			(xy 108.783823 -274.418593) (xy 108.758217 -274.464062) (xy 108.726245 -274.505304) (xy 108.688594 -274.541435)
			(xy 108.646071 -274.571682) (xy 108.599587 -274.595395) (xy 108.550138 -274.612067) (xy 108.524548 -274.61718)
			(xy 108.482892 -274.6248) (xy 108.482892 -274.781264) (xy 108.483313 -274.79502) (xy 108.490597 -274.821547)
			(xy 108.5047 -274.845167) (xy 108.524598 -274.864163) (xy 108.548845 -274.877157) (xy 108.575681 -274.883204)
			(xy 108.603158 -274.881866) (xy 108.62928 -274.87324) (xy 108.65215 -274.857952) (xy 108.661454 -274.847812)
			(xy 108.67843 -274.828834) (xy 108.716875 -274.795448) (xy 108.759685 -274.767882) (xy 108.805988 -274.746699)
			(xy 108.854837 -274.732332) (xy 108.905235 -274.725074) (xy 108.930694 -274.724622) (xy 108.957343 -274.725095)
			(xy 109.010046 -274.733038) (xy 109.060977 -274.748747) (xy 109.108998 -274.771872) (xy 109.153035 -274.801895)
			(xy 109.192106 -274.838147) (xy 109.225337 -274.879817) (xy 109.251987 -274.925975) (xy 109.271459 -274.975589)
			(xy 109.283319 -275.027551) (xy 109.287302 -275.0807) (xy 109.285303 -275.107379) (xy 109.514884 -275.107379)
			(xy 109.514884 -275.054081) (xy 109.522827 -275.001377) (xy 109.538537 -274.950447) (xy 109.561663 -274.902426)
			(xy 109.591687 -274.858389) (xy 109.627939 -274.819318) (xy 109.66961 -274.786087) (xy 109.715768 -274.759438)
			(xy 109.765382 -274.739966) (xy 109.817344 -274.728106) (xy 109.870494 -274.724123) (xy 109.923644 -274.728106)
			(xy 109.975606 -274.739966) (xy 110.02522 -274.759438) (xy 110.071378 -274.786087) (xy 110.113049 -274.819318)
			(xy 110.149301 -274.858389) (xy 110.179325 -274.902426) (xy 110.202451 -274.950447) (xy 110.218161 -275.001377)
			(xy 110.226104 -275.054081) (xy 110.226602 -275.08073) (xy 110.226104 -275.107379) (xy 110.218161 -275.160083)
			(xy 110.202451 -275.211013) (xy 110.179325 -275.259034) (xy 110.149301 -275.303071) (xy 110.113049 -275.342142)
			(xy 110.071378 -275.375373) (xy 110.02522 -275.402022) (xy 109.975606 -275.421494) (xy 109.923644 -275.433354)
			(xy 109.870494 -275.437338) (xy 109.817344 -275.433354) (xy 109.765382 -275.421494) (xy 109.715768 -275.402022)
			(xy 109.66961 -275.375373) (xy 109.627939 -275.342142) (xy 109.591687 -275.303071) (xy 109.561663 -275.259034)
			(xy 109.538537 -275.211013) (xy 109.522827 -275.160083) (xy 109.514884 -275.107379) (xy 109.285303 -275.107379)
			(xy 109.283319 -275.133849) (xy 109.271459 -275.185811) (xy 109.251987 -275.235425) (xy 109.225337 -275.281583)
			(xy 109.192106 -275.323253) (xy 109.153035 -275.359505) (xy 109.108998 -275.389528) (xy 109.060977 -275.412653)
			(xy 109.010046 -275.428362) (xy 108.957343 -275.436305) (xy 108.930694 -275.436838) (xy 108.905235 -275.436403)
			(xy 108.854837 -275.429142) (xy 108.80599 -275.41477) (xy 108.75969 -275.39358) (xy 108.716885 -275.366006)
			(xy 108.678448 -275.33261) (xy 108.661454 -275.313648) (xy 108.652131 -275.303529) (xy 108.629264 -275.288251)
			(xy 108.603148 -275.279631) (xy 108.575678 -275.278295) (xy 108.548849 -275.28434) (xy 108.524607 -275.297328)
			(xy 108.504712 -275.316316) (xy 108.490607 -275.339926) (xy 108.483317 -275.366444) (xy 108.482892 -275.380196)
			(xy 108.482892 -275.536914) (xy 108.524548 -275.544534) (xy 108.550144 -275.549621) (xy 108.599594 -275.566293)
			(xy 108.64608 -275.590008) (xy 108.688605 -275.620256) (xy 108.726257 -275.656389) (xy 108.758229 -275.697633)
			(xy 108.783837 -275.743103) (xy 108.80253 -275.791825) (xy 108.813909 -275.842755) (xy 108.81773 -275.8948)
			(xy 108.813909 -275.946845) (xy 108.80253 -275.997775) (xy 108.783837 -276.046497) (xy 108.758229 -276.091967)
			(xy 108.726257 -276.133211) (xy 108.688605 -276.169344) (xy 108.64608 -276.199592) (xy 108.599594 -276.223307)
			(xy 108.550144 -276.239979) (xy 108.524548 -276.245066) (xy 108.482892 -276.252686) (xy 108.482892 -276.40915)
			(xy 108.483312 -276.422907) (xy 108.490593 -276.449438) (xy 108.504696 -276.473061) (xy 108.524594 -276.492061)
			(xy 108.548843 -276.505056) (xy 108.575682 -276.511104) (xy 108.603162 -276.509766) (xy 108.629286 -276.501137)
			(xy 108.652157 -276.485846) (xy 108.661454 -276.475698) (xy 108.678699 -276.456452) (xy 108.717786 -276.42265)
			(xy 108.761347 -276.394849) (xy 108.808466 -276.373633) (xy 108.858156 -276.359446) (xy 108.883704 -276.355556)
			(xy 108.908342 -276.352254) (xy 109.080808 -276.053804) (xy 109.071156 -276.03069) (xy 109.062638 -276.009058)
			(xy 109.050646 -275.964141) (xy 109.044599 -275.918045) (xy 109.044232 -275.8948) (xy 109.04473 -275.868151)
			(xy 109.052673 -275.815447) (xy 109.068383 -275.764517) (xy 109.091509 -275.716496) (xy 109.121533 -275.672459)
			(xy 109.157785 -275.633388) (xy 109.199456 -275.600157) (xy 109.245614 -275.573508) (xy 109.295228 -275.554036)
			(xy 109.34719 -275.542176) (xy 109.40034 -275.538193) (xy 109.45349 -275.542176) (xy 109.505452 -275.554036)
			(xy 109.555066 -275.573508) (xy 109.601224 -275.600157) (xy 109.642895 -275.633388) (xy 109.679147 -275.672459)
			(xy 109.709171 -275.716496) (xy 109.732297 -275.764517) (xy 109.748007 -275.815447) (xy 109.75595 -275.868151)
			(xy 109.756448 -275.8948) (xy 109.755997 -275.920413) (xy 109.755847 -275.921449) (xy 109.984784 -275.921449)
			(xy 109.984784 -275.868151) (xy 109.992727 -275.815447) (xy 110.008437 -275.764517) (xy 110.031563 -275.716496)
			(xy 110.061587 -275.672459) (xy 110.097839 -275.633388) (xy 110.13951 -275.600157) (xy 110.185668 -275.573508)
			(xy 110.235282 -275.554036) (xy 110.287244 -275.542176) (xy 110.340394 -275.538193) (xy 110.393544 -275.542176)
			(xy 110.445506 -275.554036) (xy 110.49512 -275.573508) (xy 110.541278 -275.600157) (xy 110.582949 -275.633388)
			(xy 110.619201 -275.672459) (xy 110.649225 -275.716496) (xy 110.672351 -275.764517) (xy 110.688061 -275.815447)
			(xy 110.696004 -275.868151) (xy 110.696502 -275.8948) (xy 110.696004 -275.921449) (xy 110.688061 -275.974153)
			(xy 110.672351 -276.025083) (xy 110.649225 -276.073104) (xy 110.619201 -276.117141) (xy 110.582949 -276.156212)
			(xy 110.541278 -276.189443) (xy 110.49512 -276.216092) (xy 110.445506 -276.235564) (xy 110.393544 -276.247424)
			(xy 110.340394 -276.251408) (xy 110.287244 -276.247424) (xy 110.235282 -276.235564) (xy 110.185668 -276.216092)
			(xy 110.13951 -276.189443) (xy 110.097839 -276.156212) (xy 110.061587 -276.117141) (xy 110.031563 -276.073104)
			(xy 110.008437 -276.025083) (xy 109.992727 -275.974153) (xy 109.984784 -275.921449) (xy 109.755847 -275.921449)
			(xy 109.748647 -275.97111) (xy 109.734114 -276.020232) (xy 109.712697 -276.066767) (xy 109.684837 -276.109755)
			(xy 109.651109 -276.148311) (xy 109.612207 -276.18164) (xy 109.568933 -276.209055) (xy 109.52218 -276.229991)
			(xy 109.472911 -276.244017) (xy 109.447584 -276.24786) (xy 109.422692 -276.251162) (xy 109.250226 -276.549612)
			(xy 109.259878 -276.572726) (xy 109.268395 -276.594358) (xy 109.280383 -276.639276) (xy 109.286428 -276.685371)
			(xy 109.286802 -276.708616) (xy 109.286278 -276.735265) (xy 109.514884 -276.735265) (xy 109.514884 -276.681967)
			(xy 109.522827 -276.629263) (xy 109.538537 -276.578333) (xy 109.561663 -276.530312) (xy 109.591687 -276.486275)
			(xy 109.627939 -276.447204) (xy 109.66961 -276.413973) (xy 109.715768 -276.387324) (xy 109.765382 -276.367852)
			(xy 109.817344 -276.355992) (xy 109.870494 -276.352009) (xy 109.923644 -276.355992) (xy 109.975606 -276.367852)
			(xy 110.02522 -276.387324) (xy 110.071378 -276.413973) (xy 110.113049 -276.447204) (xy 110.149301 -276.486275)
			(xy 110.179325 -276.530312) (xy 110.202451 -276.578333) (xy 110.218161 -276.629263) (xy 110.226104 -276.681967)
			(xy 110.226602 -276.708616) (xy 110.226104 -276.735265) (xy 110.218161 -276.787969) (xy 110.202451 -276.838899)
			(xy 110.179325 -276.88692) (xy 110.149301 -276.930957) (xy 110.113049 -276.970028) (xy 110.071378 -277.003259)
			(xy 110.02522 -277.029908) (xy 109.975606 -277.04938) (xy 109.923644 -277.06124) (xy 109.870494 -277.065224)
			(xy 109.817344 -277.06124) (xy 109.765382 -277.04938) (xy 109.715768 -277.029908) (xy 109.66961 -277.003259)
			(xy 109.627939 -276.970028) (xy 109.591687 -276.930957) (xy 109.561663 -276.88692) (xy 109.538537 -276.838899)
			(xy 109.522827 -276.787969) (xy 109.514884 -276.735265) (xy 109.286278 -276.735265) (xy 109.286252 -276.736598)
			(xy 109.277495 -276.791873) (xy 109.260199 -276.845097) (xy 109.23479 -276.894961) (xy 109.201893 -276.940236)
			(xy 109.162319 -276.979808) (xy 109.117042 -277.012701) (xy 109.067177 -277.038107) (xy 109.013952 -277.0554)
			(xy 108.958676 -277.064154) (xy 108.930694 -277.064724) (xy 108.905234 -277.064289) (xy 108.854835 -277.05703)
			(xy 108.805985 -277.04266) (xy 108.759682 -277.021474) (xy 108.716872 -276.993904) (xy 108.67843 -276.960513)
			(xy 108.661454 -276.941534) (xy 108.652137 -276.931409) (xy 108.629276 -276.916119) (xy 108.603161 -276.90749)
			(xy 108.57569 -276.90615) (xy 108.548859 -276.912197) (xy 108.524618 -276.92519) (xy 108.504728 -276.944186)
			(xy 108.490635 -276.967804) (xy 108.483362 -276.994329) (xy 108.482892 -277.008082) (xy 108.482892 -277.164546)
			(xy 108.524548 -277.172166) (xy 108.552596 -277.177819) (xy 108.606541 -277.196877) (xy 108.656743 -277.224319)
			(xy 108.701909 -277.259439) (xy 108.740875 -277.301331) (xy 108.757212 -277.32482) (xy 109.104176 -277.32482)
			(xy 109.118414 -277.304249) (xy 109.151736 -277.266933) (xy 109.18995 -277.234645) (xy 109.232305 -277.208021)
			(xy 109.277968 -277.187585) (xy 109.326042 -277.173737) (xy 109.37558 -277.166751) (xy 109.400594 -277.166324)
			(xy 109.427243 -277.166797) (xy 109.479946 -277.17474) (xy 109.530876 -277.190449) (xy 109.578897 -277.213573)
			(xy 109.622934 -277.243597) (xy 109.662004 -277.279848) (xy 109.695235 -277.321518) (xy 109.721885 -277.367676)
			(xy 109.741357 -277.417289) (xy 109.753217 -277.469251) (xy 109.7572 -277.5224) (xy 109.755201 -277.549081)
			(xy 109.984784 -277.549081) (xy 109.984784 -277.495783) (xy 109.992727 -277.443079) (xy 110.008437 -277.392149)
			(xy 110.031563 -277.344128) (xy 110.061587 -277.300091) (xy 110.097839 -277.26102) (xy 110.13951 -277.227789)
			(xy 110.185668 -277.20114) (xy 110.235282 -277.181668) (xy 110.287244 -277.169808) (xy 110.340394 -277.165825)
			(xy 110.393544 -277.169808) (xy 110.445506 -277.181668) (xy 110.49512 -277.20114) (xy 110.541278 -277.227789)
			(xy 110.582949 -277.26102) (xy 110.619201 -277.300091) (xy 110.649225 -277.344128) (xy 110.672351 -277.392149)
			(xy 110.688061 -277.443079) (xy 110.696004 -277.495783) (xy 110.696502 -277.522432) (xy 110.696004 -277.549081)
			(xy 110.688061 -277.601785) (xy 110.672351 -277.652715) (xy 110.649225 -277.700736) (xy 110.619201 -277.744773)
			(xy 110.582949 -277.783844) (xy 110.541278 -277.817075) (xy 110.49512 -277.843724) (xy 110.445506 -277.863196)
			(xy 110.393544 -277.875056) (xy 110.340394 -277.87904) (xy 110.287244 -277.875056) (xy 110.235282 -277.863196)
			(xy 110.185668 -277.843724) (xy 110.13951 -277.817075) (xy 110.097839 -277.783844) (xy 110.061587 -277.744773)
			(xy 110.031563 -277.700736) (xy 110.008437 -277.652715) (xy 109.992727 -277.601785) (xy 109.984784 -277.549081)
			(xy 109.755201 -277.549081) (xy 109.753217 -277.575549) (xy 109.741357 -277.627511) (xy 109.721885 -277.677124)
			(xy 109.695235 -277.723282) (xy 109.662004 -277.764952) (xy 109.622934 -277.801203) (xy 109.578897 -277.831227)
			(xy 109.530876 -277.854351) (xy 109.479946 -277.87006) (xy 109.427243 -277.878003) (xy 109.400594 -277.87854)
			(xy 109.375581 -277.878117) (xy 109.326045 -277.871121) (xy 109.277975 -277.857267) (xy 109.232314 -277.836828)
			(xy 109.18996 -277.810205) (xy 109.151744 -277.777922) (xy 109.118418 -277.740611) (xy 109.104176 -277.720044)
			(xy 108.757212 -277.720044) (xy 108.740849 -277.743513) (xy 108.701877 -277.785395) (xy 108.656717 -277.820516)
			(xy 108.606528 -277.847974) (xy 108.552597 -277.867063) (xy 108.524548 -277.872698) (xy 108.482892 -277.880318)
			(xy 108.482892 -278.037036) (xy 108.48331 -278.050795) (xy 108.490589 -278.077329) (xy 108.504691 -278.100956)
			(xy 108.52459 -278.119958) (xy 108.548842 -278.132956) (xy 108.575683 -278.139004) (xy 108.603166 -278.137665)
			(xy 108.629292 -278.129034) (xy 108.652164 -278.11374) (xy 108.661454 -278.103584) (xy 108.678431 -278.084607)
			(xy 108.716876 -278.051223) (xy 108.759687 -278.02366) (xy 108.80599 -278.002479) (xy 108.854838 -277.988113)
			(xy 108.905235 -277.980856) (xy 108.930694 -277.980394) (xy 108.957345 -277.980867) (xy 109.010053 -277.98881)
			(xy 109.060987 -278.004521) (xy 109.109012 -278.027647) (xy 109.153052 -278.057673) (xy 109.192126 -278.093928)
			(xy 109.22536 -278.135601) (xy 109.252012 -278.181762) (xy 109.271486 -278.23138) (xy 109.283347 -278.283346)
			(xy 109.28733 -278.3365) (xy 109.285333 -278.363151) (xy 109.514884 -278.363151) (xy 109.514884 -278.309853)
			(xy 109.522827 -278.257149) (xy 109.538537 -278.206219) (xy 109.561663 -278.158198) (xy 109.591687 -278.114161)
			(xy 109.627939 -278.07509) (xy 109.66961 -278.041859) (xy 109.715768 -278.01521) (xy 109.765382 -277.995738)
			(xy 109.817344 -277.983878) (xy 109.870494 -277.979895) (xy 109.923644 -277.983878) (xy 109.975606 -277.995738)
			(xy 110.02522 -278.01521) (xy 110.071378 -278.041859) (xy 110.113049 -278.07509) (xy 110.149301 -278.114161)
			(xy 110.179325 -278.158198) (xy 110.202451 -278.206219) (xy 110.218161 -278.257149) (xy 110.226104 -278.309853)
			(xy 110.226602 -278.336502) (xy 110.226104 -278.363151) (xy 114.214138 -278.363151) (xy 114.214138 -278.309853)
			(xy 114.222081 -278.257149) (xy 114.237791 -278.206219) (xy 114.260917 -278.158198) (xy 114.290941 -278.114161)
			(xy 114.327193 -278.07509) (xy 114.368864 -278.041859) (xy 114.415022 -278.01521) (xy 114.464636 -277.995738)
			(xy 114.516598 -277.983878) (xy 114.569748 -277.979895) (xy 114.622898 -277.983878) (xy 114.67486 -277.995738)
			(xy 114.724474 -278.01521) (xy 114.770632 -278.041859) (xy 114.812303 -278.07509) (xy 114.848555 -278.114161)
			(xy 114.878579 -278.158198) (xy 114.901705 -278.206219) (xy 114.917415 -278.257149) (xy 114.925358 -278.309853)
			(xy 114.925856 -278.336502) (xy 114.925358 -278.363151) (xy 114.917415 -278.415855) (xy 114.901705 -278.466785)
			(xy 114.878579 -278.514806) (xy 114.848555 -278.558843) (xy 114.812303 -278.597914) (xy 114.770632 -278.631145)
			(xy 114.724474 -278.657794) (xy 114.67486 -278.677266) (xy 114.622898 -278.689126) (xy 114.569748 -278.69311)
			(xy 114.516598 -278.689126) (xy 114.464636 -278.677266) (xy 114.415022 -278.657794) (xy 114.368864 -278.631145)
			(xy 114.327193 -278.597914) (xy 114.290941 -278.558843) (xy 114.260917 -278.514806) (xy 114.237791 -278.466785)
			(xy 114.222081 -278.415855) (xy 114.214138 -278.363151) (xy 110.226104 -278.363151) (xy 110.218161 -278.415855)
			(xy 110.202451 -278.466785) (xy 110.179325 -278.514806) (xy 110.149301 -278.558843) (xy 110.113049 -278.597914)
			(xy 110.071378 -278.631145) (xy 110.02522 -278.657794) (xy 109.975606 -278.677266) (xy 109.923644 -278.689126)
			(xy 109.870494 -278.69311) (xy 109.817344 -278.689126) (xy 109.765382 -278.677266) (xy 109.715768 -278.657794)
			(xy 109.66961 -278.631145) (xy 109.627939 -278.597914) (xy 109.591687 -278.558843) (xy 109.561663 -278.514806)
			(xy 109.538537 -278.466785) (xy 109.522827 -278.415855) (xy 109.514884 -278.363151) (xy 109.285333 -278.363151)
			(xy 109.283347 -278.389654) (xy 109.271486 -278.44162) (xy 109.252012 -278.491238) (xy 109.22536 -278.537399)
			(xy 109.192126 -278.579072) (xy 109.153052 -278.615327) (xy 109.109012 -278.645353) (xy 109.060987 -278.668479)
			(xy 109.010053 -278.68419) (xy 108.957345 -278.692133) (xy 108.930694 -278.69261) (xy 108.905234 -278.692175)
			(xy 108.854835 -278.684915) (xy 108.805986 -278.670546) (xy 108.759684 -278.649359) (xy 108.716874 -278.621788)
			(xy 108.678433 -278.588397) (xy 108.661454 -278.56942) (xy 108.652136 -278.559296) (xy 108.629274 -278.544008)
			(xy 108.603158 -278.53538) (xy 108.575688 -278.534041) (xy 108.548857 -278.540087) (xy 108.524616 -278.55308)
			(xy 108.504726 -278.572074) (xy 108.49063 -278.595691) (xy 108.483355 -278.622215) (xy 108.482892 -278.635968)
			(xy 108.482892 -278.792432) (xy 108.524548 -278.800052) (xy 108.550117 -278.805169) (xy 108.599507 -278.82189)
			(xy 108.64593 -278.845637) (xy 108.688392 -278.875901) (xy 108.725986 -278.912036) (xy 108.757906 -278.953269)
			(xy 108.783469 -278.998716) (xy 108.80213 -279.047407) (xy 108.813488 -279.098299) (xy 108.817301 -279.150303)
			(xy 108.815345 -279.176967) (xy 114.683784 -279.176967) (xy 114.683784 -279.123669) (xy 114.691727 -279.070965)
			(xy 114.707437 -279.020035) (xy 114.730563 -278.972014) (xy 114.760587 -278.927977) (xy 114.796839 -278.888906)
			(xy 114.83851 -278.855675) (xy 114.884668 -278.829026) (xy 114.934282 -278.809554) (xy 114.986244 -278.797694)
			(xy 115.039394 -278.793711) (xy 115.092544 -278.797694) (xy 115.144506 -278.809554) (xy 115.19412 -278.829026)
			(xy 115.240278 -278.855675) (xy 115.281949 -278.888906) (xy 115.318201 -278.927977) (xy 115.348225 -278.972014)
			(xy 115.371351 -279.020035) (xy 115.387061 -279.070965) (xy 115.395004 -279.123669) (xy 115.395502 -279.150318)
			(xy 115.395004 -279.176967) (xy 115.387061 -279.229671) (xy 115.371351 -279.280601) (xy 115.348225 -279.328622)
			(xy 115.318201 -279.372659) (xy 115.281949 -279.41173) (xy 115.240278 -279.444961) (xy 115.19412 -279.47161)
			(xy 115.144506 -279.491082) (xy 115.092544 -279.502942) (xy 115.039394 -279.506926) (xy 114.986244 -279.502942)
			(xy 114.934282 -279.491082) (xy 114.884668 -279.47161) (xy 114.83851 -279.444961) (xy 114.796839 -279.41173)
			(xy 114.760587 -279.372659) (xy 114.730563 -279.328622) (xy 114.707437 -279.280601) (xy 114.691727 -279.229671)
			(xy 114.683784 -279.176967) (xy 108.815345 -279.176967) (xy 108.813487 -279.202308) (xy 108.802128 -279.253199)
			(xy 108.783466 -279.301889) (xy 108.757902 -279.347337) (xy 108.725981 -279.388568) (xy 108.688387 -279.424703)
			(xy 108.645925 -279.454967) (xy 108.599501 -279.478713) (xy 108.550111 -279.495433) (xy 108.524548 -279.500584)
			(xy 108.482892 -279.508204) (xy 108.482892 -279.954736) (xy 108.446845 -279.990783) (xy 113.274084 -279.990783)
			(xy 113.274084 -279.937485) (xy 113.282027 -279.884781) (xy 113.297737 -279.833851) (xy 113.320863 -279.78583)
			(xy 113.350887 -279.741793) (xy 113.387139 -279.702722) (xy 113.42881 -279.669491) (xy 113.474968 -279.642842)
			(xy 113.524582 -279.62337) (xy 113.576544 -279.61151) (xy 113.629694 -279.607527) (xy 113.682844 -279.61151)
			(xy 113.734806 -279.62337) (xy 113.78442 -279.642842) (xy 113.830578 -279.669491) (xy 113.872249 -279.702722)
			(xy 113.908501 -279.741793) (xy 113.938525 -279.78583) (xy 113.961651 -279.833851) (xy 113.977361 -279.884781)
			(xy 113.985304 -279.937485) (xy 113.985802 -279.964134) (xy 113.985304 -279.990783) (xy 113.977361 -280.043487)
			(xy 113.961651 -280.094417) (xy 113.938525 -280.142438) (xy 113.908501 -280.186475) (xy 113.872249 -280.225546)
			(xy 113.830578 -280.258777) (xy 113.78442 -280.285426) (xy 113.734806 -280.304898) (xy 113.682844 -280.316758)
			(xy 113.629694 -280.320742) (xy 113.576544 -280.316758) (xy 113.524582 -280.304898) (xy 113.474968 -280.285426)
			(xy 113.42881 -280.258777) (xy 113.387139 -280.225546) (xy 113.350887 -280.186475) (xy 113.320863 -280.142438)
			(xy 113.297737 -280.094417) (xy 113.282027 -280.043487) (xy 113.274084 -279.990783) (xy 108.446845 -279.990783)
			(xy 108.30433 -280.133298) (xy 108.301028 -280.139394) (xy 108.288796 -280.160217) (xy 108.259572 -280.198662)
			(xy 108.225421 -280.232808) (xy 108.186971 -280.262026) (xy 108.166154 -280.274268) (xy 108.160058 -280.27757)
			(xy 107.833668 -280.60396) (xy 107.847384 -280.63571) (xy 107.856798 -280.658272) (xy 107.870045 -280.70533)
			(xy 107.876718 -280.75376) (xy 107.877102 -280.778204) (xy 107.876606 -280.804853) (xy 109.984784 -280.804853)
			(xy 109.984784 -280.751555) (xy 109.992727 -280.698851) (xy 110.008437 -280.647921) (xy 110.031563 -280.5999)
			(xy 110.061587 -280.555863) (xy 110.097839 -280.516792) (xy 110.13951 -280.483561) (xy 110.185668 -280.456912)
			(xy 110.235282 -280.43744) (xy 110.287244 -280.42558) (xy 110.340394 -280.421597) (xy 110.393544 -280.42558)
			(xy 110.445506 -280.43744) (xy 110.49512 -280.456912) (xy 110.541278 -280.483561) (xy 110.582949 -280.516792)
			(xy 110.619201 -280.555863) (xy 110.649225 -280.5999) (xy 110.672351 -280.647921) (xy 110.688061 -280.698851)
			(xy 110.696004 -280.751555) (xy 110.696502 -280.778204) (xy 110.696004 -280.804853) (xy 110.688061 -280.857557)
			(xy 110.672351 -280.908487) (xy 110.649225 -280.956508) (xy 110.619201 -281.000545) (xy 110.582949 -281.039616)
			(xy 110.541278 -281.072847) (xy 110.49512 -281.099496) (xy 110.445506 -281.118968) (xy 110.393544 -281.130828)
			(xy 110.340394 -281.134812) (xy 110.287244 -281.130828) (xy 110.235282 -281.118968) (xy 110.185668 -281.099496)
			(xy 110.13951 -281.072847) (xy 110.097839 -281.039616) (xy 110.061587 -281.000545) (xy 110.031563 -280.956508)
			(xy 110.008437 -280.908487) (xy 109.992727 -280.857557) (xy 109.984784 -280.804853) (xy 107.876606 -280.804853)
			(xy 107.876581 -280.806189) (xy 107.867825 -280.86147) (xy 107.850529 -280.9147) (xy 107.825118 -280.964569)
			(xy 107.792219 -281.00985) (xy 107.752642 -281.049426) (xy 107.707361 -281.082323) (xy 107.657491 -281.107732)
			(xy 107.60426 -281.125027) (xy 107.548979 -281.133782) (xy 107.520994 -281.134312) (xy 107.496552 -281.133903)
			(xy 107.448129 -281.127216) (xy 107.401071 -281.11398) (xy 107.3785 -281.104594) (xy 107.34675 -281.090878)
			(xy 107.27055 -281.167078) (xy 107.26091 -281.177412) (xy 107.247224 -281.202124) (xy 107.240827 -281.229639)
			(xy 107.242207 -281.257855) (xy 107.251261 -281.284614) (xy 107.267295 -281.307871) (xy 107.277916 -281.317192)
			(xy 107.297805 -281.334206) (xy 107.332863 -281.373067) (xy 107.361862 -281.416638) (xy 107.384178 -281.46398)
			(xy 107.399331 -281.514077) (xy 107.406996 -281.565851) (xy 107.407456 -281.59202) (xy 107.406932 -281.618669)
			(xy 113.274084 -281.618669) (xy 113.274084 -281.565371) (xy 113.282027 -281.512667) (xy 113.297737 -281.461737)
			(xy 113.320863 -281.413716) (xy 113.350887 -281.369679) (xy 113.387139 -281.330608) (xy 113.42881 -281.297377)
			(xy 113.474968 -281.270728) (xy 113.524582 -281.251256) (xy 113.576544 -281.239396) (xy 113.629694 -281.235413)
			(xy 113.682844 -281.239396) (xy 113.734806 -281.251256) (xy 113.78442 -281.270728) (xy 113.830578 -281.297377)
			(xy 113.872249 -281.330608) (xy 113.908501 -281.369679) (xy 113.938525 -281.413716) (xy 113.961651 -281.461737)
			(xy 113.977361 -281.512667) (xy 113.985304 -281.565371) (xy 113.985802 -281.59202) (xy 113.985304 -281.618669)
			(xy 113.977361 -281.671373) (xy 113.961651 -281.722303) (xy 113.938525 -281.770324) (xy 113.908501 -281.814361)
			(xy 113.872249 -281.853432) (xy 113.830578 -281.886663) (xy 113.78442 -281.913312) (xy 113.734806 -281.932784)
			(xy 113.682844 -281.944644) (xy 113.629694 -281.948628) (xy 113.576544 -281.944644) (xy 113.524582 -281.932784)
			(xy 113.474968 -281.913312) (xy 113.42881 -281.886663) (xy 113.387139 -281.853432) (xy 113.350887 -281.814361)
			(xy 113.320863 -281.770324) (xy 113.297737 -281.722303) (xy 113.282027 -281.671373) (xy 113.274084 -281.618669)
			(xy 107.406932 -281.618669) (xy 107.406906 -281.620003) (xy 107.398148 -281.675281) (xy 107.380853 -281.728508)
			(xy 107.355444 -281.778375) (xy 107.322549 -281.823654) (xy 107.282976 -281.86323) (xy 107.237699 -281.89613)
			(xy 107.187834 -281.921542) (xy 107.134608 -281.938842) (xy 107.079331 -281.947603) (xy 107.051348 -281.948128)
			(xy 107.025177 -281.94767) (xy 106.973399 -281.940018) (xy 106.923297 -281.924871) (xy 106.875952 -281.902557)
			(xy 106.832381 -281.873554) (xy 106.793523 -281.838488) (xy 106.77652 -281.818588) (xy 106.767198 -281.807951)
			(xy 106.743955 -281.791855) (xy 106.717185 -281.782762) (xy 106.688947 -281.781372) (xy 106.661413 -281.787791)
			(xy 106.636701 -281.801525) (xy 106.626406 -281.811222) (xy 106.524552 -281.913076) (xy 106.603546 -282.049474)
			(xy 106.628184 -282.052776) (xy 106.653532 -282.056594) (xy 106.702852 -282.070562) (xy 106.749659 -282.091458)
			(xy 106.792986 -282.118852) (xy 106.831936 -282.152176) (xy 106.865704 -282.190742) (xy 106.893592 -282.233751)
			(xy 106.915024 -282.280316) (xy 106.929556 -282.329473) (xy 106.936888 -282.380206) (xy 106.937302 -282.405836)
			(xy 106.936776 -282.432485) (xy 107.165384 -282.432485) (xy 107.165384 -282.379187) (xy 107.173327 -282.326483)
			(xy 107.189037 -282.275553) (xy 107.212163 -282.227532) (xy 107.242187 -282.183495) (xy 107.278439 -282.144424)
			(xy 107.32011 -282.111193) (xy 107.366268 -282.084544) (xy 107.415882 -282.065072) (xy 107.467844 -282.053212)
			(xy 107.520994 -282.049229) (xy 107.574144 -282.053212) (xy 107.626106 -282.065072) (xy 107.67572 -282.084544)
			(xy 107.721878 -282.111193) (xy 107.763549 -282.144424) (xy 107.799801 -282.183495) (xy 107.829825 -282.227532)
			(xy 107.852951 -282.275553) (xy 107.868661 -282.326483) (xy 107.876604 -282.379187) (xy 107.877102 -282.405836)
			(xy 107.876604 -282.432485) (xy 109.984784 -282.432485) (xy 109.984784 -282.379187) (xy 109.992727 -282.326483)
			(xy 110.008437 -282.275553) (xy 110.031563 -282.227532) (xy 110.061587 -282.183495) (xy 110.097839 -282.144424)
			(xy 110.13951 -282.111193) (xy 110.185668 -282.084544) (xy 110.235282 -282.065072) (xy 110.287244 -282.053212)
			(xy 110.340394 -282.049229) (xy 110.393544 -282.053212) (xy 110.445506 -282.065072) (xy 110.49512 -282.084544)
			(xy 110.541278 -282.111193) (xy 110.582949 -282.144424) (xy 110.619201 -282.183495) (xy 110.649225 -282.227532)
			(xy 110.672351 -282.275553) (xy 110.688061 -282.326483) (xy 110.696004 -282.379187) (xy 110.696502 -282.405836)
			(xy 110.696004 -282.432485) (xy 110.688061 -282.485189) (xy 110.672351 -282.536119) (xy 110.649225 -282.58414)
			(xy 110.619201 -282.628177) (xy 110.582949 -282.667248) (xy 110.541278 -282.700479) (xy 110.49512 -282.727128)
			(xy 110.445506 -282.7466) (xy 110.393544 -282.75846) (xy 110.340394 -282.762444) (xy 110.287244 -282.75846)
			(xy 110.235282 -282.7466) (xy 110.185668 -282.727128) (xy 110.13951 -282.700479) (xy 110.097839 -282.667248)
			(xy 110.061587 -282.628177) (xy 110.031563 -282.58414) (xy 110.008437 -282.536119) (xy 109.992727 -282.485189)
			(xy 109.984784 -282.432485) (xy 107.876604 -282.432485) (xy 107.868661 -282.485189) (xy 107.852951 -282.536119)
			(xy 107.829825 -282.58414) (xy 107.799801 -282.628177) (xy 107.763549 -282.667248) (xy 107.721878 -282.700479)
			(xy 107.67572 -282.727128) (xy 107.626106 -282.7466) (xy 107.574144 -282.75846) (xy 107.520994 -282.762444)
			(xy 107.467844 -282.75846) (xy 107.415882 -282.7466) (xy 107.366268 -282.727128) (xy 107.32011 -282.700479)
			(xy 107.278439 -282.667248) (xy 107.242187 -282.628177) (xy 107.212163 -282.58414) (xy 107.189037 -282.536119)
			(xy 107.173327 -282.485189) (xy 107.165384 -282.432485) (xy 106.936776 -282.432485) (xy 106.93675 -282.433817)
			(xy 106.927991 -282.48909) (xy 106.910693 -282.542311) (xy 106.885283 -282.592172) (xy 106.852386 -282.637444)
			(xy 106.812812 -282.677013) (xy 106.767536 -282.709905) (xy 106.717673 -282.735309) (xy 106.664449 -282.752601)
			(xy 106.609175 -282.761354) (xy 106.581194 -282.761944) (xy 106.555133 -282.76149) (xy 106.503567 -282.753891)
			(xy 106.453659 -282.738858) (xy 106.406476 -282.716712) (xy 106.363024 -282.687924) (xy 106.324233 -282.65311)
			(xy 106.29093 -282.613014) (xy 106.263827 -282.568493) (xy 106.243503 -282.520496) (xy 106.230391 -282.470049)
			(xy 106.227118 -282.44419) (xy 106.225113 -282.430026) (xy 106.214297 -282.403556) (xy 106.19656 -282.381128)
			(xy 106.173295 -282.364504) (xy 106.14633 -282.354988) (xy 106.117784 -282.35333) (xy 106.089899 -282.35966)
			(xy 106.064866 -282.373479) (xy 106.054398 -282.38323) (xy 105.996232 -282.441396) (xy 105.993692 -282.45816)
			(xy 105.989543 -282.483077) (xy 105.975133 -282.531489) (xy 105.954027 -282.57738) (xy 105.92665 -282.619828)
			(xy 105.893549 -282.657983) (xy 105.85539 -282.691078) (xy 105.812938 -282.71845) (xy 105.767044 -282.73955)
			(xy 105.71863 -282.753954) (xy 105.693718 -282.758134) (xy 105.676954 -282.760674) (xy 105.647998 -282.78963)
			(xy 105.49128 -283.060902) (xy 105.500932 -283.084016) (xy 105.50945 -283.105648) (xy 105.521441 -283.150565)
			(xy 105.527488 -283.196661) (xy 105.527856 -283.219906) (xy 105.527333 -283.246555) (xy 105.755684 -283.246555)
			(xy 105.755684 -283.193257) (xy 105.763627 -283.140553) (xy 105.779337 -283.089623) (xy 105.802463 -283.041602)
			(xy 105.832487 -282.997565) (xy 105.868739 -282.958494) (xy 105.91041 -282.925263) (xy 105.956568 -282.898614)
			(xy 106.006182 -282.879142) (xy 106.058144 -282.867282) (xy 106.111294 -282.863299) (xy 106.164444 -282.867282)
			(xy 106.216406 -282.879142) (xy 106.26602 -282.898614) (xy 106.312178 -282.925263) (xy 106.353849 -282.958494)
			(xy 106.390101 -282.997565) (xy 106.420125 -283.041602) (xy 106.443251 -283.089623) (xy 106.458961 -283.140553)
			(xy 106.466904 -283.193257) (xy 106.467402 -283.219906) (xy 106.466904 -283.246555) (xy 106.695738 -283.246555)
			(xy 106.695738 -283.193257) (xy 106.703681 -283.140553) (xy 106.719391 -283.089623) (xy 106.742517 -283.041602)
			(xy 106.772541 -282.997565) (xy 106.808793 -282.958494) (xy 106.850464 -282.925263) (xy 106.896622 -282.898614)
			(xy 106.946236 -282.879142) (xy 106.998198 -282.867282) (xy 107.051348 -282.863299) (xy 107.104498 -282.867282)
			(xy 107.15646 -282.879142) (xy 107.206074 -282.898614) (xy 107.252232 -282.925263) (xy 107.293903 -282.958494)
			(xy 107.330155 -282.997565) (xy 107.360179 -283.041602) (xy 107.383305 -283.089623) (xy 107.399015 -283.140553)
			(xy 107.406958 -283.193257) (xy 107.407456 -283.219906) (xy 107.406958 -283.246555) (xy 113.274084 -283.246555)
			(xy 113.274084 -283.193257) (xy 113.282027 -283.140553) (xy 113.297737 -283.089623) (xy 113.320863 -283.041602)
			(xy 113.350887 -282.997565) (xy 113.387139 -282.958494) (xy 113.42881 -282.925263) (xy 113.474968 -282.898614)
			(xy 113.524582 -282.879142) (xy 113.576544 -282.867282) (xy 113.629694 -282.863299) (xy 113.682844 -282.867282)
			(xy 113.734806 -282.879142) (xy 113.78442 -282.898614) (xy 113.830578 -282.925263) (xy 113.872249 -282.958494)
			(xy 113.908501 -282.997565) (xy 113.938525 -283.041602) (xy 113.961651 -283.089623) (xy 113.977361 -283.140553)
			(xy 113.985304 -283.193257) (xy 113.985802 -283.219906) (xy 113.985304 -283.246555) (xy 116.093738 -283.246555)
			(xy 116.093738 -283.193257) (xy 116.101681 -283.140553) (xy 116.117391 -283.089623) (xy 116.140517 -283.041602)
			(xy 116.170541 -282.997565) (xy 116.206793 -282.958494) (xy 116.248464 -282.925263) (xy 116.294622 -282.898614)
			(xy 116.344236 -282.879142) (xy 116.396198 -282.867282) (xy 116.449348 -282.863299) (xy 116.502498 -282.867282)
			(xy 116.55446 -282.879142) (xy 116.604074 -282.898614) (xy 116.650232 -282.925263) (xy 116.691903 -282.958494)
			(xy 116.728155 -282.997565) (xy 116.758179 -283.041602) (xy 116.781305 -283.089623) (xy 116.797015 -283.140553)
			(xy 116.804958 -283.193257) (xy 116.805456 -283.219906) (xy 116.804958 -283.246555) (xy 116.797015 -283.299259)
			(xy 116.781305 -283.350189) (xy 116.758179 -283.39821) (xy 116.728155 -283.442247) (xy 116.691903 -283.481318)
			(xy 116.650232 -283.514549) (xy 116.604074 -283.541198) (xy 116.55446 -283.56067) (xy 116.502498 -283.57253)
			(xy 116.449348 -283.576514) (xy 116.396198 -283.57253) (xy 116.344236 -283.56067) (xy 116.294622 -283.541198)
			(xy 116.248464 -283.514549) (xy 116.206793 -283.481318) (xy 116.170541 -283.442247) (xy 116.140517 -283.39821)
			(xy 116.117391 -283.350189) (xy 116.101681 -283.299259) (xy 116.093738 -283.246555) (xy 113.985304 -283.246555)
			(xy 113.977361 -283.299259) (xy 113.961651 -283.350189) (xy 113.938525 -283.39821) (xy 113.908501 -283.442247)
			(xy 113.872249 -283.481318) (xy 113.830578 -283.514549) (xy 113.78442 -283.541198) (xy 113.734806 -283.56067)
			(xy 113.682844 -283.57253) (xy 113.629694 -283.576514) (xy 113.576544 -283.57253) (xy 113.524582 -283.56067)
			(xy 113.474968 -283.541198) (xy 113.42881 -283.514549) (xy 113.387139 -283.481318) (xy 113.350887 -283.442247)
			(xy 113.320863 -283.39821) (xy 113.297737 -283.350189) (xy 113.282027 -283.299259) (xy 113.274084 -283.246555)
			(xy 107.406958 -283.246555) (xy 107.399015 -283.299259) (xy 107.383305 -283.350189) (xy 107.360179 -283.39821)
			(xy 107.330155 -283.442247) (xy 107.293903 -283.481318) (xy 107.252232 -283.514549) (xy 107.206074 -283.541198)
			(xy 107.15646 -283.56067) (xy 107.104498 -283.57253) (xy 107.051348 -283.576514) (xy 106.998198 -283.57253)
			(xy 106.946236 -283.56067) (xy 106.896622 -283.541198) (xy 106.850464 -283.514549) (xy 106.808793 -283.481318)
			(xy 106.772541 -283.442247) (xy 106.742517 -283.39821) (xy 106.719391 -283.350189) (xy 106.703681 -283.299259)
			(xy 106.695738 -283.246555) (xy 106.466904 -283.246555) (xy 106.458961 -283.299259) (xy 106.443251 -283.350189)
			(xy 106.420125 -283.39821) (xy 106.390101 -283.442247) (xy 106.353849 -283.481318) (xy 106.312178 -283.514549)
			(xy 106.26602 -283.541198) (xy 106.216406 -283.56067) (xy 106.164444 -283.57253) (xy 106.111294 -283.576514)
			(xy 106.058144 -283.57253) (xy 106.006182 -283.56067) (xy 105.956568 -283.541198) (xy 105.91041 -283.514549)
			(xy 105.868739 -283.481318) (xy 105.832487 -283.442247) (xy 105.802463 -283.39821) (xy 105.779337 -283.350189)
			(xy 105.763627 -283.299259) (xy 105.755684 -283.246555) (xy 105.527333 -283.246555) (xy 105.527307 -283.24789)
			(xy 105.518551 -283.303169) (xy 105.501257 -283.356399) (xy 105.475849 -283.406268) (xy 105.442954 -283.451548)
			(xy 105.40338 -283.491126) (xy 105.358103 -283.524027) (xy 105.308238 -283.549441) (xy 105.25501 -283.566741)
			(xy 105.199732 -283.575503) (xy 105.171748 -283.576014) (xy 105.145963 -283.575539) (xy 105.094936 -283.568069)
			(xy 105.04552 -283.55332) (xy 104.998746 -283.531601) (xy 104.97693 -283.517848) (xy 104.942386 -283.495242)
			(xy 104.867202 -283.570426) (xy 104.856694 -283.581658) (xy 104.842374 -283.608862) (xy 104.836797 -283.639095)
			(xy 104.840467 -283.669618) (xy 104.853053 -283.697667) (xy 104.873414 -283.720702) (xy 104.886252 -283.729176)
			(xy 104.908339 -283.743102) (xy 104.948555 -283.776401) (xy 104.983476 -283.815217) (xy 105.012353 -283.858718)
			(xy 105.034566 -283.90597) (xy 105.049638 -283.95596) (xy 105.057247 -284.007615) (xy 105.057702 -284.033722)
			(xy 105.05722 -284.060371) (xy 105.285784 -284.060371) (xy 105.285784 -284.007073) (xy 105.293727 -283.954369)
			(xy 105.309437 -283.903439) (xy 105.332563 -283.855418) (xy 105.362587 -283.811381) (xy 105.398839 -283.77231)
			(xy 105.44051 -283.739079) (xy 105.486668 -283.71243) (xy 105.536282 -283.692958) (xy 105.588244 -283.681098)
			(xy 105.641394 -283.677115) (xy 105.694544 -283.681098) (xy 105.746506 -283.692958) (xy 105.79612 -283.71243)
			(xy 105.842278 -283.739079) (xy 105.883949 -283.77231) (xy 105.920201 -283.811381) (xy 105.950225 -283.855418)
			(xy 105.973351 -283.903439) (xy 105.989061 -283.954369) (xy 105.997004 -284.007073) (xy 105.997502 -284.033722)
			(xy 105.997004 -284.060371) (xy 107.165384 -284.060371) (xy 107.165384 -284.007073) (xy 107.173327 -283.954369)
			(xy 107.189037 -283.903439) (xy 107.212163 -283.855418) (xy 107.242187 -283.811381) (xy 107.278439 -283.77231)
			(xy 107.32011 -283.739079) (xy 107.366268 -283.71243) (xy 107.415882 -283.692958) (xy 107.467844 -283.681098)
			(xy 107.520994 -283.677115) (xy 107.574144 -283.681098) (xy 107.626106 -283.692958) (xy 107.67572 -283.71243)
			(xy 107.721878 -283.739079) (xy 107.763549 -283.77231) (xy 107.799801 -283.811381) (xy 107.829825 -283.855418)
			(xy 107.852951 -283.903439) (xy 107.868661 -283.954369) (xy 107.876604 -284.007073) (xy 107.877102 -284.033722)
			(xy 107.876604 -284.060371) (xy 109.984784 -284.060371) (xy 109.984784 -284.007073) (xy 109.992727 -283.954369)
			(xy 110.008437 -283.903439) (xy 110.031563 -283.855418) (xy 110.061587 -283.811381) (xy 110.097839 -283.77231)
			(xy 110.13951 -283.739079) (xy 110.185668 -283.71243) (xy 110.235282 -283.692958) (xy 110.287244 -283.681098)
			(xy 110.340394 -283.677115) (xy 110.393544 -283.681098) (xy 110.445506 -283.692958) (xy 110.49512 -283.71243)
			(xy 110.541278 -283.739079) (xy 110.582949 -283.77231) (xy 110.619201 -283.811381) (xy 110.649225 -283.855418)
			(xy 110.672351 -283.903439) (xy 110.688061 -283.954369) (xy 110.696004 -284.007073) (xy 110.696502 -284.033722)
			(xy 110.696004 -284.060371) (xy 110.688061 -284.113075) (xy 110.672351 -284.164005) (xy 110.649225 -284.212026)
			(xy 110.619201 -284.256063) (xy 110.582949 -284.295134) (xy 110.541278 -284.328365) (xy 110.49512 -284.355014)
			(xy 110.445506 -284.374486) (xy 110.393544 -284.386346) (xy 110.340394 -284.39033) (xy 110.287244 -284.386346)
			(xy 110.235282 -284.374486) (xy 110.185668 -284.355014) (xy 110.13951 -284.328365) (xy 110.097839 -284.295134)
			(xy 110.061587 -284.256063) (xy 110.031563 -284.212026) (xy 110.008437 -284.164005) (xy 109.992727 -284.113075)
			(xy 109.984784 -284.060371) (xy 107.876604 -284.060371) (xy 107.868661 -284.113075) (xy 107.852951 -284.164005)
			(xy 107.829825 -284.212026) (xy 107.799801 -284.256063) (xy 107.763549 -284.295134) (xy 107.721878 -284.328365)
			(xy 107.67572 -284.355014) (xy 107.626106 -284.374486) (xy 107.574144 -284.386346) (xy 107.520994 -284.39033)
			(xy 107.467844 -284.386346) (xy 107.415882 -284.374486) (xy 107.366268 -284.355014) (xy 107.32011 -284.328365)
			(xy 107.278439 -284.295134) (xy 107.242187 -284.256063) (xy 107.212163 -284.212026) (xy 107.189037 -284.164005)
			(xy 107.173327 -284.113075) (xy 107.165384 -284.060371) (xy 105.997004 -284.060371) (xy 105.989061 -284.113075)
			(xy 105.973351 -284.164005) (xy 105.950225 -284.212026) (xy 105.920201 -284.256063) (xy 105.883949 -284.295134)
			(xy 105.842278 -284.328365) (xy 105.79612 -284.355014) (xy 105.746506 -284.374486) (xy 105.694544 -284.386346)
			(xy 105.641394 -284.39033) (xy 105.588244 -284.386346) (xy 105.536282 -284.374486) (xy 105.486668 -284.355014)
			(xy 105.44051 -284.328365) (xy 105.398839 -284.295134) (xy 105.362587 -284.256063) (xy 105.332563 -284.212026)
			(xy 105.309437 -284.164005) (xy 105.293727 -284.113075) (xy 105.285784 -284.060371) (xy 105.05722 -284.060371)
			(xy 105.057215 -284.060623) (xy 105.049129 -284.113812) (xy 105.033129 -284.165179) (xy 105.009579 -284.213553)
			(xy 104.979017 -284.25783) (xy 104.942139 -284.297004) (xy 104.899785 -284.33018) (xy 104.85292 -284.356603)
			(xy 104.802611 -284.375672) (xy 104.750006 -284.386951) (xy 104.723184 -284.389068) (xy 104.70784 -284.390528)
			(xy 104.679037 -284.401457) (xy 104.654797 -284.42047) (xy 104.637319 -284.44584) (xy 104.628192 -284.475264)
			(xy 104.62768 -284.490668) (xy 104.62768 -284.874187) (xy 104.815884 -284.874187) (xy 104.815884 -284.820889)
			(xy 104.823827 -284.768185) (xy 104.839537 -284.717255) (xy 104.862663 -284.669234) (xy 104.892687 -284.625197)
			(xy 104.928939 -284.586126) (xy 104.97061 -284.552895) (xy 105.016768 -284.526246) (xy 105.066382 -284.506774)
			(xy 105.118344 -284.494914) (xy 105.171494 -284.490931) (xy 105.224644 -284.494914) (xy 105.276606 -284.506774)
			(xy 105.32622 -284.526246) (xy 105.372378 -284.552895) (xy 105.414049 -284.586126) (xy 105.450301 -284.625197)
			(xy 105.480325 -284.669234) (xy 105.503451 -284.717255) (xy 105.519161 -284.768185) (xy 105.527104 -284.820889)
			(xy 105.527602 -284.847538) (xy 105.527104 -284.874187) (xy 113.274084 -284.874187) (xy 113.274084 -284.820889)
			(xy 113.282027 -284.768185) (xy 113.297737 -284.717255) (xy 113.320863 -284.669234) (xy 113.350887 -284.625197)
			(xy 113.387139 -284.586126) (xy 113.42881 -284.552895) (xy 113.474968 -284.526246) (xy 113.524582 -284.506774)
			(xy 113.576544 -284.494914) (xy 113.629694 -284.490931) (xy 113.682844 -284.494914) (xy 113.734806 -284.506774)
			(xy 113.78442 -284.526246) (xy 113.830578 -284.552895) (xy 113.872249 -284.586126) (xy 113.908501 -284.625197)
			(xy 113.938525 -284.669234) (xy 113.961651 -284.717255) (xy 113.977361 -284.768185) (xy 113.985304 -284.820889)
			(xy 113.985802 -284.847538) (xy 113.985304 -284.874187) (xy 116.093738 -284.874187) (xy 116.093738 -284.820889)
			(xy 116.101681 -284.768185) (xy 116.117391 -284.717255) (xy 116.140517 -284.669234) (xy 116.170541 -284.625197)
			(xy 116.206793 -284.586126) (xy 116.248464 -284.552895) (xy 116.294622 -284.526246) (xy 116.344236 -284.506774)
			(xy 116.396198 -284.494914) (xy 116.449348 -284.490931) (xy 116.502498 -284.494914) (xy 116.55446 -284.506774)
			(xy 116.604074 -284.526246) (xy 116.650232 -284.552895) (xy 116.691903 -284.586126) (xy 116.728155 -284.625197)
			(xy 116.758179 -284.669234) (xy 116.781305 -284.717255) (xy 116.797015 -284.768185) (xy 116.804958 -284.820889)
			(xy 116.805456 -284.847538) (xy 116.804958 -284.874187) (xy 117.973338 -284.874187) (xy 117.973338 -284.820889)
			(xy 117.981281 -284.768185) (xy 117.996991 -284.717255) (xy 118.020117 -284.669234) (xy 118.050141 -284.625197)
			(xy 118.086393 -284.586126) (xy 118.128064 -284.552895) (xy 118.174222 -284.526246) (xy 118.223836 -284.506774)
			(xy 118.275798 -284.494914) (xy 118.328948 -284.490931) (xy 118.382098 -284.494914) (xy 118.43406 -284.506774)
			(xy 118.483674 -284.526246) (xy 118.529832 -284.552895) (xy 118.571503 -284.586126) (xy 118.607755 -284.625197)
			(xy 118.637779 -284.669234) (xy 118.660905 -284.717255) (xy 118.676615 -284.768185) (xy 118.684558 -284.820889)
			(xy 118.685056 -284.847538) (xy 118.684558 -284.874187) (xy 118.676615 -284.926891) (xy 118.660905 -284.977821)
			(xy 118.637779 -285.025842) (xy 118.607755 -285.069879) (xy 118.571503 -285.10895) (xy 118.529832 -285.142181)
			(xy 118.483674 -285.16883) (xy 118.43406 -285.188302) (xy 118.382098 -285.200162) (xy 118.328948 -285.204146)
			(xy 118.275798 -285.200162) (xy 118.223836 -285.188302) (xy 118.174222 -285.16883) (xy 118.128064 -285.142181)
			(xy 118.086393 -285.10895) (xy 118.050141 -285.069879) (xy 118.020117 -285.025842) (xy 117.996991 -284.977821)
			(xy 117.981281 -284.926891) (xy 117.973338 -284.874187) (xy 116.804958 -284.874187) (xy 116.797015 -284.926891)
			(xy 116.781305 -284.977821) (xy 116.758179 -285.025842) (xy 116.728155 -285.069879) (xy 116.691903 -285.10895)
			(xy 116.650232 -285.142181) (xy 116.604074 -285.16883) (xy 116.55446 -285.188302) (xy 116.502498 -285.200162)
			(xy 116.449348 -285.204146) (xy 116.396198 -285.200162) (xy 116.344236 -285.188302) (xy 116.294622 -285.16883)
			(xy 116.248464 -285.142181) (xy 116.206793 -285.10895) (xy 116.170541 -285.069879) (xy 116.140517 -285.025842)
			(xy 116.117391 -284.977821) (xy 116.101681 -284.926891) (xy 116.093738 -284.874187) (xy 113.985304 -284.874187)
			(xy 113.977361 -284.926891) (xy 113.961651 -284.977821) (xy 113.938525 -285.025842) (xy 113.908501 -285.069879)
			(xy 113.872249 -285.10895) (xy 113.830578 -285.142181) (xy 113.78442 -285.16883) (xy 113.734806 -285.188302)
			(xy 113.682844 -285.200162) (xy 113.629694 -285.204146) (xy 113.576544 -285.200162) (xy 113.524582 -285.188302)
			(xy 113.474968 -285.16883) (xy 113.42881 -285.142181) (xy 113.387139 -285.10895) (xy 113.350887 -285.069879)
			(xy 113.320863 -285.025842) (xy 113.297737 -284.977821) (xy 113.282027 -284.926891) (xy 113.274084 -284.874187)
			(xy 105.527104 -284.874187) (xy 105.519161 -284.926891) (xy 105.503451 -284.977821) (xy 105.480325 -285.025842)
			(xy 105.450301 -285.069879) (xy 105.414049 -285.10895) (xy 105.372378 -285.142181) (xy 105.32622 -285.16883)
			(xy 105.276606 -285.188302) (xy 105.224644 -285.200162) (xy 105.171494 -285.204146) (xy 105.118344 -285.200162)
			(xy 105.066382 -285.188302) (xy 105.016768 -285.16883) (xy 104.97061 -285.142181) (xy 104.928939 -285.10895)
			(xy 104.892687 -285.069879) (xy 104.862663 -285.025842) (xy 104.839537 -284.977821) (xy 104.823827 -284.926891)
			(xy 104.815884 -284.874187) (xy 104.62768 -284.874187) (xy 104.62768 -285.204408) (xy 104.628173 -285.219815)
			(xy 104.637284 -285.249248) (xy 104.654764 -285.27462) (xy 104.679019 -285.293619) (xy 104.70784 -285.304513)
			(xy 104.723184 -285.306008) (xy 104.750003 -285.30813) (xy 104.802598 -285.319432) (xy 104.852894 -285.338518)
			(xy 104.899746 -285.364953) (xy 104.942089 -285.398136) (xy 104.978957 -285.437311) (xy 105.009512 -285.481587)
			(xy 105.033059 -285.529955) (xy 105.049061 -285.581316) (xy 105.057155 -285.634499) (xy 105.057155 -285.688003)
			(xy 107.165384 -285.688003) (xy 107.165384 -285.634705) (xy 107.173327 -285.582001) (xy 107.189037 -285.531071)
			(xy 107.212163 -285.48305) (xy 107.242187 -285.439013) (xy 107.278439 -285.399942) (xy 107.32011 -285.366711)
			(xy 107.366268 -285.340062) (xy 107.415882 -285.32059) (xy 107.467844 -285.30873) (xy 107.520994 -285.304747)
			(xy 107.574144 -285.30873) (xy 107.626106 -285.32059) (xy 107.67572 -285.340062) (xy 107.721878 -285.366711)
			(xy 107.763549 -285.399942) (xy 107.799801 -285.439013) (xy 107.829825 -285.48305) (xy 107.852951 -285.531071)
			(xy 107.868661 -285.582001) (xy 107.876604 -285.634705) (xy 107.877102 -285.661354) (xy 107.876604 -285.688003)
			(xy 109.984784 -285.688003) (xy 109.984784 -285.634705) (xy 109.992727 -285.582001) (xy 110.008437 -285.531071)
			(xy 110.031563 -285.48305) (xy 110.061587 -285.439013) (xy 110.097839 -285.399942) (xy 110.13951 -285.366711)
			(xy 110.185668 -285.340062) (xy 110.235282 -285.32059) (xy 110.287244 -285.30873) (xy 110.340394 -285.304747)
			(xy 110.393544 -285.30873) (xy 110.445506 -285.32059) (xy 110.49512 -285.340062) (xy 110.541278 -285.366711)
			(xy 110.582949 -285.399942) (xy 110.619201 -285.439013) (xy 110.649225 -285.48305) (xy 110.672351 -285.531071)
			(xy 110.688061 -285.582001) (xy 110.696004 -285.634705) (xy 110.696502 -285.661354) (xy 110.696004 -285.688003)
			(xy 118.443238 -285.688003) (xy 118.443238 -285.634705) (xy 118.451181 -285.582001) (xy 118.466891 -285.531071)
			(xy 118.490017 -285.48305) (xy 118.520041 -285.439013) (xy 118.556293 -285.399942) (xy 118.597964 -285.366711)
			(xy 118.644122 -285.340062) (xy 118.693736 -285.32059) (xy 118.745698 -285.30873) (xy 118.798848 -285.304747)
			(xy 118.851998 -285.30873) (xy 118.90396 -285.32059) (xy 118.953574 -285.340062) (xy 118.999732 -285.366711)
			(xy 119.041403 -285.399942) (xy 119.077655 -285.439013) (xy 119.107679 -285.48305) (xy 119.130805 -285.531071)
			(xy 119.146515 -285.582001) (xy 119.154458 -285.634705) (xy 119.154956 -285.661354) (xy 119.154458 -285.688003)
			(xy 119.146515 -285.740707) (xy 119.130805 -285.791637) (xy 119.107679 -285.839658) (xy 119.077655 -285.883695)
			(xy 119.041403 -285.922766) (xy 118.999732 -285.955997) (xy 118.953574 -285.982646) (xy 118.90396 -286.002118)
			(xy 118.851998 -286.013978) (xy 118.798848 -286.017962) (xy 118.745698 -286.013978) (xy 118.693736 -286.002118)
			(xy 118.644122 -285.982646) (xy 118.597964 -285.955997) (xy 118.556293 -285.922766) (xy 118.520041 -285.883695)
			(xy 118.490017 -285.839658) (xy 118.466891 -285.791637) (xy 118.451181 -285.740707) (xy 118.443238 -285.688003)
			(xy 110.696004 -285.688003) (xy 110.688061 -285.740707) (xy 110.672351 -285.791637) (xy 110.649225 -285.839658)
			(xy 110.619201 -285.883695) (xy 110.582949 -285.922766) (xy 110.541278 -285.955997) (xy 110.49512 -285.982646)
			(xy 110.445506 -286.002118) (xy 110.393544 -286.013978) (xy 110.340394 -286.017962) (xy 110.287244 -286.013978)
			(xy 110.235282 -286.002118) (xy 110.185668 -285.982646) (xy 110.13951 -285.955997) (xy 110.097839 -285.922766)
			(xy 110.061587 -285.883695) (xy 110.031563 -285.839658) (xy 110.008437 -285.791637) (xy 109.992727 -285.740707)
			(xy 109.984784 -285.688003) (xy 107.876604 -285.688003) (xy 107.868661 -285.740707) (xy 107.852951 -285.791637)
			(xy 107.829825 -285.839658) (xy 107.799801 -285.883695) (xy 107.763549 -285.922766) (xy 107.721878 -285.955997)
			(xy 107.67572 -285.982646) (xy 107.626106 -286.002118) (xy 107.574144 -286.013978) (xy 107.520994 -286.017962)
			(xy 107.467844 -286.013978) (xy 107.415882 -286.002118) (xy 107.366268 -285.982646) (xy 107.32011 -285.955997)
			(xy 107.278439 -285.922766) (xy 107.242187 -285.883695) (xy 107.212163 -285.839658) (xy 107.189037 -285.791637)
			(xy 107.173327 -285.740707) (xy 107.165384 -285.688003) (xy 105.057155 -285.688003) (xy 105.057155 -285.688295)
			(xy 105.049062 -285.741479) (xy 105.033061 -285.792839) (xy 105.009515 -285.841208) (xy 104.97896 -285.885485)
			(xy 104.942093 -285.92466) (xy 104.899751 -285.957844) (xy 104.852899 -285.98428) (xy 104.802603 -286.003367)
			(xy 104.750008 -286.01467) (xy 104.723184 -286.0167) (xy 104.707836 -286.018158) (xy 104.679024 -286.029086)
			(xy 104.654772 -286.048096) (xy 104.637279 -286.073465) (xy 104.628134 -286.102892) (xy 104.62768 -286.1183)
			(xy 104.62768 -286.502073) (xy 104.816138 -286.502073) (xy 104.816138 -286.448775) (xy 104.824081 -286.396071)
			(xy 104.839791 -286.345141) (xy 104.862917 -286.29712) (xy 104.892941 -286.253083) (xy 104.929193 -286.214012)
			(xy 104.970864 -286.180781) (xy 105.017022 -286.154132) (xy 105.066636 -286.13466) (xy 105.118598 -286.1228)
			(xy 105.171748 -286.118817) (xy 105.224898 -286.1228) (xy 105.27686 -286.13466) (xy 105.326474 -286.154132)
			(xy 105.372632 -286.180781) (xy 105.414303 -286.214012) (xy 105.450555 -286.253083) (xy 105.480579 -286.29712)
			(xy 105.503705 -286.345141) (xy 105.519415 -286.396071) (xy 105.527358 -286.448775) (xy 105.527856 -286.475424)
			(xy 105.527358 -286.502073) (xy 113.274084 -286.502073) (xy 113.274084 -286.448775) (xy 113.282027 -286.396071)
			(xy 113.297737 -286.345141) (xy 113.320863 -286.29712) (xy 113.350887 -286.253083) (xy 113.387139 -286.214012)
			(xy 113.42881 -286.180781) (xy 113.474968 -286.154132) (xy 113.524582 -286.13466) (xy 113.576544 -286.1228)
			(xy 113.629694 -286.118817) (xy 113.682844 -286.1228) (xy 113.734806 -286.13466) (xy 113.78442 -286.154132)
			(xy 113.830578 -286.180781) (xy 113.872249 -286.214012) (xy 113.908501 -286.253083) (xy 113.938525 -286.29712)
			(xy 113.961651 -286.345141) (xy 113.977361 -286.396071) (xy 113.985304 -286.448775) (xy 113.985802 -286.475424)
			(xy 113.985304 -286.502073) (xy 116.093738 -286.502073) (xy 116.093738 -286.448775) (xy 116.101681 -286.396071)
			(xy 116.117391 -286.345141) (xy 116.140517 -286.29712) (xy 116.170541 -286.253083) (xy 116.206793 -286.214012)
			(xy 116.248464 -286.180781) (xy 116.294622 -286.154132) (xy 116.344236 -286.13466) (xy 116.396198 -286.1228)
			(xy 116.449348 -286.118817) (xy 116.502498 -286.1228) (xy 116.55446 -286.13466) (xy 116.604074 -286.154132)
			(xy 116.650232 -286.180781) (xy 116.691903 -286.214012) (xy 116.728155 -286.253083) (xy 116.758179 -286.29712)
			(xy 116.781305 -286.345141) (xy 116.797015 -286.396071) (xy 116.804958 -286.448775) (xy 116.805456 -286.475424)
			(xy 116.804958 -286.502073) (xy 116.797015 -286.554777) (xy 116.781305 -286.605707) (xy 116.758179 -286.653728)
			(xy 116.728155 -286.697765) (xy 116.691903 -286.736836) (xy 116.650232 -286.770067) (xy 116.604074 -286.796716)
			(xy 116.55446 -286.816188) (xy 116.502498 -286.828048) (xy 116.449348 -286.832032) (xy 116.396198 -286.828048)
			(xy 116.344236 -286.816188) (xy 116.294622 -286.796716) (xy 116.248464 -286.770067) (xy 116.206793 -286.736836)
			(xy 116.170541 -286.697765) (xy 116.140517 -286.653728) (xy 116.117391 -286.605707) (xy 116.101681 -286.554777)
			(xy 116.093738 -286.502073) (xy 113.985304 -286.502073) (xy 113.977361 -286.554777) (xy 113.961651 -286.605707)
			(xy 113.938525 -286.653728) (xy 113.908501 -286.697765) (xy 113.872249 -286.736836) (xy 113.830578 -286.770067)
			(xy 113.78442 -286.796716) (xy 113.734806 -286.816188) (xy 113.682844 -286.828048) (xy 113.629694 -286.832032)
			(xy 113.576544 -286.828048) (xy 113.524582 -286.816188) (xy 113.474968 -286.796716) (xy 113.42881 -286.770067)
			(xy 113.387139 -286.736836) (xy 113.350887 -286.697765) (xy 113.320863 -286.653728) (xy 113.297737 -286.605707)
			(xy 113.282027 -286.554777) (xy 113.274084 -286.502073) (xy 105.527358 -286.502073) (xy 105.519415 -286.554777)
			(xy 105.503705 -286.605707) (xy 105.480579 -286.653728) (xy 105.450555 -286.697765) (xy 105.414303 -286.736836)
			(xy 105.372632 -286.770067) (xy 105.326474 -286.796716) (xy 105.27686 -286.816188) (xy 105.224898 -286.828048)
			(xy 105.171748 -286.832032) (xy 105.118598 -286.828048) (xy 105.066636 -286.816188) (xy 105.017022 -286.796716)
			(xy 104.970864 -286.770067) (xy 104.929193 -286.736836) (xy 104.892941 -286.697765) (xy 104.862917 -286.653728)
			(xy 104.839791 -286.605707) (xy 104.824081 -286.554777) (xy 104.816138 -286.502073) (xy 104.62768 -286.502073)
			(xy 104.62768 -286.832294) (xy 104.628171 -286.847702) (xy 104.637279 -286.877139) (xy 104.654759 -286.902515)
			(xy 104.679015 -286.921517) (xy 104.707838 -286.932413) (xy 104.723184 -286.933894) (xy 104.750021 -286.935981)
			(xy 104.802662 -286.947225) (xy 104.85301 -286.966266) (xy 104.899916 -286.992672) (xy 104.942311 -287.02584)
			(xy 104.979228 -287.065013) (xy 105.009826 -287.109299) (xy 105.033407 -287.157687) (xy 105.049432 -287.209074)
			(xy 105.057537 -287.262288) (xy 105.057537 -287.315889) (xy 107.165384 -287.315889) (xy 107.165384 -287.262591)
			(xy 107.173327 -287.209887) (xy 107.189037 -287.158957) (xy 107.212163 -287.110936) (xy 107.242187 -287.066899)
			(xy 107.278439 -287.027828) (xy 107.32011 -286.994597) (xy 107.366268 -286.967948) (xy 107.415882 -286.948476)
			(xy 107.467844 -286.936616) (xy 107.520994 -286.932633) (xy 107.574144 -286.936616) (xy 107.626106 -286.948476)
			(xy 107.67572 -286.967948) (xy 107.721878 -286.994597) (xy 107.763549 -287.027828) (xy 107.799801 -287.066899)
			(xy 107.829825 -287.110936) (xy 107.852951 -287.158957) (xy 107.868661 -287.209887) (xy 107.876604 -287.262591)
			(xy 107.877102 -287.28924) (xy 107.876604 -287.315889) (xy 109.984784 -287.315889) (xy 109.984784 -287.262591)
			(xy 109.992727 -287.209887) (xy 110.008437 -287.158957) (xy 110.031563 -287.110936) (xy 110.061587 -287.066899)
			(xy 110.097839 -287.027828) (xy 110.13951 -286.994597) (xy 110.185668 -286.967948) (xy 110.235282 -286.948476)
			(xy 110.287244 -286.936616) (xy 110.340394 -286.932633) (xy 110.393544 -286.936616) (xy 110.445506 -286.948476)
			(xy 110.49512 -286.967948) (xy 110.541278 -286.994597) (xy 110.582949 -287.027828) (xy 110.619201 -287.066899)
			(xy 110.649225 -287.110936) (xy 110.672351 -287.158957) (xy 110.688061 -287.209887) (xy 110.696004 -287.262591)
			(xy 110.696502 -287.28924) (xy 110.696004 -287.315889) (xy 110.688061 -287.368593) (xy 110.672351 -287.419523)
			(xy 110.649225 -287.467544) (xy 110.619201 -287.511581) (xy 110.582949 -287.550652) (xy 110.541278 -287.583883)
			(xy 110.49512 -287.610532) (xy 110.445506 -287.630004) (xy 110.393544 -287.641864) (xy 110.340394 -287.645848)
			(xy 110.287244 -287.641864) (xy 110.235282 -287.630004) (xy 110.185668 -287.610532) (xy 110.13951 -287.583883)
			(xy 110.097839 -287.550652) (xy 110.061587 -287.511581) (xy 110.031563 -287.467544) (xy 110.008437 -287.419523)
			(xy 109.992727 -287.368593) (xy 109.984784 -287.315889) (xy 107.876604 -287.315889) (xy 107.868661 -287.368593)
			(xy 107.852951 -287.419523) (xy 107.829825 -287.467544) (xy 107.799801 -287.511581) (xy 107.763549 -287.550652)
			(xy 107.721878 -287.583883) (xy 107.67572 -287.610532) (xy 107.626106 -287.630004) (xy 107.574144 -287.641864)
			(xy 107.520994 -287.645848) (xy 107.467844 -287.641864) (xy 107.415882 -287.630004) (xy 107.366268 -287.610532)
			(xy 107.32011 -287.583883) (xy 107.278439 -287.550652) (xy 107.242187 -287.511581) (xy 107.212163 -287.467544)
			(xy 107.189037 -287.419523) (xy 107.173327 -287.368593) (xy 107.165384 -287.315889) (xy 105.057537 -287.315889)
			(xy 105.057537 -287.316116) (xy 105.049431 -287.369331) (xy 105.033405 -287.420717) (xy 105.009824 -287.469105)
			(xy 104.979225 -287.51339) (xy 104.942307 -287.552563) (xy 104.899912 -287.58573) (xy 104.853005 -287.612136)
			(xy 104.802658 -287.631177) (xy 104.750017 -287.642419) (xy 104.723184 -287.644586) (xy 104.707836 -287.646044)
			(xy 104.679021 -287.656971) (xy 104.654767 -287.675981) (xy 104.637271 -287.70135) (xy 104.628122 -287.730777)
			(xy 104.62768 -287.746186) (xy 104.62768 -288.129705) (xy 104.816138 -288.129705) (xy 104.816138 -288.076407)
			(xy 104.824081 -288.023703) (xy 104.839791 -287.972773) (xy 104.862917 -287.924752) (xy 104.892941 -287.880715)
			(xy 104.929193 -287.841644) (xy 104.970864 -287.808413) (xy 105.017022 -287.781764) (xy 105.066636 -287.762292)
			(xy 105.118598 -287.750432) (xy 105.171748 -287.746449) (xy 105.224898 -287.750432) (xy 105.27686 -287.762292)
			(xy 105.326474 -287.781764) (xy 105.372632 -287.808413) (xy 105.414303 -287.841644) (xy 105.450555 -287.880715)
			(xy 105.480579 -287.924752) (xy 105.503705 -287.972773) (xy 105.519415 -288.023703) (xy 105.527358 -288.076407)
			(xy 105.527856 -288.103056) (xy 105.527358 -288.129705) (xy 113.274084 -288.129705) (xy 113.274084 -288.076407)
			(xy 113.282027 -288.023703) (xy 113.297737 -287.972773) (xy 113.320863 -287.924752) (xy 113.350887 -287.880715)
			(xy 113.387139 -287.841644) (xy 113.42881 -287.808413) (xy 113.474968 -287.781764) (xy 113.524582 -287.762292)
			(xy 113.576544 -287.750432) (xy 113.629694 -287.746449) (xy 113.682844 -287.750432) (xy 113.734806 -287.762292)
			(xy 113.78442 -287.781764) (xy 113.830578 -287.808413) (xy 113.872249 -287.841644) (xy 113.908501 -287.880715)
			(xy 113.938525 -287.924752) (xy 113.961651 -287.972773) (xy 113.977361 -288.023703) (xy 113.985304 -288.076407)
			(xy 113.985802 -288.103056) (xy 113.985304 -288.129705) (xy 116.093738 -288.129705) (xy 116.093738 -288.076407)
			(xy 116.101681 -288.023703) (xy 116.117391 -287.972773) (xy 116.140517 -287.924752) (xy 116.170541 -287.880715)
			(xy 116.206793 -287.841644) (xy 116.248464 -287.808413) (xy 116.294622 -287.781764) (xy 116.344236 -287.762292)
			(xy 116.396198 -287.750432) (xy 116.449348 -287.746449) (xy 116.502498 -287.750432) (xy 116.55446 -287.762292)
			(xy 116.604074 -287.781764) (xy 116.650232 -287.808413) (xy 116.691903 -287.841644) (xy 116.728155 -287.880715)
			(xy 116.758179 -287.924752) (xy 116.781305 -287.972773) (xy 116.797015 -288.023703) (xy 116.804958 -288.076407)
			(xy 116.805456 -288.103056) (xy 116.804958 -288.129705) (xy 116.797015 -288.182409) (xy 116.781305 -288.233339)
			(xy 116.758179 -288.28136) (xy 116.728155 -288.325397) (xy 116.691903 -288.364468) (xy 116.650232 -288.397699)
			(xy 116.604074 -288.424348) (xy 116.55446 -288.44382) (xy 116.502498 -288.45568) (xy 116.449348 -288.459664)
			(xy 116.396198 -288.45568) (xy 116.344236 -288.44382) (xy 116.294622 -288.424348) (xy 116.248464 -288.397699)
			(xy 116.206793 -288.364468) (xy 116.170541 -288.325397) (xy 116.140517 -288.28136) (xy 116.117391 -288.233339)
			(xy 116.101681 -288.182409) (xy 116.093738 -288.129705) (xy 113.985304 -288.129705) (xy 113.977361 -288.182409)
			(xy 113.961651 -288.233339) (xy 113.938525 -288.28136) (xy 113.908501 -288.325397) (xy 113.872249 -288.364468)
			(xy 113.830578 -288.397699) (xy 113.78442 -288.424348) (xy 113.734806 -288.44382) (xy 113.682844 -288.45568)
			(xy 113.629694 -288.459664) (xy 113.576544 -288.45568) (xy 113.524582 -288.44382) (xy 113.474968 -288.424348)
			(xy 113.42881 -288.397699) (xy 113.387139 -288.364468) (xy 113.350887 -288.325397) (xy 113.320863 -288.28136)
			(xy 113.297737 -288.233339) (xy 113.282027 -288.182409) (xy 113.274084 -288.129705) (xy 105.527358 -288.129705)
			(xy 105.519415 -288.182409) (xy 105.503705 -288.233339) (xy 105.480579 -288.28136) (xy 105.450555 -288.325397)
			(xy 105.414303 -288.364468) (xy 105.372632 -288.397699) (xy 105.326474 -288.424348) (xy 105.27686 -288.44382)
			(xy 105.224898 -288.45568) (xy 105.171748 -288.459664) (xy 105.118598 -288.45568) (xy 105.066636 -288.44382)
			(xy 105.017022 -288.424348) (xy 104.970864 -288.397699) (xy 104.929193 -288.364468) (xy 104.892941 -288.325397)
			(xy 104.862917 -288.28136) (xy 104.839791 -288.233339) (xy 104.824081 -288.182409) (xy 104.816138 -288.129705)
			(xy 104.62768 -288.129705) (xy 104.62768 -288.46018) (xy 104.628169 -288.47559) (xy 104.637275 -288.50503)
			(xy 104.654753 -288.530409) (xy 104.679011 -288.549415) (xy 104.707835 -288.560312) (xy 104.723184 -288.56178)
			(xy 104.750023 -288.563861) (xy 104.802668 -288.575097) (xy 104.853019 -288.594135) (xy 104.899926 -288.620543)
			(xy 104.94232 -288.653716) (xy 104.979232 -288.692898) (xy 105.009819 -288.737194) (xy 105.033382 -288.785593)
			(xy 105.049385 -288.83699) (xy 105.057462 -288.890211) (xy 105.057956 -288.917126) (xy 105.057431 -288.943775)
			(xy 107.165638 -288.943775) (xy 107.165638 -288.890477) (xy 107.173581 -288.837773) (xy 107.189291 -288.786843)
			(xy 107.212417 -288.738822) (xy 107.242441 -288.694785) (xy 107.278693 -288.655714) (xy 107.320364 -288.622483)
			(xy 107.366522 -288.595834) (xy 107.416136 -288.576362) (xy 107.468098 -288.564502) (xy 107.521248 -288.560519)
			(xy 107.574398 -288.564502) (xy 107.62636 -288.576362) (xy 107.675974 -288.595834) (xy 107.722132 -288.622483)
			(xy 107.763803 -288.655714) (xy 107.800055 -288.694785) (xy 107.830079 -288.738822) (xy 107.853205 -288.786843)
			(xy 107.868915 -288.837773) (xy 107.876858 -288.890477) (xy 107.877356 -288.917126) (xy 107.876858 -288.943775)
			(xy 107.868915 -288.996479) (xy 107.861667 -289.019975) (xy 109.985038 -289.019975) (xy 109.985038 -288.966677)
			(xy 109.992981 -288.913973) (xy 110.008691 -288.863043) (xy 110.031817 -288.815022) (xy 110.061841 -288.770985)
			(xy 110.098093 -288.731914) (xy 110.139764 -288.698683) (xy 110.185922 -288.672034) (xy 110.235536 -288.652562)
			(xy 110.287498 -288.640702) (xy 110.340648 -288.636719) (xy 110.393798 -288.640702) (xy 110.44576 -288.652562)
			(xy 110.495374 -288.672034) (xy 110.541532 -288.698683) (xy 110.583203 -288.731914) (xy 110.619455 -288.770985)
			(xy 110.649479 -288.815022) (xy 110.672605 -288.863043) (xy 110.688315 -288.913973) (xy 110.692806 -288.943775)
			(xy 119.383038 -288.943775) (xy 119.383038 -288.890477) (xy 119.390981 -288.837773) (xy 119.406691 -288.786843)
			(xy 119.429817 -288.738822) (xy 119.459841 -288.694785) (xy 119.496093 -288.655714) (xy 119.537764 -288.622483)
			(xy 119.583922 -288.595834) (xy 119.633536 -288.576362) (xy 119.685498 -288.564502) (xy 119.738648 -288.560519)
			(xy 119.791798 -288.564502) (xy 119.84376 -288.576362) (xy 119.893374 -288.595834) (xy 119.939532 -288.622483)
			(xy 119.981203 -288.655714) (xy 120.017455 -288.694785) (xy 120.047479 -288.738822) (xy 120.070605 -288.786843)
			(xy 120.086315 -288.837773) (xy 120.094258 -288.890477) (xy 120.094756 -288.917126) (xy 120.094258 -288.943775)
			(xy 120.086315 -288.996479) (xy 120.070605 -289.047409) (xy 120.047479 -289.09543) (xy 120.017455 -289.139467)
			(xy 119.981203 -289.178538) (xy 119.939532 -289.211769) (xy 119.893374 -289.238418) (xy 119.84376 -289.25789)
			(xy 119.791798 -289.26975) (xy 119.738648 -289.273734) (xy 119.685498 -289.26975) (xy 119.633536 -289.25789)
			(xy 119.583922 -289.238418) (xy 119.537764 -289.211769) (xy 119.496093 -289.178538) (xy 119.459841 -289.139467)
			(xy 119.429817 -289.09543) (xy 119.406691 -289.047409) (xy 119.390981 -288.996479) (xy 119.383038 -288.943775)
			(xy 110.692806 -288.943775) (xy 110.696258 -288.966677) (xy 110.696756 -288.993326) (xy 110.696258 -289.019975)
			(xy 110.688315 -289.072679) (xy 110.672605 -289.123609) (xy 110.649479 -289.17163) (xy 110.619455 -289.215667)
			(xy 110.583203 -289.254738) (xy 110.541532 -289.287969) (xy 110.495374 -289.314618) (xy 110.44576 -289.33409)
			(xy 110.393798 -289.34595) (xy 110.340648 -289.349934) (xy 110.287498 -289.34595) (xy 110.235536 -289.33409)
			(xy 110.185922 -289.314618) (xy 110.139764 -289.287969) (xy 110.098093 -289.254738) (xy 110.061841 -289.215667)
			(xy 110.031817 -289.17163) (xy 110.008691 -289.123609) (xy 109.992981 -289.072679) (xy 109.985038 -289.019975)
			(xy 107.861667 -289.019975) (xy 107.853205 -289.047409) (xy 107.830079 -289.09543) (xy 107.800055 -289.139467)
			(xy 107.763803 -289.178538) (xy 107.722132 -289.211769) (xy 107.675974 -289.238418) (xy 107.62636 -289.25789)
			(xy 107.574398 -289.26975) (xy 107.521248 -289.273734) (xy 107.468098 -289.26975) (xy 107.416136 -289.25789)
			(xy 107.366522 -289.238418) (xy 107.320364 -289.211769) (xy 107.278693 -289.178538) (xy 107.242441 -289.139467)
			(xy 107.212417 -289.09543) (xy 107.189291 -289.047409) (xy 107.173581 -288.996479) (xy 107.165638 -288.943775)
			(xy 105.057431 -288.943775) (xy 105.057405 -288.945109) (xy 105.048647 -289.000386) (xy 105.031351 -289.053613)
			(xy 105.005942 -289.103479) (xy 104.973047 -289.148757) (xy 104.933474 -289.188332) (xy 104.888198 -289.221231)
			(xy 104.838333 -289.246643) (xy 104.785107 -289.263942) (xy 104.729831 -289.272703) (xy 104.701848 -289.273234)
			(xy 104.680881 -289.272917) (xy 104.639243 -289.267951) (xy 104.61879 -289.263328) (xy 104.591104 -289.256724)
			(xy 104.459024 -289.388804) (xy 104.449473 -289.398978) (xy 104.435827 -289.423306) (xy 104.429262 -289.450418)
			(xy 104.430269 -289.478295) (xy 104.438772 -289.504862) (xy 104.454139 -289.528143) (xy 104.464358 -289.537648)
			(xy 104.483377 -289.554626) (xy 104.516838 -289.593089) (xy 104.544468 -289.635935) (xy 104.565699 -289.682285)
			(xy 104.580097 -289.731191) (xy 104.587367 -289.781651) (xy 104.587802 -289.807142) (xy 104.587276 -289.833791)
			(xy 118.912884 -289.833791) (xy 118.912884 -289.780493) (xy 118.920827 -289.727789) (xy 118.936537 -289.676859)
			(xy 118.959663 -289.628838) (xy 118.989687 -289.584801) (xy 119.025939 -289.54573) (xy 119.06761 -289.512499)
			(xy 119.113768 -289.48585) (xy 119.163382 -289.466378) (xy 119.215344 -289.454518) (xy 119.268494 -289.450535)
			(xy 119.321644 -289.454518) (xy 119.373606 -289.466378) (xy 119.42322 -289.48585) (xy 119.469378 -289.512499)
			(xy 119.511049 -289.54573) (xy 119.547301 -289.584801) (xy 119.577325 -289.628838) (xy 119.600451 -289.676859)
			(xy 119.616161 -289.727789) (xy 119.624104 -289.780493) (xy 119.624602 -289.807142) (xy 119.852186 -289.807142)
			(xy 119.852644 -289.781504) (xy 119.859993 -289.730756) (xy 119.874544 -289.681588) (xy 119.895998 -289.635015)
			(xy 119.923909 -289.592) (xy 119.957702 -289.553434) (xy 119.996676 -289.520113) (xy 120.040027 -289.492727)
			(xy 120.086858 -289.471842) (xy 120.1362 -289.45789) (xy 120.161558 -289.454082) (xy 120.187466 -289.45078)
			(xy 120.372378 -289.101022) (xy 120.36044 -289.077654) (xy 120.348406 -289.052627) (xy 120.331423 -288.999757)
			(xy 120.32285 -288.944892) (xy 120.32234 -288.917126) (xy 120.322838 -288.890477) (xy 120.330781 -288.837773)
			(xy 120.346491 -288.786843) (xy 120.369617 -288.738822) (xy 120.399641 -288.694785) (xy 120.435893 -288.655714)
			(xy 120.477564 -288.622483) (xy 120.523722 -288.595834) (xy 120.573336 -288.576362) (xy 120.625298 -288.564502)
			(xy 120.678448 -288.560519) (xy 120.731598 -288.564502) (xy 120.78356 -288.576362) (xy 120.833174 -288.595834)
			(xy 120.879332 -288.622483) (xy 120.921003 -288.655714) (xy 120.957255 -288.694785) (xy 120.987279 -288.738822)
			(xy 121.010405 -288.786843) (xy 121.026115 -288.837773) (xy 121.034058 -288.890477) (xy 121.034556 -288.917126)
			(xy 121.034118 -288.942766) (xy 121.026772 -288.993516) (xy 121.012222 -289.042688) (xy 120.990768 -289.089264)
			(xy 120.962855 -289.132281) (xy 120.92906 -289.170848) (xy 120.890081 -289.204169) (xy 120.846726 -289.231553)
			(xy 120.79989 -289.252434) (xy 120.750544 -289.266381) (xy 120.725184 -289.270186) (xy 120.699276 -289.273488)
			(xy 120.514364 -289.623246) (xy 120.526302 -289.646614) (xy 120.53832 -289.671648) (xy 120.55531 -289.724515)
			(xy 120.563889 -289.779377) (xy 120.564402 -289.807142) (xy 120.563904 -289.833791) (xy 120.792484 -289.833791)
			(xy 120.792484 -289.780493) (xy 120.800427 -289.727789) (xy 120.816137 -289.676859) (xy 120.839263 -289.628838)
			(xy 120.869287 -289.584801) (xy 120.905539 -289.54573) (xy 120.94721 -289.512499) (xy 120.993368 -289.48585)
			(xy 121.042982 -289.466378) (xy 121.094944 -289.454518) (xy 121.148094 -289.450535) (xy 121.201244 -289.454518)
			(xy 121.253206 -289.466378) (xy 121.30282 -289.48585) (xy 121.348978 -289.512499) (xy 121.390649 -289.54573)
			(xy 121.426901 -289.584801) (xy 121.456925 -289.628838) (xy 121.480051 -289.676859) (xy 121.495761 -289.727789)
			(xy 121.503704 -289.780493) (xy 121.504202 -289.807142) (xy 121.503704 -289.833791) (xy 121.495761 -289.886495)
			(xy 121.480051 -289.937425) (xy 121.456925 -289.985446) (xy 121.426901 -290.029483) (xy 121.390649 -290.068554)
			(xy 121.348978 -290.101785) (xy 121.30282 -290.128434) (xy 121.253206 -290.147906) (xy 121.201244 -290.159766)
			(xy 121.148094 -290.16375) (xy 121.094944 -290.159766) (xy 121.042982 -290.147906) (xy 120.993368 -290.128434)
			(xy 120.94721 -290.101785) (xy 120.905539 -290.068554) (xy 120.869287 -290.029483) (xy 120.839263 -289.985446)
			(xy 120.816137 -289.937425) (xy 120.800427 -289.886495) (xy 120.792484 -289.833791) (xy 120.563904 -289.833791)
			(xy 120.555961 -289.886495) (xy 120.540251 -289.937425) (xy 120.517125 -289.985446) (xy 120.487101 -290.029483)
			(xy 120.450849 -290.068554) (xy 120.409178 -290.101785) (xy 120.36302 -290.128434) (xy 120.313406 -290.147906)
			(xy 120.261444 -290.159766) (xy 120.208294 -290.16375) (xy 120.155144 -290.159766) (xy 120.103182 -290.147906)
			(xy 120.053568 -290.128434) (xy 120.00741 -290.101785) (xy 119.965739 -290.068554) (xy 119.929487 -290.029483)
			(xy 119.899463 -289.985446) (xy 119.876337 -289.937425) (xy 119.860627 -289.886495) (xy 119.852684 -289.833791)
			(xy 119.852186 -289.807142) (xy 119.624602 -289.807142) (xy 119.624104 -289.833791) (xy 119.616161 -289.886495)
			(xy 119.600451 -289.937425) (xy 119.577325 -289.985446) (xy 119.547301 -290.029483) (xy 119.511049 -290.068554)
			(xy 119.469378 -290.101785) (xy 119.42322 -290.128434) (xy 119.373606 -290.147906) (xy 119.321644 -290.159766)
			(xy 119.268494 -290.16375) (xy 119.215344 -290.159766) (xy 119.163382 -290.147906) (xy 119.113768 -290.128434)
			(xy 119.06761 -290.101785) (xy 119.025939 -290.068554) (xy 118.989687 -290.029483) (xy 118.959663 -289.985446)
			(xy 118.936537 -289.937425) (xy 118.920827 -289.886495) (xy 118.912884 -289.833791) (xy 104.587276 -289.833791)
			(xy 104.58725 -289.835123) (xy 104.57849 -289.890395) (xy 104.561191 -289.943616) (xy 104.535781 -289.993476)
			(xy 104.502884 -290.038747) (xy 104.46331 -290.078315) (xy 104.418035 -290.111206) (xy 104.368171 -290.13661)
			(xy 104.314948 -290.153901) (xy 104.259675 -290.162654) (xy 104.231694 -290.16325) (xy 104.206203 -290.162813)
			(xy 104.155744 -290.155539) (xy 104.106838 -290.14114) (xy 104.060487 -290.119911) (xy 104.017639 -290.092286)
			(xy 103.97917 -290.058831) (xy 103.9622 -290.039806) (xy 103.952748 -290.029525) (xy 103.929462 -290.014124)
			(xy 103.902875 -290.005605) (xy 103.874975 -290.004605) (xy 103.847846 -290.011198) (xy 103.823517 -290.024891)
			(xy 103.813356 -290.034472) (xy 103.12908 -290.718748) (xy 87.30488 -290.718748) (xy 86.16188 -291.861748)
			(xy 86.16188 -292.983252) (xy 103.237758 -292.983252) (xy 103.237758 -292.928748) (xy 103.245515 -292.874798)
			(xy 103.26087 -292.822501) (xy 103.283512 -292.772922) (xy 103.312979 -292.727069) (xy 103.348671 -292.685877)
			(xy 103.389863 -292.650184) (xy 103.435715 -292.620716) (xy 103.485293 -292.598073) (xy 103.53759 -292.582716)
			(xy 103.59154 -292.574958) (xy 103.618792 -292.574472) (xy 103.646868 -292.574976) (xy 103.702416 -292.583189)
			(xy 103.756161 -292.599453) (xy 103.806942 -292.623417) (xy 103.853664 -292.654564) (xy 103.874824 -292.673024)
			(xy 103.886451 -292.682837) (xy 103.913985 -292.695741) (xy 103.9441 -292.699951) (xy 103.974118 -292.695092)
			(xy 104.001367 -292.681597) (xy 104.012746 -292.6715) (xy 104.034133 -292.651991) (xy 104.081698 -292.619001)
			(xy 104.133705 -292.593584) (xy 104.188957 -292.576325) (xy 104.246185 -292.56762) (xy 104.275128 -292.567106)
			(xy 104.302379 -292.567566) (xy 104.356326 -292.575326) (xy 104.408619 -292.590684) (xy 104.458194 -292.613327)
			(xy 104.504043 -292.642796) (xy 104.545231 -292.678488) (xy 104.580921 -292.719679) (xy 104.610386 -292.76553)
			(xy 104.633026 -292.815107) (xy 104.64838 -292.867402) (xy 104.656136 -292.921349) (xy 104.656136 -292.975851)
			(xy 104.655072 -292.983252) (xy 109.276358 -292.983252) (xy 109.276358 -292.928748) (xy 109.284114 -292.874798)
			(xy 109.29947 -292.822502) (xy 109.322111 -292.772923) (xy 109.351578 -292.727071) (xy 109.38727 -292.685878)
			(xy 109.428461 -292.650185) (xy 109.474312 -292.620717) (xy 109.523891 -292.598074) (xy 109.576187 -292.582717)
			(xy 109.630136 -292.574959) (xy 109.657388 -292.574472) (xy 109.685428 -292.574974) (xy 109.740905 -292.583173)
			(xy 109.794587 -292.599397) (xy 109.84532 -292.623297) (xy 109.892012 -292.654359) (xy 109.913166 -292.67277)
			(xy 109.924608 -292.682415) (xy 109.951651 -292.695195) (xy 109.981238 -292.699581) (xy 110.010825 -292.695195)
			(xy 110.037868 -292.682415) (xy 110.04931 -292.67277) (xy 110.070435 -292.654319) (xy 110.11712 -292.62323)
			(xy 110.167857 -292.599321) (xy 110.221552 -292.583108) (xy 110.277043 -292.574941) (xy 110.305088 -292.574472)
			(xy 110.333128 -292.574974) (xy 110.388605 -292.583173) (xy 110.442287 -292.599397) (xy 110.49302 -292.623297)
			(xy 110.539712 -292.654359) (xy 110.560866 -292.67277) (xy 110.572308 -292.682415) (xy 110.599351 -292.695195)
			(xy 110.628938 -292.699581) (xy 110.658525 -292.695195) (xy 110.685568 -292.682415) (xy 110.69701 -292.67277)
			(xy 110.718135 -292.654319) (xy 110.76482 -292.62323) (xy 110.815557 -292.599321) (xy 110.869252 -292.583108)
			(xy 110.924743 -292.574941) (xy 110.952788 -292.574472) (xy 110.98004 -292.574974) (xy 111.033989 -292.58273)
			(xy 111.086286 -292.598084) (xy 111.135865 -292.620724) (xy 111.181717 -292.650191) (xy 111.222909 -292.685882)
			(xy 111.258602 -292.727073) (xy 111.28807 -292.772924) (xy 111.310712 -292.822503) (xy 111.326068 -292.874799)
			(xy 111.333825 -292.928748) (xy 111.333825 -292.983252) (xy 115.746758 -292.983252) (xy 115.746758 -292.928748)
			(xy 115.754514 -292.874799) (xy 115.769869 -292.822503) (xy 115.792511 -292.772924) (xy 115.821977 -292.727072)
			(xy 115.857669 -292.68588) (xy 115.898859 -292.650187) (xy 115.94471 -292.620718) (xy 115.994288 -292.598075)
			(xy 116.046583 -292.582718) (xy 116.100532 -292.574959) (xy 116.127784 -292.574472) (xy 116.155155 -292.57493)
			(xy 116.209335 -292.582747) (xy 116.261839 -292.598237) (xy 116.311586 -292.621081) (xy 116.357551 -292.650809)
			(xy 116.378482 -292.668452) (xy 116.38981 -292.677688) (xy 116.416367 -292.689864) (xy 116.445284 -292.694037)
			(xy 116.474201 -292.689864) (xy 116.500758 -292.677688) (xy 116.512086 -292.668452) (xy 116.533019 -292.650811)
			(xy 116.578987 -292.621087) (xy 116.628733 -292.598241) (xy 116.681235 -292.582745) (xy 116.735413 -292.574916)
			(xy 116.790155 -292.574916) (xy 116.844333 -292.582745) (xy 116.896835 -292.598241) (xy 116.946581 -292.621087)
			(xy 116.992549 -292.650811) (xy 117.013482 -292.668452) (xy 117.02481 -292.677688) (xy 117.051367 -292.689864)
			(xy 117.080284 -292.694037) (xy 117.109201 -292.689864) (xy 117.135758 -292.677688) (xy 117.147086 -292.668452)
			(xy 117.168019 -292.650814) (xy 117.213991 -292.6211) (xy 117.263738 -292.598263) (xy 117.316239 -292.582772)
			(xy 117.370415 -292.574945) (xy 117.397784 -292.574472) (xy 117.425036 -292.574974) (xy 117.478986 -292.582729)
			(xy 117.531283 -292.598083) (xy 117.580863 -292.620723) (xy 117.626715 -292.650189) (xy 117.667908 -292.685881)
			(xy 117.703601 -292.727072) (xy 117.733069 -292.772923) (xy 117.755712 -292.822502) (xy 117.771068 -292.874798)
			(xy 117.778825 -292.928748) (xy 117.778825 -292.95598) (xy 122.307602 -292.95598) (xy 122.311673 -292.900358)
			(xy 122.323799 -292.845921) (xy 122.343722 -292.79383) (xy 122.371018 -292.745195) (xy 122.405104 -292.701052)
			(xy 122.445253 -292.662343) (xy 122.490611 -292.629892) (xy 122.540211 -292.604391) (xy 122.592995 -292.586384)
			(xy 122.647838 -292.576254) (xy 122.703572 -292.574217) (xy 122.759009 -292.580317) (xy 122.812966 -292.594423)
			(xy 122.864295 -292.616235) (xy 122.911901 -292.645289) (xy 122.954769 -292.680964) (xy 122.991986 -292.722501)
			(xy 123.022759 -292.769014) (xy 123.046431 -292.819511) (xy 123.062499 -292.872918) (xy 123.070619 -292.928094)
			(xy 123.071128 -292.95598) (xy 123.070619 -292.983866) (xy 123.062499 -293.039042) (xy 123.046431 -293.092449)
			(xy 123.022759 -293.142946) (xy 122.991986 -293.189459) (xy 122.954769 -293.230996) (xy 122.911901 -293.266671)
			(xy 122.864295 -293.295725) (xy 122.812966 -293.317537) (xy 122.759009 -293.331643) (xy 122.703572 -293.337743)
			(xy 122.647838 -293.335706) (xy 122.592995 -293.325576) (xy 122.540211 -293.307569) (xy 122.490611 -293.282068)
			(xy 122.445253 -293.249617) (xy 122.405104 -293.210908) (xy 122.371018 -293.166765) (xy 122.343722 -293.11813)
			(xy 122.323799 -293.066039) (xy 122.311673 -293.011602) (xy 122.307602 -292.95598) (xy 117.778825 -292.95598)
			(xy 117.778825 -292.983252) (xy 117.771068 -293.037202) (xy 117.755712 -293.089498) (xy 117.733069 -293.139077)
			(xy 117.703601 -293.184928) (xy 117.667908 -293.226119) (xy 117.626715 -293.261811) (xy 117.580863 -293.291277)
			(xy 117.531283 -293.313917) (xy 117.478986 -293.329271) (xy 117.425036 -293.337026) (xy 117.397784 -293.337488)
			(xy 117.370413 -293.337034) (xy 117.316234 -293.329214) (xy 117.26373 -293.313722) (xy 117.213984 -293.290878)
			(xy 117.168017 -293.26115) (xy 117.147086 -293.243508) (xy 117.135758 -293.234272) (xy 117.109201 -293.222096)
			(xy 117.080284 -293.217923) (xy 117.051367 -293.222096) (xy 117.02481 -293.234272) (xy 117.013482 -293.243508)
			(xy 116.992549 -293.261149) (xy 116.946581 -293.290873) (xy 116.896835 -293.313719) (xy 116.844333 -293.329215)
			(xy 116.790155 -293.337044) (xy 116.735413 -293.337044) (xy 116.681235 -293.329215) (xy 116.628733 -293.313719)
			(xy 116.578987 -293.290873) (xy 116.533019 -293.261149) (xy 116.512086 -293.243508) (xy 116.500758 -293.234272)
			(xy 116.474201 -293.222096) (xy 116.445284 -293.217923) (xy 116.416367 -293.222096) (xy 116.38981 -293.234272)
			(xy 116.378482 -293.243508) (xy 116.357531 -293.261123) (xy 116.311563 -293.290838) (xy 116.26182 -293.313679)
			(xy 116.209324 -293.329176) (xy 116.155152 -293.33701) (xy 116.127784 -293.337488) (xy 116.100532 -293.337041)
			(xy 116.046583 -293.329282) (xy 115.994288 -293.313925) (xy 115.94471 -293.291282) (xy 115.898859 -293.261813)
			(xy 115.857669 -293.22612) (xy 115.821977 -293.184928) (xy 115.792511 -293.139076) (xy 115.769869 -293.089497)
			(xy 115.754514 -293.037201) (xy 115.746758 -292.983252) (xy 111.333825 -292.983252) (xy 111.326068 -293.037201)
			(xy 111.310712 -293.089497) (xy 111.28807 -293.139076) (xy 111.258602 -293.184927) (xy 111.222909 -293.226118)
			(xy 111.181717 -293.261809) (xy 111.135865 -293.291276) (xy 111.086286 -293.313916) (xy 111.033989 -293.32927)
			(xy 110.98004 -293.337026) (xy 110.952788 -293.337488) (xy 110.924747 -293.337011) (xy 110.869268 -293.328807)
			(xy 110.815585 -293.312578) (xy 110.764853 -293.288672) (xy 110.718163 -293.257604) (xy 110.69701 -293.23919)
			(xy 110.685568 -293.229545) (xy 110.658525 -293.216765) (xy 110.628938 -293.212379) (xy 110.599351 -293.216765)
			(xy 110.572308 -293.229545) (xy 110.560866 -293.23919) (xy 110.539705 -293.257598) (xy 110.493031 -293.288695)
			(xy 110.442303 -293.312613) (xy 110.388616 -293.328836) (xy 110.333131 -293.337013) (xy 110.305088 -293.337488)
			(xy 110.277047 -293.337011) (xy 110.221568 -293.328807) (xy 110.167885 -293.312578) (xy 110.117153 -293.288672)
			(xy 110.070463 -293.257604) (xy 110.04931 -293.23919) (xy 110.037868 -293.229545) (xy 110.010825 -293.216765)
			(xy 109.981238 -293.212379) (xy 109.951651 -293.216765) (xy 109.924608 -293.229545) (xy 109.913166 -293.23919)
			(xy 109.892005 -293.257598) (xy 109.845331 -293.288695) (xy 109.794603 -293.312613) (xy 109.740916 -293.328836)
			(xy 109.685431 -293.337013) (xy 109.657388 -293.337488) (xy 109.630136 -293.337041) (xy 109.576187 -293.329283)
			(xy 109.523891 -293.313926) (xy 109.474312 -293.291283) (xy 109.428461 -293.261815) (xy 109.38727 -293.226122)
			(xy 109.351578 -293.184929) (xy 109.322111 -293.139077) (xy 109.29947 -293.089498) (xy 109.284114 -293.037202)
			(xy 109.276358 -292.983252) (xy 104.655072 -292.983252) (xy 104.64838 -293.029798) (xy 104.633026 -293.082093)
			(xy 104.610386 -293.13167) (xy 104.580921 -293.177521) (xy 104.545231 -293.218712) (xy 104.504043 -293.254404)
			(xy 104.458194 -293.283873) (xy 104.408619 -293.306516) (xy 104.356326 -293.321874) (xy 104.302379 -293.329634)
			(xy 104.275128 -293.330122) (xy 104.247052 -293.329608) (xy 104.191505 -293.321398) (xy 104.13776 -293.305136)
			(xy 104.086978 -293.281174) (xy 104.040256 -293.250029) (xy 104.019096 -293.23157) (xy 104.00753 -293.221678)
			(xy 103.979974 -293.208784) (xy 103.94984 -293.20459) (xy 103.91981 -293.209469) (xy 103.892553 -293.222986)
			(xy 103.881174 -293.233094) (xy 103.859778 -293.252592) (xy 103.812216 -293.285584) (xy 103.760211 -293.311003)
			(xy 103.70496 -293.328265) (xy 103.647735 -293.336973) (xy 103.618792 -293.337488) (xy 103.59154 -293.337042)
			(xy 103.53759 -293.329284) (xy 103.485293 -293.313927) (xy 103.435715 -293.291284) (xy 103.389863 -293.261816)
			(xy 103.348671 -293.226123) (xy 103.312979 -293.184931) (xy 103.283512 -293.139078) (xy 103.26087 -293.089499)
			(xy 103.245515 -293.037202) (xy 103.237758 -292.983252) (xy 86.16188 -292.983252) (xy 86.16188 -295.066052)
			(xy 103.237758 -295.066052) (xy 103.237758 -295.011548) (xy 103.245515 -294.957598) (xy 103.26087 -294.905301)
			(xy 103.283512 -294.855722) (xy 103.312979 -294.809869) (xy 103.348671 -294.768677) (xy 103.389863 -294.732984)
			(xy 103.435715 -294.703516) (xy 103.485293 -294.680873) (xy 103.53759 -294.665516) (xy 103.59154 -294.657758)
			(xy 103.618792 -294.657272) (xy 103.646868 -294.657776) (xy 103.702416 -294.665989) (xy 103.756161 -294.682253)
			(xy 103.806942 -294.706217) (xy 103.853664 -294.737364) (xy 103.874824 -294.755824) (xy 103.886451 -294.765637)
			(xy 103.913985 -294.778541) (xy 103.9441 -294.782751) (xy 103.974118 -294.777892) (xy 104.001367 -294.764397)
			(xy 104.012746 -294.7543) (xy 104.034133 -294.734791) (xy 104.081698 -294.701801) (xy 104.133705 -294.676384)
			(xy 104.188957 -294.659125) (xy 104.246185 -294.65042) (xy 104.275128 -294.649906) (xy 104.302379 -294.650366)
			(xy 104.356326 -294.658126) (xy 104.408619 -294.673484) (xy 104.458194 -294.696127) (xy 104.504043 -294.725596)
			(xy 104.545231 -294.761288) (xy 104.580921 -294.802479) (xy 104.610386 -294.84833) (xy 104.633026 -294.897907)
			(xy 104.64838 -294.950202) (xy 104.656136 -295.004149) (xy 104.656136 -295.058651) (xy 104.655072 -295.066052)
			(xy 109.276358 -295.066052) (xy 109.276358 -295.011548) (xy 109.284114 -294.957598) (xy 109.29947 -294.905302)
			(xy 109.322111 -294.855723) (xy 109.351578 -294.809871) (xy 109.38727 -294.768678) (xy 109.428461 -294.732985)
			(xy 109.474312 -294.703517) (xy 109.523891 -294.680874) (xy 109.576187 -294.665517) (xy 109.630136 -294.657759)
			(xy 109.657388 -294.657272) (xy 109.685428 -294.657774) (xy 109.740905 -294.665973) (xy 109.794587 -294.682197)
			(xy 109.84532 -294.706097) (xy 109.892012 -294.737159) (xy 109.913166 -294.75557) (xy 109.924608 -294.765215)
			(xy 109.951651 -294.777995) (xy 109.981238 -294.782381) (xy 110.010825 -294.777995) (xy 110.037868 -294.765215)
			(xy 110.04931 -294.75557) (xy 110.070435 -294.737119) (xy 110.11712 -294.70603) (xy 110.167857 -294.682121)
			(xy 110.221552 -294.665908) (xy 110.277043 -294.657741) (xy 110.305088 -294.657272) (xy 110.333128 -294.657774)
			(xy 110.388605 -294.665973) (xy 110.442287 -294.682197) (xy 110.49302 -294.706097) (xy 110.539712 -294.737159)
			(xy 110.560866 -294.75557) (xy 110.572308 -294.765215) (xy 110.599351 -294.777995) (xy 110.628938 -294.782381)
			(xy 110.658525 -294.777995) (xy 110.685568 -294.765215) (xy 110.69701 -294.75557) (xy 110.718135 -294.737119)
			(xy 110.76482 -294.70603) (xy 110.815557 -294.682121) (xy 110.869252 -294.665908) (xy 110.924743 -294.657741)
			(xy 110.952788 -294.657272) (xy 110.98004 -294.657774) (xy 111.033989 -294.66553) (xy 111.086286 -294.680884)
			(xy 111.135865 -294.703524) (xy 111.181717 -294.732991) (xy 111.222909 -294.768682) (xy 111.258602 -294.809873)
			(xy 111.28807 -294.855724) (xy 111.310712 -294.905303) (xy 111.326068 -294.957599) (xy 111.333825 -295.011548)
			(xy 111.333825 -295.066052) (xy 115.746758 -295.066052) (xy 115.746758 -295.011548) (xy 115.754514 -294.957599)
			(xy 115.769869 -294.905303) (xy 115.792511 -294.855724) (xy 115.821977 -294.809872) (xy 115.857669 -294.76868)
			(xy 115.898859 -294.732987) (xy 115.94471 -294.703518) (xy 115.994288 -294.680875) (xy 116.046583 -294.665518)
			(xy 116.100532 -294.657759) (xy 116.127784 -294.657272) (xy 116.155155 -294.65773) (xy 116.209335 -294.665547)
			(xy 116.261839 -294.681037) (xy 116.311586 -294.703881) (xy 116.357551 -294.733609) (xy 116.378482 -294.751252)
			(xy 116.38981 -294.760488) (xy 116.416367 -294.772664) (xy 116.445284 -294.776837) (xy 116.474201 -294.772664)
			(xy 116.500758 -294.760488) (xy 116.512086 -294.751252) (xy 116.533019 -294.733611) (xy 116.578987 -294.703887)
			(xy 116.628733 -294.681041) (xy 116.681235 -294.665545) (xy 116.735413 -294.657716) (xy 116.790155 -294.657716)
			(xy 116.844333 -294.665545) (xy 116.896835 -294.681041) (xy 116.946581 -294.703887) (xy 116.992549 -294.733611)
			(xy 117.013482 -294.751252) (xy 117.02481 -294.760488) (xy 117.051367 -294.772664) (xy 117.080284 -294.776837)
			(xy 117.109201 -294.772664) (xy 117.135758 -294.760488) (xy 117.147086 -294.751252) (xy 117.168019 -294.733614)
			(xy 117.213991 -294.7039) (xy 117.263738 -294.681063) (xy 117.316239 -294.665572) (xy 117.370415 -294.657745)
			(xy 117.397784 -294.657272) (xy 117.425036 -294.657774) (xy 117.478986 -294.665529) (xy 117.531283 -294.680883)
			(xy 117.580863 -294.703523) (xy 117.626715 -294.732989) (xy 117.667908 -294.768681) (xy 117.703601 -294.809872)
			(xy 117.733069 -294.855723) (xy 117.755712 -294.905302) (xy 117.771068 -294.957598) (xy 117.778825 -295.011548)
			(xy 117.778825 -295.03878) (xy 122.307602 -295.03878) (xy 122.311673 -294.983158) (xy 122.323799 -294.928721)
			(xy 122.343722 -294.87663) (xy 122.371018 -294.827995) (xy 122.405104 -294.783852) (xy 122.445253 -294.745143)
			(xy 122.490611 -294.712692) (xy 122.540211 -294.687191) (xy 122.592995 -294.669184) (xy 122.647838 -294.659054)
			(xy 122.703572 -294.657017) (xy 122.759009 -294.663117) (xy 122.812966 -294.677223) (xy 122.864295 -294.699035)
			(xy 122.911901 -294.728089) (xy 122.954769 -294.763764) (xy 122.991986 -294.805301) (xy 123.022759 -294.851814)
			(xy 123.046431 -294.902311) (xy 123.062499 -294.955718) (xy 123.070619 -295.010894) (xy 123.071128 -295.03878)
			(xy 123.070619 -295.066666) (xy 123.062499 -295.121842) (xy 123.046431 -295.175249) (xy 123.022759 -295.225746)
			(xy 122.991986 -295.272259) (xy 122.954769 -295.313796) (xy 122.911901 -295.349471) (xy 122.864295 -295.378525)
			(xy 122.812966 -295.400337) (xy 122.759009 -295.414443) (xy 122.703572 -295.420543) (xy 122.647838 -295.418506)
			(xy 122.592995 -295.408376) (xy 122.540211 -295.390369) (xy 122.490611 -295.364868) (xy 122.445253 -295.332417)
			(xy 122.405104 -295.293708) (xy 122.371018 -295.249565) (xy 122.343722 -295.20093) (xy 122.323799 -295.148839)
			(xy 122.311673 -295.094402) (xy 122.307602 -295.03878) (xy 117.778825 -295.03878) (xy 117.778825 -295.066052)
			(xy 117.771068 -295.120002) (xy 117.755712 -295.172298) (xy 117.733069 -295.221877) (xy 117.703601 -295.267728)
			(xy 117.667908 -295.308919) (xy 117.626715 -295.344611) (xy 117.580863 -295.374077) (xy 117.531283 -295.396717)
			(xy 117.478986 -295.412071) (xy 117.425036 -295.419826) (xy 117.397784 -295.420288) (xy 117.370413 -295.419834)
			(xy 117.316234 -295.412014) (xy 117.26373 -295.396522) (xy 117.213984 -295.373678) (xy 117.168017 -295.34395)
			(xy 117.147086 -295.326308) (xy 117.135758 -295.317072) (xy 117.109201 -295.304896) (xy 117.080284 -295.300723)
			(xy 117.051367 -295.304896) (xy 117.02481 -295.317072) (xy 117.013482 -295.326308) (xy 116.992549 -295.343949)
			(xy 116.946581 -295.373673) (xy 116.896835 -295.396519) (xy 116.844333 -295.412015) (xy 116.790155 -295.419844)
			(xy 116.735413 -295.419844) (xy 116.681235 -295.412015) (xy 116.628733 -295.396519) (xy 116.578987 -295.373673)
			(xy 116.533019 -295.343949) (xy 116.512086 -295.326308) (xy 116.500758 -295.317072) (xy 116.474201 -295.304896)
			(xy 116.445284 -295.300723) (xy 116.416367 -295.304896) (xy 116.38981 -295.317072) (xy 116.378482 -295.326308)
			(xy 116.357531 -295.343923) (xy 116.311563 -295.373638) (xy 116.26182 -295.396479) (xy 116.209324 -295.411976)
			(xy 116.155152 -295.41981) (xy 116.127784 -295.420288) (xy 116.100532 -295.419841) (xy 116.046583 -295.412082)
			(xy 115.994288 -295.396725) (xy 115.94471 -295.374082) (xy 115.898859 -295.344613) (xy 115.857669 -295.30892)
			(xy 115.821977 -295.267728) (xy 115.792511 -295.221876) (xy 115.769869 -295.172297) (xy 115.754514 -295.120001)
			(xy 115.746758 -295.066052) (xy 111.333825 -295.066052) (xy 111.326068 -295.120001) (xy 111.310712 -295.172297)
			(xy 111.28807 -295.221876) (xy 111.258602 -295.267727) (xy 111.222909 -295.308918) (xy 111.181717 -295.344609)
			(xy 111.135865 -295.374076) (xy 111.086286 -295.396716) (xy 111.033989 -295.41207) (xy 110.98004 -295.419826)
			(xy 110.952788 -295.420288) (xy 110.924747 -295.419811) (xy 110.869268 -295.411607) (xy 110.815585 -295.395378)
			(xy 110.764853 -295.371472) (xy 110.718163 -295.340404) (xy 110.69701 -295.32199) (xy 110.685568 -295.312345)
			(xy 110.658525 -295.299565) (xy 110.628938 -295.295179) (xy 110.599351 -295.299565) (xy 110.572308 -295.312345)
			(xy 110.560866 -295.32199) (xy 110.539705 -295.340398) (xy 110.493031 -295.371495) (xy 110.442303 -295.395413)
			(xy 110.388616 -295.411636) (xy 110.333131 -295.419813) (xy 110.305088 -295.420288) (xy 110.277047 -295.419811)
			(xy 110.221568 -295.411607) (xy 110.167885 -295.395378) (xy 110.117153 -295.371472) (xy 110.070463 -295.340404)
			(xy 110.04931 -295.32199) (xy 110.037868 -295.312345) (xy 110.010825 -295.299565) (xy 109.981238 -295.295179)
			(xy 109.951651 -295.299565) (xy 109.924608 -295.312345) (xy 109.913166 -295.32199) (xy 109.892005 -295.340398)
			(xy 109.845331 -295.371495) (xy 109.794603 -295.395413) (xy 109.740916 -295.411636) (xy 109.685431 -295.419813)
			(xy 109.657388 -295.420288) (xy 109.630136 -295.419841) (xy 109.576187 -295.412083) (xy 109.523891 -295.396726)
			(xy 109.474312 -295.374083) (xy 109.428461 -295.344615) (xy 109.38727 -295.308922) (xy 109.351578 -295.267729)
			(xy 109.322111 -295.221877) (xy 109.29947 -295.172298) (xy 109.284114 -295.120002) (xy 109.276358 -295.066052)
			(xy 104.655072 -295.066052) (xy 104.64838 -295.112598) (xy 104.633026 -295.164893) (xy 104.610386 -295.21447)
			(xy 104.580921 -295.260321) (xy 104.545231 -295.301512) (xy 104.504043 -295.337204) (xy 104.458194 -295.366673)
			(xy 104.408619 -295.389316) (xy 104.356326 -295.404674) (xy 104.302379 -295.412434) (xy 104.275128 -295.412922)
			(xy 104.247052 -295.412408) (xy 104.191505 -295.404198) (xy 104.13776 -295.387936) (xy 104.086978 -295.363974)
			(xy 104.040256 -295.332829) (xy 104.019096 -295.31437) (xy 104.00753 -295.304478) (xy 103.979974 -295.291584)
			(xy 103.94984 -295.28739) (xy 103.91981 -295.292269) (xy 103.892553 -295.305786) (xy 103.881174 -295.315894)
			(xy 103.859778 -295.335392) (xy 103.812216 -295.368384) (xy 103.760211 -295.393803) (xy 103.70496 -295.411065)
			(xy 103.647735 -295.419773) (xy 103.618792 -295.420288) (xy 103.59154 -295.419842) (xy 103.53759 -295.412084)
			(xy 103.485293 -295.396727) (xy 103.435715 -295.374084) (xy 103.389863 -295.344616) (xy 103.348671 -295.308923)
			(xy 103.312979 -295.267731) (xy 103.283512 -295.221878) (xy 103.26087 -295.172299) (xy 103.245515 -295.120002)
			(xy 103.237758 -295.066052) (xy 86.16188 -295.066052) (xy 86.16188 -297.515026) (xy 88.21548 -297.515026)
			(xy 88.219461 -297.382006) (xy 88.23139 -297.249461) (xy 88.251225 -297.117868) (xy 88.278894 -296.987696)
			(xy 88.314298 -296.859411) (xy 88.357311 -296.733474) (xy 88.407778 -296.610335) (xy 88.465519 -296.490434)
			(xy 88.530328 -296.374201) (xy 88.601972 -296.262051) (xy 88.680194 -296.154387) (xy 88.764715 -296.051594)
			(xy 88.855233 -295.954039) (xy 88.951422 -295.862073) (xy 89.05294 -295.776023) (xy 89.159421 -295.696199)
			(xy 89.270486 -295.622886) (xy 89.385737 -295.556346) (xy 89.504761 -295.496817) (xy 89.627132 -295.444513)
			(xy 89.752411 -295.399621) (xy 89.880152 -295.362302) (xy 90.009895 -295.332689) (xy 90.141177 -295.310888)
			(xy 90.273528 -295.296978) (xy 90.406474 -295.291007) (xy 90.539539 -295.292998) (xy 90.672247 -295.302943)
			(xy 90.804123 -295.320807) (xy 90.934694 -295.346525) (xy 91.063494 -295.380006) (xy 91.19006 -295.42113)
			(xy 91.313941 -295.46975) (xy 91.434692 -295.525691) (xy 91.551882 -295.588753) (xy 91.665091 -295.658711)
			(xy 91.773913 -295.735315) (xy 91.877959 -295.818289) (xy 91.976857 -295.907337) (xy 92.070252 -296.00214)
			(xy 92.15781 -296.102358) (xy 92.239219 -296.207634) (xy 92.314185 -296.31759) (xy 92.382442 -296.431832)
			(xy 92.443744 -296.549952) (xy 92.497873 -296.671527) (xy 92.544634 -296.796121) (xy 92.58386 -296.923289)
			(xy 92.61541 -297.052575) (xy 92.624896 -297.104848) (xy 103.237816 -297.104848) (xy 103.237816 -297.050352)
			(xy 103.245572 -296.99641) (xy 103.260925 -296.944121) (xy 103.283563 -296.89455) (xy 103.313026 -296.848704)
			(xy 103.348713 -296.807518) (xy 103.389898 -296.771831) (xy 103.435743 -296.742367) (xy 103.485314 -296.719728)
			(xy 103.537602 -296.704373) (xy 103.591544 -296.696617) (xy 103.618792 -296.69613) (xy 103.647293 -296.696651)
			(xy 103.703661 -296.705141) (xy 103.758134 -296.721932) (xy 103.809499 -296.74665) (xy 103.856609 -296.778743)
			(xy 103.877872 -296.79773) (xy 103.889426 -296.807651) (xy 103.916861 -296.820834) (xy 103.94696 -296.825361)
			(xy 103.977059 -296.820834) (xy 104.004494 -296.807651) (xy 104.016048 -296.79773) (xy 104.037326 -296.778766)
			(xy 104.08445 -296.746708) (xy 104.135814 -296.722005) (xy 104.190277 -296.705207) (xy 104.246631 -296.696685)
			(xy 104.275128 -296.69613) (xy 104.302381 -296.696542) (xy 104.356331 -296.704302) (xy 104.408627 -296.719661)
			(xy 104.458206 -296.742306) (xy 104.504057 -296.771776) (xy 104.545248 -296.807471) (xy 104.58094 -296.848665)
			(xy 104.610407 -296.894519) (xy 104.633048 -296.944099) (xy 104.648404 -296.996397) (xy 104.65616 -297.050347)
			(xy 104.65616 -297.104853) (xy 104.648404 -297.158803) (xy 104.633048 -297.211101) (xy 104.626677 -297.225052)
			(xy 109.276358 -297.225052) (xy 109.276358 -297.170548) (xy 109.284114 -297.116598) (xy 109.29947 -297.064302)
			(xy 109.322111 -297.014723) (xy 109.351578 -296.968871) (xy 109.38727 -296.927678) (xy 109.428461 -296.891985)
			(xy 109.474312 -296.862517) (xy 109.523891 -296.839874) (xy 109.576187 -296.824517) (xy 109.630136 -296.816759)
			(xy 109.657388 -296.816272) (xy 109.685428 -296.816774) (xy 109.740905 -296.824973) (xy 109.794587 -296.841197)
			(xy 109.84532 -296.865097) (xy 109.892012 -296.896159) (xy 109.913166 -296.91457) (xy 109.924608 -296.924215)
			(xy 109.951651 -296.936995) (xy 109.981238 -296.941381) (xy 110.010825 -296.936995) (xy 110.037868 -296.924215)
			(xy 110.04931 -296.91457) (xy 110.070435 -296.896119) (xy 110.11712 -296.86503) (xy 110.167857 -296.841121)
			(xy 110.221552 -296.824908) (xy 110.277043 -296.816741) (xy 110.305088 -296.816272) (xy 110.333128 -296.816774)
			(xy 110.388605 -296.824973) (xy 110.442287 -296.841197) (xy 110.49302 -296.865097) (xy 110.539712 -296.896159)
			(xy 110.560866 -296.91457) (xy 110.572308 -296.924215) (xy 110.599351 -296.936995) (xy 110.628938 -296.941381)
			(xy 110.658525 -296.936995) (xy 110.685568 -296.924215) (xy 110.69701 -296.91457) (xy 110.718135 -296.896119)
			(xy 110.76482 -296.86503) (xy 110.815557 -296.841121) (xy 110.869252 -296.824908) (xy 110.924743 -296.816741)
			(xy 110.952788 -296.816272) (xy 110.98004 -296.816774) (xy 111.033989 -296.82453) (xy 111.086286 -296.839884)
			(xy 111.135865 -296.862524) (xy 111.181717 -296.891991) (xy 111.222909 -296.927682) (xy 111.258602 -296.968873)
			(xy 111.28807 -297.014724) (xy 111.310712 -297.064303) (xy 111.326068 -297.116599) (xy 111.333825 -297.170548)
			(xy 111.333825 -297.225052) (xy 115.746758 -297.225052) (xy 115.746758 -297.170548) (xy 115.754514 -297.116599)
			(xy 115.769869 -297.064303) (xy 115.792511 -297.014724) (xy 115.821977 -296.968872) (xy 115.857669 -296.92768)
			(xy 115.898859 -296.891987) (xy 115.94471 -296.862518) (xy 115.994288 -296.839875) (xy 116.046583 -296.824518)
			(xy 116.100532 -296.816759) (xy 116.127784 -296.816272) (xy 116.155155 -296.81673) (xy 116.209335 -296.824547)
			(xy 116.261839 -296.840037) (xy 116.311586 -296.862881) (xy 116.357551 -296.892609) (xy 116.378482 -296.910252)
			(xy 116.38981 -296.919488) (xy 116.416367 -296.931664) (xy 116.445284 -296.935837) (xy 116.474201 -296.931664)
			(xy 116.500758 -296.919488) (xy 116.512086 -296.910252) (xy 116.533019 -296.892611) (xy 116.578987 -296.862887)
			(xy 116.628733 -296.840041) (xy 116.681235 -296.824545) (xy 116.735413 -296.816716) (xy 116.790155 -296.816716)
			(xy 116.844333 -296.824545) (xy 116.896835 -296.840041) (xy 116.946581 -296.862887) (xy 116.992549 -296.892611)
			(xy 117.013482 -296.910252) (xy 117.02481 -296.919488) (xy 117.051367 -296.931664) (xy 117.080284 -296.935837)
			(xy 117.109201 -296.931664) (xy 117.135758 -296.919488) (xy 117.147086 -296.910252) (xy 117.168019 -296.892614)
			(xy 117.213991 -296.8629) (xy 117.263738 -296.840063) (xy 117.316239 -296.824572) (xy 117.370415 -296.816745)
			(xy 117.397784 -296.816272) (xy 117.425036 -296.816774) (xy 117.478986 -296.824529) (xy 117.531283 -296.839883)
			(xy 117.580863 -296.862523) (xy 117.626715 -296.891989) (xy 117.667908 -296.927681) (xy 117.703601 -296.968872)
			(xy 117.733069 -297.014723) (xy 117.755712 -297.064302) (xy 117.771068 -297.116598) (xy 117.778825 -297.170548)
			(xy 117.778825 -297.19778) (xy 122.307602 -297.19778) (xy 122.311673 -297.142158) (xy 122.323799 -297.087721)
			(xy 122.343722 -297.03563) (xy 122.371018 -296.986995) (xy 122.405104 -296.942852) (xy 122.445253 -296.904143)
			(xy 122.490611 -296.871692) (xy 122.540211 -296.846191) (xy 122.592995 -296.828184) (xy 122.647838 -296.818054)
			(xy 122.703572 -296.816017) (xy 122.759009 -296.822117) (xy 122.812966 -296.836223) (xy 122.864295 -296.858035)
			(xy 122.911901 -296.887089) (xy 122.954769 -296.922764) (xy 122.991986 -296.964301) (xy 123.022759 -297.010814)
			(xy 123.046431 -297.061311) (xy 123.062499 -297.114718) (xy 123.070619 -297.169894) (xy 123.071128 -297.19778)
			(xy 123.070619 -297.225666) (xy 123.062499 -297.280842) (xy 123.046431 -297.334249) (xy 123.022759 -297.384746)
			(xy 122.991986 -297.431259) (xy 122.954769 -297.472796) (xy 122.911901 -297.508471) (xy 122.90116 -297.515026)
			(xy 131.195582 -297.515026) (xy 131.199563 -297.382006) (xy 131.211492 -297.249461) (xy 131.231327 -297.117868)
			(xy 131.258996 -296.987696) (xy 131.2944 -296.859411) (xy 131.337413 -296.733474) (xy 131.38788 -296.610335)
			(xy 131.445621 -296.490434) (xy 131.51043 -296.374201) (xy 131.582074 -296.262051) (xy 131.660296 -296.154387)
			(xy 131.744817 -296.051594) (xy 131.835335 -295.954039) (xy 131.931524 -295.862073) (xy 132.033042 -295.776023)
			(xy 132.139523 -295.696199) (xy 132.250588 -295.622886) (xy 132.365839 -295.556346) (xy 132.484863 -295.496817)
			(xy 132.607234 -295.444513) (xy 132.732513 -295.399621) (xy 132.860254 -295.362302) (xy 132.989997 -295.332689)
			(xy 133.121279 -295.310888) (xy 133.25363 -295.296978) (xy 133.386576 -295.291007) (xy 133.519641 -295.292998)
			(xy 133.652349 -295.302943) (xy 133.784225 -295.320807) (xy 133.914796 -295.346525) (xy 134.043596 -295.380006)
			(xy 134.170162 -295.42113) (xy 134.294043 -295.46975) (xy 134.414794 -295.525691) (xy 134.531984 -295.588753)
			(xy 134.645193 -295.658711) (xy 134.754015 -295.735315) (xy 134.858061 -295.818289) (xy 134.956959 -295.907337)
			(xy 135.050354 -296.00214) (xy 135.137912 -296.102358) (xy 135.219321 -296.207634) (xy 135.294287 -296.31759)
			(xy 135.362544 -296.431832) (xy 135.423846 -296.549952) (xy 135.477975 -296.671527) (xy 135.524736 -296.796121)
			(xy 135.563962 -296.923289) (xy 135.595512 -297.052575) (xy 135.619275 -297.183516) (xy 135.635164 -297.315644)
			(xy 135.643122 -297.448486) (xy 135.64362 -297.515026) (xy 135.643122 -297.581566) (xy 135.635164 -297.714408)
			(xy 135.619275 -297.846536) (xy 135.595512 -297.977477) (xy 135.563962 -298.106763) (xy 135.524736 -298.233931)
			(xy 135.477975 -298.358525) (xy 135.423846 -298.4801) (xy 135.362544 -298.59822) (xy 135.294287 -298.712462)
			(xy 135.219321 -298.822418) (xy 135.137912 -298.927694) (xy 135.050354 -299.027912) (xy 134.956959 -299.122715)
			(xy 134.858061 -299.211763) (xy 134.754015 -299.294737) (xy 134.645193 -299.371341) (xy 134.531984 -299.441299)
			(xy 134.414794 -299.504361) (xy 134.294043 -299.560302) (xy 134.170162 -299.608922) (xy 134.043596 -299.650046)
			(xy 133.914796 -299.683527) (xy 133.784225 -299.709245) (xy 133.652349 -299.727109) (xy 133.519641 -299.737054)
			(xy 133.386576 -299.739045) (xy 133.25363 -299.733074) (xy 133.121279 -299.719164) (xy 132.989997 -299.697363)
			(xy 132.860254 -299.66775) (xy 132.732513 -299.630431) (xy 132.607234 -299.585539) (xy 132.484863 -299.533235)
			(xy 132.365839 -299.473706) (xy 132.250588 -299.407166) (xy 132.139523 -299.333853) (xy 132.033042 -299.254029)
			(xy 131.931524 -299.167979) (xy 131.835335 -299.076013) (xy 131.744817 -298.978458) (xy 131.660296 -298.875665)
			(xy 131.582074 -298.768001) (xy 131.51043 -298.655851) (xy 131.445621 -298.539618) (xy 131.38788 -298.419717)
			(xy 131.337413 -298.296578) (xy 131.2944 -298.170641) (xy 131.258996 -298.042356) (xy 131.231327 -297.912184)
			(xy 131.211492 -297.780591) (xy 131.199563 -297.648046) (xy 131.195582 -297.515026) (xy 122.90116 -297.515026)
			(xy 122.864295 -297.537525) (xy 122.812966 -297.559337) (xy 122.759009 -297.573443) (xy 122.703572 -297.579543)
			(xy 122.647838 -297.577506) (xy 122.592995 -297.567376) (xy 122.540211 -297.549369) (xy 122.490611 -297.523868)
			(xy 122.445253 -297.491417) (xy 122.405104 -297.452708) (xy 122.371018 -297.408565) (xy 122.343722 -297.35993)
			(xy 122.323799 -297.307839) (xy 122.311673 -297.253402) (xy 122.307602 -297.19778) (xy 117.778825 -297.19778)
			(xy 117.778825 -297.225052) (xy 117.771068 -297.279002) (xy 117.755712 -297.331298) (xy 117.733069 -297.380877)
			(xy 117.703601 -297.426728) (xy 117.667908 -297.467919) (xy 117.626715 -297.503611) (xy 117.580863 -297.533077)
			(xy 117.531283 -297.555717) (xy 117.478986 -297.571071) (xy 117.425036 -297.578826) (xy 117.397784 -297.579288)
			(xy 117.370413 -297.578834) (xy 117.316234 -297.571014) (xy 117.26373 -297.555522) (xy 117.213984 -297.532678)
			(xy 117.168017 -297.50295) (xy 117.147086 -297.485308) (xy 117.135758 -297.476072) (xy 117.109201 -297.463896)
			(xy 117.080284 -297.459723) (xy 117.051367 -297.463896) (xy 117.02481 -297.476072) (xy 117.013482 -297.485308)
			(xy 116.992549 -297.502949) (xy 116.946581 -297.532673) (xy 116.896835 -297.555519) (xy 116.844333 -297.571015)
			(xy 116.790155 -297.578844) (xy 116.735413 -297.578844) (xy 116.681235 -297.571015) (xy 116.628733 -297.555519)
			(xy 116.578987 -297.532673) (xy 116.533019 -297.502949) (xy 116.512086 -297.485308) (xy 116.500758 -297.476072)
			(xy 116.474201 -297.463896) (xy 116.445284 -297.459723) (xy 116.416367 -297.463896) (xy 116.38981 -297.476072)
			(xy 116.378482 -297.485308) (xy 116.357531 -297.502923) (xy 116.311563 -297.532638) (xy 116.26182 -297.555479)
			(xy 116.209324 -297.570976) (xy 116.155152 -297.57881) (xy 116.127784 -297.579288) (xy 116.100532 -297.578841)
			(xy 116.046583 -297.571082) (xy 115.994288 -297.555725) (xy 115.94471 -297.533082) (xy 115.898859 -297.503613)
			(xy 115.857669 -297.46792) (xy 115.821977 -297.426728) (xy 115.792511 -297.380876) (xy 115.769869 -297.331297)
			(xy 115.754514 -297.279001) (xy 115.746758 -297.225052) (xy 111.333825 -297.225052) (xy 111.326068 -297.279001)
			(xy 111.310712 -297.331297) (xy 111.28807 -297.380876) (xy 111.258602 -297.426727) (xy 111.222909 -297.467918)
			(xy 111.181717 -297.503609) (xy 111.135865 -297.533076) (xy 111.086286 -297.555716) (xy 111.033989 -297.57107)
			(xy 110.98004 -297.578826) (xy 110.952788 -297.579288) (xy 110.924747 -297.578811) (xy 110.869268 -297.570607)
			(xy 110.815585 -297.554378) (xy 110.764853 -297.530472) (xy 110.718163 -297.499404) (xy 110.69701 -297.48099)
			(xy 110.685568 -297.471345) (xy 110.658525 -297.458565) (xy 110.628938 -297.454179) (xy 110.599351 -297.458565)
			(xy 110.572308 -297.471345) (xy 110.560866 -297.48099) (xy 110.539705 -297.499398) (xy 110.493031 -297.530495)
			(xy 110.442303 -297.554413) (xy 110.388616 -297.570636) (xy 110.333131 -297.578813) (xy 110.305088 -297.579288)
			(xy 110.277047 -297.578811) (xy 110.221568 -297.570607) (xy 110.167885 -297.554378) (xy 110.117153 -297.530472)
			(xy 110.070463 -297.499404) (xy 110.04931 -297.48099) (xy 110.037868 -297.471345) (xy 110.010825 -297.458565)
			(xy 109.981238 -297.454179) (xy 109.951651 -297.458565) (xy 109.924608 -297.471345) (xy 109.913166 -297.48099)
			(xy 109.892005 -297.499398) (xy 109.845331 -297.530495) (xy 109.794603 -297.554413) (xy 109.740916 -297.570636)
			(xy 109.685431 -297.578813) (xy 109.657388 -297.579288) (xy 109.630136 -297.578841) (xy 109.576187 -297.571083)
			(xy 109.523891 -297.555726) (xy 109.474312 -297.533083) (xy 109.428461 -297.503615) (xy 109.38727 -297.467922)
			(xy 109.351578 -297.426729) (xy 109.322111 -297.380877) (xy 109.29947 -297.331298) (xy 109.284114 -297.279002)
			(xy 109.276358 -297.225052) (xy 104.626677 -297.225052) (xy 104.610407 -297.260681) (xy 104.58094 -297.306535)
			(xy 104.545248 -297.347729) (xy 104.504057 -297.383424) (xy 104.458206 -297.412894) (xy 104.408627 -297.435539)
			(xy 104.356331 -297.450898) (xy 104.302381 -297.458658) (xy 104.275128 -297.459146) (xy 104.246627 -297.458619)
			(xy 104.19026 -297.450131) (xy 104.135786 -297.433342) (xy 104.084421 -297.408625) (xy 104.037311 -297.376532)
			(xy 104.016048 -297.357546) (xy 104.004494 -297.347625) (xy 103.977059 -297.334442) (xy 103.94696 -297.329915)
			(xy 103.916861 -297.334442) (xy 103.889426 -297.347625) (xy 103.877872 -297.357546) (xy 103.856582 -297.376496)
			(xy 103.809462 -297.408558) (xy 103.758101 -297.433263) (xy 103.703641 -297.450065) (xy 103.647288 -297.458589)
			(xy 103.618792 -297.459146) (xy 103.591544 -297.458583) (xy 103.537602 -297.450827) (xy 103.485314 -297.435472)
			(xy 103.435743 -297.412833) (xy 103.389898 -297.383369) (xy 103.348713 -297.347682) (xy 103.313026 -297.306496)
			(xy 103.283563 -297.26065) (xy 103.260925 -297.211079) (xy 103.245572 -297.15879) (xy 103.237816 -297.104848)
			(xy 92.624896 -297.104848) (xy 92.639173 -297.183516) (xy 92.655062 -297.315644) (xy 92.66302 -297.448486)
			(xy 92.663518 -297.515026) (xy 92.66302 -297.581566) (xy 92.655062 -297.714408) (xy 92.639173 -297.846536)
			(xy 92.61541 -297.977477) (xy 92.58386 -298.106763) (xy 92.544634 -298.233931) (xy 92.497873 -298.358525)
			(xy 92.443744 -298.4801) (xy 92.382442 -298.59822) (xy 92.314185 -298.712462) (xy 92.239219 -298.822418)
			(xy 92.15781 -298.927694) (xy 92.070252 -299.027912) (xy 91.976857 -299.122715) (xy 91.877959 -299.211763)
			(xy 91.773913 -299.294737) (xy 91.665091 -299.371341) (xy 91.551882 -299.441299) (xy 91.434692 -299.504361)
			(xy 91.313941 -299.560302) (xy 91.19006 -299.608922) (xy 91.063494 -299.650046) (xy 90.934694 -299.683527)
			(xy 90.804123 -299.709245) (xy 90.672247 -299.727109) (xy 90.539539 -299.737054) (xy 90.406474 -299.739045)
			(xy 90.273528 -299.733074) (xy 90.141177 -299.719164) (xy 90.009895 -299.697363) (xy 89.880152 -299.66775)
			(xy 89.752411 -299.630431) (xy 89.627132 -299.585539) (xy 89.504761 -299.533235) (xy 89.385737 -299.473706)
			(xy 89.270486 -299.407166) (xy 89.159421 -299.333853) (xy 89.05294 -299.254029) (xy 88.951422 -299.167979)
			(xy 88.855233 -299.076013) (xy 88.764715 -298.978458) (xy 88.680194 -298.875665) (xy 88.601972 -298.768001)
			(xy 88.530328 -298.655851) (xy 88.465519 -298.539618) (xy 88.407778 -298.419717) (xy 88.357311 -298.296578)
			(xy 88.314298 -298.170641) (xy 88.278894 -298.042356) (xy 88.251225 -297.912184) (xy 88.23139 -297.780591)
			(xy 88.219461 -297.648046) (xy 88.21548 -297.515026) (xy 86.16188 -297.515026) (xy 86.16188 -312.918348)
			(xy 85.635279 -315.709738) (xy 97.636834 -315.709738) (xy 97.636834 -315.625042) (xy 97.644885 -315.540728)
			(xy 97.660914 -315.457562) (xy 97.684775 -315.376295) (xy 97.716254 -315.297665) (xy 97.755065 -315.222384)
			(xy 97.800855 -315.151132) (xy 97.853211 -315.084556) (xy 97.911659 -315.023258) (xy 97.975669 -314.967793)
			(xy 98.044661 -314.918664) (xy 98.118011 -314.876315) (xy 98.195054 -314.841131) (xy 98.275093 -314.813429)
			(xy 98.357402 -314.793461) (xy 98.441237 -314.781408) (xy 98.525838 -314.777378) (xy 98.610439 -314.781408)
			(xy 98.694274 -314.793461) (xy 98.776583 -314.813429) (xy 98.856622 -314.841131) (xy 98.933665 -314.876315)
			(xy 99.007015 -314.918664) (xy 99.076007 -314.967793) (xy 99.140017 -315.023258) (xy 99.198465 -315.084556)
			(xy 99.250821 -315.151132) (xy 99.296611 -315.222384) (xy 99.335422 -315.297665) (xy 99.366901 -315.376295)
			(xy 99.390762 -315.457562) (xy 99.406791 -315.540728) (xy 99.414842 -315.625042) (xy 99.415346 -315.66739)
			(xy 99.610423 -315.66739) (xy 99.614445 -315.58167) (xy 99.626476 -315.496702) (xy 99.646412 -315.413235)
			(xy 99.674075 -315.332001) (xy 99.709224 -315.253715) (xy 99.75155 -315.179064) (xy 99.800679 -315.108705)
			(xy 99.856182 -315.043255) (xy 99.917569 -314.983291) (xy 99.984302 -314.929338) (xy 100.055794 -314.881871)
			(xy 100.131416 -314.841307) (xy 100.210505 -314.808003) (xy 100.292365 -314.782251) (xy 100.376276 -314.764278)
			(xy 100.461502 -314.754242) (xy 100.547294 -314.75223) (xy 100.632896 -314.758261) (xy 100.717558 -314.772281)
			(xy 100.800535 -314.794167) (xy 100.881098 -314.823728) (xy 100.958538 -314.860702) (xy 101.032177 -314.904766)
			(xy 101.101365 -314.955532) (xy 101.165496 -315.012553) (xy 101.224005 -315.075329) (xy 101.276378 -315.143309)
			(xy 101.322156 -315.215894) (xy 101.360936 -315.292446) (xy 101.392377 -315.372294) (xy 101.416203 -315.454735)
			(xy 101.432204 -315.539045) (xy 101.440239 -315.624483) (xy 101.440742 -315.66739) (xy 101.440246 -315.709738)
			(xy 103.834434 -315.709738) (xy 103.834434 -315.625042) (xy 103.842485 -315.540728) (xy 103.858514 -315.457562)
			(xy 103.882375 -315.376295) (xy 103.913854 -315.297665) (xy 103.952665 -315.222384) (xy 103.998455 -315.151132)
			(xy 104.050811 -315.084556) (xy 104.109259 -315.023258) (xy 104.173269 -314.967793) (xy 104.242261 -314.918664)
			(xy 104.315611 -314.876315) (xy 104.392654 -314.841131) (xy 104.472693 -314.813429) (xy 104.555002 -314.793461)
			(xy 104.638837 -314.781408) (xy 104.723438 -314.777378) (xy 104.808039 -314.781408) (xy 104.891874 -314.793461)
			(xy 104.974183 -314.813429) (xy 105.054222 -314.841131) (xy 105.131265 -314.876315) (xy 105.204615 -314.918664)
			(xy 105.273607 -314.967793) (xy 105.337617 -315.023258) (xy 105.396065 -315.084556) (xy 105.448421 -315.151132)
			(xy 105.494211 -315.222384) (xy 105.533022 -315.297665) (xy 105.564501 -315.376295) (xy 105.588362 -315.457562)
			(xy 105.604391 -315.540728) (xy 105.612442 -315.625042) (xy 105.612946 -315.66739) (xy 105.808023 -315.66739)
			(xy 105.812045 -315.58167) (xy 105.824076 -315.496702) (xy 105.844012 -315.413235) (xy 105.871675 -315.332001)
			(xy 105.906824 -315.253715) (xy 105.94915 -315.179064) (xy 105.998279 -315.108705) (xy 106.053782 -315.043255)
			(xy 106.115169 -314.983291) (xy 106.181902 -314.929338) (xy 106.253394 -314.881871) (xy 106.329016 -314.841307)
			(xy 106.408105 -314.808003) (xy 106.489965 -314.782251) (xy 106.573876 -314.764278) (xy 106.659102 -314.754242)
			(xy 106.744894 -314.75223) (xy 106.830496 -314.758261) (xy 106.915158 -314.772281) (xy 106.998135 -314.794167)
			(xy 107.078698 -314.823728) (xy 107.156138 -314.860702) (xy 107.229777 -314.904766) (xy 107.298965 -314.955532)
			(xy 107.363096 -315.012553) (xy 107.421605 -315.075329) (xy 107.473978 -315.143309) (xy 107.519756 -315.215894)
			(xy 107.558536 -315.292446) (xy 107.589977 -315.372294) (xy 107.613803 -315.454735) (xy 107.629804 -315.539045)
			(xy 107.637839 -315.624483) (xy 107.638342 -315.66739) (xy 107.637846 -315.709738) (xy 110.012222 -315.709738)
			(xy 110.012222 -315.625042) (xy 110.020273 -315.540728) (xy 110.036302 -315.457562) (xy 110.060163 -315.376295)
			(xy 110.091642 -315.297665) (xy 110.130453 -315.222384) (xy 110.176243 -315.151132) (xy 110.228599 -315.084556)
			(xy 110.287047 -315.023258) (xy 110.351057 -314.967793) (xy 110.420049 -314.918664) (xy 110.493399 -314.876315)
			(xy 110.570442 -314.841131) (xy 110.650481 -314.813429) (xy 110.73279 -314.793461) (xy 110.816625 -314.781408)
			(xy 110.901226 -314.777378) (xy 110.985827 -314.781408) (xy 111.069662 -314.793461) (xy 111.151971 -314.813429)
			(xy 111.23201 -314.841131) (xy 111.309053 -314.876315) (xy 111.382403 -314.918664) (xy 111.451395 -314.967793)
			(xy 111.515405 -315.023258) (xy 111.573853 -315.084556) (xy 111.626209 -315.151132) (xy 111.671999 -315.222384)
			(xy 111.71081 -315.297665) (xy 111.742289 -315.376295) (xy 111.76615 -315.457562) (xy 111.782179 -315.540728)
			(xy 111.79023 -315.625042) (xy 111.790734 -315.66739) (xy 111.985811 -315.66739) (xy 111.989833 -315.58167)
			(xy 112.001864 -315.496702) (xy 112.0218 -315.413235) (xy 112.049463 -315.332001) (xy 112.084612 -315.253715)
			(xy 112.126938 -315.179064) (xy 112.176067 -315.108705) (xy 112.23157 -315.043255) (xy 112.292957 -314.983291)
			(xy 112.35969 -314.929338) (xy 112.431182 -314.881871) (xy 112.506804 -314.841307) (xy 112.585893 -314.808003)
			(xy 112.667753 -314.782251) (xy 112.751664 -314.764278) (xy 112.83689 -314.754242) (xy 112.922682 -314.75223)
			(xy 113.008284 -314.758261) (xy 113.092946 -314.772281) (xy 113.175923 -314.794167) (xy 113.256486 -314.823728)
			(xy 113.333926 -314.860702) (xy 113.407565 -314.904766) (xy 113.476753 -314.955532) (xy 113.540884 -315.012553)
			(xy 113.599393 -315.075329) (xy 113.651766 -315.143309) (xy 113.697544 -315.215894) (xy 113.736324 -315.292446)
			(xy 113.767765 -315.372294) (xy 113.791591 -315.454735) (xy 113.807592 -315.539045) (xy 113.815627 -315.624483)
			(xy 113.81613 -315.66739) (xy 113.815634 -315.709738) (xy 116.209822 -315.709738) (xy 116.209822 -315.625042)
			(xy 116.217873 -315.540728) (xy 116.233902 -315.457562) (xy 116.257763 -315.376295) (xy 116.289242 -315.297665)
			(xy 116.328053 -315.222384) (xy 116.373843 -315.151132) (xy 116.426199 -315.084556) (xy 116.484647 -315.023258)
			(xy 116.548657 -314.967793) (xy 116.617649 -314.918664) (xy 116.690999 -314.876315) (xy 116.768042 -314.841131)
			(xy 116.848081 -314.813429) (xy 116.93039 -314.793461) (xy 117.014225 -314.781408) (xy 117.098826 -314.777378)
			(xy 117.183427 -314.781408) (xy 117.267262 -314.793461) (xy 117.349571 -314.813429) (xy 117.42961 -314.841131)
			(xy 117.506653 -314.876315) (xy 117.580003 -314.918664) (xy 117.648995 -314.967793) (xy 117.713005 -315.023258)
			(xy 117.771453 -315.084556) (xy 117.823809 -315.151132) (xy 117.869599 -315.222384) (xy 117.90841 -315.297665)
			(xy 117.939889 -315.376295) (xy 117.96375 -315.457562) (xy 117.979779 -315.540728) (xy 117.98783 -315.625042)
			(xy 117.988334 -315.66739) (xy 118.183411 -315.66739) (xy 118.187433 -315.58167) (xy 118.199464 -315.496702)
			(xy 118.2194 -315.413235) (xy 118.247063 -315.332001) (xy 118.282212 -315.253715) (xy 118.324538 -315.179064)
			(xy 118.373667 -315.108705) (xy 118.42917 -315.043255) (xy 118.490557 -314.983291) (xy 118.55729 -314.929338)
			(xy 118.628782 -314.881871) (xy 118.704404 -314.841307) (xy 118.783493 -314.808003) (xy 118.865353 -314.782251)
			(xy 118.949264 -314.764278) (xy 119.03449 -314.754242) (xy 119.120282 -314.75223) (xy 119.205884 -314.758261)
			(xy 119.290546 -314.772281) (xy 119.373523 -314.794167) (xy 119.454086 -314.823728) (xy 119.531526 -314.860702)
			(xy 119.605165 -314.904766) (xy 119.674353 -314.955532) (xy 119.738484 -315.012553) (xy 119.796993 -315.075329)
			(xy 119.849366 -315.143309) (xy 119.895144 -315.215894) (xy 119.933924 -315.292446) (xy 119.965365 -315.372294)
			(xy 119.989191 -315.454735) (xy 120.005192 -315.539045) (xy 120.013227 -315.624483) (xy 120.01373 -315.66739)
			(xy 120.013234 -315.709738) (xy 122.407422 -315.709738) (xy 122.407422 -315.625042) (xy 122.415473 -315.540728)
			(xy 122.431502 -315.457562) (xy 122.455363 -315.376295) (xy 122.486842 -315.297665) (xy 122.525653 -315.222384)
			(xy 122.571443 -315.151132) (xy 122.623799 -315.084556) (xy 122.682247 -315.023258) (xy 122.746257 -314.967793)
			(xy 122.815249 -314.918664) (xy 122.888599 -314.876315) (xy 122.965642 -314.841131) (xy 123.045681 -314.813429)
			(xy 123.12799 -314.793461) (xy 123.211825 -314.781408) (xy 123.296426 -314.777378) (xy 123.381027 -314.781408)
			(xy 123.464862 -314.793461) (xy 123.547171 -314.813429) (xy 123.62721 -314.841131) (xy 123.704253 -314.876315)
			(xy 123.777603 -314.918664) (xy 123.846595 -314.967793) (xy 123.910605 -315.023258) (xy 123.969053 -315.084556)
			(xy 124.021409 -315.151132) (xy 124.067199 -315.222384) (xy 124.10601 -315.297665) (xy 124.137489 -315.376295)
			(xy 124.16135 -315.457562) (xy 124.177379 -315.540728) (xy 124.18543 -315.625042) (xy 124.185934 -315.66739)
			(xy 124.381011 -315.66739) (xy 124.385033 -315.58167) (xy 124.397064 -315.496702) (xy 124.417 -315.413235)
			(xy 124.444663 -315.332001) (xy 124.479812 -315.253715) (xy 124.522138 -315.179064) (xy 124.571267 -315.108705)
			(xy 124.62677 -315.043255) (xy 124.688157 -314.983291) (xy 124.75489 -314.929338) (xy 124.826382 -314.881871)
			(xy 124.902004 -314.841307) (xy 124.981093 -314.808003) (xy 125.062953 -314.782251) (xy 125.146864 -314.764278)
			(xy 125.23209 -314.754242) (xy 125.317882 -314.75223) (xy 125.403484 -314.758261) (xy 125.488146 -314.772281)
			(xy 125.571123 -314.794167) (xy 125.651686 -314.823728) (xy 125.729126 -314.860702) (xy 125.802765 -314.904766)
			(xy 125.871953 -314.955532) (xy 125.936084 -315.012553) (xy 125.994593 -315.075329) (xy 126.046966 -315.143309)
			(xy 126.092744 -315.215894) (xy 126.131524 -315.292446) (xy 126.162965 -315.372294) (xy 126.186791 -315.454735)
			(xy 126.202792 -315.539045) (xy 126.210827 -315.624483) (xy 126.21133 -315.66739) (xy 126.210827 -315.710297)
			(xy 126.202792 -315.795735) (xy 126.186791 -315.880045) (xy 126.162965 -315.962486) (xy 126.131524 -316.042334)
			(xy 126.092744 -316.118886) (xy 126.046966 -316.191471) (xy 125.994593 -316.259451) (xy 125.936084 -316.322227)
			(xy 125.871953 -316.379248) (xy 125.802765 -316.430014) (xy 125.729126 -316.474078) (xy 125.651686 -316.511052)
			(xy 125.571123 -316.540613) (xy 125.488146 -316.562499) (xy 125.403484 -316.576519) (xy 125.317882 -316.58255)
			(xy 125.23209 -316.580538) (xy 125.146864 -316.570502) (xy 125.062953 -316.552529) (xy 124.981093 -316.526777)
			(xy 124.902004 -316.493473) (xy 124.826382 -316.452909) (xy 124.75489 -316.405442) (xy 124.688157 -316.351489)
			(xy 124.62677 -316.291525) (xy 124.571267 -316.226075) (xy 124.522138 -316.155716) (xy 124.479812 -316.081065)
			(xy 124.444663 -316.002779) (xy 124.417 -315.921545) (xy 124.397064 -315.838078) (xy 124.385033 -315.75311)
			(xy 124.381011 -315.66739) (xy 124.185934 -315.66739) (xy 124.18543 -315.709738) (xy 124.177379 -315.794052)
			(xy 124.16135 -315.877218) (xy 124.137489 -315.958485) (xy 124.10601 -316.037115) (xy 124.067199 -316.112396)
			(xy 124.021409 -316.183648) (xy 123.969053 -316.250224) (xy 123.910605 -316.311522) (xy 123.846595 -316.366987)
			(xy 123.777603 -316.416116) (xy 123.704253 -316.458465) (xy 123.62721 -316.493649) (xy 123.547171 -316.521351)
			(xy 123.464862 -316.541319) (xy 123.381027 -316.553372) (xy 123.296426 -316.557403) (xy 123.211825 -316.553372)
			(xy 123.12799 -316.541319) (xy 123.045681 -316.521351) (xy 122.965642 -316.493649) (xy 122.888599 -316.458465)
			(xy 122.815249 -316.416116) (xy 122.746257 -316.366987) (xy 122.682247 -316.311522) (xy 122.623799 -316.250224)
			(xy 122.571443 -316.183648) (xy 122.525653 -316.112396) (xy 122.486842 -316.037115) (xy 122.455363 -315.958485)
			(xy 122.431502 -315.877218) (xy 122.415473 -315.794052) (xy 122.407422 -315.709738) (xy 120.013234 -315.709738)
			(xy 120.013227 -315.710297) (xy 120.005192 -315.795735) (xy 119.989191 -315.880045) (xy 119.965365 -315.962486)
			(xy 119.933924 -316.042334) (xy 119.895144 -316.118886) (xy 119.849366 -316.191471) (xy 119.796993 -316.259451)
			(xy 119.738484 -316.322227) (xy 119.674353 -316.379248) (xy 119.605165 -316.430014) (xy 119.531526 -316.474078)
			(xy 119.454086 -316.511052) (xy 119.373523 -316.540613) (xy 119.290546 -316.562499) (xy 119.205884 -316.576519)
			(xy 119.120282 -316.58255) (xy 119.03449 -316.580538) (xy 118.949264 -316.570502) (xy 118.865353 -316.552529)
			(xy 118.783493 -316.526777) (xy 118.704404 -316.493473) (xy 118.628782 -316.452909) (xy 118.55729 -316.405442)
			(xy 118.490557 -316.351489) (xy 118.42917 -316.291525) (xy 118.373667 -316.226075) (xy 118.324538 -316.155716)
			(xy 118.282212 -316.081065) (xy 118.247063 -316.002779) (xy 118.2194 -315.921545) (xy 118.199464 -315.838078)
			(xy 118.187433 -315.75311) (xy 118.183411 -315.66739) (xy 117.988334 -315.66739) (xy 117.98783 -315.709738)
			(xy 117.979779 -315.794052) (xy 117.96375 -315.877218) (xy 117.939889 -315.958485) (xy 117.90841 -316.037115)
			(xy 117.869599 -316.112396) (xy 117.823809 -316.183648) (xy 117.771453 -316.250224) (xy 117.713005 -316.311522)
			(xy 117.648995 -316.366987) (xy 117.580003 -316.416116) (xy 117.506653 -316.458465) (xy 117.42961 -316.493649)
			(xy 117.349571 -316.521351) (xy 117.267262 -316.541319) (xy 117.183427 -316.553372) (xy 117.098826 -316.557403)
			(xy 117.014225 -316.553372) (xy 116.93039 -316.541319) (xy 116.848081 -316.521351) (xy 116.768042 -316.493649)
			(xy 116.690999 -316.458465) (xy 116.617649 -316.416116) (xy 116.548657 -316.366987) (xy 116.484647 -316.311522)
			(xy 116.426199 -316.250224) (xy 116.373843 -316.183648) (xy 116.328053 -316.112396) (xy 116.289242 -316.037115)
			(xy 116.257763 -315.958485) (xy 116.233902 -315.877218) (xy 116.217873 -315.794052) (xy 116.209822 -315.709738)
			(xy 113.815634 -315.709738) (xy 113.815627 -315.710297) (xy 113.807592 -315.795735) (xy 113.791591 -315.880045)
			(xy 113.767765 -315.962486) (xy 113.736324 -316.042334) (xy 113.697544 -316.118886) (xy 113.651766 -316.191471)
			(xy 113.599393 -316.259451) (xy 113.540884 -316.322227) (xy 113.476753 -316.379248) (xy 113.407565 -316.430014)
			(xy 113.333926 -316.474078) (xy 113.256486 -316.511052) (xy 113.175923 -316.540613) (xy 113.092946 -316.562499)
			(xy 113.008284 -316.576519) (xy 112.922682 -316.58255) (xy 112.83689 -316.580538) (xy 112.751664 -316.570502)
			(xy 112.667753 -316.552529) (xy 112.585893 -316.526777) (xy 112.506804 -316.493473) (xy 112.431182 -316.452909)
			(xy 112.35969 -316.405442) (xy 112.292957 -316.351489) (xy 112.23157 -316.291525) (xy 112.176067 -316.226075)
			(xy 112.126938 -316.155716) (xy 112.084612 -316.081065) (xy 112.049463 -316.002779) (xy 112.0218 -315.921545)
			(xy 112.001864 -315.838078) (xy 111.989833 -315.75311) (xy 111.985811 -315.66739) (xy 111.790734 -315.66739)
			(xy 111.79023 -315.709738) (xy 111.782179 -315.794052) (xy 111.76615 -315.877218) (xy 111.742289 -315.958485)
			(xy 111.71081 -316.037115) (xy 111.671999 -316.112396) (xy 111.626209 -316.183648) (xy 111.573853 -316.250224)
			(xy 111.515405 -316.311522) (xy 111.451395 -316.366987) (xy 111.382403 -316.416116) (xy 111.309053 -316.458465)
			(xy 111.23201 -316.493649) (xy 111.151971 -316.521351) (xy 111.069662 -316.541319) (xy 110.985827 -316.553372)
			(xy 110.901226 -316.557403) (xy 110.816625 -316.553372) (xy 110.73279 -316.541319) (xy 110.650481 -316.521351)
			(xy 110.570442 -316.493649) (xy 110.493399 -316.458465) (xy 110.420049 -316.416116) (xy 110.351057 -316.366987)
			(xy 110.287047 -316.311522) (xy 110.228599 -316.250224) (xy 110.176243 -316.183648) (xy 110.130453 -316.112396)
			(xy 110.091642 -316.037115) (xy 110.060163 -315.958485) (xy 110.036302 -315.877218) (xy 110.020273 -315.794052)
			(xy 110.012222 -315.709738) (xy 107.637846 -315.709738) (xy 107.637839 -315.710297) (xy 107.629804 -315.795735)
			(xy 107.613803 -315.880045) (xy 107.589977 -315.962486) (xy 107.558536 -316.042334) (xy 107.519756 -316.118886)
			(xy 107.473978 -316.191471) (xy 107.421605 -316.259451) (xy 107.363096 -316.322227) (xy 107.298965 -316.379248)
			(xy 107.229777 -316.430014) (xy 107.156138 -316.474078) (xy 107.078698 -316.511052) (xy 106.998135 -316.540613)
			(xy 106.915158 -316.562499) (xy 106.830496 -316.576519) (xy 106.744894 -316.58255) (xy 106.659102 -316.580538)
			(xy 106.573876 -316.570502) (xy 106.489965 -316.552529) (xy 106.408105 -316.526777) (xy 106.329016 -316.493473)
			(xy 106.253394 -316.452909) (xy 106.181902 -316.405442) (xy 106.115169 -316.351489) (xy 106.053782 -316.291525)
			(xy 105.998279 -316.226075) (xy 105.94915 -316.155716) (xy 105.906824 -316.081065) (xy 105.871675 -316.002779)
			(xy 105.844012 -315.921545) (xy 105.824076 -315.838078) (xy 105.812045 -315.75311) (xy 105.808023 -315.66739)
			(xy 105.612946 -315.66739) (xy 105.612442 -315.709738) (xy 105.604391 -315.794052) (xy 105.588362 -315.877218)
			(xy 105.564501 -315.958485) (xy 105.533022 -316.037115) (xy 105.494211 -316.112396) (xy 105.448421 -316.183648)
			(xy 105.396065 -316.250224) (xy 105.337617 -316.311522) (xy 105.273607 -316.366987) (xy 105.204615 -316.416116)
			(xy 105.131265 -316.458465) (xy 105.054222 -316.493649) (xy 104.974183 -316.521351) (xy 104.891874 -316.541319)
			(xy 104.808039 -316.553372) (xy 104.723438 -316.557403) (xy 104.638837 -316.553372) (xy 104.555002 -316.541319)
			(xy 104.472693 -316.521351) (xy 104.392654 -316.493649) (xy 104.315611 -316.458465) (xy 104.242261 -316.416116)
			(xy 104.173269 -316.366987) (xy 104.109259 -316.311522) (xy 104.050811 -316.250224) (xy 103.998455 -316.183648)
			(xy 103.952665 -316.112396) (xy 103.913854 -316.037115) (xy 103.882375 -315.958485) (xy 103.858514 -315.877218)
			(xy 103.842485 -315.794052) (xy 103.834434 -315.709738) (xy 101.440246 -315.709738) (xy 101.440239 -315.710297)
			(xy 101.432204 -315.795735) (xy 101.416203 -315.880045) (xy 101.392377 -315.962486) (xy 101.360936 -316.042334)
			(xy 101.322156 -316.118886) (xy 101.276378 -316.191471) (xy 101.224005 -316.259451) (xy 101.165496 -316.322227)
			(xy 101.101365 -316.379248) (xy 101.032177 -316.430014) (xy 100.958538 -316.474078) (xy 100.881098 -316.511052)
			(xy 100.800535 -316.540613) (xy 100.717558 -316.562499) (xy 100.632896 -316.576519) (xy 100.547294 -316.58255)
			(xy 100.461502 -316.580538) (xy 100.376276 -316.570502) (xy 100.292365 -316.552529) (xy 100.210505 -316.526777)
			(xy 100.131416 -316.493473) (xy 100.055794 -316.452909) (xy 99.984302 -316.405442) (xy 99.917569 -316.351489)
			(xy 99.856182 -316.291525) (xy 99.800679 -316.226075) (xy 99.75155 -316.155716) (xy 99.709224 -316.081065)
			(xy 99.674075 -316.002779) (xy 99.646412 -315.921545) (xy 99.626476 -315.838078) (xy 99.614445 -315.75311)
			(xy 99.610423 -315.66739) (xy 99.415346 -315.66739) (xy 99.414842 -315.709738) (xy 99.406791 -315.794052)
			(xy 99.390762 -315.877218) (xy 99.366901 -315.958485) (xy 99.335422 -316.037115) (xy 99.296611 -316.112396)
			(xy 99.250821 -316.183648) (xy 99.198465 -316.250224) (xy 99.140017 -316.311522) (xy 99.076007 -316.366987)
			(xy 99.007015 -316.416116) (xy 98.933665 -316.458465) (xy 98.856622 -316.493649) (xy 98.776583 -316.521351)
			(xy 98.694274 -316.541319) (xy 98.610439 -316.553372) (xy 98.525838 -316.557403) (xy 98.441237 -316.553372)
			(xy 98.357402 -316.541319) (xy 98.275093 -316.521351) (xy 98.195054 -316.493649) (xy 98.118011 -316.458465)
			(xy 98.044661 -316.416116) (xy 97.975669 -316.366987) (xy 97.911659 -316.311522) (xy 97.853211 -316.250224)
			(xy 97.800855 -316.183648) (xy 97.755065 -316.112396) (xy 97.716254 -316.037115) (xy 97.684775 -315.958485)
			(xy 97.660914 -315.877218) (xy 97.644885 -315.794052) (xy 97.636834 -315.709738) (xy 85.635279 -315.709738)
			(xy 84.433156 -322.081906) (xy 84.05368 -323.433948) (xy 80.37068 -328.285348) (xy 80.37068 -332.451202)
			(xy 80.67548 -332.756002) (xy 83.831176 -332.756002)
		)
		(stroke
			(width 0)
			(type solid)
		)
		(fill yes)
		(layer "In15.Cu")
		(net "PVCCIN_CPU1")
	)
	(gr_poly
		(pts
			(xy 332.378812 -331.909166) (xy 332.393544 -331.89418) (xy 332.393544 -330.858876) (xy 332.393973 -330.848809)
			(xy 332.401698 -330.830215) (xy 332.40853 -330.822808) (xy 334.193388 -329.03795) (xy 334.200783 -329.031096)
			(xy 334.219382 -329.02335) (xy 334.229456 -329.022964) (xy 339.780372 -329.022964) (xy 339.790333 -329.022476)
			(xy 339.808752 -329.014883) (xy 339.816186 -329.008232) (xy 343.032588 -325.79183) (xy 343.039985 -325.784979)
			(xy 343.058583 -325.777235) (xy 343.068656 -325.776844) (xy 371.907816 -325.776844) (xy 371.917884 -325.777271)
			(xy 371.93648 -325.784995) (xy 371.943884 -325.79183) (xy 372.015512 -325.863458) (xy 372.015766 -325.863458)
			(xy 372.10492 -325.952612) (xy 372.104666 -325.952612) (xy 375.336054 -329.184) (xy 375.35104 -329.198732)
			(xy 379.937264 -329.198732) (xy 379.947328 -329.199167) (xy 379.965913 -329.206902) (xy 379.973332 -329.213718)
			(xy 381.713232 -330.953364) (xy 382.003808 -331.24394) (xy 382.018794 -331.258672) (xy 387.854444 -331.258672)
			(xy 388.34568 -330.767436) (xy 388.34568 -327.040748) (xy 385.485386 -311.65546) (xy 385.265676 -310.74741)
			(xy 385.256806 -310.709273) (xy 385.244399 -310.631956) (xy 385.238155 -310.553899) (xy 385.237736 -310.514746)
			(xy 385.239006 -310.466486) (xy 385.2418 -310.407558) (xy 385.24434 -310.358536) (xy 385.19608 -310.098948)
			(xy 385.19608 -291.328348) (xy 383.97688 -290.109148) (xy 383.32029 -290.109148) (xy 383.310892 -290.112958)
			(xy 383.290877 -290.120836) (xy 383.249318 -290.131925) (xy 383.206669 -290.137515) (xy 383.185162 -290.13785)
			(xy 383.163657 -290.137487) (xy 383.121013 -290.131887) (xy 383.07945 -290.120824) (xy 383.059432 -290.112958)
			(xy 383.050034 -290.109148) (xy 382.38049 -290.109148) (xy 382.371092 -290.112958) (xy 382.351077 -290.120836)
			(xy 382.309518 -290.131925) (xy 382.266869 -290.137515) (xy 382.245362 -290.13785) (xy 382.223857 -290.137487)
			(xy 382.181213 -290.131887) (xy 382.13965 -290.120824) (xy 382.119632 -290.112958) (xy 382.110234 -290.109148)
			(xy 381.494538 -290.109148) (xy 381.473197 -290.121994) (xy 381.427688 -290.142245) (xy 381.3798 -290.155953)
			(xy 381.330468 -290.162851) (xy 381.305562 -290.16325) (xy 381.280656 -290.162853) (xy 381.231324 -290.155952)
			(xy 381.183433 -290.142248) (xy 381.137919 -290.122008) (xy 381.116586 -290.109148) (xy 380.554738 -290.109148)
			(xy 380.533397 -290.121994) (xy 380.487888 -290.142245) (xy 380.44 -290.155953) (xy 380.390668 -290.162851)
			(xy 380.365762 -290.16325) (xy 380.340856 -290.162853) (xy 380.291524 -290.155952) (xy 380.243633 -290.142248)
			(xy 380.198119 -290.122008) (xy 380.176786 -290.109148) (xy 379.614938 -290.109148) (xy 379.593597 -290.121994)
			(xy 379.548088 -290.142245) (xy 379.5002 -290.155953) (xy 379.450868 -290.162851) (xy 379.425962 -290.16325)
			(xy 379.401056 -290.162853) (xy 379.351724 -290.155952) (xy 379.303833 -290.142248) (xy 379.258319 -290.122008)
			(xy 379.236986 -290.109148) (xy 378.675138 -290.109148) (xy 378.653797 -290.121994) (xy 378.608288 -290.142245)
			(xy 378.5604 -290.155953) (xy 378.511068 -290.162851) (xy 378.486162 -290.16325) (xy 378.461256 -290.162853)
			(xy 378.411924 -290.155952) (xy 378.364033 -290.142248) (xy 378.318519 -290.122008) (xy 378.297186 -290.109148)
			(xy 377.735338 -290.109148) (xy 377.713997 -290.121994) (xy 377.668488 -290.142245) (xy 377.6206 -290.155953)
			(xy 377.571268 -290.162851) (xy 377.546362 -290.16325) (xy 377.521456 -290.162853) (xy 377.472124 -290.155952)
			(xy 377.424233 -290.142248) (xy 377.378719 -290.122008) (xy 377.357386 -290.109148) (xy 376.795538 -290.109148)
			(xy 376.774197 -290.121994) (xy 376.728688 -290.142245) (xy 376.6808 -290.155953) (xy 376.631468 -290.162851)
			(xy 376.606562 -290.16325) (xy 376.581656 -290.162853) (xy 376.532324 -290.155952) (xy 376.484433 -290.142248)
			(xy 376.438919 -290.122008) (xy 376.417586 -290.109148) (xy 375.855738 -290.109148) (xy 375.834397 -290.121994)
			(xy 375.788888 -290.142245) (xy 375.741 -290.155953) (xy 375.691668 -290.162851) (xy 375.666762 -290.16325)
			(xy 375.641856 -290.162853) (xy 375.592524 -290.155952) (xy 375.544633 -290.142248) (xy 375.499119 -290.122008)
			(xy 375.477786 -290.109148) (xy 374.915938 -290.109148) (xy 374.894597 -290.121994) (xy 374.849088 -290.142245)
			(xy 374.8012 -290.155953) (xy 374.751868 -290.162851) (xy 374.726962 -290.16325) (xy 374.702056 -290.162853)
			(xy 374.652724 -290.155952) (xy 374.604833 -290.142248) (xy 374.559319 -290.122008) (xy 374.537986 -290.109148)
			(xy 373.976138 -290.109148) (xy 373.954797 -290.121994) (xy 373.909288 -290.142245) (xy 373.8614 -290.155953)
			(xy 373.812068 -290.162851) (xy 373.787162 -290.16325) (xy 373.762256 -290.162853) (xy 373.712924 -290.155952)
			(xy 373.665033 -290.142248) (xy 373.619519 -290.122008) (xy 373.598186 -290.109148) (xy 373.036338 -290.109148)
			(xy 373.014997 -290.121994) (xy 372.969488 -290.142245) (xy 372.9216 -290.155953) (xy 372.872268 -290.162851)
			(xy 372.847362 -290.16325) (xy 372.822456 -290.162853) (xy 372.773124 -290.155952) (xy 372.725233 -290.142248)
			(xy 372.679719 -290.122008) (xy 372.658386 -290.109148) (xy 372.096538 -290.109148) (xy 372.075197 -290.121994)
			(xy 372.029688 -290.142245) (xy 371.9818 -290.155953) (xy 371.932468 -290.162851) (xy 371.907562 -290.16325)
			(xy 371.882656 -290.162853) (xy 371.833324 -290.155952) (xy 371.785433 -290.142248) (xy 371.739919 -290.122008)
			(xy 371.718586 -290.109148) (xy 371.42928 -290.109148) (xy 371.371114 -290.050982) (xy 371.361382 -290.041816)
			(xy 371.338229 -290.028465) (xy 371.312407 -290.021574) (xy 371.28568 -290.021616) (xy 371.259879 -290.028586)
			(xy 371.236768 -290.042008) (xy 371.227096 -290.051236) (xy 371.206756 -290.072007) (xy 371.160567 -290.107302)
			(xy 371.109257 -290.134623) (xy 371.054189 -290.153242) (xy 370.996828 -290.162666) (xy 370.967762 -290.16325)
			(xy 370.93978 -290.162698) (xy 370.884505 -290.153939) (xy 370.83128 -290.136641) (xy 370.781416 -290.111232)
			(xy 370.73614 -290.078336) (xy 370.696567 -290.038763) (xy 370.66367 -289.993487) (xy 370.63826 -289.943624)
			(xy 370.620962 -289.890399) (xy 370.612202 -289.835124) (xy 370.611654 -289.807142) (xy 370.612233 -289.778078)
			(xy 370.621677 -289.720722) (xy 370.640305 -289.665659) (xy 370.667622 -289.61435) (xy 370.702905 -289.568154)
			(xy 370.723668 -289.547808) (xy 370.732861 -289.538109) (xy 370.746277 -289.515007) (xy 370.753245 -289.489217)
			(xy 370.753287 -289.462502) (xy 370.746401 -289.43669) (xy 370.733056 -289.413546) (xy 370.723922 -289.40379)
			(xy 370.583968 -289.263836) (xy 370.55806 -289.268154) (xy 370.544852 -289.270186) (xy 370.518944 -289.273742)
			(xy 370.479574 -289.34791) (xy 370.334032 -289.623246) (xy 370.34597 -289.646614) (xy 370.357753 -289.671149)
			(xy 370.374562 -289.722914) (xy 370.383301 -289.776633) (xy 370.38407 -289.80384) (xy 370.38407 -289.812476)
			(xy 370.383131 -289.840187) (xy 370.373728 -289.894827) (xy 370.35597 -289.94735) (xy 370.330286 -289.996485)
			(xy 370.297298 -290.041047) (xy 370.257803 -290.079958) (xy 370.212753 -290.112277) (xy 370.16324 -290.137225)
			(xy 370.110458 -290.154197) (xy 370.055684 -290.162784) (xy 370.027962 -290.16325) (xy 369.99998 -290.162698)
			(xy 369.944705 -290.153939) (xy 369.89148 -290.136641) (xy 369.841616 -290.111232) (xy 369.79634 -290.078336)
			(xy 369.756767 -290.038763) (xy 369.72387 -289.993487) (xy 369.69846 -289.943624) (xy 369.681162 -289.890399)
			(xy 369.672402 -289.835124) (xy 369.671854 -289.807142) (xy 369.672304 -289.781506) (xy 369.679665 -289.730766)
			(xy 369.694225 -289.681605) (xy 369.715685 -289.635041) (xy 369.7436 -289.592034) (xy 369.777393 -289.553476)
			(xy 369.816367 -289.520162) (xy 369.859715 -289.49278) (xy 369.906541 -289.471898) (xy 369.955878 -289.457946)
			(xy 369.981226 -289.454082) (xy 370.007134 -289.450526) (xy 370.046504 -289.376358) (xy 370.192046 -289.101022)
			(xy 370.180108 -289.077654) (xy 370.175746 -289.068893) (xy 370.167869 -289.050976) (xy 370.16436 -289.04184)
			(xy 370.153184 -289.012376) (xy 369.903248 -289.012376) (xy 369.890802 -289.044888) (xy 369.880737 -289.069748)
			(xy 369.854219 -289.116365) (xy 369.821009 -289.158476) (xy 369.781856 -289.195128) (xy 369.737648 -289.225492)
			(xy 369.689386 -289.24888) (xy 369.63816 -289.264763) (xy 369.585132 -289.272782) (xy 369.558316 -289.273234)
			(xy 369.532422 -289.272777) (xy 369.48118 -289.265288) (xy 369.431563 -289.250453) (xy 369.38462 -289.228585)
			(xy 369.341342 -289.200144) (xy 369.302642 -289.165732) (xy 369.269338 -289.126075) (xy 369.242132 -289.08201)
			(xy 369.221599 -289.034467) (xy 369.208173 -288.984451) (xy 369.204748 -288.958782) (xy 369.203224 -288.947352)
			(xy 369.201954 -288.917126) (xy 369.202317 -288.893839) (xy 369.208354 -288.847658) (xy 369.220354 -288.802656)
			(xy 369.228878 -288.780982) (xy 369.23853 -288.757868) (xy 369.171982 -288.642552) (xy 369.066064 -288.459418)
			(xy 369.041426 -288.456116) (xy 369.016083 -288.452293) (xy 368.966773 -288.438315) (xy 368.919977 -288.417412)
			(xy 368.876662 -288.390015) (xy 368.837724 -288.356689) (xy 368.803966 -288.318125) (xy 368.776087 -288.275118)
			(xy 368.754663 -288.228559) (xy 368.740136 -288.179408) (xy 368.732807 -288.128682) (xy 368.732308 -288.103056)
			(xy 368.73277 -288.076888) (xy 368.74042 -288.025114) (xy 368.747548 -287.999932) (xy 368.756438 -287.970722)
			(xy 368.174778 -287.389062) (xy 368.164292 -287.379312) (xy 368.139199 -287.365546) (xy 368.111272 -287.359282)
			(xy 368.082703 -287.361012) (xy 368.055736 -287.3706) (xy 368.032487 -287.387293) (xy 368.014782 -287.409781)
			(xy 368.008916 -287.422844) (xy 367.998545 -287.447145) (xy 367.971681 -287.492639) (xy 367.938396 -287.533669)
			(xy 367.899419 -287.569337) (xy 367.855604 -287.598861) (xy 367.807911 -287.621593) (xy 367.757385 -287.637036)
			(xy 367.705133 -287.644852) (xy 367.678716 -287.645348) (xy 367.650731 -287.6448) (xy 367.595449 -287.636047)
			(xy 367.542218 -287.618755) (xy 367.492346 -287.593348) (xy 367.447063 -287.560453) (xy 367.407483 -287.520879)
			(xy 367.374581 -287.475601) (xy 367.349167 -287.425734) (xy 367.331866 -287.372505) (xy 367.323104 -287.317225)
			(xy 367.322608 -287.28924) (xy 367.323085 -287.262821) (xy 367.330885 -287.210561) (xy 367.34632 -287.160027)
			(xy 367.36905 -287.112327) (xy 367.398578 -287.068509) (xy 367.434255 -287.029534) (xy 367.475298 -286.996257)
			(xy 367.520807 -286.969408) (xy 367.545112 -286.95904) (xy 367.558224 -286.953232) (xy 367.580784 -286.935549)
			(xy 367.597535 -286.912287) (xy 367.607152 -286.885284) (xy 367.608877 -286.856671) (xy 367.602573 -286.828708)
			(xy 367.588738 -286.803603) (xy 367.578894 -286.793178) (xy 367.487708 -286.702246) (xy 367.451894 -286.735774)
			(xy 367.431994 -286.753675) (xy 367.387828 -286.783913) (xy 367.339637 -286.807204) (xy 367.288503 -286.823025)
			(xy 367.235579 -286.831019) (xy 367.208816 -286.831532) (xy 367.180831 -286.830984) (xy 367.125551 -286.822231)
			(xy 367.07232 -286.804939) (xy 367.02245 -286.779532) (xy 366.977168 -286.746636) (xy 366.93759 -286.707062)
			(xy 366.904689 -286.661784) (xy 366.879277 -286.611917) (xy 366.861978 -286.558688) (xy 366.853219 -286.503409)
			(xy 366.852708 -286.475424) (xy 366.853232 -286.44782) (xy 366.86176 -286.393274) (xy 366.878599 -286.340697)
			(xy 366.903346 -286.291346) (xy 366.93541 -286.246403) (xy 366.974022 -286.206944) (xy 367.018259 -286.173913)
			(xy 367.067062 -286.148101) (xy 367.119262 -286.130125) (xy 367.173609 -286.120416) (xy 367.201196 -286.119316)
			(xy 367.215696 -286.11786) (xy 367.243022 -286.107766) (xy 367.266392 -286.090374) (xy 367.283907 -286.067097)
			(xy 367.294145 -286.039825) (xy 367.296275 -286.010772) (xy 367.290124 -285.982298) (xy 367.276191 -285.956715)
			(xy 367.26622 -285.946088) (xy 367.180114 -285.859982) (xy 367.16949 -285.850004) (xy 367.143927 -285.836025)
			(xy 367.115461 -285.829815) (xy 367.086399 -285.831877) (xy 367.059095 -285.842044) (xy 367.035762 -285.859492)
			(xy 367.026698 -285.870904) (xy 367.009817 -285.893185) (xy 366.970277 -285.932695) (xy 366.925046 -285.965536)
			(xy 366.875236 -285.990902) (xy 366.822073 -286.008169) (xy 366.766864 -286.016911) (xy 366.738916 -286.017462)
			(xy 366.710931 -286.016943) (xy 366.65565 -286.008189) (xy 366.60242 -285.990894) (xy 366.552551 -285.965483)
			(xy 366.507271 -285.932584) (xy 366.467696 -285.893006) (xy 366.434801 -285.847724) (xy 366.409395 -285.797852)
			(xy 366.392104 -285.74462) (xy 366.383355 -285.689339) (xy 366.382808 -285.661354) (xy 366.383352 -285.633404)
			(xy 366.392085 -285.57819) (xy 366.409347 -285.525021) (xy 366.43471 -285.475207) (xy 366.467553 -285.429971)
			(xy 366.507065 -285.390429) (xy 366.529366 -285.373572) (xy 366.540783 -285.364496) (xy 366.558306 -285.341195)
			(xy 366.568517 -285.313887) (xy 366.570582 -285.284806) (xy 366.564332 -285.256329) (xy 366.550277 -285.230786)
			(xy 366.540288 -285.220156) (xy 366.466374 -285.146242) (xy 366.433354 -285.163514) (xy 366.407827 -285.176164)
			(xy 366.353745 -285.194065) (xy 366.2975 -285.203109) (xy 366.269016 -285.203646) (xy 366.263428 -285.203646)
			(xy 366.235733 -285.202685) (xy 366.18113 -285.193246) (xy 366.128648 -285.175462) (xy 366.079554 -285.149763)
			(xy 366.035034 -285.116769) (xy 365.996162 -285.077278) (xy 365.963877 -285.032241) (xy 365.938958 -284.982747)
			(xy 365.922007 -284.92999) (xy 365.913433 -284.875245) (xy 365.912908 -284.847538) (xy 365.913349 -284.822024)
			(xy 365.920638 -284.77152) (xy 365.935057 -284.722571) (xy 365.956311 -284.676181) (xy 365.983967 -284.633297)
			(xy 366.017457 -284.594797) (xy 366.056097 -284.561469) (xy 366.099097 -284.533994) (xy 366.145576 -284.512935)
			(xy 366.169956 -284.5054) (xy 366.206532 -284.494732) (xy 366.206532 -283.572712) (xy 366.169956 -283.562044)
			(xy 366.145566 -283.55453) (xy 366.099071 -283.533489) (xy 366.056058 -283.506024) (xy 366.017407 -283.472698)
			(xy 365.983912 -283.434194) (xy 365.956258 -283.391301) (xy 365.935014 -283.344899) (xy 365.920614 -283.295939)
			(xy 365.913353 -283.245423) (xy 365.912908 -283.219906) (xy 365.913411 -283.192858) (xy 365.921592 -283.139383)
			(xy 365.937768 -283.087761) (xy 365.961567 -283.03918) (xy 365.992439 -282.994758) (xy 366.010698 -282.974796)
			(xy 366.020372 -282.962911) (xy 366.032765 -282.934897) (xy 366.036304 -282.90447) (xy 366.030673 -282.874359)
			(xy 366.016378 -282.847267) (xy 366.005872 -282.836112) (xy 365.913924 -282.744164) (xy 365.894366 -282.749244)
			(xy 365.8712 -282.755198) (xy 365.823794 -282.761568) (xy 365.799878 -282.761944) (xy 365.799116 -282.761944)
			(xy 365.771131 -282.761396) (xy 365.71585 -282.752643) (xy 365.662618 -282.735351) (xy 365.612747 -282.709944)
			(xy 365.567464 -282.677049) (xy 365.527885 -282.637475) (xy 365.494983 -282.592197) (xy 365.469569 -282.54233)
			(xy 365.452269 -282.489101) (xy 365.443508 -282.433821) (xy 365.443008 -282.405836) (xy 365.443008 -282.405074)
			(xy 365.443378 -282.381158) (xy 365.44975 -282.333751) (xy 365.455708 -282.310586) (xy 365.460788 -282.291028)
			(xy 364.494826 -281.325066) (xy 364.494826 -280.421842) (xy 364.494427 -280.40845) (xy 364.487473 -280.382585)
			(xy 364.474031 -280.359418) (xy 364.455028 -280.340544) (xy 364.43177 -280.327262) (xy 364.405858 -280.320484)
			(xy 364.392464 -280.320242) (xy 364.389416 -280.320242) (xy 364.362762 -280.31977) (xy 364.310048 -280.311827)
			(xy 364.259107 -280.296115) (xy 364.211076 -280.272987) (xy 364.16703 -280.242958) (xy 364.127951 -280.2067)
			(xy 364.094712 -280.165022) (xy 364.068057 -280.118856) (xy 364.048581 -280.069232) (xy 364.036718 -280.01726)
			(xy 364.032734 -279.9641) (xy 364.036718 -279.91094) (xy 364.048581 -279.858968) (xy 364.068057 -279.809344)
			(xy 364.094712 -279.763178) (xy 364.127951 -279.7215) (xy 364.16703 -279.685242) (xy 364.211076 -279.655213)
			(xy 364.259107 -279.632085) (xy 364.310048 -279.616373) (xy 364.362762 -279.60843) (xy 364.389416 -279.608026)
			(xy 364.392464 -279.608026) (xy 364.405853 -279.607719) (xy 364.431755 -279.600947) (xy 364.455007 -279.587675)
			(xy 364.474009 -279.568815) (xy 364.487455 -279.545663) (xy 364.494421 -279.519812) (xy 364.494826 -279.506426)
			(xy 364.494826 -278.97328) (xy 363.94898 -278.427434) (xy 363.938533 -278.417678) (xy 363.913518 -278.403869)
			(xy 363.88566 -278.397521) (xy 363.857132 -278.399131) (xy 363.830165 -278.408573) (xy 363.806863 -278.425108)
			(xy 363.789047 -278.447447) (xy 363.783118 -278.460454) (xy 363.773216 -278.485628) (xy 363.746903 -278.53289)
			(xy 363.713744 -278.575628) (xy 363.674502 -278.612858) (xy 363.63008 -278.643725) (xy 363.5815 -278.667517)
			(xy 363.52988 -278.683688) (xy 363.476409 -278.691864) (xy 363.449362 -278.692356) (xy 363.421379 -278.691804)
			(xy 363.366104 -278.683045) (xy 363.312879 -278.665748) (xy 363.263015 -278.640338) (xy 363.217738 -278.607442)
			(xy 363.178164 -278.567869) (xy 363.145267 -278.522594) (xy 363.119856 -278.47273) (xy 363.102558 -278.419506)
			(xy 363.093797 -278.364231) (xy 363.093254 -278.336248) (xy 363.093761 -278.309204) (xy 363.101947 -278.25574)
			(xy 363.118124 -278.204128) (xy 363.141919 -278.155555) (xy 363.172784 -278.111139) (xy 363.210011 -278.071901)
			(xy 363.252744 -278.038744) (xy 363.299998 -278.012429) (xy 363.325156 -278.002492) (xy 363.338183 -277.996586)
			(xy 363.360547 -277.978773) (xy 363.377104 -277.955464) (xy 363.386558 -277.928481) (xy 363.38817 -277.899936)
			(xy 363.381815 -277.87206) (xy 363.367988 -277.847035) (xy 363.358176 -277.83663) (xy 363.263942 -277.742396)
			(xy 363.228128 -277.777448) (xy 363.208045 -277.796294) (xy 363.163151 -277.828194) (xy 363.113884 -277.852807)
			(xy 363.061417 -277.869547) (xy 363.006999 -277.878015) (xy 362.979462 -277.87854) (xy 362.953631 -277.878077)
			(xy 362.902512 -277.87061) (xy 362.853008 -277.855836) (xy 362.806157 -277.834068) (xy 362.762942 -277.80576)
			(xy 362.724269 -277.771506) (xy 362.690949 -277.732026) (xy 362.663681 -277.688147) (xy 362.643038 -277.640789)
			(xy 362.629451 -277.590946) (xy 362.625894 -277.565358) (xy 362.62437 -277.553166) (xy 362.6231 -277.522432)
			(xy 362.62361 -277.494894) (xy 362.632078 -277.440473) (xy 362.648817 -277.388002) (xy 362.673428 -277.338731)
			(xy 362.705327 -277.293833) (xy 362.724192 -277.273766) (xy 362.730803 -277.266346) (xy 362.738276 -277.247953)
			(xy 362.738207 -277.2281) (xy 362.730608 -277.209759) (xy 362.723938 -277.202392) (xy 362.580174 -277.058628)
			(xy 362.555282 -277.061676) (xy 362.543967 -277.063075) (xy 362.521217 -277.064603) (xy 362.509816 -277.064724)
			(xy 362.481832 -277.064176) (xy 362.426552 -277.055423) (xy 362.373321 -277.03813) (xy 362.323452 -277.012723)
			(xy 362.278171 -276.979828) (xy 362.238593 -276.940254) (xy 362.205693 -276.894976) (xy 362.180282 -276.845108)
			(xy 362.162984 -276.79188) (xy 362.154226 -276.7366) (xy 362.153708 -276.708616) (xy 362.153829 -276.697215)
			(xy 362.155353 -276.674465) (xy 362.156756 -276.66315) (xy 362.159804 -276.638258) (xy 361.953302 -276.431756)
			(xy 361.953302 -276.242018) (xy 361.919774 -276.23008) (xy 361.894221 -276.220396) (xy 361.846197 -276.194324)
			(xy 361.802719 -276.161222) (xy 361.764808 -276.121868) (xy 361.733353 -276.077184) (xy 361.709091 -276.028221)
			(xy 361.692594 -275.976126) (xy 361.684247 -275.922122) (xy 361.684247 -275.867478) (xy 361.692594 -275.813474)
			(xy 361.709091 -275.761379) (xy 361.733353 -275.712416) (xy 361.764808 -275.667732) (xy 361.802719 -275.628378)
			(xy 361.846197 -275.595276) (xy 361.894221 -275.569204) (xy 361.919774 -275.55952) (xy 361.953302 -275.547582)
			(xy 361.953302 -275.441156) (xy 361.952838 -275.426948) (xy 361.945015 -275.399629) (xy 361.929961 -275.375528)
			(xy 361.908844 -275.356514) (xy 361.883302 -275.344061) (xy 361.855316 -275.339137) (xy 361.827057 -275.342122)
			(xy 361.800717 -275.352786) (xy 361.789218 -275.361146) (xy 361.765565 -275.378915) (xy 361.713598 -275.407177)
			(xy 361.657678 -275.426471) (xy 361.599339 -275.436266) (xy 361.569762 -275.436838) (xy 361.543112 -275.436338)
			(xy 361.490409 -275.428389) (xy 361.439479 -275.412674) (xy 361.391459 -275.389544) (xy 361.347423 -275.359517)
			(xy 361.308354 -275.323262) (xy 361.275124 -275.281589) (xy 361.248476 -275.235429) (xy 361.229005 -275.185814)
			(xy 361.217145 -275.13385) (xy 361.213162 -275.0807) (xy 361.217145 -275.02755) (xy 361.229005 -274.975586)
			(xy 361.248476 -274.925971) (xy 361.275124 -274.879811) (xy 361.308354 -274.838138) (xy 361.347423 -274.801883)
			(xy 361.391459 -274.771856) (xy 361.439479 -274.748726) (xy 361.490409 -274.733011) (xy 361.543112 -274.725062)
			(xy 361.569762 -274.724622) (xy 361.59934 -274.725204) (xy 361.657683 -274.73498) (xy 361.713606 -274.754268)
			(xy 361.76557 -274.782538) (xy 361.789218 -274.800314) (xy 361.800705 -274.808677) (xy 361.827044 -274.8193)
			(xy 361.855291 -274.822258) (xy 361.88326 -274.817322) (xy 361.908788 -274.804874) (xy 361.929901 -274.785876)
			(xy 361.944964 -274.761799) (xy 361.952814 -274.734504) (xy 361.953302 -274.720304) (xy 361.953302 -274.614132)
			(xy 361.91952 -274.602194) (xy 361.893967 -274.592511) (xy 361.845946 -274.56644) (xy 361.802471 -274.533339)
			(xy 361.764563 -274.493983) (xy 361.733114 -274.449299) (xy 361.70886 -274.400334) (xy 361.692373 -274.348238)
			(xy 361.684037 -274.294235) (xy 361.683554 -274.266914) (xy 361.684102 -274.238929) (xy 361.692855 -274.183648)
			(xy 361.710148 -274.130417) (xy 361.735555 -274.080546) (xy 361.76845 -274.035263) (xy 361.808023 -273.995684)
			(xy 361.853301 -273.962782) (xy 361.903169 -273.937368) (xy 361.956397 -273.920067) (xy 362.011677 -273.911306)
			(xy 362.039662 -273.910806) (xy 362.052405 -273.910902) (xy 362.07783 -273.912681) (xy 362.090462 -273.914362)
			(xy 362.090462 -273.914108) (xy 362.118245 -273.918696) (xy 362.171998 -273.935469) (xy 362.222453 -273.960469)
			(xy 362.268359 -273.993076) (xy 362.288836 -274.012406) (xy 362.370116 -273.931126) (xy 362.379473 -273.921176)
			(xy 362.393004 -273.897461) (xy 362.399762 -273.871008) (xy 362.399265 -273.843709) (xy 362.391548 -273.817519)
			(xy 362.377162 -273.794313) (xy 362.357139 -273.775752) (xy 362.345224 -273.769074) (xy 362.320824 -273.755791)
			(xy 362.27611 -273.722826) (xy 362.23706 -273.683316) (xy 362.204621 -273.638219) (xy 362.17958 -273.58863)
			(xy 362.162547 -273.535754) (xy 362.153933 -273.480874) (xy 362.153454 -273.453098) (xy 362.154003 -273.425114)
			(xy 362.162758 -273.369835) (xy 362.180052 -273.316606) (xy 362.20546 -273.266737) (xy 362.238355 -273.221456)
			(xy 362.277929 -273.181879) (xy 362.323206 -273.148979) (xy 362.373072 -273.123566) (xy 362.4263 -273.106267)
			(xy 362.481578 -273.097506) (xy 362.509562 -273.09699) (xy 362.535584 -273.097439) (xy 362.587073 -273.105013)
			(xy 362.63691 -273.120004) (xy 362.684033 -273.142094) (xy 362.727437 -273.17081) (xy 362.766195 -273.205542)
			(xy 362.799483 -273.245547) (xy 362.82659 -273.289974) (xy 362.846937 -273.337874) (xy 362.853986 -273.362928)
			(xy 362.863892 -273.400774) (xy 363.095032 -273.400774) (xy 363.104938 -273.362928) (xy 363.111986 -273.33788)
			(xy 363.132351 -273.289997) (xy 363.159469 -273.245589) (xy 363.192763 -273.205602) (xy 363.231522 -273.170886)
			(xy 363.274922 -273.142183) (xy 363.322038 -273.120102) (xy 363.371866 -273.105115) (xy 363.423345 -273.097541)
			(xy 363.475379 -273.097541) (xy 363.526858 -273.105115) (xy 363.576686 -273.120102) (xy 363.623802 -273.142183)
			(xy 363.667202 -273.170886) (xy 363.705961 -273.205602) (xy 363.739255 -273.245589) (xy 363.766373 -273.289997)
			(xy 363.786738 -273.33788) (xy 363.793786 -273.362928) (xy 363.803692 -273.400774) (xy 364.035086 -273.400774)
			(xy 364.044992 -273.362928) (xy 364.05204 -273.33788) (xy 364.072405 -273.289997) (xy 364.099523 -273.245589)
			(xy 364.132817 -273.205602) (xy 364.171576 -273.170886) (xy 364.214976 -273.142183) (xy 364.262092 -273.120102)
			(xy 364.31192 -273.105115) (xy 364.363399 -273.097541) (xy 364.415433 -273.097541) (xy 364.466912 -273.105115)
			(xy 364.51674 -273.120102) (xy 364.563856 -273.142183) (xy 364.607256 -273.170886) (xy 364.646015 -273.205602)
			(xy 364.679309 -273.245589) (xy 364.706427 -273.289997) (xy 364.726792 -273.33788) (xy 364.73384 -273.362928)
			(xy 364.743746 -273.400774) (xy 364.974886 -273.400774) (xy 364.984792 -273.362928) (xy 364.99184 -273.33788)
			(xy 365.012205 -273.289997) (xy 365.039323 -273.245589) (xy 365.072617 -273.205602) (xy 365.111376 -273.170886)
			(xy 365.154776 -273.142183) (xy 365.201892 -273.120102) (xy 365.25172 -273.105115) (xy 365.303199 -273.097541)
			(xy 365.355233 -273.097541) (xy 365.406712 -273.105115) (xy 365.45654 -273.120102) (xy 365.503656 -273.142183)
			(xy 365.547056 -273.170886) (xy 365.585815 -273.205602) (xy 365.619109 -273.245589) (xy 365.646227 -273.289997)
			(xy 365.666592 -273.33788) (xy 365.67364 -273.362928) (xy 365.683546 -273.400774) (xy 365.914686 -273.400774)
			(xy 365.924592 -273.362928) (xy 365.931712 -273.337622) (xy 365.952365 -273.289282) (xy 365.97989 -273.244496)
			(xy 366.013691 -273.204235) (xy 366.053034 -273.169372) (xy 366.097069 -273.140661) (xy 366.144841 -273.118724)
			(xy 366.169956 -273.11096) (xy 366.206532 -273.100546) (xy 366.206532 -272.979642) (xy 366.206043 -272.964999)
			(xy 366.197722 -272.936921) (xy 366.181781 -272.912354) (xy 366.159527 -272.893317) (xy 366.132788 -272.881372)
			(xy 366.103759 -272.8775) (xy 366.074825 -272.882019) (xy 366.048359 -272.894558) (xy 366.037114 -272.90395)
			(xy 366.017399 -272.921079) (xy 365.973896 -272.949973) (xy 365.926638 -272.972203) (xy 365.87664 -272.987291)
			(xy 365.824975 -272.994914) (xy 365.798862 -272.99539) (xy 365.772216 -272.994889) (xy 365.71952 -272.986941)
			(xy 365.668596 -272.971229) (xy 365.620584 -272.948102) (xy 365.576553 -272.918079) (xy 365.537489 -272.881829)
			(xy 365.504264 -272.840162) (xy 365.47762 -272.794008) (xy 365.458151 -272.7444) (xy 365.446293 -272.692443)
			(xy 365.442311 -272.6393) (xy 365.446293 -272.586157) (xy 365.458151 -272.5342) (xy 365.47762 -272.484592)
			(xy 365.504264 -272.438438) (xy 365.537489 -272.396771) (xy 365.576553 -272.360521) (xy 365.620584 -272.330498)
			(xy 365.668596 -272.307371) (xy 365.71952 -272.291659) (xy 365.772216 -272.283711) (xy 365.798862 -272.283174)
			(xy 365.824976 -272.283629) (xy 365.876645 -272.291252) (xy 365.926647 -272.30634) (xy 365.973909 -272.328569)
			(xy 366.017417 -272.357463) (xy 366.037114 -272.374614) (xy 366.04834 -272.384031) (xy 366.074803 -272.396588)
			(xy 366.10374 -272.401117) (xy 366.132774 -272.397246) (xy 366.159514 -272.385293) (xy 366.181762 -272.366242)
			(xy 366.197687 -272.341659) (xy 366.205979 -272.313568) (xy 366.206532 -272.298922) (xy 366.206532 -272.178018)
			(xy 366.169702 -272.16735) (xy 366.143871 -272.159369) (xy 366.094795 -272.136693) (xy 366.04971 -272.10686)
			(xy 366.009652 -272.070555) (xy 365.975542 -272.028612) (xy 365.948162 -271.981996) (xy 365.928144 -271.931777)
			(xy 365.915945 -271.87911) (xy 365.911847 -271.825203) (xy 365.915944 -271.771297) (xy 365.928142 -271.718629)
			(xy 365.94816 -271.66841) (xy 365.975538 -271.621793) (xy 366.009647 -271.57985) (xy 366.049705 -271.543545)
			(xy 366.094789 -271.51371) (xy 366.143865 -271.491033) (xy 366.169702 -271.483074) (xy 366.206532 -271.472406)
			(xy 366.206532 -271.351756) (xy 366.206045 -271.337112) (xy 366.197727 -271.30903) (xy 366.181785 -271.284459)
			(xy 366.15953 -271.265419) (xy 366.132789 -271.253473) (xy 366.103757 -271.2496) (xy 366.07482 -271.254121)
			(xy 366.048352 -271.266662) (xy 366.037114 -271.276064) (xy 366.017399 -271.293192) (xy 365.973895 -271.322085)
			(xy 365.926637 -271.344314) (xy 365.87664 -271.359402) (xy 365.824974 -271.367024) (xy 365.798862 -271.367504)
			(xy 365.772215 -271.367004) (xy 365.719516 -271.359055) (xy 365.668591 -271.343342) (xy 365.620576 -271.320215)
			(xy 365.576544 -271.29019) (xy 365.537479 -271.253939) (xy 365.504252 -271.21227) (xy 365.477607 -271.166115)
			(xy 365.458137 -271.116504) (xy 365.446279 -271.064545) (xy 365.442296 -271.0114) (xy 365.446279 -270.958255)
			(xy 365.458137 -270.906296) (xy 365.477607 -270.856685) (xy 365.504252 -270.81053) (xy 365.537479 -270.768861)
			(xy 365.576544 -270.73261) (xy 365.620576 -270.702585) (xy 365.668591 -270.679458) (xy 365.719516 -270.663745)
			(xy 365.772215 -270.655796) (xy 365.798862 -270.655288) (xy 365.824976 -270.655743) (xy 365.876645 -270.663366)
			(xy 365.926646 -270.678455) (xy 365.973908 -270.700685) (xy 366.017415 -270.729579) (xy 366.037114 -270.746728)
			(xy 366.048341 -270.756144) (xy 366.074804 -270.768699) (xy 366.103742 -270.773227) (xy 366.132776 -270.769356)
			(xy 366.159516 -270.757404) (xy 366.181765 -270.738354) (xy 366.197692 -270.713773) (xy 366.205988 -270.685681)
			(xy 366.206532 -270.671036) (xy 366.206532 -270.550386) (xy 366.169956 -270.539718) (xy 366.144141 -270.531723)
			(xy 366.095099 -270.509026) (xy 366.050048 -270.479181) (xy 366.010023 -270.442873) (xy 365.975942 -270.400935)
			(xy 365.948588 -270.35433) (xy 365.928588 -270.304127) (xy 365.916402 -270.251479) (xy 365.91231 -270.197594)
			(xy 365.916404 -270.14371) (xy 365.928592 -270.091062) (xy 365.948593 -270.04086) (xy 365.975949 -269.994256)
			(xy 366.010031 -269.952319) (xy 366.050057 -269.916012) (xy 366.095108 -269.886168) (xy 366.144152 -269.863473)
			(xy 366.169956 -269.855442) (xy 366.206532 -269.844774) (xy 366.206532 -269.72387) (xy 366.20602 -269.709236)
			(xy 366.197659 -269.681184) (xy 366.181691 -269.656652) (xy 366.159424 -269.637652) (xy 366.132685 -269.625743)
			(xy 366.103668 -269.621901) (xy 366.074751 -269.626442) (xy 366.048307 -269.638992) (xy 366.037114 -269.648432)
			(xy 366.01741 -269.66552) (xy 365.973941 -269.694341) (xy 365.926732 -269.716512) (xy 365.876793 -269.731557)
			(xy 365.825194 -269.739154) (xy 365.799116 -269.739618) (xy 365.772463 -269.739146) (xy 365.719753 -269.731203)
			(xy 365.668815 -269.715493) (xy 365.620788 -269.692366) (xy 365.576745 -269.66234) (xy 365.537668 -269.626084)
			(xy 365.504432 -269.584409) (xy 365.477779 -269.538245) (xy 365.458304 -269.488625) (xy 365.446442 -269.436656)
			(xy 365.442458 -269.3835) (xy 365.446442 -269.330344) (xy 365.458304 -269.278375) (xy 365.477779 -269.228755)
			(xy 365.504432 -269.182591) (xy 365.537668 -269.140916) (xy 365.576745 -269.10466) (xy 365.620788 -269.074634)
			(xy 365.668815 -269.051507) (xy 365.719753 -269.035797) (xy 365.772463 -269.027854) (xy 365.799116 -269.027402)
			(xy 365.825194 -269.027858) (xy 365.876793 -269.035464) (xy 365.926731 -269.050511) (xy 365.973942 -269.072678)
			(xy 366.017418 -269.101491) (xy 366.037114 -269.118588) (xy 366.048331 -269.127992) (xy 366.074766 -269.140535)
			(xy 366.103671 -269.145072) (xy 366.132677 -269.141231) (xy 366.159405 -269.129328) (xy 366.181664 -269.110337)
			(xy 366.197629 -269.085817) (xy 366.20599 -269.057778) (xy 366.206532 -269.04315) (xy 366.206532 -268.9225)
			(xy 366.169956 -268.911832) (xy 366.14414 -268.903837) (xy 366.095096 -268.88114) (xy 366.050043 -268.851294)
			(xy 366.010016 -268.814985) (xy 365.975933 -268.773046) (xy 365.948578 -268.726439) (xy 365.928577 -268.676235)
			(xy 365.91639 -268.623585) (xy 365.912296 -268.569698) (xy 365.91639 -268.515812) (xy 365.928578 -268.463162)
			(xy 365.948579 -268.412958) (xy 365.975935 -268.366351) (xy 366.010018 -268.324413) (xy 366.050045 -268.288104)
			(xy 366.095099 -268.258258) (xy 366.144143 -268.235562) (xy 366.169956 -268.227556) (xy 366.206532 -268.216888)
			(xy 366.206532 -268.096238) (xy 366.206043 -268.081596) (xy 366.197721 -268.053518) (xy 366.181779 -268.028953)
			(xy 366.159526 -268.009917) (xy 366.132788 -267.997972) (xy 366.10376 -267.9941) (xy 366.074826 -267.998619)
			(xy 366.048361 -268.011157) (xy 366.037114 -268.020546) (xy 366.017399 -268.037675) (xy 365.973896 -268.066569)
			(xy 365.926638 -268.088799) (xy 365.87664 -268.103888) (xy 365.824975 -268.111511) (xy 365.798862 -268.111986)
			(xy 365.772216 -268.111485) (xy 365.719521 -268.103537) (xy 365.668598 -268.087825) (xy 365.620586 -268.064699)
			(xy 365.576556 -268.034676) (xy 365.537492 -267.998426) (xy 365.504267 -267.95676) (xy 365.477623 -267.910607)
			(xy 365.458155 -267.860998) (xy 365.446297 -267.809043) (xy 365.442315 -267.7559) (xy 365.446297 -267.702757)
			(xy 365.458155 -267.650802) (xy 365.477623 -267.601193) (xy 365.504267 -267.55504) (xy 365.537492 -267.513374)
			(xy 365.576556 -267.477124) (xy 365.620586 -267.447101) (xy 365.668598 -267.423975) (xy 365.719521 -267.408263)
			(xy 365.772216 -267.400315) (xy 365.798862 -267.39977) (xy 365.824976 -267.400225) (xy 365.876645 -267.407848)
			(xy 365.926647 -267.422936) (xy 365.973909 -267.445165) (xy 366.017417 -267.474058) (xy 366.037114 -267.49121)
			(xy 366.048346 -267.500621) (xy 366.074814 -267.513167) (xy 366.103754 -267.517689) (xy 366.132788 -267.513817)
			(xy 366.15953 -267.501868) (xy 366.181786 -267.482824) (xy 366.197725 -267.45825) (xy 366.206038 -267.430163)
			(xy 366.206532 -267.415518) (xy 366.206532 -267.294614) (xy 366.169702 -267.283946) (xy 366.143872 -267.275965)
			(xy 366.094796 -267.253289) (xy 366.049711 -267.223456) (xy 366.009654 -267.187151) (xy 365.975544 -267.145209)
			(xy 365.948165 -267.098593) (xy 365.928147 -267.048375) (xy 365.915949 -266.995708) (xy 365.911851 -266.941802)
			(xy 365.915948 -266.887896) (xy 365.928146 -266.835229) (xy 365.948163 -266.785011) (xy 365.975542 -266.738394)
			(xy 366.009651 -266.696452) (xy 366.049708 -266.660147) (xy 366.094792 -266.630313) (xy 366.143867 -266.607637)
			(xy 366.169702 -266.59967) (xy 366.206532 -266.589002) (xy 366.206532 -266.468606) (xy 366.206052 -266.453957)
			(xy 366.197741 -266.425861) (xy 366.181801 -266.401278) (xy 366.159542 -266.382227) (xy 366.132792 -266.370273)
			(xy 366.10375 -266.3664) (xy 366.074803 -266.370926) (xy 366.048329 -266.383478) (xy 366.037114 -266.392914)
			(xy 366.017398 -266.41004) (xy 365.973893 -266.43893) (xy 365.926635 -266.461155) (xy 365.876638 -266.476241)
			(xy 365.824974 -266.483862) (xy 365.798862 -266.484354) (xy 365.772211 -266.483854) (xy 365.719505 -266.475904)
			(xy 365.668573 -266.460189) (xy 365.620551 -266.437058) (xy 365.576513 -266.407029) (xy 365.537442 -266.370773)
			(xy 365.504211 -266.329098) (xy 365.477562 -266.282936) (xy 365.458089 -266.233319) (xy 365.446229 -266.181353)
			(xy 365.442246 -266.1282) (xy 365.446229 -266.075047) (xy 365.458089 -266.023081) (xy 365.477562 -265.973464)
			(xy 365.504211 -265.927302) (xy 365.537442 -265.885627) (xy 365.576513 -265.849371) (xy 365.620551 -265.819342)
			(xy 365.668573 -265.796211) (xy 365.719505 -265.780496) (xy 365.772211 -265.772546) (xy 365.798862 -265.772138)
			(xy 365.824976 -265.772594) (xy 365.876644 -265.780218) (xy 365.926644 -265.795308) (xy 365.973903 -265.81754)
			(xy 366.017408 -265.846438) (xy 366.037114 -265.863578) (xy 366.048344 -265.872991) (xy 366.07481 -265.88554)
			(xy 366.103749 -265.890065) (xy 366.132783 -265.886193) (xy 366.159525 -265.874243) (xy 366.181778 -265.855197)
			(xy 366.197712 -265.83062) (xy 366.206019 -265.802531) (xy 366.206532 -265.787886) (xy 366.206532 -265.666982)
			(xy 366.169956 -265.656314) (xy 366.144131 -265.64833) (xy 366.095065 -265.625651) (xy 366.049991 -265.595817)
			(xy 366.009943 -265.559513) (xy 365.975842 -265.517575) (xy 365.948471 -265.470964) (xy 365.928458 -265.420751)
			(xy 365.916264 -265.368091) (xy 365.912169 -265.314193) (xy 365.916266 -265.260295) (xy 365.928462 -265.207636)
			(xy 365.948477 -265.157424) (xy 365.97585 -265.110815) (xy 366.009952 -265.068877) (xy 366.050001 -265.032575)
			(xy 366.095077 -265.002742) (xy 366.144143 -264.980065) (xy 366.169956 -264.972038) (xy 366.206532 -264.96137)
			(xy 366.206532 -264.780268) (xy 366.207294 -264.780268) (xy 366.232281 -264.78069) (xy 366.281764 -264.78768)
			(xy 366.329783 -264.801522) (xy 366.375394 -264.821945) (xy 366.396778 -264.834878) (xy 366.399064 -264.836402)
			(xy 366.402874 -264.838688) (xy 366.446562 -264.851896) (xy 366.515904 -264.782554) (xy 366.481614 -264.74674)
			(xy 366.464711 -264.728474) (xy 366.435611 -264.688101) (xy 366.41241 -264.644073) (xy 366.395559 -264.597245)
			(xy 366.385385 -264.548529) (xy 366.383316 -264.523728) (xy 366.36862 -264.50139) (xy 366.34537 -264.453242)
			(xy 366.329571 -264.402161) (xy 366.321577 -264.349294) (xy 366.321086 -264.32256) (xy 366.321638 -264.294579)
			(xy 366.330398 -264.239306) (xy 366.347696 -264.186084) (xy 366.373106 -264.136223) (xy 366.406003 -264.09095)
			(xy 366.445576 -264.051381) (xy 366.490852 -264.018488) (xy 366.540715 -263.993083) (xy 366.593939 -263.97579)
			(xy 366.649213 -263.967035) (xy 366.677194 -263.966452) (xy 366.708436 -263.967722) (xy 366.730788 -263.969754)
			(xy 366.818926 -263.888728) (xy 366.818926 -263.830054) (xy 366.818383 -263.815671) (xy 366.810275 -263.788068)
			(xy 366.794798 -263.763816) (xy 366.773178 -263.744835) (xy 366.747127 -263.732628) (xy 366.718706 -263.728162)
			(xy 366.704372 -263.72947) (xy 366.693179 -263.730789) (xy 366.670684 -263.732187) (xy 366.659414 -263.732264)
			(xy 366.632576 -263.731778) (xy 366.579507 -263.723723) (xy 366.528248 -263.707793) (xy 366.479961 -263.68435)
			(xy 366.43574 -263.653925) (xy 366.396587 -263.617207) (xy 366.363389 -263.575028) (xy 366.336898 -263.528343)
			(xy 366.317715 -263.478211) (xy 366.306274 -263.425768) (xy 366.304068 -263.399016) (xy 366.287797 -263.375956)
			(xy 366.261981 -263.325772) (xy 366.244408 -263.272144) (xy 366.235519 -263.216413) (xy 366.23498 -263.188196)
			(xy 366.235529 -263.160213) (xy 366.244285 -263.104935) (xy 366.261579 -263.051708) (xy 366.286988 -263.001842)
			(xy 366.319884 -262.956563) (xy 366.359457 -262.916989) (xy 366.404735 -262.884092) (xy 366.454601 -262.858682)
			(xy 366.507828 -262.841387) (xy 366.563105 -262.83263) (xy 366.591088 -262.832088) (xy 366.59185 -262.832088)
			(xy 366.616627 -262.832516) (xy 366.6657 -262.839403) (xy 366.68964 -262.845804) (xy 366.71377 -262.852662)
			(xy 366.818926 -262.773668) (xy 366.818926 -260.314948) (xy 368.15268 -258.981194) (xy 368.15268 -246.977916)
			(xy 368.134376 -246.968448) (xy 368.099872 -246.945913) (xy 368.083846 -246.932958) (xy 368.072744 -246.924405)
			(xy 368.047081 -246.913165) (xy 368.01933 -246.909322) (xy 367.991579 -246.913165) (xy 367.965916 -246.924405)
			(xy 367.954814 -246.932958) (xy 367.93338 -246.950113) (xy 367.886276 -246.978308) (xy 367.835402 -246.998938)
			(xy 367.781965 -247.011515) (xy 367.72723 -247.01574) (xy 367.672495 -247.011515) (xy 367.619058 -246.998938)
			(xy 367.568184 -246.978308) (xy 367.52108 -246.950113) (xy 367.499646 -246.932958) (xy 367.488544 -246.924405)
			(xy 367.462881 -246.913165) (xy 367.43513 -246.909322) (xy 367.407379 -246.913165) (xy 367.381716 -246.924405)
			(xy 367.370614 -246.932958) (xy 367.363756 -246.938546) (xy 367.344407 -246.953362) (xy 367.302429 -246.978119)
			(xy 367.257463 -246.996908) (xy 367.21035 -247.009375) (xy 367.18621 -247.012714) (xy 367.173764 -247.014238)
			(xy 367.14303 -247.015508) (xy 367.117912 -247.01508) (xy 367.068175 -247.008026) (xy 367.019922 -246.994054)
			(xy 366.97411 -246.973441) (xy 366.931649 -246.946597) (xy 366.893381 -246.914053) (xy 366.860065 -246.876455)
			(xy 366.84585 -246.855742) (xy 366.844834 -246.853964) (xy 366.84331 -246.851678) (xy 366.835029 -246.839751)
			(xy 366.813093 -246.820747) (xy 366.786693 -246.808692) (xy 366.757966 -246.804562) (xy 366.729239 -246.808692)
			(xy 366.702839 -246.820747) (xy 366.680903 -246.839751) (xy 366.672622 -246.851678) (xy 366.658476 -246.872834)
			(xy 366.625137 -246.911284) (xy 366.586667 -246.944601) (xy 366.543848 -246.972106) (xy 366.497553 -246.993239)
			(xy 366.448721 -247.007572) (xy 366.398348 -247.014812) (xy 366.372902 -247.015254) (xy 366.372648 -247.015254)
			(xy 366.347042 -247.014811) (xy 366.296358 -247.007473) (xy 366.24725 -246.99294) (xy 366.200735 -246.971515)
			(xy 366.157774 -246.943639) (xy 366.138206 -246.927116) (xy 366.126736 -246.918449) (xy 366.100262 -246.907274)
			(xy 366.071724 -246.903901) (xy 366.043374 -246.908595) (xy 366.017447 -246.920987) (xy 366.00638 -246.930164)
			(xy 365.986501 -246.947943) (xy 365.942449 -246.978004) (xy 365.894411 -247.001167) (xy 365.843459 -247.016916)
			(xy 365.790729 -247.024899) (xy 365.764064 -247.025414) (xy 365.76381 -247.025414) (xy 365.737158 -247.024941)
			(xy 365.684449 -247.016998) (xy 365.633513 -247.001288) (xy 365.585487 -246.978161) (xy 365.541444 -246.948134)
			(xy 365.502369 -246.911879) (xy 365.469134 -246.870204) (xy 365.442482 -246.824042) (xy 365.423007 -246.774423)
			(xy 365.411145 -246.722455) (xy 365.407162 -246.6693) (xy 365.411145 -246.616145) (xy 365.423007 -246.564177)
			(xy 365.442482 -246.514558) (xy 365.469134 -246.468396) (xy 365.502369 -246.426721) (xy 365.541444 -246.390466)
			(xy 365.585487 -246.360439) (xy 365.633513 -246.337312) (xy 365.684449 -246.321602) (xy 365.737158 -246.313659)
			(xy 365.76381 -246.313198) (xy 365.764064 -246.313198) (xy 365.78967 -246.313642) (xy 365.840352 -246.320983)
			(xy 365.889457 -246.335518) (xy 365.93597 -246.356947) (xy 365.978927 -246.384827) (xy 365.998506 -246.401336)
			(xy 366.009975 -246.410004) (xy 366.036448 -246.421181) (xy 366.064985 -246.424553) (xy 366.093334 -246.419855)
			(xy 366.119257 -246.407456) (xy 366.130332 -246.398288) (xy 366.149515 -246.381071) (xy 366.191927 -246.351778)
			(xy 366.23812 -246.328906) (xy 366.287128 -246.312935) (xy 366.31245 -246.308118) (xy 366.329976 -246.305578)
			(xy 366.342168 -246.304054) (xy 366.372902 -246.302784) (xy 366.398019 -246.303215) (xy 366.447754 -246.310272)
			(xy 366.496004 -246.324247) (xy 366.541812 -246.344862) (xy 366.58427 -246.371708) (xy 366.622536 -246.404252)
			(xy 366.655849 -246.44185) (xy 366.670082 -246.46255) (xy 366.671098 -246.464328) (xy 366.672622 -246.466614)
			(xy 366.680903 -246.478541) (xy 366.702839 -246.497545) (xy 366.729239 -246.5096) (xy 366.757966 -246.51373)
			(xy 366.786693 -246.5096) (xy 366.813093 -246.497545) (xy 366.835029 -246.478541) (xy 366.84331 -246.466614)
			(xy 366.857457 -246.44546) (xy 366.890798 -246.407013) (xy 366.929268 -246.373701) (xy 366.972087 -246.346201)
			(xy 367.018383 -246.325072) (xy 367.067213 -246.310743) (xy 367.117585 -246.303508) (xy 367.14303 -246.303038)
			(xy 367.167733 -246.303463) (xy 367.216663 -246.310301) (xy 367.264177 -246.323843) (xy 367.309361 -246.343827)
			(xy 367.351346 -246.369869) (xy 367.370614 -246.385334) (xy 367.381716 -246.393887) (xy 367.407379 -246.405127)
			(xy 367.43513 -246.40897) (xy 367.462881 -246.405127) (xy 367.488544 -246.393887) (xy 367.499646 -246.385334)
			(xy 367.52108 -246.368179) (xy 367.568184 -246.339984) (xy 367.619058 -246.319354) (xy 367.672495 -246.306777)
			(xy 367.72723 -246.302552) (xy 367.781965 -246.306777) (xy 367.835402 -246.319354) (xy 367.886276 -246.339984)
			(xy 367.93338 -246.368179) (xy 367.954814 -246.385334) (xy 367.965916 -246.393887) (xy 367.991579 -246.405127)
			(xy 368.01933 -246.40897) (xy 368.047081 -246.405127) (xy 368.072744 -246.393887) (xy 368.083846 -246.385334)
			(xy 368.099869 -246.372375) (xy 368.134376 -246.349845) (xy 368.15268 -246.340376) (xy 368.15268 -239.65662)
			(xy 368.126264 -239.642142) (xy 368.1116 -239.633844) (xy 368.08374 -239.61489) (xy 368.070638 -239.604296)
			(xy 368.059508 -239.595669) (xy 368.033748 -239.584322) (xy 368.005868 -239.580441) (xy 367.977988 -239.584322)
			(xy 367.952228 -239.595669) (xy 367.941098 -239.604296) (xy 367.919682 -239.621419) (xy 367.872625 -239.649558)
			(xy 367.821808 -239.670147) (xy 367.768435 -239.682699) (xy 367.713768 -239.686916) (xy 367.659101 -239.682699)
			(xy 367.605728 -239.670147) (xy 367.554911 -239.649558) (xy 367.507854 -239.621419) (xy 367.486438 -239.604296)
			(xy 367.475308 -239.595669) (xy 367.449548 -239.584322) (xy 367.421668 -239.580441) (xy 367.393788 -239.584322)
			(xy 367.368028 -239.595669) (xy 367.356898 -239.604296) (xy 367.33765 -239.619732) (xy 367.2957 -239.645703)
			(xy 367.250563 -239.665625) (xy 367.203105 -239.679117) (xy 367.154237 -239.685919) (xy 367.129568 -239.686338)
			(xy 367.102307 -239.685815) (xy 367.048422 -239.677495) (xy 366.996437 -239.661055) (xy 366.947568 -239.636879)
			(xy 366.902957 -239.605532) (xy 366.882934 -239.587024) (xy 366.872071 -239.577256) (xy 366.846142 -239.563822)
			(xy 366.817472 -239.558274) (xy 366.788404 -239.561065) (xy 366.761313 -239.571967) (xy 366.749584 -239.580674)
			(xy 366.730343 -239.596063) (xy 366.688424 -239.621951) (xy 366.643336 -239.641813) (xy 366.595941 -239.655269)
			(xy 366.547142 -239.662063) (xy 366.522508 -239.662462) (xy 366.497804 -239.66204) (xy 366.448871 -239.655206)
			(xy 366.401355 -239.641669) (xy 366.356167 -239.621688) (xy 366.314178 -239.595649) (xy 366.294924 -239.580166)
			(xy 366.283822 -239.571613) (xy 366.258159 -239.560373) (xy 366.230408 -239.55653) (xy 366.202657 -239.560373)
			(xy 366.176994 -239.571613) (xy 366.165892 -239.580166) (xy 366.144458 -239.597321) (xy 366.097354 -239.625516)
			(xy 366.04648 -239.646146) (xy 365.993043 -239.658723) (xy 365.938308 -239.662948) (xy 365.883573 -239.658723)
			(xy 365.830136 -239.646146) (xy 365.779262 -239.625516) (xy 365.732158 -239.597321) (xy 365.710724 -239.580166)
			(xy 365.699622 -239.571613) (xy 365.673959 -239.560373) (xy 365.646208 -239.55653) (xy 365.618457 -239.560373)
			(xy 365.592794 -239.571613) (xy 365.581692 -239.580166) (xy 365.562431 -239.59564) (xy 365.520444 -239.62168)
			(xy 365.475258 -239.641662) (xy 365.427743 -239.655201) (xy 365.378811 -239.662037) (xy 365.354108 -239.662462)
			(xy 365.32746 -239.661989) (xy 365.274759 -239.654047) (xy 365.22383 -239.638339) (xy 365.175812 -239.615215)
			(xy 365.131776 -239.585193) (xy 365.092707 -239.548943) (xy 365.059477 -239.507275) (xy 365.032828 -239.461119)
			(xy 365.013357 -239.411507) (xy 365.001497 -239.359547) (xy 364.997514 -239.3064) (xy 365.001497 -239.253253)
			(xy 365.013357 -239.201293) (xy 365.032828 -239.151681) (xy 365.059477 -239.105525) (xy 365.092707 -239.063857)
			(xy 365.131776 -239.027607) (xy 365.175812 -238.997585) (xy 365.22383 -238.974461) (xy 365.274759 -238.958753)
			(xy 365.32746 -238.950811) (xy 365.354108 -238.950246) (xy 365.378811 -238.950669) (xy 365.427743 -238.957505)
			(xy 365.475258 -238.971045) (xy 365.520444 -238.991027) (xy 365.562431 -239.017068) (xy 365.581692 -239.032542)
			(xy 365.592794 -239.041095) (xy 365.618457 -239.052335) (xy 365.646208 -239.056178) (xy 365.673959 -239.052335)
			(xy 365.699622 -239.041095) (xy 365.710724 -239.032542) (xy 365.732158 -239.015387) (xy 365.779262 -238.987192)
			(xy 365.830136 -238.966562) (xy 365.883573 -238.953985) (xy 365.938308 -238.94976) (xy 365.993043 -238.953985)
			(xy 366.04648 -238.966562) (xy 366.097354 -238.987192) (xy 366.144458 -239.015387) (xy 366.165892 -239.032542)
			(xy 366.176994 -239.041095) (xy 366.202657 -239.052335) (xy 366.230408 -239.056178) (xy 366.258159 -239.052335)
			(xy 366.283822 -239.041095) (xy 366.294924 -239.032542) (xy 366.314185 -239.017069) (xy 366.356172 -238.99103)
			(xy 366.401358 -238.971049) (xy 366.448874 -238.957512) (xy 366.497805 -238.950679) (xy 366.522508 -238.950246)
			(xy 366.55008 -238.950762) (xy 366.604567 -238.959258) (xy 366.657094 -238.976046) (xy 366.706408 -239.000726)
			(xy 366.751331 -239.032707) (xy 366.771428 -239.051592) (xy 366.784774 -239.062742) (xy 366.816852 -239.076116)
			(xy 366.834166 -239.077754) (xy 366.843448 -239.078056) (xy 366.861859 -239.075634) (xy 366.870742 -239.072928)
			(xy 366.891071 -239.05225) (xy 366.937202 -239.017121) (xy 366.988415 -238.989932) (xy 367.043357 -238.9714)
			(xy 367.100576 -238.962015) (xy 367.129568 -238.961422) (xy 367.158742 -238.962003) (xy 367.216311 -238.971506)
			(xy 367.271562 -238.990261) (xy 367.323019 -239.017769) (xy 367.369306 -239.053294) (xy 367.389664 -239.074198)
			(xy 367.405346 -239.078768) (xy 367.43799 -239.078768) (xy 367.453672 -239.074198) (xy 367.472154 -239.055176)
			(xy 367.513743 -239.022267) (xy 367.559751 -238.995885) (xy 367.60916 -238.976614) (xy 367.66088 -238.964878)
			(xy 367.713768 -238.960937) (xy 367.766656 -238.964878) (xy 367.818376 -238.976614) (xy 367.867785 -238.995885)
			(xy 367.913793 -239.022267) (xy 367.955382 -239.055176) (xy 367.973864 -239.074198) (xy 367.989546 -239.078768)
			(xy 368.02219 -239.078768) (xy 368.037872 -239.074198) (xy 368.057476 -239.054056) (xy 368.10188 -239.019598)
			(xy 368.126264 -239.005618) (xy 368.15268 -238.99114) (xy 368.15268 -238.025686) (xy 367.956084 -237.82909)
			(xy 367.941098 -237.793022) (xy 367.501932 -237.353856) (xy 363.573314 -237.353856) (xy 363.557832 -237.375072)
			(xy 363.521651 -237.413142) (xy 363.48027 -237.445484) (xy 363.434588 -237.471397) (xy 363.385595 -237.490319)
			(xy 363.334354 -237.501838) (xy 363.281976 -237.505706) (xy 363.229598 -237.501838) (xy 363.178357 -237.490319)
			(xy 363.129364 -237.471397) (xy 363.083682 -237.445484) (xy 363.042301 -237.413142) (xy 363.00612 -237.375072)
			(xy 362.990638 -237.353856) (xy 361.816142 -237.353856) (xy 361.816142 -237.411514) (xy 361.815592 -237.439497)
			(xy 361.806835 -237.494775) (xy 361.78954 -237.548002) (xy 361.764132 -237.597869) (xy 361.731236 -237.643147)
			(xy 361.691663 -237.682723) (xy 361.646386 -237.715621) (xy 361.596521 -237.741032) (xy 361.543294 -237.758331)
			(xy 361.488017 -237.76709) (xy 361.460034 -237.767622) (xy 361.433218 -237.767139) (xy 361.380193 -237.759102)
			(xy 361.328972 -237.743205) (xy 361.280715 -237.719807) (xy 361.236511 -237.689437) (xy 361.197361 -237.652782)
			(xy 361.16415 -237.610672) (xy 361.137629 -237.564057) (xy 361.118398 -237.513993) (xy 361.106892 -237.46161)
			(xy 361.104688 -237.434882) (xy 361.096465 -237.422535) (xy 361.081845 -237.396719) (xy 361.075478 -237.38332)
			(xy 361.061762 -237.353856) (xy 360.876342 -237.353856) (xy 360.876342 -237.411514) (xy 360.875792 -237.439497)
			(xy 360.867035 -237.494775) (xy 360.84974 -237.548002) (xy 360.824332 -237.597869) (xy 360.791436 -237.643147)
			(xy 360.751863 -237.682723) (xy 360.706586 -237.715621) (xy 360.656721 -237.741032) (xy 360.603494 -237.758331)
			(xy 360.548217 -237.76709) (xy 360.520234 -237.767622) (xy 360.493418 -237.767139) (xy 360.440393 -237.759102)
			(xy 360.389172 -237.743205) (xy 360.340915 -237.719807) (xy 360.296711 -237.689437) (xy 360.257561 -237.652782)
			(xy 360.22435 -237.610672) (xy 360.197829 -237.564057) (xy 360.178598 -237.513993) (xy 360.167092 -237.46161)
			(xy 360.164888 -237.434882) (xy 360.156665 -237.422535) (xy 360.142045 -237.396719) (xy 360.135678 -237.38332)
			(xy 360.121962 -237.353856) (xy 359.936542 -237.353856) (xy 359.936542 -237.411514) (xy 359.935992 -237.439497)
			(xy 359.927235 -237.494775) (xy 359.90994 -237.548002) (xy 359.884532 -237.597869) (xy 359.851636 -237.643147)
			(xy 359.812063 -237.682723) (xy 359.766786 -237.715621) (xy 359.716921 -237.741032) (xy 359.663694 -237.758331)
			(xy 359.608417 -237.76709) (xy 359.580434 -237.767622) (xy 359.553618 -237.767139) (xy 359.500593 -237.759102)
			(xy 359.449372 -237.743205) (xy 359.401115 -237.719807) (xy 359.356911 -237.689437) (xy 359.317761 -237.652782)
			(xy 359.28455 -237.610672) (xy 359.258029 -237.564057) (xy 359.238798 -237.513993) (xy 359.227292 -237.46161)
			(xy 359.225088 -237.434882) (xy 359.216865 -237.422535) (xy 359.202245 -237.396719) (xy 359.195878 -237.38332)
			(xy 359.182162 -237.353856) (xy 358.996742 -237.353856) (xy 358.996742 -237.411514) (xy 358.996192 -237.439497)
			(xy 358.987435 -237.494775) (xy 358.97014 -237.548002) (xy 358.944732 -237.597869) (xy 358.911836 -237.643147)
			(xy 358.872263 -237.682723) (xy 358.826986 -237.715621) (xy 358.777121 -237.741032) (xy 358.723894 -237.758331)
			(xy 358.668617 -237.76709) (xy 358.640634 -237.767622) (xy 358.613818 -237.767139) (xy 358.560793 -237.759102)
			(xy 358.509572 -237.743205) (xy 358.461315 -237.719807) (xy 358.417111 -237.689437) (xy 358.377961 -237.652782)
			(xy 358.34475 -237.610672) (xy 358.318229 -237.564057) (xy 358.298998 -237.513993) (xy 358.287492 -237.46161)
			(xy 358.285288 -237.434882) (xy 358.277065 -237.422535) (xy 358.262445 -237.396719) (xy 358.256078 -237.38332)
			(xy 358.242362 -237.353856) (xy 358.056942 -237.353856) (xy 358.056942 -237.411514) (xy 358.056392 -237.439497)
			(xy 358.047635 -237.494775) (xy 358.03034 -237.548002) (xy 358.004932 -237.597869) (xy 357.972036 -237.643147)
			(xy 357.932463 -237.682723) (xy 357.887186 -237.715621) (xy 357.837321 -237.741032) (xy 357.784094 -237.758331)
			(xy 357.728817 -237.76709) (xy 357.700834 -237.767622) (xy 357.674018 -237.767139) (xy 357.620993 -237.759102)
			(xy 357.569772 -237.743205) (xy 357.521515 -237.719807) (xy 357.477311 -237.689437) (xy 357.438161 -237.652782)
			(xy 357.40495 -237.610672) (xy 357.378429 -237.564057) (xy 357.359198 -237.513993) (xy 357.347692 -237.46161)
			(xy 357.345488 -237.434882) (xy 357.337265 -237.422535) (xy 357.322645 -237.396719) (xy 357.316278 -237.38332)
			(xy 357.302562 -237.353856) (xy 356.954074 -237.353856) (xy 356.941374 -237.357158) (xy 356.920038 -237.362238)
			(xy 356.851966 -237.481364) (xy 356.866698 -237.506764) (xy 356.881721 -237.533928) (xy 356.903182 -237.592169)
			(xy 356.90937 -237.622588) (xy 356.909878 -237.626144) (xy 356.911402 -237.63351) (xy 356.935532 -237.669324)
			(xy 357.023924 -237.722156) (xy 357.04653 -237.713774) (xy 357.076175 -237.703597) (xy 357.137876 -237.692606)
			(xy 357.169212 -237.69193) (xy 357.169466 -237.69193) (xy 357.196293 -237.692414) (xy 357.24934 -237.700459)
			(xy 357.30058 -237.716372) (xy 357.348852 -237.739792) (xy 357.393064 -237.77019) (xy 357.432214 -237.806877)
			(xy 357.465418 -237.849022) (xy 357.491922 -237.895673) (xy 357.511126 -237.945771) (xy 357.522597 -237.998184)
			(xy 357.524812 -238.024924) (xy 357.539454 -238.047211) (xy 357.562616 -238.095244) (xy 357.578352 -238.146194)
			(xy 357.58631 -238.198922) (xy 357.586788 -238.225584) (xy 357.586294 -238.252233) (xy 357.81487 -238.252233)
			(xy 357.81487 -238.198935) (xy 357.822813 -238.146231) (xy 357.838523 -238.095301) (xy 357.861649 -238.04728)
			(xy 357.891673 -238.003243) (xy 357.927925 -237.964172) (xy 357.969596 -237.930941) (xy 358.015754 -237.904292)
			(xy 358.065368 -237.88482) (xy 358.11733 -237.87296) (xy 358.17048 -237.868977) (xy 358.22363 -237.87296)
			(xy 358.275592 -237.88482) (xy 358.325206 -237.904292) (xy 358.371364 -237.930941) (xy 358.413035 -237.964172)
			(xy 358.449287 -238.003243) (xy 358.479311 -238.04728) (xy 358.502437 -238.095301) (xy 358.518147 -238.146231)
			(xy 358.52609 -238.198935) (xy 358.526588 -238.225584) (xy 358.52609 -238.252233) (xy 358.75467 -238.252233)
			(xy 358.75467 -238.198935) (xy 358.762613 -238.146231) (xy 358.778323 -238.095301) (xy 358.801449 -238.04728)
			(xy 358.831473 -238.003243) (xy 358.867725 -237.964172) (xy 358.909396 -237.930941) (xy 358.955554 -237.904292)
			(xy 359.005168 -237.88482) (xy 359.05713 -237.87296) (xy 359.11028 -237.868977) (xy 359.16343 -237.87296)
			(xy 359.215392 -237.88482) (xy 359.265006 -237.904292) (xy 359.311164 -237.930941) (xy 359.352835 -237.964172)
			(xy 359.389087 -238.003243) (xy 359.419111 -238.04728) (xy 359.442237 -238.095301) (xy 359.457947 -238.146231)
			(xy 359.46589 -238.198935) (xy 359.466388 -238.225584) (xy 359.46589 -238.252233) (xy 359.69447 -238.252233)
			(xy 359.69447 -238.198935) (xy 359.702413 -238.146231) (xy 359.718123 -238.095301) (xy 359.741249 -238.04728)
			(xy 359.771273 -238.003243) (xy 359.807525 -237.964172) (xy 359.849196 -237.930941) (xy 359.895354 -237.904292)
			(xy 359.944968 -237.88482) (xy 359.99693 -237.87296) (xy 360.05008 -237.868977) (xy 360.10323 -237.87296)
			(xy 360.155192 -237.88482) (xy 360.204806 -237.904292) (xy 360.250964 -237.930941) (xy 360.292635 -237.964172)
			(xy 360.328887 -238.003243) (xy 360.358911 -238.04728) (xy 360.382037 -238.095301) (xy 360.397747 -238.146231)
			(xy 360.40569 -238.198935) (xy 360.406188 -238.225584) (xy 360.40569 -238.252233) (xy 360.63427 -238.252233)
			(xy 360.63427 -238.198935) (xy 360.642213 -238.146231) (xy 360.657923 -238.095301) (xy 360.681049 -238.04728)
			(xy 360.711073 -238.003243) (xy 360.747325 -237.964172) (xy 360.788996 -237.930941) (xy 360.835154 -237.904292)
			(xy 360.884768 -237.88482) (xy 360.93673 -237.87296) (xy 360.98988 -237.868977) (xy 361.04303 -237.87296)
			(xy 361.094992 -237.88482) (xy 361.144606 -237.904292) (xy 361.190764 -237.930941) (xy 361.232435 -237.964172)
			(xy 361.268687 -238.003243) (xy 361.298711 -238.04728) (xy 361.321837 -238.095301) (xy 361.337547 -238.146231)
			(xy 361.34549 -238.198935) (xy 361.345988 -238.225584) (xy 361.34549 -238.252233) (xy 361.57407 -238.252233)
			(xy 361.57407 -238.198935) (xy 361.582013 -238.146231) (xy 361.597723 -238.095301) (xy 361.620849 -238.04728)
			(xy 361.650873 -238.003243) (xy 361.687125 -237.964172) (xy 361.728796 -237.930941) (xy 361.774954 -237.904292)
			(xy 361.824568 -237.88482) (xy 361.87653 -237.87296) (xy 361.92968 -237.868977) (xy 361.98283 -237.87296)
			(xy 362.034792 -237.88482) (xy 362.084406 -237.904292) (xy 362.130564 -237.930941) (xy 362.172235 -237.964172)
			(xy 362.208487 -238.003243) (xy 362.238511 -238.04728) (xy 362.261637 -238.095301) (xy 362.277347 -238.146231)
			(xy 362.28529 -238.198935) (xy 362.285788 -238.225584) (xy 362.28529 -238.252233) (xy 362.277347 -238.304937)
			(xy 362.261637 -238.355867) (xy 362.238511 -238.403888) (xy 362.208487 -238.447925) (xy 362.172235 -238.486996)
			(xy 362.130564 -238.520227) (xy 362.084406 -238.546876) (xy 362.034792 -238.566348) (xy 361.98283 -238.578208)
			(xy 361.92968 -238.582192) (xy 361.87653 -238.578208) (xy 361.824568 -238.566348) (xy 361.774954 -238.546876)
			(xy 361.728796 -238.520227) (xy 361.687125 -238.486996) (xy 361.650873 -238.447925) (xy 361.620849 -238.403888)
			(xy 361.597723 -238.355867) (xy 361.582013 -238.304937) (xy 361.57407 -238.252233) (xy 361.34549 -238.252233)
			(xy 361.337547 -238.304937) (xy 361.321837 -238.355867) (xy 361.298711 -238.403888) (xy 361.268687 -238.447925)
			(xy 361.232435 -238.486996) (xy 361.190764 -238.520227) (xy 361.144606 -238.546876) (xy 361.094992 -238.566348)
			(xy 361.04303 -238.578208) (xy 360.98988 -238.582192) (xy 360.93673 -238.578208) (xy 360.884768 -238.566348)
			(xy 360.835154 -238.546876) (xy 360.788996 -238.520227) (xy 360.747325 -238.486996) (xy 360.711073 -238.447925)
			(xy 360.681049 -238.403888) (xy 360.657923 -238.355867) (xy 360.642213 -238.304937) (xy 360.63427 -238.252233)
			(xy 360.40569 -238.252233) (xy 360.397747 -238.304937) (xy 360.382037 -238.355867) (xy 360.358911 -238.403888)
			(xy 360.328887 -238.447925) (xy 360.292635 -238.486996) (xy 360.250964 -238.520227) (xy 360.204806 -238.546876)
			(xy 360.155192 -238.566348) (xy 360.10323 -238.578208) (xy 360.05008 -238.582192) (xy 359.99693 -238.578208)
			(xy 359.944968 -238.566348) (xy 359.895354 -238.546876) (xy 359.849196 -238.520227) (xy 359.807525 -238.486996)
			(xy 359.771273 -238.447925) (xy 359.741249 -238.403888) (xy 359.718123 -238.355867) (xy 359.702413 -238.304937)
			(xy 359.69447 -238.252233) (xy 359.46589 -238.252233) (xy 359.457947 -238.304937) (xy 359.442237 -238.355867)
			(xy 359.419111 -238.403888) (xy 359.389087 -238.447925) (xy 359.352835 -238.486996) (xy 359.311164 -238.520227)
			(xy 359.265006 -238.546876) (xy 359.215392 -238.566348) (xy 359.16343 -238.578208) (xy 359.11028 -238.582192)
			(xy 359.05713 -238.578208) (xy 359.005168 -238.566348) (xy 358.955554 -238.546876) (xy 358.909396 -238.520227)
			(xy 358.867725 -238.486996) (xy 358.831473 -238.447925) (xy 358.801449 -238.403888) (xy 358.778323 -238.355867)
			(xy 358.762613 -238.304937) (xy 358.75467 -238.252233) (xy 358.52609 -238.252233) (xy 358.518147 -238.304937)
			(xy 358.502437 -238.355867) (xy 358.479311 -238.403888) (xy 358.449287 -238.447925) (xy 358.413035 -238.486996)
			(xy 358.371364 -238.520227) (xy 358.325206 -238.546876) (xy 358.275592 -238.566348) (xy 358.22363 -238.578208)
			(xy 358.17048 -238.582192) (xy 358.11733 -238.578208) (xy 358.065368 -238.566348) (xy 358.015754 -238.546876)
			(xy 357.969596 -238.520227) (xy 357.927925 -238.486996) (xy 357.891673 -238.447925) (xy 357.861649 -238.403888)
			(xy 357.838523 -238.355867) (xy 357.822813 -238.304937) (xy 357.81487 -238.252233) (xy 357.586294 -238.252233)
			(xy 357.586269 -238.25357) (xy 357.577515 -238.308852) (xy 357.56022 -238.362084) (xy 357.53481 -238.411955)
			(xy 357.501912 -238.457237) (xy 357.462334 -238.496814) (xy 357.417052 -238.529712) (xy 357.36718 -238.555122)
			(xy 357.313948 -238.572416) (xy 357.258666 -238.581169) (xy 357.23068 -238.581692) (xy 357.203868 -238.581205)
			(xy 357.15085 -238.573161) (xy 357.099638 -238.557259) (xy 357.051389 -238.533857) (xy 357.007195 -238.503486)
			(xy 356.968054 -238.466831) (xy 356.934852 -238.424721) (xy 356.90834 -238.378109) (xy 356.889117 -238.328049)
			(xy 356.877617 -238.275672) (xy 356.875334 -238.248952) (xy 356.869175 -238.239803) (xy 356.857864 -238.220866)
			(xy 356.852728 -238.211106) (xy 356.848664 -238.20374) (xy 356.803198 -238.175546) (xy 356.798724 -238.175617)
			(xy 356.789908 -238.177152) (xy 356.785672 -238.178594) (xy 356.77348 -238.184436) (xy 356.749403 -238.195395)
			(xy 356.698824 -238.210885) (xy 356.646513 -238.218743) (xy 356.620064 -238.219234) (xy 356.593239 -238.218745)
			(xy 356.540196 -238.210692) (xy 356.488962 -238.194774) (xy 356.440695 -238.171351) (xy 356.396487 -238.140953)
			(xy 356.357339 -238.104267) (xy 356.324137 -238.062125) (xy 356.297632 -238.015479) (xy 356.278424 -237.965385)
			(xy 356.266947 -237.912977) (xy 356.264718 -237.88624) (xy 356.250077 -237.863952) (xy 356.226919 -237.81592)
			(xy 356.211186 -237.76497) (xy 356.203232 -237.712242) (xy 356.202742 -237.68558) (xy 356.202742 -237.685326)
			(xy 356.203131 -237.661897) (xy 356.209308 -237.615446) (xy 356.22152 -237.570206) (xy 356.239556 -237.526957)
			(xy 356.251002 -237.50651) (xy 356.26548 -237.48111) (xy 356.19944 -237.36554) (xy 356.174548 -237.353856)
			(xy 352.071178 -237.353856) (xy 351.525078 -237.899956) (xy 351.525078 -238.794544) (xy 351.554542 -238.80826)
			(xy 351.575595 -238.818326) (xy 351.615098 -238.843166) (xy 351.633282 -238.85779) (xy 351.647506 -238.869474)
			(xy 351.681034 -238.869474) (xy 351.71634 -238.854742) (xy 351.723198 -238.848392) (xy 351.745004 -238.828627)
			(xy 351.793449 -238.795213) (xy 351.846365 -238.769457) (xy 351.902549 -238.751941) (xy 351.960727 -238.743063)
			(xy 351.990152 -238.742474) (xy 351.990406 -238.742474) (xy 352.018221 -238.74297) (xy 352.073283 -238.750887)
			(xy 352.126659 -238.766559) (xy 352.177262 -238.789668) (xy 352.224061 -238.819741) (xy 352.266104 -238.856169)
			(xy 352.302536 -238.898209) (xy 352.332614 -238.945005) (xy 352.355727 -238.995605) (xy 352.371405 -239.048979)
			(xy 352.379327 -239.104041) (xy 352.379788 -239.131856) (xy 352.378264 -239.167416) (xy 352.387568 -239.189919)
			(xy 352.400681 -239.236813) (xy 352.407299 -239.285055) (xy 352.407728 -239.309402) (xy 352.407728 -239.314228)
			(xy 352.407563 -239.319287) (xy 352.763826 -239.319287) (xy 352.763826 -239.265989) (xy 352.771769 -239.213285)
			(xy 352.787479 -239.162355) (xy 352.810605 -239.114334) (xy 352.840629 -239.070297) (xy 352.876881 -239.031226)
			(xy 352.918552 -238.997995) (xy 352.96471 -238.971346) (xy 353.014324 -238.951874) (xy 353.066286 -238.940014)
			(xy 353.119436 -238.936031) (xy 353.172586 -238.940014) (xy 353.224548 -238.951874) (xy 353.274162 -238.971346)
			(xy 353.32032 -238.997995) (xy 353.361991 -239.031226) (xy 353.394301 -239.066049) (xy 361.10417 -239.066049)
			(xy 361.10417 -239.012751) (xy 361.112113 -238.960047) (xy 361.127823 -238.909117) (xy 361.150949 -238.861096)
			(xy 361.180973 -238.817059) (xy 361.217225 -238.777988) (xy 361.258896 -238.744757) (xy 361.305054 -238.718108)
			(xy 361.354668 -238.698636) (xy 361.40663 -238.686776) (xy 361.45978 -238.682793) (xy 361.51293 -238.686776)
			(xy 361.564892 -238.698636) (xy 361.614506 -238.718108) (xy 361.660664 -238.744757) (xy 361.702335 -238.777988)
			(xy 361.738587 -238.817059) (xy 361.768611 -238.861096) (xy 361.791737 -238.909117) (xy 361.807447 -238.960047)
			(xy 361.81539 -239.012751) (xy 361.815888 -239.0394) (xy 361.81539 -239.066049) (xy 361.807447 -239.118753)
			(xy 361.791737 -239.169683) (xy 361.768611 -239.217704) (xy 361.738587 -239.261741) (xy 361.702335 -239.300812)
			(xy 361.660664 -239.334043) (xy 361.614506 -239.360692) (xy 361.564892 -239.380164) (xy 361.51293 -239.392024)
			(xy 361.45978 -239.396008) (xy 361.40663 -239.392024) (xy 361.354668 -239.380164) (xy 361.305054 -239.360692)
			(xy 361.258896 -239.334043) (xy 361.217225 -239.300812) (xy 361.180973 -239.261741) (xy 361.150949 -239.217704)
			(xy 361.127823 -239.169683) (xy 361.112113 -239.118753) (xy 361.10417 -239.066049) (xy 353.394301 -239.066049)
			(xy 353.398243 -239.070297) (xy 353.428267 -239.114334) (xy 353.451393 -239.162355) (xy 353.467103 -239.213285)
			(xy 353.475046 -239.265989) (xy 353.475544 -239.292638) (xy 353.475046 -239.319287) (xy 353.467103 -239.371991)
			(xy 353.451393 -239.422921) (xy 353.428267 -239.470942) (xy 353.398243 -239.514979) (xy 353.361991 -239.55405)
			(xy 353.32032 -239.587281) (xy 353.274162 -239.61393) (xy 353.224548 -239.633402) (xy 353.172586 -239.645262)
			(xy 353.119436 -239.649246) (xy 353.066286 -239.645262) (xy 353.014324 -239.633402) (xy 352.96471 -239.61393)
			(xy 352.918552 -239.587281) (xy 352.876881 -239.55405) (xy 352.840629 -239.514979) (xy 352.810605 -239.470942)
			(xy 352.787479 -239.422921) (xy 352.771769 -239.371991) (xy 352.763826 -239.319287) (xy 352.407563 -239.319287)
			(xy 352.406822 -239.341961) (xy 352.397473 -239.396652) (xy 352.379753 -239.449231) (xy 352.354092 -239.498425)
			(xy 352.321111 -239.543044) (xy 352.281608 -239.582006) (xy 352.236539 -239.614369) (xy 352.186996 -239.639349)
			(xy 352.134178 -239.656342) (xy 352.079362 -239.664937) (xy 352.05162 -239.66551) (xy 352.026916 -239.665088)
			(xy 351.977983 -239.658255) (xy 351.930467 -239.644718) (xy 351.88528 -239.624736) (xy 351.843292 -239.598695)
			(xy 351.824036 -239.583214) (xy 351.812934 -239.574661) (xy 351.787271 -239.563421) (xy 351.75952 -239.559578)
			(xy 351.731769 -239.563421) (xy 351.706106 -239.574661) (xy 351.695004 -239.583214) (xy 351.690432 -239.587024)
			(xy 351.671358 -239.601835) (xy 351.629966 -239.626708) (xy 351.585584 -239.645742) (xy 351.562416 -239.652556)
			(xy 351.525078 -239.66297) (xy 351.525078 -239.879865) (xy 357.815124 -239.879865) (xy 357.815124 -239.826567)
			(xy 357.823067 -239.773863) (xy 357.838777 -239.722933) (xy 357.861903 -239.674912) (xy 357.891927 -239.630875)
			(xy 357.928179 -239.591804) (xy 357.96985 -239.558573) (xy 358.016008 -239.531924) (xy 358.065622 -239.512452)
			(xy 358.117584 -239.500592) (xy 358.170734 -239.496609) (xy 358.223884 -239.500592) (xy 358.275846 -239.512452)
			(xy 358.32546 -239.531924) (xy 358.371618 -239.558573) (xy 358.413289 -239.591804) (xy 358.449541 -239.630875)
			(xy 358.479565 -239.674912) (xy 358.502691 -239.722933) (xy 358.518401 -239.773863) (xy 358.526344 -239.826567)
			(xy 358.526842 -239.853216) (xy 358.526344 -239.879865) (xy 358.518401 -239.932569) (xy 358.502691 -239.983499)
			(xy 358.479565 -240.03152) (xy 358.449541 -240.075557) (xy 358.413289 -240.114628) (xy 358.371618 -240.147859)
			(xy 358.32546 -240.174508) (xy 358.275846 -240.19398) (xy 358.223884 -240.20584) (xy 358.170734 -240.209824)
			(xy 358.117584 -240.20584) (xy 358.065622 -240.19398) (xy 358.016008 -240.174508) (xy 357.96985 -240.147859)
			(xy 357.928179 -240.114628) (xy 357.891927 -240.075557) (xy 357.861903 -240.03152) (xy 357.838777 -239.983499)
			(xy 357.823067 -239.932569) (xy 357.815124 -239.879865) (xy 351.525078 -239.879865) (xy 351.525078 -241.172492)
			(xy 356.009956 -241.172492) (xy 356.010354 -241.147822) (xy 356.017161 -241.098954) (xy 356.030658 -241.051496)
			(xy 356.050585 -241.006359) (xy 356.07656 -240.964409) (xy 356.091998 -240.945162) (xy 356.100635 -240.934039)
			(xy 356.111985 -240.908277) (xy 356.115866 -240.880394) (xy 356.111982 -240.852511) (xy 356.100628 -240.826751)
			(xy 356.091998 -240.815622) (xy 356.076554 -240.796381) (xy 356.050596 -240.754424) (xy 356.03068 -240.709284)
			(xy 356.017187 -240.661827) (xy 356.010376 -240.612961) (xy 356.009956 -240.588292) (xy 356.010454 -240.561643)
			(xy 356.018397 -240.508939) (xy 356.034107 -240.458009) (xy 356.057233 -240.409988) (xy 356.087257 -240.365951)
			(xy 356.123509 -240.32688) (xy 356.16518 -240.293649) (xy 356.211338 -240.267) (xy 356.260952 -240.247528)
			(xy 356.312914 -240.235668) (xy 356.366064 -240.231685) (xy 356.419214 -240.235668) (xy 356.471176 -240.247528)
			(xy 356.52079 -240.267) (xy 356.566948 -240.293649) (xy 356.608619 -240.32688) (xy 356.644871 -240.365951)
			(xy 356.674895 -240.409988) (xy 356.698021 -240.458009) (xy 356.713731 -240.508939) (xy 356.721674 -240.561643)
			(xy 356.722172 -240.588292) (xy 356.721759 -240.612962) (xy 356.714955 -240.661829) (xy 356.705826 -240.693935)
			(xy 361.104424 -240.693935) (xy 361.104424 -240.640637) (xy 361.112367 -240.587933) (xy 361.128077 -240.537003)
			(xy 361.151203 -240.488982) (xy 361.181227 -240.444945) (xy 361.217479 -240.405874) (xy 361.25915 -240.372643)
			(xy 361.305308 -240.345994) (xy 361.354922 -240.326522) (xy 361.406884 -240.314662) (xy 361.460034 -240.310679)
			(xy 361.513184 -240.314662) (xy 361.565146 -240.326522) (xy 361.61476 -240.345994) (xy 361.660918 -240.372643)
			(xy 361.702589 -240.405874) (xy 361.738841 -240.444945) (xy 361.768865 -240.488982) (xy 361.791991 -240.537003)
			(xy 361.807701 -240.587933) (xy 361.815644 -240.640637) (xy 361.816142 -240.667286) (xy 361.815644 -240.693935)
			(xy 361.807701 -240.746639) (xy 361.791991 -240.797569) (xy 361.768865 -240.84559) (xy 361.738841 -240.889627)
			(xy 361.702589 -240.928698) (xy 361.660918 -240.961929) (xy 361.61476 -240.988578) (xy 361.565146 -241.00805)
			(xy 361.513184 -241.01991) (xy 361.460034 -241.023894) (xy 361.406884 -241.01991) (xy 361.354922 -241.00805)
			(xy 361.305308 -240.988578) (xy 361.25915 -240.961929) (xy 361.217479 -240.928698) (xy 361.181227 -240.889627)
			(xy 361.151203 -240.84559) (xy 361.128077 -240.797569) (xy 361.112367 -240.746639) (xy 361.104424 -240.693935)
			(xy 356.705826 -240.693935) (xy 356.701461 -240.709287) (xy 356.681537 -240.754424) (xy 356.655566 -240.796374)
			(xy 356.64013 -240.815622) (xy 356.631513 -240.826758) (xy 356.620169 -240.852517) (xy 356.616289 -240.880394)
			(xy 356.620166 -240.908271) (xy 356.631507 -240.934031) (xy 356.64013 -240.945162) (xy 356.655571 -240.964405)
			(xy 356.681529 -241.006362) (xy 356.701445 -241.051501) (xy 356.714939 -241.098958) (xy 356.721751 -241.147823)
			(xy 356.722172 -241.172492) (xy 356.721674 -241.199141) (xy 356.713731 -241.251845) (xy 356.698021 -241.302775)
			(xy 356.674895 -241.350796) (xy 356.644871 -241.394833) (xy 356.608619 -241.433904) (xy 356.566948 -241.467135)
			(xy 356.52079 -241.493784) (xy 356.485203 -241.507751) (xy 357.815124 -241.507751) (xy 357.815124 -241.454453)
			(xy 357.823067 -241.401749) (xy 357.838777 -241.350819) (xy 357.861903 -241.302798) (xy 357.891927 -241.258761)
			(xy 357.928179 -241.21969) (xy 357.96985 -241.186459) (xy 358.016008 -241.15981) (xy 358.065622 -241.140338)
			(xy 358.117584 -241.128478) (xy 358.170734 -241.124495) (xy 358.223884 -241.128478) (xy 358.275846 -241.140338)
			(xy 358.32546 -241.15981) (xy 358.371618 -241.186459) (xy 358.413289 -241.21969) (xy 358.449541 -241.258761)
			(xy 358.479565 -241.302798) (xy 358.502691 -241.350819) (xy 358.518401 -241.401749) (xy 358.526344 -241.454453)
			(xy 358.526842 -241.481102) (xy 358.526344 -241.507751) (xy 358.518401 -241.560455) (xy 358.502691 -241.611385)
			(xy 358.479565 -241.659406) (xy 358.475579 -241.665252) (xy 363.007148 -241.665252) (xy 363.007582 -241.640583)
			(xy 363.014381 -241.591717) (xy 363.027869 -241.544259) (xy 363.047789 -241.499121) (xy 363.073756 -241.457171)
			(xy 363.08919 -241.437922) (xy 363.097865 -241.426826) (xy 363.109212 -241.401054) (xy 363.113085 -241.373163)
			(xy 363.109191 -241.345274) (xy 363.097826 -241.319511) (xy 363.08919 -241.308382) (xy 363.073772 -241.289121)
			(xy 363.047811 -241.247169) (xy 363.027889 -241.202034) (xy 363.01439 -241.154582) (xy 363.007572 -241.10572)
			(xy 363.007148 -241.081052) (xy 363.007646 -241.054403) (xy 363.015589 -241.001699) (xy 363.031299 -240.950769)
			(xy 363.054425 -240.902748) (xy 363.084449 -240.858711) (xy 363.120701 -240.81964) (xy 363.162372 -240.786409)
			(xy 363.20853 -240.75976) (xy 363.258144 -240.740288) (xy 363.310106 -240.728428) (xy 363.363256 -240.724445)
			(xy 363.416406 -240.728428) (xy 363.468368 -240.740288) (xy 363.517982 -240.75976) (xy 363.56414 -240.786409)
			(xy 363.605811 -240.81964) (xy 363.642063 -240.858711) (xy 363.672087 -240.902748) (xy 363.695213 -240.950769)
			(xy 363.710923 -241.001699) (xy 363.718866 -241.054403) (xy 363.719364 -241.081052) (xy 363.71893 -241.105721)
			(xy 363.712131 -241.154587) (xy 363.698642 -241.202045) (xy 363.678723 -241.247182) (xy 363.652756 -241.289133)
			(xy 363.637322 -241.308382) (xy 363.628744 -241.319546) (xy 363.617396 -241.345294) (xy 363.613508 -241.373163)
			(xy 363.617376 -241.401034) (xy 363.628705 -241.426791) (xy 363.637322 -241.437922) (xy 363.652743 -241.45718)
			(xy 363.678704 -241.499133) (xy 363.698625 -241.544268) (xy 363.712123 -241.591722) (xy 363.718941 -241.640584)
			(xy 363.719364 -241.665252) (xy 363.718866 -241.691901) (xy 363.710923 -241.744605) (xy 363.695213 -241.795535)
			(xy 363.672087 -241.843556) (xy 363.642063 -241.887593) (xy 363.605811 -241.926664) (xy 363.56414 -241.959895)
			(xy 363.517982 -241.986544) (xy 363.468368 -242.006016) (xy 363.416406 -242.017876) (xy 363.363256 -242.02186)
			(xy 363.310106 -242.017876) (xy 363.258144 -242.006016) (xy 363.20853 -241.986544) (xy 363.162372 -241.959895)
			(xy 363.120701 -241.926664) (xy 363.084449 -241.887593) (xy 363.054425 -241.843556) (xy 363.031299 -241.795535)
			(xy 363.015589 -241.744605) (xy 363.007646 -241.691901) (xy 363.007148 -241.665252) (xy 358.475579 -241.665252)
			(xy 358.449541 -241.703443) (xy 358.413289 -241.742514) (xy 358.371618 -241.775745) (xy 358.32546 -241.802394)
			(xy 358.275846 -241.821866) (xy 358.223884 -241.833726) (xy 358.170734 -241.83771) (xy 358.117584 -241.833726)
			(xy 358.065622 -241.821866) (xy 358.016008 -241.802394) (xy 357.96985 -241.775745) (xy 357.928179 -241.742514)
			(xy 357.891927 -241.703443) (xy 357.861903 -241.659406) (xy 357.838777 -241.611385) (xy 357.823067 -241.560455)
			(xy 357.815124 -241.507751) (xy 356.485203 -241.507751) (xy 356.471176 -241.513256) (xy 356.419214 -241.525116)
			(xy 356.366064 -241.5291) (xy 356.312914 -241.525116) (xy 356.260952 -241.513256) (xy 356.211338 -241.493784)
			(xy 356.16518 -241.467135) (xy 356.123509 -241.433904) (xy 356.087257 -241.394833) (xy 356.057233 -241.350796)
			(xy 356.034107 -241.302775) (xy 356.018397 -241.251845) (xy 356.010454 -241.199141) (xy 356.009956 -241.172492)
			(xy 351.525078 -241.172492) (xy 351.525078 -242.321567) (xy 361.104424 -242.321567) (xy 361.104424 -242.268269)
			(xy 361.112367 -242.215565) (xy 361.128077 -242.164635) (xy 361.151203 -242.116614) (xy 361.181227 -242.072577)
			(xy 361.217479 -242.033506) (xy 361.25915 -242.000275) (xy 361.305308 -241.973626) (xy 361.354922 -241.954154)
			(xy 361.406884 -241.942294) (xy 361.460034 -241.938311) (xy 361.513184 -241.942294) (xy 361.565146 -241.954154)
			(xy 361.61476 -241.973626) (xy 361.660918 -242.000275) (xy 361.702589 -242.033506) (xy 361.738841 -242.072577)
			(xy 361.768865 -242.116614) (xy 361.791991 -242.164635) (xy 361.807701 -242.215565) (xy 361.815644 -242.268269)
			(xy 361.816142 -242.294918) (xy 361.815644 -242.321567) (xy 361.807701 -242.374271) (xy 361.791991 -242.425201)
			(xy 361.768865 -242.473222) (xy 361.738841 -242.517259) (xy 361.702589 -242.55633) (xy 361.660918 -242.589561)
			(xy 361.61476 -242.61621) (xy 361.565146 -242.635682) (xy 361.513184 -242.647542) (xy 361.460034 -242.651526)
			(xy 361.406884 -242.647542) (xy 361.354922 -242.635682) (xy 361.305308 -242.61621) (xy 361.25915 -242.589561)
			(xy 361.217479 -242.55633) (xy 361.181227 -242.517259) (xy 361.151203 -242.473222) (xy 361.128077 -242.425201)
			(xy 361.112367 -242.374271) (xy 361.104424 -242.321567) (xy 351.525078 -242.321567) (xy 351.525078 -243.135637)
			(xy 357.815124 -243.135637) (xy 357.815124 -243.082339) (xy 357.823067 -243.029635) (xy 357.838777 -242.978705)
			(xy 357.861903 -242.930684) (xy 357.891927 -242.886647) (xy 357.928179 -242.847576) (xy 357.96985 -242.814345)
			(xy 358.016008 -242.787696) (xy 358.065622 -242.768224) (xy 358.117584 -242.756364) (xy 358.170734 -242.752381)
			(xy 358.223884 -242.756364) (xy 358.275846 -242.768224) (xy 358.32546 -242.787696) (xy 358.371618 -242.814345)
			(xy 358.413289 -242.847576) (xy 358.449541 -242.886647) (xy 358.479565 -242.930684) (xy 358.494116 -242.9609)
			(xy 365.407174 -242.9609) (xy 365.411157 -242.907747) (xy 365.423018 -242.855781) (xy 365.442492 -242.806163)
			(xy 365.469144 -242.760002) (xy 365.502378 -242.718329) (xy 365.541452 -242.682075) (xy 365.585493 -242.652049)
			(xy 365.633517 -242.628923) (xy 365.684452 -242.613213) (xy 365.737159 -242.60527) (xy 365.76381 -242.604798)
			(xy 365.764064 -242.604798) (xy 365.789972 -242.605301) (xy 365.841238 -242.612839) (xy 365.890873 -242.627717)
			(xy 365.937832 -242.649623) (xy 365.981125 -242.678096) (xy 366.000792 -242.694968) (xy 366.012186 -242.704456)
			(xy 366.039034 -242.717005) (xy 366.068356 -242.721309) (xy 366.097678 -242.717005) (xy 366.124526 -242.704456)
			(xy 366.13592 -242.694968) (xy 366.15555 -242.678046) (xy 366.198837 -242.649543) (xy 366.245802 -242.627625)
			(xy 366.295452 -242.612758) (xy 366.346734 -242.605256) (xy 366.372648 -242.604798) (xy 366.372902 -242.604798)
			(xy 366.399552 -242.605284) (xy 366.452256 -242.613228) (xy 366.503187 -242.628938) (xy 366.551208 -242.652064)
			(xy 366.595246 -242.682089) (xy 366.634317 -242.718342) (xy 366.667548 -242.760013) (xy 366.694198 -242.806172)
			(xy 366.71367 -242.855787) (xy 366.72553 -242.90775) (xy 366.729514 -242.9609) (xy 366.72553 -243.01405)
			(xy 366.71367 -243.066013) (xy 366.694198 -243.115628) (xy 366.667548 -243.161787) (xy 366.634317 -243.203458)
			(xy 366.595246 -243.239711) (xy 366.551208 -243.269736) (xy 366.503187 -243.292862) (xy 366.452256 -243.308572)
			(xy 366.399552 -243.316516) (xy 366.372902 -243.317014) (xy 366.372648 -243.317014) (xy 366.34674 -243.316501)
			(xy 366.295475 -243.308965) (xy 366.24584 -243.294089) (xy 366.198881 -243.272185) (xy 366.155587 -243.243715)
			(xy 366.13592 -243.226844) (xy 366.124526 -243.217356) (xy 366.097678 -243.204807) (xy 366.068356 -243.200503)
			(xy 366.039034 -243.204807) (xy 366.012186 -243.217356) (xy 366.000792 -243.226844) (xy 365.981159 -243.243763)
			(xy 365.937873 -243.272266) (xy 365.890908 -243.294183) (xy 365.841259 -243.309052) (xy 365.789978 -243.316555)
			(xy 365.764064 -243.317014) (xy 365.76381 -243.317014) (xy 365.737159 -243.31653) (xy 365.684452 -243.308587)
			(xy 365.633517 -243.292877) (xy 365.585493 -243.269751) (xy 365.541452 -243.239725) (xy 365.502378 -243.203471)
			(xy 365.469144 -243.161798) (xy 365.442492 -243.115637) (xy 365.423018 -243.066019) (xy 365.411157 -243.014053)
			(xy 365.407174 -242.9609) (xy 358.494116 -242.9609) (xy 358.502691 -242.978705) (xy 358.518401 -243.029635)
			(xy 358.526344 -243.082339) (xy 358.526842 -243.108988) (xy 358.526344 -243.135637) (xy 358.518401 -243.188341)
			(xy 358.502691 -243.239271) (xy 358.479565 -243.287292) (xy 358.449541 -243.331329) (xy 358.413289 -243.3704)
			(xy 358.371618 -243.403631) (xy 358.32546 -243.43028) (xy 358.275846 -243.449752) (xy 358.223884 -243.461612)
			(xy 358.170734 -243.465596) (xy 358.117584 -243.461612) (xy 358.065622 -243.449752) (xy 358.016008 -243.43028)
			(xy 357.96985 -243.403631) (xy 357.928179 -243.3704) (xy 357.891927 -243.331329) (xy 357.861903 -243.287292)
			(xy 357.838777 -243.239271) (xy 357.823067 -243.188341) (xy 357.815124 -243.135637) (xy 351.525078 -243.135637)
			(xy 351.525078 -243.225066) (xy 352.249465 -243.949453) (xy 361.104424 -243.949453) (xy 361.104424 -243.896155)
			(xy 361.112367 -243.843451) (xy 361.128077 -243.792521) (xy 361.151203 -243.7445) (xy 361.181227 -243.700463)
			(xy 361.217479 -243.661392) (xy 361.25915 -243.628161) (xy 361.305308 -243.601512) (xy 361.354922 -243.58204)
			(xy 361.406884 -243.57018) (xy 361.460034 -243.566197) (xy 361.513184 -243.57018) (xy 361.565146 -243.58204)
			(xy 361.61476 -243.601512) (xy 361.660918 -243.628161) (xy 361.702589 -243.661392) (xy 361.738841 -243.700463)
			(xy 361.768865 -243.7445) (xy 361.791991 -243.792521) (xy 361.807701 -243.843451) (xy 361.815644 -243.896155)
			(xy 361.816142 -243.922804) (xy 361.815644 -243.949453) (xy 361.807701 -244.002157) (xy 361.791991 -244.053087)
			(xy 361.768865 -244.101108) (xy 361.738841 -244.145145) (xy 361.702589 -244.184216) (xy 361.660918 -244.217447)
			(xy 361.61476 -244.244096) (xy 361.565146 -244.263568) (xy 361.513184 -244.275428) (xy 361.460034 -244.279412)
			(xy 361.406884 -244.275428) (xy 361.354922 -244.263568) (xy 361.305308 -244.244096) (xy 361.25915 -244.217447)
			(xy 361.217479 -244.184216) (xy 361.181227 -244.145145) (xy 361.151203 -244.101108) (xy 361.128077 -244.053087)
			(xy 361.112367 -244.002157) (xy 361.104424 -243.949453) (xy 352.249465 -243.949453) (xy 353.31146 -245.011448)
			(xy 353.31146 -245.347236) (xy 356.017576 -245.347236) (xy 356.017994 -245.322567) (xy 356.024796 -245.273699)
			(xy 356.038288 -245.226241) (xy 356.058211 -245.181104) (xy 356.084182 -245.139154) (xy 356.099618 -245.119906)
			(xy 356.108212 -245.108752) (xy 356.119565 -245.083001) (xy 356.123453 -245.055128) (xy 356.11958 -245.027253)
			(xy 356.108241 -245.001495) (xy 356.099618 -244.990366) (xy 356.084182 -244.971119) (xy 356.058225 -244.929162)
			(xy 356.038308 -244.884024) (xy 356.024813 -244.836569) (xy 356.017998 -244.787704) (xy 356.017576 -244.763036)
			(xy 356.018074 -244.736387) (xy 356.026017 -244.683683) (xy 356.041727 -244.632753) (xy 356.064853 -244.584732)
			(xy 356.094877 -244.540695) (xy 356.131129 -244.501624) (xy 356.1728 -244.468393) (xy 356.218958 -244.441744)
			(xy 356.268572 -244.422272) (xy 356.320534 -244.410412) (xy 356.373684 -244.406429) (xy 356.426834 -244.410412)
			(xy 356.478796 -244.422272) (xy 356.52841 -244.441744) (xy 356.574568 -244.468393) (xy 356.616239 -244.501624)
			(xy 356.652491 -244.540695) (xy 356.682515 -244.584732) (xy 356.705641 -244.632753) (xy 356.721351 -244.683683)
			(xy 356.729294 -244.736387) (xy 356.729792 -244.763036) (xy 356.729788 -244.763269) (xy 357.815124 -244.763269)
			(xy 357.815124 -244.709971) (xy 357.823067 -244.657267) (xy 357.838777 -244.606337) (xy 357.861903 -244.558316)
			(xy 357.891927 -244.514279) (xy 357.928179 -244.475208) (xy 357.96985 -244.441977) (xy 358.016008 -244.415328)
			(xy 358.065622 -244.395856) (xy 358.117584 -244.383996) (xy 358.170734 -244.380013) (xy 358.223884 -244.383996)
			(xy 358.275846 -244.395856) (xy 358.32546 -244.415328) (xy 358.371618 -244.441977) (xy 358.413289 -244.475208)
			(xy 358.449541 -244.514279) (xy 358.479565 -244.558316) (xy 358.502691 -244.606337) (xy 358.518401 -244.657267)
			(xy 358.526344 -244.709971) (xy 358.526842 -244.73662) (xy 358.526344 -244.763269) (xy 358.518401 -244.815973)
			(xy 358.502691 -244.866903) (xy 358.479565 -244.914924) (xy 358.449541 -244.958961) (xy 358.413289 -244.998032)
			(xy 358.371618 -245.031263) (xy 358.32546 -245.057912) (xy 358.275846 -245.077384) (xy 358.223884 -245.089244)
			(xy 358.170734 -245.093228) (xy 358.117584 -245.089244) (xy 358.065622 -245.077384) (xy 358.016008 -245.057912)
			(xy 357.96985 -245.031263) (xy 357.928179 -244.998032) (xy 357.891927 -244.958961) (xy 357.861903 -244.914924)
			(xy 357.838777 -244.866903) (xy 357.823067 -244.815973) (xy 357.815124 -244.763269) (xy 356.729788 -244.763269)
			(xy 356.729342 -244.787704) (xy 356.722546 -244.83657) (xy 356.70906 -244.884027) (xy 356.689145 -244.929165)
			(xy 356.663182 -244.971116) (xy 356.64775 -244.990366) (xy 356.63909 -245.001472) (xy 356.627749 -245.027241)
			(xy 356.623876 -245.055128) (xy 356.627764 -245.083013) (xy 356.639119 -245.108776) (xy 356.64775 -245.119906)
			(xy 356.663168 -245.139166) (xy 356.689129 -245.181119) (xy 356.70905 -245.226254) (xy 356.722549 -245.273707)
			(xy 356.729368 -245.322568) (xy 356.729792 -245.347236) (xy 356.729294 -245.373885) (xy 356.721351 -245.426589)
			(xy 356.705641 -245.477519) (xy 356.682515 -245.52554) (xy 356.652491 -245.569577) (xy 356.645289 -245.577339)
			(xy 361.104424 -245.577339) (xy 361.104424 -245.524041) (xy 361.112367 -245.471337) (xy 361.128077 -245.420407)
			(xy 361.151203 -245.372386) (xy 361.181227 -245.328349) (xy 361.217479 -245.289278) (xy 361.25915 -245.256047)
			(xy 361.305308 -245.229398) (xy 361.354922 -245.209926) (xy 361.406884 -245.198066) (xy 361.460034 -245.194083)
			(xy 361.513184 -245.198066) (xy 361.565146 -245.209926) (xy 361.61476 -245.229398) (xy 361.660918 -245.256047)
			(xy 361.702589 -245.289278) (xy 361.738841 -245.328349) (xy 361.768865 -245.372386) (xy 361.780484 -245.396512)
			(xy 362.999528 -245.396512) (xy 362.999943 -245.371843) (xy 363.006747 -245.322975) (xy 363.02024 -245.275518)
			(xy 363.040163 -245.23038) (xy 363.066134 -245.18843) (xy 363.08157 -245.169182) (xy 363.090183 -245.158043)
			(xy 363.101527 -245.132286) (xy 363.105409 -245.104409) (xy 363.101532 -245.076532) (xy 363.090193 -245.050773)
			(xy 363.08157 -245.039642) (xy 363.066131 -245.020398) (xy 363.040173 -244.978441) (xy 363.020256 -244.933302)
			(xy 363.006762 -244.885846) (xy 362.999949 -244.836981) (xy 362.999528 -244.812312) (xy 363.000026 -244.785663)
			(xy 363.007969 -244.732959) (xy 363.023679 -244.682029) (xy 363.046805 -244.634008) (xy 363.076829 -244.589971)
			(xy 363.113081 -244.5509) (xy 363.154752 -244.517669) (xy 363.20091 -244.49102) (xy 363.250524 -244.471548)
			(xy 363.302486 -244.459688) (xy 363.355636 -244.455705) (xy 363.408786 -244.459688) (xy 363.460748 -244.471548)
			(xy 363.510362 -244.49102) (xy 363.55652 -244.517669) (xy 363.598191 -244.5509) (xy 363.634443 -244.589971)
			(xy 363.664467 -244.634008) (xy 363.687593 -244.682029) (xy 363.703303 -244.732959) (xy 363.711246 -244.785663)
			(xy 363.711744 -244.812312) (xy 363.711349 -244.836982) (xy 363.704541 -244.88585) (xy 363.691043 -244.933309)
			(xy 363.671116 -244.978446) (xy 363.64514 -245.020395) (xy 363.629702 -245.039642) (xy 363.621061 -245.050763)
			(xy 363.609712 -245.076526) (xy 363.605832 -245.104409) (xy 363.609717 -245.132292) (xy 363.621071 -245.158053)
			(xy 363.629702 -245.169182) (xy 363.645102 -245.188457) (xy 363.671067 -245.230405) (xy 363.690992 -245.275536)
			(xy 363.704495 -245.322986) (xy 363.711318 -245.371845) (xy 363.711744 -245.396512) (xy 363.711246 -245.423161)
			(xy 363.703303 -245.475865) (xy 363.687593 -245.526795) (xy 363.664467 -245.574816) (xy 363.634443 -245.618853)
			(xy 363.598191 -245.657924) (xy 363.55652 -245.691155) (xy 363.510362 -245.717804) (xy 363.460748 -245.737276)
			(xy 363.408786 -245.749136) (xy 363.355636 -245.75312) (xy 363.302486 -245.749136) (xy 363.250524 -245.737276)
			(xy 363.20091 -245.717804) (xy 363.154752 -245.691155) (xy 363.113081 -245.657924) (xy 363.076829 -245.618853)
			(xy 363.046805 -245.574816) (xy 363.023679 -245.526795) (xy 363.007969 -245.475865) (xy 363.000026 -245.423161)
			(xy 362.999528 -245.396512) (xy 361.780484 -245.396512) (xy 361.791991 -245.420407) (xy 361.807701 -245.471337)
			(xy 361.815644 -245.524041) (xy 361.816142 -245.55069) (xy 361.815644 -245.577339) (xy 361.807701 -245.630043)
			(xy 361.791991 -245.680973) (xy 361.768865 -245.728994) (xy 361.738841 -245.773031) (xy 361.702589 -245.812102)
			(xy 361.660918 -245.845333) (xy 361.61476 -245.871982) (xy 361.565146 -245.891454) (xy 361.513184 -245.903314)
			(xy 361.460034 -245.907298) (xy 361.406884 -245.903314) (xy 361.354922 -245.891454) (xy 361.305308 -245.871982)
			(xy 361.25915 -245.845333) (xy 361.217479 -245.812102) (xy 361.181227 -245.773031) (xy 361.151203 -245.728994)
			(xy 361.128077 -245.680973) (xy 361.112367 -245.630043) (xy 361.104424 -245.577339) (xy 356.645289 -245.577339)
			(xy 356.616239 -245.608648) (xy 356.574568 -245.641879) (xy 356.52841 -245.668528) (xy 356.478796 -245.688)
			(xy 356.426834 -245.69986) (xy 356.373684 -245.703844) (xy 356.320534 -245.69986) (xy 356.268572 -245.688)
			(xy 356.218958 -245.668528) (xy 356.1728 -245.641879) (xy 356.131129 -245.608648) (xy 356.094877 -245.569577)
			(xy 356.064853 -245.52554) (xy 356.041727 -245.477519) (xy 356.026017 -245.426589) (xy 356.018074 -245.373885)
			(xy 356.017576 -245.347236) (xy 353.31146 -245.347236) (xy 353.31146 -246.333518) (xy 353.34067 -246.347234)
			(xy 353.36058 -246.357037) (xy 353.39803 -246.380851) (xy 353.415346 -246.394732) (xy 353.426268 -246.40413)
			(xy 353.437512 -246.413038) (xy 353.463665 -246.424792) (xy 353.492054 -246.428816) (xy 353.520443 -246.424792)
			(xy 353.546596 -246.413038) (xy 353.55784 -246.40413) (xy 353.577554 -246.387109) (xy 353.620992 -246.358377)
			(xy 353.668148 -246.33627) (xy 353.718019 -246.321259) (xy 353.769544 -246.313665) (xy 353.795584 -246.313198)
			(xy 353.822235 -246.31367) (xy 353.874943 -246.321612) (xy 353.925879 -246.337322) (xy 353.973904 -246.360447)
			(xy 354.017946 -246.390473) (xy 354.018681 -246.391155) (xy 357.815124 -246.391155) (xy 357.815124 -246.337857)
			(xy 357.823067 -246.285153) (xy 357.838777 -246.234223) (xy 357.861903 -246.186202) (xy 357.891927 -246.142165)
			(xy 357.928179 -246.103094) (xy 357.96985 -246.069863) (xy 358.016008 -246.043214) (xy 358.065622 -246.023742)
			(xy 358.117584 -246.011882) (xy 358.170734 -246.007899) (xy 358.223884 -246.011882) (xy 358.275846 -246.023742)
			(xy 358.32546 -246.043214) (xy 358.371618 -246.069863) (xy 358.413289 -246.103094) (xy 358.449541 -246.142165)
			(xy 358.479565 -246.186202) (xy 358.502691 -246.234223) (xy 358.518401 -246.285153) (xy 358.526344 -246.337857)
			(xy 358.526842 -246.364506) (xy 358.526344 -246.391155) (xy 358.518401 -246.443859) (xy 358.502691 -246.494789)
			(xy 358.479565 -246.54281) (xy 358.449541 -246.586847) (xy 358.413289 -246.625918) (xy 358.371618 -246.659149)
			(xy 358.32546 -246.685798) (xy 358.275846 -246.70527) (xy 358.223884 -246.71713) (xy 358.170734 -246.721114)
			(xy 358.117584 -246.71713) (xy 358.065622 -246.70527) (xy 358.016008 -246.685798) (xy 357.96985 -246.659149)
			(xy 357.928179 -246.625918) (xy 357.891927 -246.586847) (xy 357.861903 -246.54281) (xy 357.838777 -246.494789)
			(xy 357.823067 -246.443859) (xy 357.815124 -246.391155) (xy 354.018681 -246.391155) (xy 354.05702 -246.426727)
			(xy 354.090255 -246.4684) (xy 354.116907 -246.514562) (xy 354.136381 -246.56418) (xy 354.148243 -246.616146)
			(xy 354.152226 -246.6693) (xy 354.148243 -246.722454) (xy 354.136381 -246.77442) (xy 354.116907 -246.824038)
			(xy 354.090255 -246.8702) (xy 354.05702 -246.911873) (xy 354.017946 -246.948127) (xy 353.973904 -246.978153)
			(xy 353.925879 -247.001278) (xy 353.874943 -247.016988) (xy 353.822235 -247.02493) (xy 353.795584 -247.025414)
			(xy 353.76954 -247.024967) (xy 353.718007 -247.017392) (xy 353.668126 -247.00239) (xy 353.620964 -246.980283)
			(xy 353.577524 -246.951541) (xy 353.55784 -246.934482) (xy 353.546596 -246.925574) (xy 353.520443 -246.91382)
			(xy 353.492054 -246.909796) (xy 353.463665 -246.91382) (xy 353.437512 -246.925574) (xy 353.426268 -246.934482)
			(xy 353.415346 -246.94388) (xy 353.398036 -246.957769) (xy 353.360586 -246.981584) (xy 353.34067 -246.991378)
			(xy 353.31146 -247.005094) (xy 353.31146 -247.204971) (xy 361.104424 -247.204971) (xy 361.104424 -247.151673)
			(xy 361.112367 -247.098969) (xy 361.128077 -247.048039) (xy 361.151203 -247.000018) (xy 361.181227 -246.955981)
			(xy 361.217479 -246.91691) (xy 361.25915 -246.883679) (xy 361.305308 -246.85703) (xy 361.354922 -246.837558)
			(xy 361.406884 -246.825698) (xy 361.460034 -246.821715) (xy 361.513184 -246.825698) (xy 361.565146 -246.837558)
			(xy 361.61476 -246.85703) (xy 361.660918 -246.883679) (xy 361.702589 -246.91691) (xy 361.738841 -246.955981)
			(xy 361.768865 -247.000018) (xy 361.791991 -247.048039) (xy 361.807701 -247.098969) (xy 361.815644 -247.151673)
			(xy 361.816142 -247.178322) (xy 361.815644 -247.204971) (xy 361.807701 -247.257675) (xy 361.791991 -247.308605)
			(xy 361.768865 -247.356626) (xy 361.738841 -247.400663) (xy 361.702589 -247.439734) (xy 361.660918 -247.472965)
			(xy 361.61476 -247.499614) (xy 361.565146 -247.519086) (xy 361.513184 -247.530946) (xy 361.460034 -247.53493)
			(xy 361.406884 -247.530946) (xy 361.354922 -247.519086) (xy 361.305308 -247.499614) (xy 361.25915 -247.472965)
			(xy 361.217479 -247.439734) (xy 361.181227 -247.400663) (xy 361.151203 -247.356626) (xy 361.128077 -247.308605)
			(xy 361.112367 -247.257675) (xy 361.104424 -247.204971) (xy 353.31146 -247.204971) (xy 353.31146 -248.018787)
			(xy 357.815124 -248.018787) (xy 357.815124 -247.965489) (xy 357.823067 -247.912785) (xy 357.838777 -247.861855)
			(xy 357.861903 -247.813834) (xy 357.891927 -247.769797) (xy 357.928179 -247.730726) (xy 357.96985 -247.697495)
			(xy 358.016008 -247.670846) (xy 358.065622 -247.651374) (xy 358.117584 -247.639514) (xy 358.170734 -247.635531)
			(xy 358.223884 -247.639514) (xy 358.275846 -247.651374) (xy 358.32546 -247.670846) (xy 358.371618 -247.697495)
			(xy 358.413289 -247.730726) (xy 358.449541 -247.769797) (xy 358.479565 -247.813834) (xy 358.502691 -247.861855)
			(xy 358.518401 -247.912785) (xy 358.526344 -247.965489) (xy 358.526842 -247.992138) (xy 358.526344 -248.018787)
			(xy 358.518401 -248.071491) (xy 358.502691 -248.122421) (xy 358.479565 -248.170442) (xy 358.449541 -248.214479)
			(xy 358.413289 -248.25355) (xy 358.371618 -248.286781) (xy 358.32546 -248.31343) (xy 358.275846 -248.332902)
			(xy 358.223884 -248.344762) (xy 358.170734 -248.348746) (xy 358.117584 -248.344762) (xy 358.065622 -248.332902)
			(xy 358.016008 -248.31343) (xy 357.96985 -248.286781) (xy 357.928179 -248.25355) (xy 357.891927 -248.214479)
			(xy 357.861903 -248.170442) (xy 357.838777 -248.122421) (xy 357.823067 -248.071491) (xy 357.815124 -248.018787)
			(xy 353.31146 -248.018787) (xy 353.31146 -248.564146) (xy 352.870516 -249.00509) (xy 356.017576 -249.00509)
			(xy 356.017968 -248.98042) (xy 356.024776 -248.931551) (xy 356.038274 -248.884093) (xy 356.058203 -248.838956)
			(xy 356.084179 -248.797007) (xy 356.099618 -248.77776) (xy 356.108255 -248.766637) (xy 356.119603 -248.740875)
			(xy 356.123482 -248.712992) (xy 356.119599 -248.68511) (xy 356.108247 -248.659349) (xy 356.099618 -248.64822)
			(xy 356.084207 -248.628954) (xy 356.058246 -248.587003) (xy 356.038325 -248.541869) (xy 356.024824 -248.494418)
			(xy 356.018002 -248.445557) (xy 356.017576 -248.42089) (xy 356.018074 -248.394241) (xy 356.026017 -248.341537)
			(xy 356.041727 -248.290607) (xy 356.064853 -248.242586) (xy 356.094877 -248.198549) (xy 356.131129 -248.159478)
			(xy 356.1728 -248.126247) (xy 356.218958 -248.099598) (xy 356.268572 -248.080126) (xy 356.320534 -248.068266)
			(xy 356.373684 -248.064283) (xy 356.426834 -248.068266) (xy 356.478796 -248.080126) (xy 356.52841 -248.099598)
			(xy 356.574568 -248.126247) (xy 356.616239 -248.159478) (xy 356.652491 -248.198549) (xy 356.682515 -248.242586)
			(xy 356.705641 -248.290607) (xy 356.721351 -248.341537) (xy 356.729294 -248.394241) (xy 356.729792 -248.42089)
			(xy 356.729374 -248.445559) (xy 356.72257 -248.494426) (xy 356.709077 -248.541884) (xy 356.689155 -248.587021)
			(xy 356.663185 -248.628972) (xy 356.64775 -248.64822) (xy 356.639134 -248.659357) (xy 356.627788 -248.685115)
			(xy 356.623906 -248.712992) (xy 356.627783 -248.74087) (xy 356.639126 -248.76663) (xy 356.64775 -248.77776)
			(xy 356.663193 -248.797001) (xy 356.685375 -248.832857) (xy 361.104424 -248.832857) (xy 361.104424 -248.779559)
			(xy 361.112367 -248.726855) (xy 361.128077 -248.675925) (xy 361.151203 -248.627904) (xy 361.181227 -248.583867)
			(xy 361.217479 -248.544796) (xy 361.25915 -248.511565) (xy 361.305308 -248.484916) (xy 361.354922 -248.465444)
			(xy 361.406884 -248.453584) (xy 361.460034 -248.449601) (xy 361.513184 -248.453584) (xy 361.565146 -248.465444)
			(xy 361.61476 -248.484916) (xy 361.660918 -248.511565) (xy 361.702589 -248.544796) (xy 361.738841 -248.583867)
			(xy 361.768865 -248.627904) (xy 361.791991 -248.675925) (xy 361.807701 -248.726855) (xy 361.815644 -248.779559)
			(xy 361.816142 -248.806208) (xy 361.815644 -248.832857) (xy 361.807701 -248.885561) (xy 361.791991 -248.936491)
			(xy 361.768865 -248.984512) (xy 361.738841 -249.028549) (xy 361.702589 -249.06762) (xy 361.660918 -249.100851)
			(xy 361.61476 -249.1275) (xy 361.565146 -249.146972) (xy 361.513184 -249.158832) (xy 361.460034 -249.162816)
			(xy 361.406884 -249.158832) (xy 361.354922 -249.146972) (xy 361.305308 -249.1275) (xy 361.25915 -249.100851)
			(xy 361.217479 -249.06762) (xy 361.181227 -249.028549) (xy 361.151203 -248.984512) (xy 361.128077 -248.936491)
			(xy 361.112367 -248.885561) (xy 361.104424 -248.832857) (xy 356.685375 -248.832857) (xy 356.68915 -248.838959)
			(xy 356.709066 -248.884099) (xy 356.722559 -248.931556) (xy 356.729372 -248.980421) (xy 356.729792 -249.00509)
			(xy 356.729294 -249.031739) (xy 356.721351 -249.084443) (xy 356.705641 -249.135373) (xy 356.682515 -249.183394)
			(xy 356.652899 -249.226832) (xy 362.966508 -249.226832) (xy 362.966939 -249.202163) (xy 362.97374 -249.153297)
			(xy 362.98723 -249.105839) (xy 363.007149 -249.060702) (xy 363.033116 -249.018751) (xy 363.04855 -248.999502)
			(xy 363.057145 -248.98835) (xy 363.068494 -248.962598) (xy 363.07238 -248.934725) (xy 363.068508 -248.90685)
			(xy 363.057171 -248.881092) (xy 363.04855 -248.869962) (xy 363.033117 -248.850713) (xy 363.007159 -248.808757)
			(xy 362.987241 -248.763619) (xy 362.973745 -248.716164) (xy 362.96693 -248.6673) (xy 362.966508 -248.642632)
			(xy 362.967006 -248.615983) (xy 362.974949 -248.563279) (xy 362.990659 -248.512349) (xy 363.013785 -248.464328)
			(xy 363.043809 -248.420291) (xy 363.080061 -248.38122) (xy 363.121732 -248.347989) (xy 363.16789 -248.32134)
			(xy 363.217504 -248.301868) (xy 363.269466 -248.290008) (xy 363.322616 -248.286025) (xy 363.375766 -248.290008)
			(xy 363.427728 -248.301868) (xy 363.477342 -248.32134) (xy 363.5235 -248.347989) (xy 363.565171 -248.38122)
			(xy 363.601423 -248.420291) (xy 363.631447 -248.464328) (xy 363.654573 -248.512349) (xy 363.670283 -248.563279)
			(xy 363.678226 -248.615983) (xy 363.678724 -248.642632) (xy 363.678345 -248.667303) (xy 363.671534 -248.716172)
			(xy 363.658033 -248.76363) (xy 363.638101 -248.808767) (xy 363.612122 -248.850715) (xy 363.596682 -248.869962)
			(xy 363.588023 -248.881069) (xy 363.576678 -248.906838) (xy 363.572803 -248.934725) (xy 363.576692 -248.96261)
			(xy 363.588049 -248.988373) (xy 363.596682 -248.999502) (xy 363.612103 -249.01876) (xy 363.638062 -249.060714)
			(xy 363.657982 -249.105849) (xy 363.671481 -249.153302) (xy 363.6783 -249.202164) (xy 363.678724 -249.226832)
			(xy 363.678226 -249.253481) (xy 363.670283 -249.306185) (xy 363.654573 -249.357115) (xy 363.631447 -249.405136)
			(xy 363.601423 -249.449173) (xy 363.565171 -249.488244) (xy 363.5235 -249.521475) (xy 363.477342 -249.548124)
			(xy 363.427728 -249.567596) (xy 363.375766 -249.579456) (xy 363.322616 -249.58344) (xy 363.269466 -249.579456)
			(xy 363.217504 -249.567596) (xy 363.16789 -249.548124) (xy 363.121732 -249.521475) (xy 363.080061 -249.488244)
			(xy 363.043809 -249.449173) (xy 363.013785 -249.405136) (xy 362.990659 -249.357115) (xy 362.974949 -249.306185)
			(xy 362.967006 -249.253481) (xy 362.966508 -249.226832) (xy 356.652899 -249.226832) (xy 356.652491 -249.227431)
			(xy 356.616239 -249.266502) (xy 356.574568 -249.299733) (xy 356.52841 -249.326382) (xy 356.478796 -249.345854)
			(xy 356.426834 -249.357714) (xy 356.373684 -249.361698) (xy 356.320534 -249.357714) (xy 356.268572 -249.345854)
			(xy 356.218958 -249.326382) (xy 356.1728 -249.299733) (xy 356.131129 -249.266502) (xy 356.094877 -249.227431)
			(xy 356.064853 -249.183394) (xy 356.041727 -249.135373) (xy 356.026017 -249.084443) (xy 356.018074 -249.031739)
			(xy 356.017576 -249.00509) (xy 352.870516 -249.00509) (xy 352.228933 -249.646673) (xy 357.815124 -249.646673)
			(xy 357.815124 -249.593375) (xy 357.823067 -249.540671) (xy 357.838777 -249.489741) (xy 357.861903 -249.44172)
			(xy 357.891927 -249.397683) (xy 357.928179 -249.358612) (xy 357.96985 -249.325381) (xy 358.016008 -249.298732)
			(xy 358.065622 -249.27926) (xy 358.117584 -249.2674) (xy 358.170734 -249.263417) (xy 358.223884 -249.2674)
			(xy 358.275846 -249.27926) (xy 358.32546 -249.298732) (xy 358.371618 -249.325381) (xy 358.413289 -249.358612)
			(xy 358.449541 -249.397683) (xy 358.479565 -249.44172) (xy 358.502691 -249.489741) (xy 358.518401 -249.540671)
			(xy 358.526344 -249.593375) (xy 358.526842 -249.620024) (xy 358.526344 -249.646673) (xy 358.518401 -249.699377)
			(xy 358.502691 -249.750307) (xy 358.479565 -249.798328) (xy 358.449541 -249.842365) (xy 358.413289 -249.881436)
			(xy 358.371618 -249.914667) (xy 358.32546 -249.941316) (xy 358.275846 -249.960788) (xy 358.223884 -249.972648)
			(xy 358.170734 -249.976632) (xy 358.117584 -249.972648) (xy 358.065622 -249.960788) (xy 358.016008 -249.941316)
			(xy 357.96985 -249.914667) (xy 357.928179 -249.881436) (xy 357.891927 -249.842365) (xy 357.861903 -249.798328)
			(xy 357.838777 -249.750307) (xy 357.823067 -249.699377) (xy 357.815124 -249.646673) (xy 352.228933 -249.646673)
			(xy 351.89922 -249.976386) (xy 351.89922 -250.3371) (xy 353.040134 -250.3371) (xy 353.044118 -250.283941)
			(xy 353.05598 -250.23197) (xy 353.075456 -250.182347) (xy 353.10211 -250.136182) (xy 353.135347 -250.094504)
			(xy 353.174424 -250.058246) (xy 353.218469 -250.028217) (xy 353.266498 -250.005088) (xy 353.317438 -249.989376)
			(xy 353.37015 -249.981431) (xy 353.396804 -249.980958) (xy 353.422644 -249.981418) (xy 353.473781 -249.988901)
			(xy 353.5233 -250.003694) (xy 353.570161 -250.025487) (xy 353.613382 -250.053823) (xy 353.633024 -250.07062)
			(xy 353.644402 -250.08001) (xy 353.671154 -250.092413) (xy 353.700334 -250.096665) (xy 353.729514 -250.092413)
			(xy 353.756266 -250.08001) (xy 353.767644 -250.07062) (xy 353.787266 -250.053798) (xy 353.830488 -250.025457)
			(xy 353.877354 -250.003666) (xy 353.926879 -249.988881) (xy 353.978022 -249.981415) (xy 354.003864 -249.980958)
			(xy 354.030514 -249.981497) (xy 354.08322 -249.989436) (xy 354.134154 -250.005142) (xy 354.182178 -250.028265)
			(xy 354.226219 -250.058288) (xy 354.265293 -250.094539) (xy 354.298527 -250.13621) (xy 354.325179 -250.182369)
			(xy 354.344653 -250.231984) (xy 354.356515 -250.283948) (xy 354.360498 -250.3371) (xy 365.407134 -250.3371)
			(xy 365.411118 -250.283941) (xy 365.42298 -250.231969) (xy 365.442456 -250.182346) (xy 365.469111 -250.13618)
			(xy 365.502349 -250.094502) (xy 365.541427 -250.058244) (xy 365.585473 -250.028215) (xy 365.633502 -250.005086)
			(xy 365.684443 -249.989374) (xy 365.737156 -249.981431) (xy 365.76381 -249.980958) (xy 365.764064 -249.980958)
			(xy 365.789973 -249.981446) (xy 365.84124 -249.988985) (xy 365.890876 -250.003866) (xy 365.937834 -250.025776)
			(xy 365.981126 -250.054253) (xy 366.000792 -250.071128) (xy 366.012186 -250.080616) (xy 366.039034 -250.093165)
			(xy 366.068356 -250.097469) (xy 366.097678 -250.093165) (xy 366.124526 -250.080616) (xy 366.13592 -250.071128)
			(xy 366.155558 -250.054215) (xy 366.198842 -250.025709) (xy 366.245805 -250.003789) (xy 366.295453 -249.988919)
			(xy 366.346734 -249.981416) (xy 366.372648 -249.980958) (xy 366.372902 -249.980958) (xy 366.399549 -249.981524)
			(xy 366.452247 -249.989467) (xy 366.503172 -250.005176) (xy 366.551188 -250.028299) (xy 366.595221 -250.058321)
			(xy 366.634287 -250.094569) (xy 366.667515 -250.136236) (xy 366.694161 -250.182389) (xy 366.713632 -250.231999)
			(xy 366.72549 -250.283956) (xy 366.729473 -250.3371) (xy 366.72549 -250.390244) (xy 366.713632 -250.442201)
			(xy 366.694161 -250.491811) (xy 366.667515 -250.537964) (xy 366.634287 -250.579631) (xy 366.595221 -250.615879)
			(xy 366.551188 -250.645901) (xy 366.503172 -250.669024) (xy 366.452247 -250.684733) (xy 366.399549 -250.692676)
			(xy 366.372902 -250.693174) (xy 366.372648 -250.693174) (xy 366.34674 -250.692671) (xy 366.295474 -250.685134)
			(xy 366.245839 -250.670256) (xy 366.19888 -250.64835) (xy 366.155587 -250.619877) (xy 366.13592 -250.603004)
			(xy 366.124526 -250.593516) (xy 366.097678 -250.580967) (xy 366.068356 -250.576663) (xy 366.039034 -250.580967)
			(xy 366.012186 -250.593516) (xy 366.000792 -250.603004) (xy 365.981153 -250.619916) (xy 365.93787 -250.648422)
			(xy 365.890906 -250.670341) (xy 365.841258 -250.685211) (xy 365.789978 -250.692715) (xy 365.764064 -250.693174)
			(xy 365.76381 -250.693174) (xy 365.737156 -250.692769) (xy 365.684443 -250.684826) (xy 365.633502 -250.669114)
			(xy 365.585473 -250.645985) (xy 365.541427 -250.615956) (xy 365.502349 -250.579698) (xy 365.469111 -250.53802)
			(xy 365.442456 -250.491854) (xy 365.42298 -250.442231) (xy 365.411118 -250.390259) (xy 365.407134 -250.3371)
			(xy 354.360498 -250.3371) (xy 354.356515 -250.390252) (xy 354.344653 -250.442216) (xy 354.325179 -250.491831)
			(xy 354.298527 -250.53799) (xy 354.265293 -250.579661) (xy 354.226219 -250.615912) (xy 354.182178 -250.645935)
			(xy 354.134154 -250.669058) (xy 354.08322 -250.684764) (xy 354.030514 -250.692703) (xy 354.003864 -250.693174)
			(xy 353.978023 -250.692725) (xy 353.926886 -250.685238) (xy 353.877368 -250.670442) (xy 353.830507 -250.648647)
			(xy 353.787286 -250.62031) (xy 353.767644 -250.603512) (xy 353.756266 -250.594122) (xy 353.729514 -250.581719)
			(xy 353.700334 -250.577467) (xy 353.671154 -250.581719) (xy 353.644402 -250.594122) (xy 353.633024 -250.603512)
			(xy 353.613367 -250.620292) (xy 353.570156 -250.648641) (xy 353.523299 -250.670442) (xy 353.473781 -250.685236)
			(xy 353.422644 -250.692712) (xy 353.396804 -250.693174) (xy 353.37015 -250.692769) (xy 353.317438 -250.684824)
			(xy 353.266498 -250.669112) (xy 353.218469 -250.645983) (xy 353.174424 -250.615954) (xy 353.135347 -250.579696)
			(xy 353.10211 -250.538018) (xy 353.075456 -250.491853) (xy 353.05598 -250.44223) (xy 353.044118 -250.390259)
			(xy 353.040134 -250.3371) (xy 351.89922 -250.3371) (xy 351.89922 -252.659134) (xy 356.017576 -252.659134)
			(xy 356.017993 -252.634465) (xy 356.024795 -252.585597) (xy 356.038287 -252.538139) (xy 356.05821 -252.493002)
			(xy 356.084182 -252.451052) (xy 356.099618 -252.431804) (xy 356.108213 -252.420652) (xy 356.119567 -252.3949)
			(xy 356.123454 -252.367026) (xy 356.119581 -252.339151) (xy 356.108241 -252.313393) (xy 356.099618 -252.302264)
			(xy 356.084181 -252.283018) (xy 356.058224 -252.241061) (xy 356.038308 -252.195922) (xy 356.024813 -252.148467)
			(xy 356.017998 -252.099603) (xy 356.017576 -252.074934) (xy 356.018074 -252.048285) (xy 356.026017 -251.995581)
			(xy 356.041727 -251.944651) (xy 356.064853 -251.89663) (xy 356.094877 -251.852593) (xy 356.131129 -251.813522)
			(xy 356.1728 -251.780291) (xy 356.218958 -251.753642) (xy 356.268572 -251.73417) (xy 356.320534 -251.72231)
			(xy 356.373684 -251.718327) (xy 356.426834 -251.72231) (xy 356.478796 -251.73417) (xy 356.52841 -251.753642)
			(xy 356.574568 -251.780291) (xy 356.616239 -251.813522) (xy 356.652491 -251.852593) (xy 356.682515 -251.89663)
			(xy 356.705641 -251.944651) (xy 356.721351 -251.995581) (xy 356.729294 -252.048285) (xy 356.729792 -252.074934)
			(xy 356.729341 -252.099602) (xy 356.722545 -252.148468) (xy 356.70906 -252.195925) (xy 356.689145 -252.241063)
			(xy 356.663182 -252.283014) (xy 356.64775 -252.302264) (xy 356.639092 -252.313371) (xy 356.627751 -252.33914)
			(xy 356.623877 -252.367026) (xy 356.627765 -252.394911) (xy 356.63912 -252.420674) (xy 356.64775 -252.431804)
			(xy 356.663167 -252.451065) (xy 356.689128 -252.493018) (xy 356.709049 -252.538152) (xy 356.722548 -252.585605)
			(xy 356.729368 -252.634466) (xy 356.729792 -252.659134) (xy 356.729294 -252.685783) (xy 356.721351 -252.738487)
			(xy 356.705641 -252.789417) (xy 356.697803 -252.805692) (xy 363.017308 -252.805692) (xy 363.017716 -252.781022)
			(xy 363.024523 -252.732155) (xy 363.038018 -252.684697) (xy 363.057942 -252.63956) (xy 363.083914 -252.59761)
			(xy 363.09935 -252.578362) (xy 363.107983 -252.567237) (xy 363.119328 -252.541475) (xy 363.123206 -252.513594)
			(xy 363.119324 -252.485713) (xy 363.107977 -252.459952) (xy 363.09935 -252.448822) (xy 363.083898 -252.429587)
			(xy 363.057943 -252.387627) (xy 363.038029 -252.342486) (xy 363.024537 -252.295028) (xy 363.017727 -252.246161)
			(xy 363.017308 -252.221492) (xy 363.017806 -252.194843) (xy 363.025749 -252.142139) (xy 363.041459 -252.091209)
			(xy 363.064585 -252.043188) (xy 363.094609 -251.999151) (xy 363.130861 -251.96008) (xy 363.172532 -251.926849)
			(xy 363.21869 -251.9002) (xy 363.268304 -251.880728) (xy 363.320266 -251.868868) (xy 363.373416 -251.864885)
			(xy 363.426566 -251.868868) (xy 363.478528 -251.880728) (xy 363.528142 -251.9002) (xy 363.5743 -251.926849)
			(xy 363.615971 -251.96008) (xy 363.652223 -251.999151) (xy 363.682247 -252.043188) (xy 363.705373 -252.091209)
			(xy 363.721083 -252.142139) (xy 363.729026 -252.194843) (xy 363.729524 -252.221492) (xy 363.729122 -252.246162)
			(xy 363.722316 -252.29503) (xy 363.708821 -252.342488) (xy 363.688894 -252.387625) (xy 363.66292 -252.429575)
			(xy 363.647482 -252.448822) (xy 363.638862 -252.459957) (xy 363.627512 -252.485715) (xy 363.623629 -252.513594)
			(xy 363.627509 -252.541473) (xy 363.638855 -252.567233) (xy 363.647482 -252.578362) (xy 363.662931 -252.597599)
			(xy 363.688886 -252.639558) (xy 363.7088 -252.684699) (xy 363.722292 -252.732157) (xy 363.729104 -252.781023)
			(xy 363.729524 -252.805692) (xy 363.729026 -252.832341) (xy 363.721083 -252.885045) (xy 363.705373 -252.935975)
			(xy 363.682247 -252.983996) (xy 363.652223 -253.028033) (xy 363.615971 -253.067104) (xy 363.5743 -253.100335)
			(xy 363.528142 -253.126984) (xy 363.478528 -253.146456) (xy 363.426566 -253.158316) (xy 363.373416 -253.1623)
			(xy 363.320266 -253.158316) (xy 363.268304 -253.146456) (xy 363.21869 -253.126984) (xy 363.172532 -253.100335)
			(xy 363.130861 -253.067104) (xy 363.094609 -253.028033) (xy 363.064585 -252.983996) (xy 363.041459 -252.935975)
			(xy 363.025749 -252.885045) (xy 363.017806 -252.832341) (xy 363.017308 -252.805692) (xy 356.697803 -252.805692)
			(xy 356.682515 -252.837438) (xy 356.652491 -252.881475) (xy 356.616239 -252.920546) (xy 356.574568 -252.953777)
			(xy 356.52841 -252.980426) (xy 356.478796 -252.999898) (xy 356.426834 -253.011758) (xy 356.373684 -253.015742)
			(xy 356.320534 -253.011758) (xy 356.268572 -252.999898) (xy 356.218958 -252.980426) (xy 356.1728 -252.953777)
			(xy 356.131129 -252.920546) (xy 356.094877 -252.881475) (xy 356.064853 -252.837438) (xy 356.041727 -252.789417)
			(xy 356.026017 -252.738487) (xy 356.018074 -252.685783) (xy 356.017576 -252.659134) (xy 351.89922 -252.659134)
			(xy 351.89922 -254.015) (xy 353.040154 -254.015) (xy 353.044137 -253.961844) (xy 353.055999 -253.909876)
			(xy 353.075474 -253.860256) (xy 353.102126 -253.814093) (xy 353.135361 -253.772418) (xy 353.174437 -253.736162)
			(xy 353.218479 -253.706134) (xy 353.266505 -253.683006) (xy 353.317442 -253.667295) (xy 353.370152 -253.659351)
			(xy 353.396804 -253.658878) (xy 353.422643 -253.659358) (xy 353.473778 -253.666839) (xy 353.523296 -253.681629)
			(xy 353.570158 -253.703417) (xy 353.61338 -253.731746) (xy 353.633024 -253.74854) (xy 353.644402 -253.75793)
			(xy 353.671154 -253.770333) (xy 353.700334 -253.774585) (xy 353.729514 -253.770333) (xy 353.756266 -253.75793)
			(xy 353.767644 -253.74854) (xy 353.787269 -253.731721) (xy 353.830489 -253.703379) (xy 353.877355 -253.681587)
			(xy 353.926879 -253.666802) (xy 353.978022 -253.659335) (xy 354.003864 -253.658878) (xy 354.030516 -253.659377)
			(xy 354.083225 -253.667316) (xy 354.134162 -253.683024) (xy 354.182188 -253.706148) (xy 354.226232 -253.736172)
			(xy 354.265308 -253.772426) (xy 354.298544 -253.814099) (xy 354.325197 -253.86026) (xy 354.344672 -253.909878)
			(xy 354.353005 -253.946385) (xy 361.214152 -253.946385) (xy 361.214152 -253.893087) (xy 361.222095 -253.840383)
			(xy 361.237805 -253.789453) (xy 361.260931 -253.741432) (xy 361.290955 -253.697395) (xy 361.327207 -253.658324)
			(xy 361.368878 -253.625093) (xy 361.415036 -253.598444) (xy 361.46465 -253.578972) (xy 361.516612 -253.567112)
			(xy 361.569762 -253.563129) (xy 361.622912 -253.567112) (xy 361.674874 -253.578972) (xy 361.724488 -253.598444)
			(xy 361.770646 -253.625093) (xy 361.812317 -253.658324) (xy 361.848569 -253.697395) (xy 361.878593 -253.741432)
			(xy 361.901719 -253.789453) (xy 361.917429 -253.840383) (xy 361.925372 -253.893087) (xy 361.92587 -253.919736)
			(xy 361.925372 -253.946385) (xy 361.917429 -253.999089) (xy 361.912521 -254.015) (xy 365.407154 -254.015)
			(xy 365.411138 -253.961844) (xy 365.422999 -253.909875) (xy 365.442474 -253.860255) (xy 365.469127 -253.814091)
			(xy 365.502363 -253.772416) (xy 365.541439 -253.736159) (xy 365.585483 -253.706132) (xy 365.63351 -253.683005)
			(xy 365.684447 -253.667294) (xy 365.737157 -253.659351) (xy 365.76381 -253.658878) (xy 365.764064 -253.658878)
			(xy 365.789973 -253.659361) (xy 365.841241 -253.6669) (xy 365.890876 -253.681783) (xy 365.937835 -253.703694)
			(xy 365.981127 -253.732172) (xy 366.000792 -253.749048) (xy 366.012186 -253.758536) (xy 366.039034 -253.771085)
			(xy 366.068356 -253.775389) (xy 366.097678 -253.771085) (xy 366.124526 -253.758536) (xy 366.13592 -253.749048)
			(xy 366.155548 -253.732122) (xy 366.198835 -253.703621) (xy 366.245801 -253.681704) (xy 366.295451 -253.666838)
			(xy 366.346734 -253.659336) (xy 366.372648 -253.658878) (xy 366.372902 -253.658878) (xy 366.39955 -253.659404)
			(xy 366.452251 -253.667347) (xy 366.50318 -253.683057) (xy 366.551198 -253.706182) (xy 366.595233 -253.736205)
			(xy 366.634302 -253.772456) (xy 366.667532 -253.814124) (xy 366.69418 -253.86028) (xy 366.713651 -253.909893)
			(xy 366.725511 -253.961853) (xy 366.729494 -254.015) (xy 366.725511 -254.068147) (xy 366.713651 -254.120107)
			(xy 366.69418 -254.16972) (xy 366.667532 -254.215876) (xy 366.634302 -254.257544) (xy 366.595233 -254.293795)
			(xy 366.551198 -254.323818) (xy 366.50318 -254.346943) (xy 366.452251 -254.362653) (xy 366.39955 -254.370596)
			(xy 366.372902 -254.371094) (xy 366.372648 -254.371094) (xy 366.34674 -254.370586) (xy 366.295474 -254.36305)
			(xy 366.245839 -254.348172) (xy 366.198881 -254.326267) (xy 366.155587 -254.297796) (xy 366.13592 -254.280924)
			(xy 366.124526 -254.271436) (xy 366.097678 -254.258887) (xy 366.068356 -254.254583) (xy 366.039034 -254.258887)
			(xy 366.012186 -254.271436) (xy 366.000792 -254.280924) (xy 365.981156 -254.297839) (xy 365.937871 -254.326344)
			(xy 365.890907 -254.348262) (xy 365.841259 -254.363131) (xy 365.789978 -254.370635) (xy 365.764064 -254.371094)
			(xy 365.76381 -254.371094) (xy 365.737157 -254.370649) (xy 365.684447 -254.362706) (xy 365.63351 -254.346995)
			(xy 365.585483 -254.323868) (xy 365.541439 -254.293841) (xy 365.502363 -254.257584) (xy 365.469127 -254.215909)
			(xy 365.442474 -254.169745) (xy 365.422999 -254.120125) (xy 365.411138 -254.068156) (xy 365.407154 -254.015)
			(xy 361.912521 -254.015) (xy 361.901719 -254.050019) (xy 361.878593 -254.09804) (xy 361.848569 -254.142077)
			(xy 361.812317 -254.181148) (xy 361.770646 -254.214379) (xy 361.724488 -254.241028) (xy 361.674874 -254.2605)
			(xy 361.622912 -254.27236) (xy 361.569762 -254.276344) (xy 361.516612 -254.27236) (xy 361.46465 -254.2605)
			(xy 361.415036 -254.241028) (xy 361.368878 -254.214379) (xy 361.327207 -254.181148) (xy 361.290955 -254.142077)
			(xy 361.260931 -254.09804) (xy 361.237805 -254.050019) (xy 361.222095 -253.999089) (xy 361.214152 -253.946385)
			(xy 354.353005 -253.946385) (xy 354.356534 -253.961845) (xy 354.360518 -254.015) (xy 354.356534 -254.068155)
			(xy 354.344672 -254.120122) (xy 354.325197 -254.16974) (xy 354.298544 -254.215901) (xy 354.265308 -254.257574)
			(xy 354.226232 -254.293828) (xy 354.182188 -254.323852) (xy 354.134162 -254.346976) (xy 354.083225 -254.362684)
			(xy 354.030516 -254.370623) (xy 354.003864 -254.371094) (xy 353.978023 -254.37064) (xy 353.926887 -254.363154)
			(xy 353.877369 -254.348358) (xy 353.830508 -254.326564) (xy 353.787286 -254.298229) (xy 353.767644 -254.281432)
			(xy 353.756266 -254.272042) (xy 353.729514 -254.259639) (xy 353.700334 -254.255387) (xy 353.671154 -254.259639)
			(xy 353.644402 -254.272042) (xy 353.633024 -254.281432) (xy 353.613369 -254.298215) (xy 353.570157 -254.326563)
			(xy 353.5233 -254.348363) (xy 353.473781 -254.363156) (xy 353.422644 -254.370632) (xy 353.396804 -254.371094)
			(xy 353.370152 -254.370649) (xy 353.317442 -254.362705) (xy 353.266505 -254.346994) (xy 353.218479 -254.323866)
			(xy 353.174437 -254.293838) (xy 353.135361 -254.257582) (xy 353.102126 -254.215907) (xy 353.075474 -254.169744)
			(xy 353.055999 -254.120124) (xy 353.044137 -254.068156) (xy 353.040154 -254.015) (xy 351.89922 -254.015)
			(xy 351.89922 -254.760201) (xy 357.924852 -254.760201) (xy 357.924852 -254.706903) (xy 357.932795 -254.654199)
			(xy 357.948505 -254.603269) (xy 357.971631 -254.555248) (xy 358.001655 -254.511211) (xy 358.037907 -254.47214)
			(xy 358.079578 -254.438909) (xy 358.125736 -254.41226) (xy 358.17535 -254.392788) (xy 358.227312 -254.380928)
			(xy 358.280462 -254.376945) (xy 358.333612 -254.380928) (xy 358.385574 -254.392788) (xy 358.435188 -254.41226)
			(xy 358.481346 -254.438909) (xy 358.523017 -254.47214) (xy 358.559269 -254.511211) (xy 358.589293 -254.555248)
			(xy 358.612419 -254.603269) (xy 358.628129 -254.654199) (xy 358.636072 -254.706903) (xy 358.63657 -254.733552)
			(xy 358.636072 -254.760201) (xy 358.628129 -254.812905) (xy 358.612419 -254.863835) (xy 358.589293 -254.911856)
			(xy 358.559269 -254.955893) (xy 358.523017 -254.994964) (xy 358.481346 -255.028195) (xy 358.435188 -255.054844)
			(xy 358.385574 -255.074316) (xy 358.333612 -255.086176) (xy 358.280462 -255.09016) (xy 358.227312 -255.086176)
			(xy 358.17535 -255.074316) (xy 358.125736 -255.054844) (xy 358.079578 -255.028195) (xy 358.037907 -254.994964)
			(xy 358.001655 -254.955893) (xy 357.971631 -254.911856) (xy 357.948505 -254.863835) (xy 357.932795 -254.812905)
			(xy 357.924852 -254.760201) (xy 351.89922 -254.760201) (xy 351.89922 -256.330196) (xy 356.017576 -256.330196)
			(xy 356.017971 -256.305526) (xy 356.024779 -256.256657) (xy 356.038276 -256.209199) (xy 356.058204 -256.164062)
			(xy 356.08418 -256.122113) (xy 356.099618 -256.102866) (xy 356.10825 -256.091739) (xy 356.119598 -256.065978)
			(xy 356.123479 -256.038097) (xy 356.119596 -256.010216) (xy 356.108246 -255.984455) (xy 356.099618 -255.973326)
			(xy 356.084163 -255.954094) (xy 356.058209 -255.912133) (xy 356.038296 -255.866991) (xy 356.024806 -255.819532)
			(xy 356.017995 -255.770665) (xy 356.017576 -255.745996) (xy 356.018074 -255.719347) (xy 356.026017 -255.666643)
			(xy 356.041727 -255.615713) (xy 356.064853 -255.567692) (xy 356.094877 -255.523655) (xy 356.131129 -255.484584)
			(xy 356.1728 -255.451353) (xy 356.218958 -255.424704) (xy 356.268572 -255.405232) (xy 356.320534 -255.393372)
			(xy 356.373684 -255.389389) (xy 356.426834 -255.393372) (xy 356.478796 -255.405232) (xy 356.52841 -255.424704)
			(xy 356.574568 -255.451353) (xy 356.616239 -255.484584) (xy 356.652491 -255.523655) (xy 356.682515 -255.567692)
			(xy 356.685683 -255.574271) (xy 361.214152 -255.574271) (xy 361.214152 -255.520973) (xy 361.222095 -255.468269)
			(xy 361.237805 -255.417339) (xy 361.260931 -255.369318) (xy 361.290955 -255.325281) (xy 361.327207 -255.28621)
			(xy 361.368878 -255.252979) (xy 361.415036 -255.22633) (xy 361.46465 -255.206858) (xy 361.516612 -255.194998)
			(xy 361.569762 -255.191015) (xy 361.622912 -255.194998) (xy 361.674874 -255.206858) (xy 361.724488 -255.22633)
			(xy 361.770646 -255.252979) (xy 361.812317 -255.28621) (xy 361.848569 -255.325281) (xy 361.878593 -255.369318)
			(xy 361.901719 -255.417339) (xy 361.917429 -255.468269) (xy 361.925372 -255.520973) (xy 361.92587 -255.547622)
			(xy 361.925372 -255.574271) (xy 361.917429 -255.626975) (xy 361.901719 -255.677905) (xy 361.878593 -255.725926)
			(xy 361.848569 -255.769963) (xy 361.812317 -255.809034) (xy 361.770646 -255.842265) (xy 361.724488 -255.868914)
			(xy 361.674874 -255.888386) (xy 361.622912 -255.900246) (xy 361.569762 -255.90423) (xy 361.516612 -255.900246)
			(xy 361.46465 -255.888386) (xy 361.415036 -255.868914) (xy 361.368878 -255.842265) (xy 361.327207 -255.809034)
			(xy 361.290955 -255.769963) (xy 361.260931 -255.725926) (xy 361.237805 -255.677905) (xy 361.222095 -255.626975)
			(xy 361.214152 -255.574271) (xy 356.685683 -255.574271) (xy 356.705641 -255.615713) (xy 356.721351 -255.666643)
			(xy 356.729294 -255.719347) (xy 356.729792 -255.745996) (xy 356.729377 -255.770665) (xy 356.722572 -255.819532)
			(xy 356.709079 -255.86699) (xy 356.689156 -255.912127) (xy 356.663186 -255.954078) (xy 356.64775 -255.973326)
			(xy 356.639128 -255.984459) (xy 356.627782 -256.010218) (xy 356.623901 -256.038097) (xy 356.627781 -256.065976)
			(xy 356.639125 -256.091736) (xy 356.64775 -256.102866) (xy 356.663196 -256.122105) (xy 356.689152 -256.164064)
			(xy 356.709068 -256.209204) (xy 356.72256 -256.256661) (xy 356.729372 -256.305527) (xy 356.729792 -256.330196)
			(xy 356.729294 -256.356845) (xy 356.724586 -256.388087) (xy 357.924852 -256.388087) (xy 357.924852 -256.334789)
			(xy 357.932795 -256.282085) (xy 357.948505 -256.231155) (xy 357.971631 -256.183134) (xy 358.001655 -256.139097)
			(xy 358.037907 -256.100026) (xy 358.079578 -256.066795) (xy 358.125736 -256.040146) (xy 358.17535 -256.020674)
			(xy 358.227312 -256.008814) (xy 358.280462 -256.004831) (xy 358.333612 -256.008814) (xy 358.385574 -256.020674)
			(xy 358.435188 -256.040146) (xy 358.481346 -256.066795) (xy 358.523017 -256.100026) (xy 358.559269 -256.139097)
			(xy 358.589293 -256.183134) (xy 358.612419 -256.231155) (xy 358.628129 -256.282085) (xy 358.636072 -256.334789)
			(xy 358.63657 -256.361438) (xy 358.636072 -256.388087) (xy 358.635839 -256.389632) (xy 363.012228 -256.389632)
			(xy 363.012655 -256.364963) (xy 363.019456 -256.316096) (xy 363.032947 -256.268639) (xy 363.052867 -256.223501)
			(xy 363.078836 -256.181551) (xy 363.09427 -256.162302) (xy 363.102863 -256.151149) (xy 363.11421 -256.125397)
			(xy 363.118096 -256.097525) (xy 363.114224 -256.069651) (xy 363.10289 -256.043893) (xy 363.09427 -256.032762)
			(xy 363.07884 -256.01351) (xy 363.052881 -255.971556) (xy 363.032962 -255.926419) (xy 363.019466 -255.878964)
			(xy 363.01265 -255.8301) (xy 363.012228 -255.805432) (xy 363.012726 -255.778783) (xy 363.020669 -255.726079)
			(xy 363.036379 -255.675149) (xy 363.059505 -255.627128) (xy 363.089529 -255.583091) (xy 363.125781 -255.54402)
			(xy 363.167452 -255.510789) (xy 363.21361 -255.48414) (xy 363.263224 -255.464668) (xy 363.315186 -255.452808)
			(xy 363.368336 -255.448825) (xy 363.421486 -255.452808) (xy 363.473448 -255.464668) (xy 363.523062 -255.48414)
			(xy 363.56922 -255.510789) (xy 363.610891 -255.54402) (xy 363.647143 -255.583091) (xy 363.677167 -255.627128)
			(xy 363.700293 -255.675149) (xy 363.716003 -255.726079) (xy 363.723946 -255.778783) (xy 363.724444 -255.805432)
			(xy 363.724061 -255.830103) (xy 363.71725 -255.878971) (xy 363.70375 -255.92643) (xy 363.683819 -255.971567)
			(xy 363.657841 -256.013515) (xy 363.642402 -256.032762) (xy 363.633742 -256.043869) (xy 363.622395 -256.069637)
			(xy 363.618519 -256.097525) (xy 363.622409 -256.125411) (xy 363.633768 -256.151173) (xy 363.642402 -256.162302)
			(xy 363.657811 -256.18157) (xy 363.683774 -256.22352) (xy 363.703698 -256.268653) (xy 363.717199 -256.316104)
			(xy 363.724019 -256.364965) (xy 363.724444 -256.389632) (xy 363.723946 -256.416281) (xy 363.716003 -256.468985)
			(xy 363.700293 -256.519915) (xy 363.677167 -256.567936) (xy 363.647143 -256.611973) (xy 363.610891 -256.651044)
			(xy 363.56922 -256.684275) (xy 363.523062 -256.710924) (xy 363.473448 -256.730396) (xy 363.421486 -256.742256)
			(xy 363.368336 -256.74624) (xy 363.315186 -256.742256) (xy 363.263224 -256.730396) (xy 363.21361 -256.710924)
			(xy 363.167452 -256.684275) (xy 363.125781 -256.651044) (xy 363.089529 -256.611973) (xy 363.059505 -256.567936)
			(xy 363.036379 -256.519915) (xy 363.020669 -256.468985) (xy 363.012726 -256.416281) (xy 363.012228 -256.389632)
			(xy 358.635839 -256.389632) (xy 358.628129 -256.440791) (xy 358.612419 -256.491721) (xy 358.589293 -256.539742)
			(xy 358.559269 -256.583779) (xy 358.523017 -256.62285) (xy 358.481346 -256.656081) (xy 358.435188 -256.68273)
			(xy 358.385574 -256.702202) (xy 358.333612 -256.714062) (xy 358.280462 -256.718046) (xy 358.227312 -256.714062)
			(xy 358.17535 -256.702202) (xy 358.125736 -256.68273) (xy 358.079578 -256.656081) (xy 358.037907 -256.62285)
			(xy 358.001655 -256.583779) (xy 357.971631 -256.539742) (xy 357.948505 -256.491721) (xy 357.932795 -256.440791)
			(xy 357.924852 -256.388087) (xy 356.724586 -256.388087) (xy 356.721351 -256.409549) (xy 356.705641 -256.460479)
			(xy 356.682515 -256.5085) (xy 356.652491 -256.552537) (xy 356.616239 -256.591608) (xy 356.574568 -256.624839)
			(xy 356.52841 -256.651488) (xy 356.478796 -256.67096) (xy 356.426834 -256.68282) (xy 356.373684 -256.686804)
			(xy 356.320534 -256.68282) (xy 356.268572 -256.67096) (xy 356.218958 -256.651488) (xy 356.1728 -256.624839)
			(xy 356.131129 -256.591608) (xy 356.094877 -256.552537) (xy 356.064853 -256.5085) (xy 356.041727 -256.460479)
			(xy 356.026017 -256.409549) (xy 356.018074 -256.356845) (xy 356.017576 -256.330196) (xy 351.89922 -256.330196)
			(xy 351.89922 -257.201903) (xy 361.214152 -257.201903) (xy 361.214152 -257.148605) (xy 361.222095 -257.095901)
			(xy 361.237805 -257.044971) (xy 361.260931 -256.99695) (xy 361.290955 -256.952913) (xy 361.327207 -256.913842)
			(xy 361.368878 -256.880611) (xy 361.415036 -256.853962) (xy 361.46465 -256.83449) (xy 361.516612 -256.82263)
			(xy 361.569762 -256.818647) (xy 361.622912 -256.82263) (xy 361.674874 -256.83449) (xy 361.724488 -256.853962)
			(xy 361.770646 -256.880611) (xy 361.812317 -256.913842) (xy 361.848569 -256.952913) (xy 361.878593 -256.99695)
			(xy 361.901719 -257.044971) (xy 361.917429 -257.095901) (xy 361.925372 -257.148605) (xy 361.92587 -257.175254)
			(xy 361.925372 -257.201903) (xy 361.917429 -257.254607) (xy 361.901719 -257.305537) (xy 361.878593 -257.353558)
			(xy 361.848569 -257.397595) (xy 361.812317 -257.436666) (xy 361.770646 -257.469897) (xy 361.724488 -257.496546)
			(xy 361.674874 -257.516018) (xy 361.622912 -257.527878) (xy 361.569762 -257.531862) (xy 361.516612 -257.527878)
			(xy 361.46465 -257.516018) (xy 361.415036 -257.496546) (xy 361.368878 -257.469897) (xy 361.327207 -257.436666)
			(xy 361.290955 -257.397595) (xy 361.260931 -257.353558) (xy 361.237805 -257.305537) (xy 361.222095 -257.254607)
			(xy 361.214152 -257.201903) (xy 351.89922 -257.201903) (xy 351.89922 -257.287014) (xy 351.94621 -257.337052)
			(xy 351.964752 -257.339084) (xy 351.990253 -257.342524) (xy 352.039967 -257.355799) (xy 352.087251 -257.376095)
			(xy 352.13112 -257.402988) (xy 352.151188 -257.419094) (xy 352.16229 -257.427647) (xy 352.187953 -257.438887)
			(xy 352.215704 -257.44273) (xy 352.243455 -257.438887) (xy 352.269118 -257.427647) (xy 352.28022 -257.419094)
			(xy 352.299482 -257.403622) (xy 352.34147 -257.377586) (xy 352.386656 -257.357608) (xy 352.434171 -257.344073)
			(xy 352.483101 -257.337239) (xy 352.507804 -257.336798) (xy 352.534453 -257.337296) (xy 352.587155 -257.34524)
			(xy 352.638084 -257.36095) (xy 352.686103 -257.384075) (xy 352.730139 -257.414099) (xy 352.769209 -257.450351)
			(xy 352.802439 -257.49202) (xy 352.829087 -257.538177) (xy 352.848559 -257.587791) (xy 352.860419 -257.639752)
			(xy 352.864402 -257.6929) (xy 353.040174 -257.6929) (xy 353.044157 -257.639747) (xy 353.056018 -257.587782)
			(xy 353.075492 -257.538165) (xy 353.102143 -257.492004) (xy 353.135376 -257.450331) (xy 353.174449 -257.414077)
			(xy 353.218489 -257.384051) (xy 353.266513 -257.360925) (xy 353.317447 -257.345215) (xy 353.370153 -257.337271)
			(xy 353.396804 -257.336798) (xy 353.422644 -257.337273) (xy 353.473779 -257.344755) (xy 353.523297 -257.359545)
			(xy 353.570159 -257.381334) (xy 353.613381 -257.409665) (xy 353.633024 -257.42646) (xy 353.644402 -257.43585)
			(xy 353.671154 -257.448253) (xy 353.700334 -257.452505) (xy 353.729514 -257.448253) (xy 353.756266 -257.43585)
			(xy 353.767644 -257.42646) (xy 353.787271 -257.409644) (xy 353.830491 -257.381301) (xy 353.877356 -257.359508)
			(xy 353.92688 -257.344722) (xy 353.978022 -257.337256) (xy 354.003864 -257.336798) (xy 354.030517 -257.337257)
			(xy 354.083229 -257.345197) (xy 354.134169 -257.360905) (xy 354.182198 -257.38403) (xy 354.226244 -257.414056)
			(xy 354.265322 -257.450312) (xy 354.29856 -257.491987) (xy 354.325215 -257.538151) (xy 354.344692 -257.587773)
			(xy 354.356554 -257.639742) (xy 354.360538 -257.6929) (xy 354.356554 -257.746058) (xy 354.344692 -257.798027)
			(xy 354.325215 -257.847649) (xy 354.29856 -257.893813) (xy 354.265322 -257.935488) (xy 354.226244 -257.971744)
			(xy 354.182198 -258.00177) (xy 354.153227 -258.015719) (xy 357.924852 -258.015719) (xy 357.924852 -257.962421)
			(xy 357.932795 -257.909717) (xy 357.948505 -257.858787) (xy 357.971631 -257.810766) (xy 358.001655 -257.766729)
			(xy 358.037907 -257.727658) (xy 358.079578 -257.694427) (xy 358.125736 -257.667778) (xy 358.17535 -257.648306)
			(xy 358.227312 -257.636446) (xy 358.280462 -257.632463) (xy 358.333612 -257.636446) (xy 358.385574 -257.648306)
			(xy 358.435188 -257.667778) (xy 358.478701 -257.6929) (xy 365.407174 -257.6929) (xy 365.411157 -257.639747)
			(xy 365.423018 -257.587781) (xy 365.442492 -257.538163) (xy 365.469144 -257.492002) (xy 365.502378 -257.450329)
			(xy 365.541452 -257.414075) (xy 365.585493 -257.384049) (xy 365.633517 -257.360923) (xy 365.684452 -257.345213)
			(xy 365.737159 -257.33727) (xy 365.76381 -257.336798) (xy 365.764064 -257.336798) (xy 365.789972 -257.337301)
			(xy 365.841238 -257.344839) (xy 365.890873 -257.359717) (xy 365.937832 -257.381623) (xy 365.981125 -257.410096)
			(xy 366.000792 -257.426968) (xy 366.012186 -257.436456) (xy 366.039034 -257.449005) (xy 366.068356 -257.453309)
			(xy 366.097678 -257.449005) (xy 366.124526 -257.436456) (xy 366.13592 -257.426968) (xy 366.15555 -257.410046)
			(xy 366.198837 -257.381543) (xy 366.245802 -257.359625) (xy 366.295452 -257.344758) (xy 366.346734 -257.337256)
			(xy 366.372648 -257.336798) (xy 366.372902 -257.336798) (xy 366.399552 -257.337284) (xy 366.452256 -257.345228)
			(xy 366.503187 -257.360938) (xy 366.551208 -257.384064) (xy 366.595246 -257.414089) (xy 366.634317 -257.450342)
			(xy 366.667548 -257.492013) (xy 366.694198 -257.538172) (xy 366.71367 -257.587787) (xy 366.72553 -257.63975)
			(xy 366.729514 -257.6929) (xy 366.72553 -257.74605) (xy 366.71367 -257.798013) (xy 366.694198 -257.847628)
			(xy 366.667548 -257.893787) (xy 366.634317 -257.935458) (xy 366.595246 -257.971711) (xy 366.551208 -258.001736)
			(xy 366.503187 -258.024862) (xy 366.452256 -258.040572) (xy 366.399552 -258.048516) (xy 366.372902 -258.049014)
			(xy 366.372648 -258.049014) (xy 366.34674 -258.048501) (xy 366.295475 -258.040965) (xy 366.24584 -258.026089)
			(xy 366.198881 -258.004185) (xy 366.155587 -257.975715) (xy 366.13592 -257.958844) (xy 366.124526 -257.949356)
			(xy 366.097678 -257.936807) (xy 366.068356 -257.932503) (xy 366.039034 -257.936807) (xy 366.012186 -257.949356)
			(xy 366.000792 -257.958844) (xy 365.981159 -257.975763) (xy 365.937873 -258.004266) (xy 365.890908 -258.026183)
			(xy 365.841259 -258.041052) (xy 365.789978 -258.048555) (xy 365.764064 -258.049014) (xy 365.76381 -258.049014)
			(xy 365.737159 -258.04853) (xy 365.684452 -258.040587) (xy 365.633517 -258.024877) (xy 365.585493 -258.001751)
			(xy 365.541452 -257.971725) (xy 365.502378 -257.935471) (xy 365.469144 -257.893798) (xy 365.442492 -257.847637)
			(xy 365.423018 -257.798019) (xy 365.411157 -257.746053) (xy 365.407174 -257.6929) (xy 358.478701 -257.6929)
			(xy 358.481346 -257.694427) (xy 358.523017 -257.727658) (xy 358.559269 -257.766729) (xy 358.589293 -257.810766)
			(xy 358.612419 -257.858787) (xy 358.628129 -257.909717) (xy 358.636072 -257.962421) (xy 358.63657 -257.98907)
			(xy 358.636072 -258.015719) (xy 358.628129 -258.068423) (xy 358.612419 -258.119353) (xy 358.589293 -258.167374)
			(xy 358.559269 -258.211411) (xy 358.523017 -258.250482) (xy 358.481346 -258.283713) (xy 358.435188 -258.310362)
			(xy 358.385574 -258.329834) (xy 358.333612 -258.341694) (xy 358.280462 -258.345678) (xy 358.227312 -258.341694)
			(xy 358.17535 -258.329834) (xy 358.125736 -258.310362) (xy 358.079578 -258.283713) (xy 358.037907 -258.250482)
			(xy 358.001655 -258.211411) (xy 357.971631 -258.167374) (xy 357.948505 -258.119353) (xy 357.932795 -258.068423)
			(xy 357.924852 -258.015719) (xy 354.153227 -258.015719) (xy 354.134169 -258.024895) (xy 354.083229 -258.040603)
			(xy 354.030517 -258.048543) (xy 354.003864 -258.049014) (xy 353.978024 -258.048555) (xy 353.926888 -258.041069)
			(xy 353.87737 -258.026275) (xy 353.830508 -258.004482) (xy 353.787287 -257.976148) (xy 353.767644 -257.959352)
			(xy 353.756266 -257.949962) (xy 353.729514 -257.937559) (xy 353.700334 -257.933307) (xy 353.671154 -257.937559)
			(xy 353.644402 -257.949962) (xy 353.633024 -257.959352) (xy 353.613372 -257.976138) (xy 353.570159 -258.004485)
			(xy 353.5233 -258.026284) (xy 353.473782 -258.041076) (xy 353.422644 -258.048552) (xy 353.396804 -258.049014)
			(xy 353.370153 -258.048529) (xy 353.317447 -258.040585) (xy 353.266513 -258.024875) (xy 353.218489 -258.001749)
			(xy 353.174449 -257.971723) (xy 353.135376 -257.935469) (xy 353.102143 -257.893796) (xy 353.075492 -257.847635)
			(xy 353.056018 -257.798018) (xy 353.044157 -257.746053) (xy 353.040174 -257.6929) (xy 352.864402 -257.6929)
			(xy 352.860419 -257.746048) (xy 352.848559 -257.798009) (xy 352.829087 -257.847623) (xy 352.802439 -257.89378)
			(xy 352.769209 -257.935449) (xy 352.730139 -257.971701) (xy 352.686103 -258.001725) (xy 352.638084 -258.02485)
			(xy 352.587155 -258.04056) (xy 352.534453 -258.048504) (xy 352.507804 -258.049014) (xy 352.483101 -258.048591)
			(xy 352.434169 -258.041756) (xy 352.386653 -258.028217) (xy 352.341468 -258.008234) (xy 352.299481 -257.982192)
			(xy 352.28022 -257.966718) (xy 352.269118 -257.958165) (xy 352.243455 -257.946925) (xy 352.215704 -257.943082)
			(xy 352.187953 -257.946925) (xy 352.16229 -257.958165) (xy 352.151188 -257.966718) (xy 352.13112 -257.982822)
			(xy 352.087243 -258.009695) (xy 352.039958 -258.029983) (xy 351.990248 -258.043262) (xy 351.964752 -258.046728)
			(xy 351.94621 -258.04876) (xy 351.89922 -258.098798) (xy 351.89922 -259.578348) (xy 356.017576 -259.578348)
			(xy 356.018001 -259.553679) (xy 356.024801 -259.504812) (xy 356.038291 -259.457354) (xy 356.058213 -259.412216)
			(xy 356.084183 -259.370266) (xy 356.099618 -259.351018) (xy 356.1082 -259.339856) (xy 356.119555 -259.314108)
			(xy 356.123445 -259.286237) (xy 356.119575 -259.258364) (xy 356.108239 -259.232607) (xy 356.099618 -259.221478)
			(xy 356.084188 -259.202227) (xy 356.05823 -259.160271) (xy 356.038312 -259.115134) (xy 356.024816 -259.067679)
			(xy 356.017999 -259.018816) (xy 356.017576 -258.994148) (xy 356.018074 -258.967499) (xy 356.026017 -258.914795)
			(xy 356.041727 -258.863865) (xy 356.064853 -258.815844) (xy 356.094877 -258.771807) (xy 356.131129 -258.732736)
			(xy 356.1728 -258.699505) (xy 356.218958 -258.672856) (xy 356.268572 -258.653384) (xy 356.320534 -258.641524)
			(xy 356.373684 -258.637541) (xy 356.426834 -258.641524) (xy 356.478796 -258.653384) (xy 356.52841 -258.672856)
			(xy 356.574568 -258.699505) (xy 356.616239 -258.732736) (xy 356.652491 -258.771807) (xy 356.682515 -258.815844)
			(xy 356.689231 -258.829789) (xy 361.214152 -258.829789) (xy 361.214152 -258.776491) (xy 361.222095 -258.723787)
			(xy 361.237805 -258.672857) (xy 361.260931 -258.624836) (xy 361.290955 -258.580799) (xy 361.327207 -258.541728)
			(xy 361.368878 -258.508497) (xy 361.415036 -258.481848) (xy 361.46465 -258.462376) (xy 361.516612 -258.450516)
			(xy 361.569762 -258.446533) (xy 361.622912 -258.450516) (xy 361.674874 -258.462376) (xy 361.724488 -258.481848)
			(xy 361.770646 -258.508497) (xy 361.812317 -258.541728) (xy 361.848569 -258.580799) (xy 361.878593 -258.624836)
			(xy 361.901719 -258.672857) (xy 361.917429 -258.723787) (xy 361.925372 -258.776491) (xy 361.92587 -258.80314)
			(xy 361.925372 -258.829789) (xy 361.917429 -258.882493) (xy 361.901719 -258.933423) (xy 361.878593 -258.981444)
			(xy 361.848569 -259.025481) (xy 361.812317 -259.064552) (xy 361.770646 -259.097783) (xy 361.724488 -259.124432)
			(xy 361.674874 -259.143904) (xy 361.622912 -259.155764) (xy 361.569762 -259.159748) (xy 361.516612 -259.155764)
			(xy 361.46465 -259.143904) (xy 361.415036 -259.124432) (xy 361.368878 -259.097783) (xy 361.327207 -259.064552)
			(xy 361.290955 -259.025481) (xy 361.260931 -258.981444) (xy 361.237805 -258.933423) (xy 361.222095 -258.882493)
			(xy 361.214152 -258.829789) (xy 356.689231 -258.829789) (xy 356.705641 -258.863865) (xy 356.721351 -258.914795)
			(xy 356.729294 -258.967499) (xy 356.729792 -258.994148) (xy 356.729349 -259.018816) (xy 356.722551 -259.067682)
			(xy 356.709064 -259.11514) (xy 356.689147 -259.160277) (xy 356.663183 -259.202229) (xy 356.64775 -259.221478)
			(xy 356.639079 -259.232576) (xy 356.627739 -259.258348) (xy 356.623868 -259.286237) (xy 356.62776 -259.314124)
			(xy 356.639118 -259.339888) (xy 356.64775 -259.351018) (xy 356.663174 -259.370274) (xy 356.689134 -259.412228)
			(xy 356.709053 -259.457364) (xy 356.722551 -259.504817) (xy 356.729369 -259.55368) (xy 356.729792 -259.578348)
			(xy 356.729294 -259.604997) (xy 356.723475 -259.643605) (xy 357.924852 -259.643605) (xy 357.924852 -259.590307)
			(xy 357.932795 -259.537603) (xy 357.948505 -259.486673) (xy 357.971631 -259.438652) (xy 358.001655 -259.394615)
			(xy 358.037907 -259.355544) (xy 358.079578 -259.322313) (xy 358.125736 -259.295664) (xy 358.17535 -259.276192)
			(xy 358.227312 -259.264332) (xy 358.280462 -259.260349) (xy 358.333612 -259.264332) (xy 358.385574 -259.276192)
			(xy 358.435188 -259.295664) (xy 358.481346 -259.322313) (xy 358.523017 -259.355544) (xy 358.559269 -259.394615)
			(xy 358.589293 -259.438652) (xy 358.612419 -259.486673) (xy 358.628129 -259.537603) (xy 358.636072 -259.590307)
			(xy 358.63657 -259.616956) (xy 358.636233 -259.63499) (xy 363.009942 -259.63499) (xy 363.010341 -259.61032)
			(xy 363.017149 -259.561452) (xy 363.030645 -259.513994) (xy 363.050572 -259.468857) (xy 363.076546 -259.426907)
			(xy 363.091984 -259.40766) (xy 363.100624 -259.396538) (xy 363.111975 -259.370776) (xy 363.115856 -259.342892)
			(xy 363.111971 -259.315009) (xy 363.100616 -259.289248) (xy 363.091984 -259.27812) (xy 363.076583 -259.258846)
			(xy 363.050619 -259.216898) (xy 363.030694 -259.171766) (xy 363.017191 -259.124316) (xy 363.010368 -259.075457)
			(xy 363.009942 -259.05079) (xy 363.01044 -259.024141) (xy 363.018383 -258.971437) (xy 363.034093 -258.920507)
			(xy 363.057219 -258.872486) (xy 363.087243 -258.828449) (xy 363.123495 -258.789378) (xy 363.165166 -258.756147)
			(xy 363.211324 -258.729498) (xy 363.260938 -258.710026) (xy 363.3129 -258.698166) (xy 363.36605 -258.694183)
			(xy 363.4192 -258.698166) (xy 363.471162 -258.710026) (xy 363.520776 -258.729498) (xy 363.566934 -258.756147)
			(xy 363.608605 -258.789378) (xy 363.644857 -258.828449) (xy 363.674881 -258.872486) (xy 363.698007 -258.920507)
			(xy 363.713717 -258.971437) (xy 363.72166 -259.024141) (xy 363.722158 -259.05079) (xy 363.721747 -259.07546)
			(xy 363.714942 -259.124327) (xy 363.701448 -259.171785) (xy 363.681524 -259.216922) (xy 363.655552 -259.258872)
			(xy 363.640116 -259.27812) (xy 363.631495 -259.289255) (xy 363.620141 -259.315013) (xy 363.616257 -259.342892)
			(xy 363.620137 -259.370772) (xy 363.631487 -259.396532) (xy 363.640116 -259.40766) (xy 363.655554 -259.426905)
			(xy 363.681512 -259.468862) (xy 363.70143 -259.514) (xy 363.714924 -259.561456) (xy 363.721737 -259.610321)
			(xy 363.722158 -259.63499) (xy 363.72166 -259.661639) (xy 363.713717 -259.714343) (xy 363.698007 -259.765273)
			(xy 363.674881 -259.813294) (xy 363.644857 -259.857331) (xy 363.608605 -259.896402) (xy 363.566934 -259.929633)
			(xy 363.520776 -259.956282) (xy 363.471162 -259.975754) (xy 363.4192 -259.987614) (xy 363.36605 -259.991598)
			(xy 363.3129 -259.987614) (xy 363.260938 -259.975754) (xy 363.211324 -259.956282) (xy 363.165166 -259.929633)
			(xy 363.123495 -259.896402) (xy 363.087243 -259.857331) (xy 363.057219 -259.813294) (xy 363.034093 -259.765273)
			(xy 363.018383 -259.714343) (xy 363.01044 -259.661639) (xy 363.009942 -259.63499) (xy 358.636233 -259.63499)
			(xy 358.636072 -259.643605) (xy 358.628129 -259.696309) (xy 358.612419 -259.747239) (xy 358.589293 -259.79526)
			(xy 358.559269 -259.839297) (xy 358.523017 -259.878368) (xy 358.481346 -259.911599) (xy 358.435188 -259.938248)
			(xy 358.385574 -259.95772) (xy 358.333612 -259.96958) (xy 358.280462 -259.973564) (xy 358.227312 -259.96958)
			(xy 358.17535 -259.95772) (xy 358.125736 -259.938248) (xy 358.079578 -259.911599) (xy 358.037907 -259.878368)
			(xy 358.001655 -259.839297) (xy 357.971631 -259.79526) (xy 357.948505 -259.747239) (xy 357.932795 -259.696309)
			(xy 357.924852 -259.643605) (xy 356.723475 -259.643605) (xy 356.721351 -259.657701) (xy 356.705641 -259.708631)
			(xy 356.682515 -259.756652) (xy 356.652491 -259.800689) (xy 356.616239 -259.83976) (xy 356.574568 -259.872991)
			(xy 356.52841 -259.89964) (xy 356.478796 -259.919112) (xy 356.426834 -259.930972) (xy 356.373684 -259.934956)
			(xy 356.320534 -259.930972) (xy 356.268572 -259.919112) (xy 356.218958 -259.89964) (xy 356.1728 -259.872991)
			(xy 356.131129 -259.83976) (xy 356.094877 -259.800689) (xy 356.064853 -259.756652) (xy 356.041727 -259.708631)
			(xy 356.026017 -259.657701) (xy 356.018074 -259.604997) (xy 356.017576 -259.578348) (xy 351.89922 -259.578348)
			(xy 351.89922 -260.457421) (xy 361.214152 -260.457421) (xy 361.214152 -260.404123) (xy 361.222095 -260.351419)
			(xy 361.237805 -260.300489) (xy 361.260931 -260.252468) (xy 361.290955 -260.208431) (xy 361.327207 -260.16936)
			(xy 361.368878 -260.136129) (xy 361.415036 -260.10948) (xy 361.46465 -260.090008) (xy 361.516612 -260.078148)
			(xy 361.569762 -260.074165) (xy 361.622912 -260.078148) (xy 361.674874 -260.090008) (xy 361.724488 -260.10948)
			(xy 361.770646 -260.136129) (xy 361.812317 -260.16936) (xy 361.848569 -260.208431) (xy 361.878593 -260.252468)
			(xy 361.901719 -260.300489) (xy 361.917429 -260.351419) (xy 361.925372 -260.404123) (xy 361.92587 -260.430772)
			(xy 361.925372 -260.457421) (xy 361.917429 -260.510125) (xy 361.901719 -260.561055) (xy 361.878593 -260.609076)
			(xy 361.848569 -260.653113) (xy 361.812317 -260.692184) (xy 361.770646 -260.725415) (xy 361.724488 -260.752064)
			(xy 361.674874 -260.771536) (xy 361.622912 -260.783396) (xy 361.569762 -260.78738) (xy 361.516612 -260.783396)
			(xy 361.46465 -260.771536) (xy 361.415036 -260.752064) (xy 361.368878 -260.725415) (xy 361.327207 -260.692184)
			(xy 361.290955 -260.653113) (xy 361.260931 -260.609076) (xy 361.237805 -260.561055) (xy 361.222095 -260.510125)
			(xy 361.214152 -260.457421) (xy 351.89922 -260.457421) (xy 351.89922 -261.3289) (xy 352.221284 -261.3289)
			(xy 352.225267 -261.275748) (xy 352.237128 -261.223784) (xy 352.256601 -261.174168) (xy 352.283252 -261.128009)
			(xy 352.316485 -261.086337) (xy 352.355557 -261.050084) (xy 352.399597 -261.020059) (xy 352.447619 -260.996933)
			(xy 352.498552 -260.981224) (xy 352.551258 -260.973281) (xy 352.577908 -260.972808) (xy 352.578162 -260.972808)
			(xy 352.605457 -260.973339) (xy 352.659404 -260.981702) (xy 352.711446 -260.998191) (xy 352.760365 -261.022422)
			(xy 352.805018 -261.053828) (xy 352.82505 -261.072376) (xy 352.836672 -261.082773) (xy 352.864606 -261.096597)
			(xy 352.895408 -261.101353) (xy 352.92621 -261.096597) (xy 352.954144 -261.082773) (xy 352.965766 -261.072376)
			(xy 352.985797 -261.053784) (xy 353.030486 -261.022325) (xy 353.07946 -260.998073) (xy 353.131568 -260.981596)
			(xy 353.185582 -260.973284) (xy 353.212908 -260.972808) (xy 353.240229 -260.973322) (xy 353.294231 -260.981661)
			(xy 353.346328 -260.998144) (xy 353.395299 -261.022383) (xy 353.439998 -261.053812) (xy 353.46005 -261.072376)
			(xy 353.471672 -261.082773) (xy 353.499606 -261.096597) (xy 353.530408 -261.101353) (xy 353.56121 -261.096597)
			(xy 353.589144 -261.082773) (xy 353.600766 -261.072376) (xy 353.620797 -261.053784) (xy 353.665486 -261.022325)
			(xy 353.71446 -260.998073) (xy 353.766568 -260.981596) (xy 353.820582 -260.973284) (xy 353.847908 -260.972808)
			(xy 353.875229 -260.973322) (xy 353.929231 -260.981661) (xy 353.981328 -260.998144) (xy 354.030299 -261.022383)
			(xy 354.074998 -261.053812) (xy 354.09505 -261.072376) (xy 354.106672 -261.082773) (xy 354.134606 -261.096597)
			(xy 354.165408 -261.101353) (xy 354.19621 -261.096597) (xy 354.224144 -261.082773) (xy 354.235766 -261.072376)
			(xy 354.255797 -261.053784) (xy 354.300486 -261.022325) (xy 354.34946 -260.998073) (xy 354.401568 -260.981596)
			(xy 354.455582 -260.973284) (xy 354.482908 -260.972808) (xy 354.510229 -260.973322) (xy 354.564231 -260.981661)
			(xy 354.616328 -260.998144) (xy 354.665299 -261.022383) (xy 354.709998 -261.053812) (xy 354.73005 -261.072376)
			(xy 354.741672 -261.082773) (xy 354.769606 -261.096597) (xy 354.800408 -261.101353) (xy 354.83121 -261.096597)
			(xy 354.859144 -261.082773) (xy 354.870766 -261.072376) (xy 354.890778 -261.0538) (xy 354.93542 -261.022365)
			(xy 354.984342 -260.99812) (xy 355.036394 -260.981637) (xy 355.090354 -260.973301) (xy 355.117654 -260.972808)
			(xy 355.117908 -260.972808) (xy 355.144558 -260.973274) (xy 355.197263 -260.981219) (xy 355.248195 -260.996931)
			(xy 355.296216 -261.020058) (xy 355.340255 -261.050083) (xy 355.379326 -261.086337) (xy 355.412558 -261.128009)
			(xy 355.439208 -261.174169) (xy 355.45868 -261.223785) (xy 355.469568 -261.271491) (xy 357.924852 -261.271491)
			(xy 357.924852 -261.218193) (xy 357.932795 -261.165489) (xy 357.948505 -261.114559) (xy 357.971631 -261.066538)
			(xy 358.001655 -261.022501) (xy 358.037907 -260.98343) (xy 358.079578 -260.950199) (xy 358.125736 -260.92355)
			(xy 358.17535 -260.904078) (xy 358.227312 -260.892218) (xy 358.280462 -260.888235) (xy 358.333612 -260.892218)
			(xy 358.385574 -260.904078) (xy 358.435188 -260.92355) (xy 358.481346 -260.950199) (xy 358.523017 -260.98343)
			(xy 358.559269 -261.022501) (xy 358.589293 -261.066538) (xy 358.612419 -261.114559) (xy 358.628129 -261.165489)
			(xy 358.636072 -261.218193) (xy 358.63657 -261.244842) (xy 358.636072 -261.271491) (xy 358.628129 -261.324195)
			(xy 358.612419 -261.375125) (xy 358.589293 -261.423146) (xy 358.559269 -261.467183) (xy 358.523017 -261.506254)
			(xy 358.481346 -261.539485) (xy 358.435188 -261.566134) (xy 358.385574 -261.585606) (xy 358.333612 -261.597466)
			(xy 358.280462 -261.60145) (xy 358.227312 -261.597466) (xy 358.17535 -261.585606) (xy 358.125736 -261.566134)
			(xy 358.079578 -261.539485) (xy 358.037907 -261.506254) (xy 358.001655 -261.467183) (xy 357.971631 -261.423146)
			(xy 357.948505 -261.375125) (xy 357.932795 -261.324195) (xy 357.924852 -261.271491) (xy 355.469568 -261.271491)
			(xy 355.47054 -261.275749) (xy 355.474524 -261.3289) (xy 355.47054 -261.382051) (xy 355.45868 -261.434015)
			(xy 355.439208 -261.483631) (xy 355.412558 -261.529791) (xy 355.379326 -261.571463) (xy 355.340255 -261.607717)
			(xy 355.296216 -261.637742) (xy 355.248195 -261.660869) (xy 355.197263 -261.676581) (xy 355.144558 -261.684526)
			(xy 355.117908 -261.685024) (xy 355.117654 -261.685024) (xy 355.09036 -261.684474) (xy 355.036414 -261.676115)
			(xy 354.984373 -261.659629) (xy 354.935454 -261.635403) (xy 354.890799 -261.604002) (xy 354.870766 -261.585456)
			(xy 354.859144 -261.575059) (xy 354.83121 -261.561235) (xy 354.800408 -261.556479) (xy 354.769606 -261.561235)
			(xy 354.741672 -261.575059) (xy 354.73005 -261.585456) (xy 354.710044 -261.604077) (xy 354.66535 -261.635534)
			(xy 354.616369 -261.659783) (xy 354.564256 -261.676252) (xy 354.510236 -261.684554) (xy 354.482908 -261.685024)
			(xy 354.455588 -261.684491) (xy 354.401587 -261.676155) (xy 354.349491 -261.659677) (xy 354.300519 -261.635442)
			(xy 354.255819 -261.604018) (xy 354.235766 -261.585456) (xy 354.224144 -261.575059) (xy 354.19621 -261.561235)
			(xy 354.165408 -261.556479) (xy 354.134606 -261.561235) (xy 354.106672 -261.575059) (xy 354.09505 -261.585456)
			(xy 354.075044 -261.604077) (xy 354.03035 -261.635534) (xy 353.981369 -261.659783) (xy 353.929256 -261.676252)
			(xy 353.875236 -261.684554) (xy 353.847908 -261.685024) (xy 353.820588 -261.684491) (xy 353.766587 -261.676155)
			(xy 353.714491 -261.659677) (xy 353.665519 -261.635442) (xy 353.620819 -261.604018) (xy 353.600766 -261.585456)
			(xy 353.589144 -261.575059) (xy 353.56121 -261.561235) (xy 353.530408 -261.556479) (xy 353.499606 -261.561235)
			(xy 353.471672 -261.575059) (xy 353.46005 -261.585456) (xy 353.440044 -261.604077) (xy 353.39535 -261.635534)
			(xy 353.346369 -261.659783) (xy 353.294256 -261.676252) (xy 353.240236 -261.684554) (xy 353.212908 -261.685024)
			(xy 353.185588 -261.684491) (xy 353.131587 -261.676155) (xy 353.079491 -261.659677) (xy 353.030519 -261.635442)
			(xy 352.985819 -261.604018) (xy 352.965766 -261.585456) (xy 352.954144 -261.575059) (xy 352.92621 -261.561235)
			(xy 352.895408 -261.556479) (xy 352.864606 -261.561235) (xy 352.836672 -261.575059) (xy 352.82505 -261.585456)
			(xy 352.805021 -261.604013) (xy 352.760384 -261.635454) (xy 352.711467 -261.659703) (xy 352.659418 -261.67619)
			(xy 352.605461 -261.684529) (xy 352.578162 -261.685024) (xy 352.577908 -261.685024) (xy 352.551258 -261.684519)
			(xy 352.498552 -261.676576) (xy 352.447619 -261.660867) (xy 352.399597 -261.637741) (xy 352.355557 -261.607716)
			(xy 352.316485 -261.571463) (xy 352.283252 -261.529791) (xy 352.256601 -261.483632) (xy 352.237128 -261.434016)
			(xy 352.225267 -261.382052) (xy 352.221284 -261.3289) (xy 351.89922 -261.3289) (xy 351.89922 -261.590028)
			(xy 352.394499 -262.085307) (xy 361.214152 -262.085307) (xy 361.214152 -262.032009) (xy 361.222095 -261.979305)
			(xy 361.237805 -261.928375) (xy 361.260931 -261.880354) (xy 361.290955 -261.836317) (xy 361.327207 -261.797246)
			(xy 361.368878 -261.764015) (xy 361.415036 -261.737366) (xy 361.46465 -261.717894) (xy 361.516612 -261.706034)
			(xy 361.569762 -261.702051) (xy 361.622912 -261.706034) (xy 361.674874 -261.717894) (xy 361.724488 -261.737366)
			(xy 361.770646 -261.764015) (xy 361.812317 -261.797246) (xy 361.848569 -261.836317) (xy 361.878593 -261.880354)
			(xy 361.901719 -261.928375) (xy 361.917429 -261.979305) (xy 361.925372 -262.032009) (xy 361.92587 -262.058658)
			(xy 361.925372 -262.085307) (xy 361.917429 -262.138011) (xy 361.901719 -262.188941) (xy 361.878593 -262.236962)
			(xy 361.848569 -262.280999) (xy 361.812317 -262.32007) (xy 361.770646 -262.353301) (xy 361.724488 -262.37995)
			(xy 361.674874 -262.399422) (xy 361.622912 -262.411282) (xy 361.569762 -262.415266) (xy 361.516612 -262.411282)
			(xy 361.46465 -262.399422) (xy 361.415036 -262.37995) (xy 361.368878 -262.353301) (xy 361.327207 -262.32007)
			(xy 361.290955 -262.280999) (xy 361.260931 -262.236962) (xy 361.237805 -262.188941) (xy 361.222095 -262.138011)
			(xy 361.214152 -262.085307) (xy 352.394499 -262.085307) (xy 353.208315 -262.899123) (xy 357.924852 -262.899123)
			(xy 357.924852 -262.845825) (xy 357.932795 -262.793121) (xy 357.948505 -262.742191) (xy 357.971631 -262.69417)
			(xy 358.001655 -262.650133) (xy 358.037907 -262.611062) (xy 358.079578 -262.577831) (xy 358.125736 -262.551182)
			(xy 358.17535 -262.53171) (xy 358.227312 -262.51985) (xy 358.280462 -262.515867) (xy 358.333612 -262.51985)
			(xy 358.385574 -262.53171) (xy 358.435188 -262.551182) (xy 358.481346 -262.577831) (xy 358.523017 -262.611062)
			(xy 358.559269 -262.650133) (xy 358.589293 -262.69417) (xy 358.611187 -262.739632) (xy 363.900974 -262.739632)
			(xy 363.900974 -262.739378) (xy 363.901539 -262.712084) (xy 363.909895 -262.658139) (xy 363.926377 -262.606098)
			(xy 363.9506 -262.557179) (xy 363.981998 -262.512524) (xy 364.000542 -262.49249) (xy 364.010908 -262.480842)
			(xy 364.024737 -262.452918) (xy 364.029499 -262.422123) (xy 364.024751 -262.391326) (xy 364.010935 -262.363396)
			(xy 364.000542 -262.351774) (xy 363.981949 -262.331777) (xy 363.950513 -262.287132) (xy 363.926271 -262.238206)
			(xy 363.909792 -262.18615) (xy 363.901463 -262.132187) (xy 363.900974 -262.104886) (xy 363.900974 -262.104632)
			(xy 363.901489 -262.076804) (xy 363.910136 -262.021824) (xy 363.92724 -261.968861) (xy 363.952383 -261.919209)
			(xy 363.984952 -261.874077) (xy 364.024152 -261.834568) (xy 364.069026 -261.801646) (xy 364.093506 -261.788402)
			(xy 364.10648 -261.781268) (xy 364.127826 -261.760762) (xy 364.142388 -261.734992) (xy 364.148943 -261.706127)
			(xy 364.146938 -261.676595) (xy 364.136543 -261.648881) (xy 364.118631 -261.625316) (xy 364.106968 -261.61619)
			(xy 364.084854 -261.599236) (xy 364.045597 -261.559696) (xy 364.012977 -261.514526) (xy 363.987788 -261.464827)
			(xy 363.970645 -261.411812) (xy 363.961966 -261.356775) (xy 363.961426 -261.328916) (xy 363.961927 -261.300929)
			(xy 363.970682 -261.245645) (xy 363.987978 -261.192411) (xy 364.013389 -261.142539) (xy 364.046289 -261.097256)
			(xy 364.085869 -261.057678) (xy 364.131154 -261.024779) (xy 364.181028 -260.999371) (xy 364.234263 -260.982078)
			(xy 364.289547 -260.973326) (xy 364.317534 -260.972808) (xy 364.317788 -260.972808) (xy 364.345084 -260.973323)
			(xy 364.399032 -260.98169) (xy 364.451073 -260.998183) (xy 364.499992 -261.022417) (xy 364.544644 -261.053826)
			(xy 364.564676 -261.072376) (xy 364.576298 -261.082773) (xy 364.604232 -261.096597) (xy 364.635034 -261.101353)
			(xy 364.665836 -261.096597) (xy 364.69377 -261.082773) (xy 364.705392 -261.072376) (xy 364.725412 -261.053771)
			(xy 364.770104 -261.022315) (xy 364.819081 -260.998064) (xy 364.871191 -260.981591) (xy 364.925208 -260.973282)
			(xy 364.952534 -260.972808) (xy 364.979856 -260.973306) (xy 365.033858 -260.981649) (xy 365.085955 -260.998136)
			(xy 365.134926 -261.022378) (xy 365.179625 -261.05381) (xy 365.199676 -261.072376) (xy 365.211298 -261.082773)
			(xy 365.239232 -261.096597) (xy 365.270034 -261.101353) (xy 365.300836 -261.096597) (xy 365.32877 -261.082773)
			(xy 365.340392 -261.072376) (xy 365.360412 -261.053771) (xy 365.405104 -261.022315) (xy 365.454081 -260.998064)
			(xy 365.506191 -260.981591) (xy 365.560208 -260.973282) (xy 365.587534 -260.972808) (xy 365.614856 -260.973306)
			(xy 365.668858 -260.981649) (xy 365.720955 -260.998136) (xy 365.769926 -261.022378) (xy 365.814625 -261.05381)
			(xy 365.834676 -261.072376) (xy 365.846298 -261.082773) (xy 365.874232 -261.096597) (xy 365.905034 -261.101353)
			(xy 365.935836 -261.096597) (xy 365.96377 -261.082773) (xy 365.975392 -261.072376) (xy 365.995393 -261.053788)
			(xy 366.040038 -261.022354) (xy 366.088963 -260.998112) (xy 366.141018 -260.981631) (xy 366.194979 -260.973299)
			(xy 366.22228 -260.972808) (xy 366.222534 -260.972808) (xy 366.249183 -260.973276) (xy 366.301885 -260.981224)
			(xy 366.352813 -260.996938) (xy 366.400831 -261.020066) (xy 366.444866 -261.050093) (xy 366.483935 -261.086346)
			(xy 366.517163 -261.128018) (xy 366.543811 -261.174176) (xy 366.563282 -261.22379) (xy 366.575141 -261.275751)
			(xy 366.579124 -261.3289) (xy 366.575141 -261.382049) (xy 366.563282 -261.43401) (xy 366.543811 -261.483624)
			(xy 366.517163 -261.529782) (xy 366.483935 -261.571454) (xy 366.444866 -261.607707) (xy 366.400831 -261.637734)
			(xy 366.352813 -261.660862) (xy 366.301885 -261.676576) (xy 366.249183 -261.684524) (xy 366.222534 -261.685024)
			(xy 366.22228 -261.685024) (xy 366.194986 -261.684458) (xy 366.141041 -261.676102) (xy 366.089001 -261.659621)
			(xy 366.040081 -261.635398) (xy 365.995426 -261.604) (xy 365.975392 -261.585456) (xy 365.96377 -261.575059)
			(xy 365.935836 -261.561235) (xy 365.905034 -261.556479) (xy 365.874232 -261.561235) (xy 365.846298 -261.575059)
			(xy 365.834676 -261.585456) (xy 365.814659 -261.604065) (xy 365.769968 -261.635523) (xy 365.72099 -261.659774)
			(xy 365.668879 -261.676246) (xy 365.614861 -261.684552) (xy 365.587534 -261.685024) (xy 365.560214 -261.684475)
			(xy 365.506215 -261.676143) (xy 365.454118 -261.659668) (xy 365.405146 -261.635437) (xy 365.360445 -261.604016)
			(xy 365.340392 -261.585456) (xy 365.32877 -261.575059) (xy 365.300836 -261.561235) (xy 365.270034 -261.556479)
			(xy 365.239232 -261.561235) (xy 365.211298 -261.575059) (xy 365.199676 -261.585456) (xy 365.179659 -261.604065)
			(xy 365.134968 -261.635523) (xy 365.08599 -261.659774) (xy 365.033879 -261.676246) (xy 364.979861 -261.684552)
			(xy 364.952534 -261.685024) (xy 364.925214 -261.684475) (xy 364.871215 -261.676143) (xy 364.819118 -261.659668)
			(xy 364.770146 -261.635437) (xy 364.725445 -261.604016) (xy 364.705392 -261.585456) (xy 364.69377 -261.575059)
			(xy 364.665836 -261.561235) (xy 364.635034 -261.556479) (xy 364.604232 -261.561235) (xy 364.576298 -261.575059)
			(xy 364.564676 -261.585456) (xy 364.545761 -261.602971) (xy 364.503813 -261.632933) (xy 364.48111 -261.645146)
			(xy 364.46818 -261.652352) (xy 364.446836 -261.672843) (xy 364.432271 -261.698598) (xy 364.42571 -261.727449)
			(xy 364.427707 -261.75697) (xy 364.438092 -261.784675) (xy 364.455992 -261.808234) (xy 364.467648 -261.817358)
			(xy 364.489788 -261.834279) (xy 364.529043 -261.873826) (xy 364.56166 -261.919003) (xy 364.586844 -261.968708)
			(xy 364.603982 -262.021729) (xy 364.612653 -262.076771) (xy 364.61319 -262.104632) (xy 364.61319 -262.104886)
			(xy 364.612674 -262.132182) (xy 364.604308 -262.18613) (xy 364.587815 -262.238171) (xy 364.56358 -262.28709)
			(xy 364.532172 -262.331742) (xy 364.513622 -262.351774) (xy 364.503196 -262.363371) (xy 364.489378 -262.391314)
			(xy 364.48463 -262.422123) (xy 364.489392 -262.45293) (xy 364.503223 -262.480867) (xy 364.513622 -262.49249)
			(xy 364.532225 -262.512512) (xy 364.563682 -262.557203) (xy 364.587933 -262.606179) (xy 364.604407 -262.658289)
			(xy 364.612716 -262.712306) (xy 364.61319 -262.739632) (xy 364.612685 -262.766554) (xy 364.60461 -262.819789)
			(xy 364.588618 -262.871203) (xy 364.565073 -262.919626) (xy 364.550198 -262.94207) (xy 364.542231 -262.954527)
			(xy 364.533129 -262.982647) (xy 364.532462 -263.012196) (xy 364.540287 -263.040698) (xy 364.555947 -263.065764)
			(xy 364.578131 -263.085295) (xy 364.591346 -263.09193) (xy 364.612319 -263.102033) (xy 364.651688 -263.126875)
			(xy 364.669832 -263.14146) (xy 364.680962 -263.150087) (xy 364.706722 -263.161434) (xy 364.734602 -263.165315)
			(xy 364.762482 -263.161434) (xy 364.788242 -263.150087) (xy 364.799372 -263.14146) (xy 364.820788 -263.124337)
			(xy 364.867845 -263.096198) (xy 364.918662 -263.075609) (xy 364.972035 -263.063057) (xy 365.026702 -263.05884)
			(xy 365.081369 -263.063057) (xy 365.134742 -263.075609) (xy 365.185559 -263.096198) (xy 365.232616 -263.124337)
			(xy 365.254032 -263.14146) (xy 365.265162 -263.150087) (xy 365.290922 -263.161434) (xy 365.318802 -263.165315)
			(xy 365.346682 -263.161434) (xy 365.372442 -263.150087) (xy 365.383572 -263.14146) (xy 365.40281 -263.126013)
			(xy 365.444769 -263.100056) (xy 365.489909 -263.080141) (xy 365.537367 -263.066649) (xy 365.586233 -263.059837)
			(xy 365.610902 -263.059418) (xy 365.637553 -263.059864) (xy 365.69026 -263.067808) (xy 365.741194 -263.08352)
			(xy 365.789218 -263.106647) (xy 365.833258 -263.136673) (xy 365.872332 -263.172928) (xy 365.905565 -263.214602)
			(xy 365.932216 -263.260763) (xy 365.951689 -263.310381) (xy 365.96355 -263.362347) (xy 365.967534 -263.4155)
			(xy 365.96355 -263.468653) (xy 365.951689 -263.520619) (xy 365.932216 -263.570237) (xy 365.905565 -263.616398)
			(xy 365.872332 -263.658072) (xy 365.833258 -263.694327) (xy 365.789218 -263.724353) (xy 365.741194 -263.74748)
			(xy 365.69026 -263.763192) (xy 365.637553 -263.771136) (xy 365.610902 -263.771634) (xy 365.586232 -263.771233)
			(xy 365.537364 -263.764427) (xy 365.489906 -263.750931) (xy 365.444769 -263.731004) (xy 365.402819 -263.70503)
			(xy 365.383572 -263.689592) (xy 365.372442 -263.680965) (xy 365.346682 -263.669618) (xy 365.318802 -263.665737)
			(xy 365.290922 -263.669618) (xy 365.265162 -263.680965) (xy 365.254032 -263.689592) (xy 365.232616 -263.706715)
			(xy 365.185559 -263.734854) (xy 365.134742 -263.755443) (xy 365.081369 -263.767995) (xy 365.026702 -263.772212)
			(xy 364.972035 -263.767995) (xy 364.918662 -263.755443) (xy 364.867845 -263.734854) (xy 364.820788 -263.706715)
			(xy 364.799372 -263.689592) (xy 364.788242 -263.680965) (xy 364.762482 -263.669618) (xy 364.734602 -263.665737)
			(xy 364.706722 -263.669618) (xy 364.680962 -263.680965) (xy 364.669832 -263.689592) (xy 364.650599 -263.705045)
			(xy 364.608638 -263.730999) (xy 364.563496 -263.750912) (xy 364.516038 -263.764404) (xy 364.467171 -263.771214)
			(xy 364.442502 -263.771634) (xy 364.41452 -263.771057) (xy 364.359246 -263.762303) (xy 364.306021 -263.745011)
			(xy 364.256156 -263.719605) (xy 364.21088 -263.686712) (xy 364.171306 -263.647141) (xy 364.13841 -263.601868)
			(xy 364.113 -263.552005) (xy 364.095703 -263.498782) (xy 364.086945 -263.443508) (xy 364.086394 -263.415526)
			(xy 364.086394 -263.415018) (xy 364.086915 -263.388159) (xy 364.095034 -263.335058) (xy 364.11103 -263.283777)
			(xy 364.134541 -263.235477) (xy 364.149386 -263.213088) (xy 364.157409 -263.200663) (xy 364.166507 -263.172531)
			(xy 364.167166 -263.142972) (xy 364.15933 -263.114463) (xy 364.143657 -263.089392) (xy 364.121459 -263.069861)
			(xy 364.108238 -263.063228) (xy 364.085373 -263.052206) (xy 364.042741 -263.024656) (xy 364.004452 -262.991333)
			(xy 363.971283 -262.952911) (xy 363.943906 -262.910169) (xy 363.922875 -262.863972) (xy 363.908616 -262.815257)
			(xy 363.901418 -262.765011) (xy 363.900974 -262.739632) (xy 358.611187 -262.739632) (xy 358.612419 -262.742191)
			(xy 358.628129 -262.793121) (xy 358.636072 -262.845825) (xy 358.63657 -262.872474) (xy 358.636072 -262.899123)
			(xy 358.628129 -262.951827) (xy 358.612419 -263.002757) (xy 358.589293 -263.050778) (xy 358.559269 -263.094815)
			(xy 358.523017 -263.133886) (xy 358.481346 -263.167117) (xy 358.435188 -263.193766) (xy 358.385574 -263.213238)
			(xy 358.333612 -263.225098) (xy 358.280462 -263.229082) (xy 358.227312 -263.225098) (xy 358.17535 -263.213238)
			(xy 358.125736 -263.193766) (xy 358.079578 -263.167117) (xy 358.037907 -263.133886) (xy 358.001655 -263.094815)
			(xy 357.971631 -263.050778) (xy 357.948505 -263.002757) (xy 357.932795 -262.951827) (xy 357.924852 -262.899123)
			(xy 353.208315 -262.899123) (xy 353.97186 -263.662668) (xy 355.84638 -263.662668) (xy 355.896905 -263.713193)
			(xy 361.214152 -263.713193) (xy 361.214152 -263.659895) (xy 361.222095 -263.607191) (xy 361.237805 -263.556261)
			(xy 361.260931 -263.50824) (xy 361.290955 -263.464203) (xy 361.327207 -263.425132) (xy 361.368878 -263.391901)
			(xy 361.415036 -263.365252) (xy 361.46465 -263.34578) (xy 361.516612 -263.33392) (xy 361.569762 -263.329937)
			(xy 361.622912 -263.33392) (xy 361.674874 -263.34578) (xy 361.724488 -263.365252) (xy 361.770646 -263.391901)
			(xy 361.812317 -263.425132) (xy 361.848569 -263.464203) (xy 361.878593 -263.50824) (xy 361.901719 -263.556261)
			(xy 361.917429 -263.607191) (xy 361.925372 -263.659895) (xy 361.92587 -263.686544) (xy 361.925372 -263.713193)
			(xy 363.094006 -263.713193) (xy 363.094006 -263.659895) (xy 363.101949 -263.607191) (xy 363.117659 -263.556261)
			(xy 363.140785 -263.50824) (xy 363.170809 -263.464203) (xy 363.207061 -263.425132) (xy 363.248732 -263.391901)
			(xy 363.29489 -263.365252) (xy 363.344504 -263.34578) (xy 363.396466 -263.33392) (xy 363.449616 -263.329937)
			(xy 363.502766 -263.33392) (xy 363.554728 -263.34578) (xy 363.604342 -263.365252) (xy 363.6505 -263.391901)
			(xy 363.692171 -263.425132) (xy 363.728423 -263.464203) (xy 363.758447 -263.50824) (xy 363.781573 -263.556261)
			(xy 363.797283 -263.607191) (xy 363.805226 -263.659895) (xy 363.805724 -263.686544) (xy 363.805226 -263.713193)
			(xy 363.797283 -263.765897) (xy 363.781573 -263.816827) (xy 363.758447 -263.864848) (xy 363.728423 -263.908885)
			(xy 363.692171 -263.947956) (xy 363.6505 -263.981187) (xy 363.604342 -264.007836) (xy 363.554728 -264.027308)
			(xy 363.502766 -264.039168) (xy 363.449616 -264.043152) (xy 363.396466 -264.039168) (xy 363.344504 -264.027308)
			(xy 363.29489 -264.007836) (xy 363.248732 -263.981187) (xy 363.207061 -263.947956) (xy 363.170809 -263.908885)
			(xy 363.140785 -263.864848) (xy 363.117659 -263.816827) (xy 363.101949 -263.765897) (xy 363.094006 -263.713193)
			(xy 361.925372 -263.713193) (xy 361.917429 -263.765897) (xy 361.901719 -263.816827) (xy 361.878593 -263.864848)
			(xy 361.848569 -263.908885) (xy 361.812317 -263.947956) (xy 361.770646 -263.981187) (xy 361.724488 -264.007836)
			(xy 361.674874 -264.027308) (xy 361.622912 -264.039168) (xy 361.569762 -264.043152) (xy 361.516612 -264.039168)
			(xy 361.46465 -264.027308) (xy 361.415036 -264.007836) (xy 361.368878 -263.981187) (xy 361.327207 -263.947956)
			(xy 361.290955 -263.908885) (xy 361.260931 -263.864848) (xy 361.237805 -263.816827) (xy 361.222095 -263.765897)
			(xy 361.214152 -263.713193) (xy 355.896905 -263.713193) (xy 356.333552 -264.14984) (xy 356.35819 -264.146792)
			(xy 356.368881 -264.145593) (xy 356.390358 -264.144324) (xy 356.401116 -264.144252) (xy 356.429099 -264.144802)
			(xy 356.484377 -264.153559) (xy 356.537604 -264.170854) (xy 356.587471 -264.196263) (xy 356.63275 -264.229158)
			(xy 356.672326 -264.268732) (xy 356.705225 -264.314008) (xy 356.730636 -264.363873) (xy 356.747936 -264.4171)
			(xy 356.756696 -264.472377) (xy 356.757224 -264.50036) (xy 356.75716 -264.511118) (xy 356.756219 -264.527009)
			(xy 362.623852 -264.527009) (xy 362.623852 -264.473711) (xy 362.631795 -264.421007) (xy 362.647505 -264.370077)
			(xy 362.670631 -264.322056) (xy 362.700655 -264.278019) (xy 362.736907 -264.238948) (xy 362.778578 -264.205717)
			(xy 362.824736 -264.179068) (xy 362.87435 -264.159596) (xy 362.926312 -264.147736) (xy 362.979462 -264.143753)
			(xy 363.032612 -264.147736) (xy 363.084574 -264.159596) (xy 363.134188 -264.179068) (xy 363.180346 -264.205717)
			(xy 363.222017 -264.238948) (xy 363.258269 -264.278019) (xy 363.288293 -264.322056) (xy 363.311419 -264.370077)
			(xy 363.327129 -264.421007) (xy 363.335072 -264.473711) (xy 363.33557 -264.50036) (xy 363.335072 -264.527009)
			(xy 363.563652 -264.527009) (xy 363.563652 -264.473711) (xy 363.571595 -264.421007) (xy 363.587305 -264.370077)
			(xy 363.610431 -264.322056) (xy 363.640455 -264.278019) (xy 363.676707 -264.238948) (xy 363.718378 -264.205717)
			(xy 363.764536 -264.179068) (xy 363.81415 -264.159596) (xy 363.866112 -264.147736) (xy 363.919262 -264.143753)
			(xy 363.972412 -264.147736) (xy 364.024374 -264.159596) (xy 364.073988 -264.179068) (xy 364.120146 -264.205717)
			(xy 364.161817 -264.238948) (xy 364.198069 -264.278019) (xy 364.228093 -264.322056) (xy 364.251219 -264.370077)
			(xy 364.266929 -264.421007) (xy 364.274872 -264.473711) (xy 364.27537 -264.50036) (xy 364.274872 -264.527009)
			(xy 364.503452 -264.527009) (xy 364.503452 -264.473711) (xy 364.511395 -264.421007) (xy 364.527105 -264.370077)
			(xy 364.550231 -264.322056) (xy 364.580255 -264.278019) (xy 364.616507 -264.238948) (xy 364.658178 -264.205717)
			(xy 364.704336 -264.179068) (xy 364.75395 -264.159596) (xy 364.805912 -264.147736) (xy 364.859062 -264.143753)
			(xy 364.912212 -264.147736) (xy 364.964174 -264.159596) (xy 365.013788 -264.179068) (xy 365.059946 -264.205717)
			(xy 365.101617 -264.238948) (xy 365.137869 -264.278019) (xy 365.167893 -264.322056) (xy 365.191019 -264.370077)
			(xy 365.206729 -264.421007) (xy 365.214672 -264.473711) (xy 365.21517 -264.50036) (xy 365.214672 -264.527009)
			(xy 365.443252 -264.527009) (xy 365.443252 -264.473711) (xy 365.451195 -264.421007) (xy 365.466905 -264.370077)
			(xy 365.490031 -264.322056) (xy 365.520055 -264.278019) (xy 365.556307 -264.238948) (xy 365.597978 -264.205717)
			(xy 365.644136 -264.179068) (xy 365.69375 -264.159596) (xy 365.745712 -264.147736) (xy 365.798862 -264.143753)
			(xy 365.852012 -264.147736) (xy 365.903974 -264.159596) (xy 365.953588 -264.179068) (xy 365.999746 -264.205717)
			(xy 366.041417 -264.238948) (xy 366.077669 -264.278019) (xy 366.107693 -264.322056) (xy 366.130819 -264.370077)
			(xy 366.146529 -264.421007) (xy 366.154472 -264.473711) (xy 366.15497 -264.50036) (xy 366.154472 -264.527009)
			(xy 366.146529 -264.579713) (xy 366.130819 -264.630643) (xy 366.107693 -264.678664) (xy 366.077669 -264.722701)
			(xy 366.041417 -264.761772) (xy 365.999746 -264.795003) (xy 365.953588 -264.821652) (xy 365.903974 -264.841124)
			(xy 365.852012 -264.852984) (xy 365.798862 -264.856968) (xy 365.745712 -264.852984) (xy 365.69375 -264.841124)
			(xy 365.644136 -264.821652) (xy 365.597978 -264.795003) (xy 365.556307 -264.761772) (xy 365.520055 -264.722701)
			(xy 365.490031 -264.678664) (xy 365.466905 -264.630643) (xy 365.451195 -264.579713) (xy 365.443252 -264.527009)
			(xy 365.214672 -264.527009) (xy 365.206729 -264.579713) (xy 365.191019 -264.630643) (xy 365.167893 -264.678664)
			(xy 365.137869 -264.722701) (xy 365.101617 -264.761772) (xy 365.059946 -264.795003) (xy 365.013788 -264.821652)
			(xy 364.964174 -264.841124) (xy 364.912212 -264.852984) (xy 364.859062 -264.856968) (xy 364.805912 -264.852984)
			(xy 364.75395 -264.841124) (xy 364.704336 -264.821652) (xy 364.658178 -264.795003) (xy 364.616507 -264.761772)
			(xy 364.580255 -264.722701) (xy 364.550231 -264.678664) (xy 364.527105 -264.630643) (xy 364.511395 -264.579713)
			(xy 364.503452 -264.527009) (xy 364.274872 -264.527009) (xy 364.266929 -264.579713) (xy 364.251219 -264.630643)
			(xy 364.228093 -264.678664) (xy 364.198069 -264.722701) (xy 364.161817 -264.761772) (xy 364.120146 -264.795003)
			(xy 364.073988 -264.821652) (xy 364.024374 -264.841124) (xy 363.972412 -264.852984) (xy 363.919262 -264.856968)
			(xy 363.866112 -264.852984) (xy 363.81415 -264.841124) (xy 363.764536 -264.821652) (xy 363.718378 -264.795003)
			(xy 363.676707 -264.761772) (xy 363.640455 -264.722701) (xy 363.610431 -264.678664) (xy 363.587305 -264.630643)
			(xy 363.571595 -264.579713) (xy 363.563652 -264.527009) (xy 363.335072 -264.527009) (xy 363.327129 -264.579713)
			(xy 363.311419 -264.630643) (xy 363.288293 -264.678664) (xy 363.258269 -264.722701) (xy 363.222017 -264.761772)
			(xy 363.180346 -264.795003) (xy 363.134188 -264.821652) (xy 363.084574 -264.841124) (xy 363.032612 -264.852984)
			(xy 362.979462 -264.856968) (xy 362.926312 -264.852984) (xy 362.87435 -264.841124) (xy 362.824736 -264.821652)
			(xy 362.778578 -264.795003) (xy 362.736907 -264.761772) (xy 362.700655 -264.722701) (xy 362.670631 -264.678664)
			(xy 362.647505 -264.630643) (xy 362.631795 -264.579713) (xy 362.623852 -264.527009) (xy 356.756219 -264.527009)
			(xy 356.755888 -264.532596) (xy 356.754684 -264.543286) (xy 356.751636 -264.567924) (xy 356.92842 -264.744708)
			(xy 356.92842 -264.960354) (xy 356.965758 -264.970768) (xy 356.991915 -264.97854) (xy 357.041676 -265.00093)
			(xy 357.08744 -265.030645) (xy 357.12814 -265.06699) (xy 357.162822 -265.109115) (xy 357.190676 -265.156036)
			(xy 357.211051 -265.206654) (xy 357.22347 -265.259788) (xy 357.227643 -265.314194) (xy 357.225601 -265.340825)
			(xy 362.153952 -265.340825) (xy 362.153952 -265.287527) (xy 362.161895 -265.234823) (xy 362.177605 -265.183893)
			(xy 362.200731 -265.135872) (xy 362.230755 -265.091835) (xy 362.267007 -265.052764) (xy 362.308678 -265.019533)
			(xy 362.354836 -264.992884) (xy 362.40445 -264.973412) (xy 362.456412 -264.961552) (xy 362.509562 -264.957569)
			(xy 362.562712 -264.961552) (xy 362.614674 -264.973412) (xy 362.664288 -264.992884) (xy 362.710446 -265.019533)
			(xy 362.752117 -265.052764) (xy 362.788369 -265.091835) (xy 362.818393 -265.135872) (xy 362.841519 -265.183893)
			(xy 362.857229 -265.234823) (xy 362.865172 -265.287527) (xy 362.86567 -265.314176) (xy 362.865172 -265.340825)
			(xy 363.094006 -265.340825) (xy 363.094006 -265.287527) (xy 363.101949 -265.234823) (xy 363.117659 -265.183893)
			(xy 363.140785 -265.135872) (xy 363.170809 -265.091835) (xy 363.207061 -265.052764) (xy 363.248732 -265.019533)
			(xy 363.29489 -264.992884) (xy 363.344504 -264.973412) (xy 363.396466 -264.961552) (xy 363.449616 -264.957569)
			(xy 363.502766 -264.961552) (xy 363.554728 -264.973412) (xy 363.604342 -264.992884) (xy 363.6505 -265.019533)
			(xy 363.692171 -265.052764) (xy 363.728423 -265.091835) (xy 363.758447 -265.135872) (xy 363.781573 -265.183893)
			(xy 363.797283 -265.234823) (xy 363.805226 -265.287527) (xy 363.805724 -265.314176) (xy 363.805226 -265.340825)
			(xy 364.033806 -265.340825) (xy 364.033806 -265.287527) (xy 364.041749 -265.234823) (xy 364.057459 -265.183893)
			(xy 364.080585 -265.135872) (xy 364.110609 -265.091835) (xy 364.146861 -265.052764) (xy 364.188532 -265.019533)
			(xy 364.23469 -264.992884) (xy 364.284304 -264.973412) (xy 364.336266 -264.961552) (xy 364.389416 -264.957569)
			(xy 364.442566 -264.961552) (xy 364.494528 -264.973412) (xy 364.544142 -264.992884) (xy 364.5903 -265.019533)
			(xy 364.631971 -265.052764) (xy 364.668223 -265.091835) (xy 364.698247 -265.135872) (xy 364.721373 -265.183893)
			(xy 364.737083 -265.234823) (xy 364.745026 -265.287527) (xy 364.745524 -265.314176) (xy 364.745026 -265.340825)
			(xy 364.973606 -265.340825) (xy 364.973606 -265.287527) (xy 364.981549 -265.234823) (xy 364.997259 -265.183893)
			(xy 365.020385 -265.135872) (xy 365.050409 -265.091835) (xy 365.086661 -265.052764) (xy 365.128332 -265.019533)
			(xy 365.17449 -264.992884) (xy 365.224104 -264.973412) (xy 365.276066 -264.961552) (xy 365.329216 -264.957569)
			(xy 365.382366 -264.961552) (xy 365.434328 -264.973412) (xy 365.483942 -264.992884) (xy 365.5301 -265.019533)
			(xy 365.571771 -265.052764) (xy 365.608023 -265.091835) (xy 365.638047 -265.135872) (xy 365.661173 -265.183893)
			(xy 365.676883 -265.234823) (xy 365.684826 -265.287527) (xy 365.685324 -265.314176) (xy 365.684826 -265.340825)
			(xy 365.676883 -265.393529) (xy 365.661173 -265.444459) (xy 365.638047 -265.49248) (xy 365.608023 -265.536517)
			(xy 365.571771 -265.575588) (xy 365.5301 -265.608819) (xy 365.483942 -265.635468) (xy 365.434328 -265.65494)
			(xy 365.382366 -265.6668) (xy 365.329216 -265.670784) (xy 365.276066 -265.6668) (xy 365.224104 -265.65494)
			(xy 365.17449 -265.635468) (xy 365.128332 -265.608819) (xy 365.086661 -265.575588) (xy 365.050409 -265.536517)
			(xy 365.020385 -265.49248) (xy 364.997259 -265.444459) (xy 364.981549 -265.393529) (xy 364.973606 -265.340825)
			(xy 364.745026 -265.340825) (xy 364.737083 -265.393529) (xy 364.721373 -265.444459) (xy 364.698247 -265.49248)
			(xy 364.668223 -265.536517) (xy 364.631971 -265.575588) (xy 364.5903 -265.608819) (xy 364.544142 -265.635468)
			(xy 364.494528 -265.65494) (xy 364.442566 -265.6668) (xy 364.389416 -265.670784) (xy 364.336266 -265.6668)
			(xy 364.284304 -265.65494) (xy 364.23469 -265.635468) (xy 364.188532 -265.608819) (xy 364.146861 -265.575588)
			(xy 364.110609 -265.536517) (xy 364.080585 -265.49248) (xy 364.057459 -265.444459) (xy 364.041749 -265.393529)
			(xy 364.033806 -265.340825) (xy 363.805226 -265.340825) (xy 363.797283 -265.393529) (xy 363.781573 -265.444459)
			(xy 363.758447 -265.49248) (xy 363.728423 -265.536517) (xy 363.692171 -265.575588) (xy 363.6505 -265.608819)
			(xy 363.604342 -265.635468) (xy 363.554728 -265.65494) (xy 363.502766 -265.6668) (xy 363.449616 -265.670784)
			(xy 363.396466 -265.6668) (xy 363.344504 -265.65494) (xy 363.29489 -265.635468) (xy 363.248732 -265.608819)
			(xy 363.207061 -265.575588) (xy 363.170809 -265.536517) (xy 363.140785 -265.49248) (xy 363.117659 -265.444459)
			(xy 363.101949 -265.393529) (xy 363.094006 -265.340825) (xy 362.865172 -265.340825) (xy 362.857229 -265.393529)
			(xy 362.841519 -265.444459) (xy 362.818393 -265.49248) (xy 362.788369 -265.536517) (xy 362.752117 -265.575588)
			(xy 362.710446 -265.608819) (xy 362.664288 -265.635468) (xy 362.614674 -265.65494) (xy 362.562712 -265.6668)
			(xy 362.509562 -265.670784) (xy 362.456412 -265.6668) (xy 362.40445 -265.65494) (xy 362.354836 -265.635468)
			(xy 362.308678 -265.608819) (xy 362.267007 -265.575588) (xy 362.230755 -265.536517) (xy 362.200731 -265.49248)
			(xy 362.177605 -265.444459) (xy 362.161895 -265.393529) (xy 362.153952 -265.340825) (xy 357.225601 -265.340825)
			(xy 357.223472 -265.368599) (xy 357.211055 -265.421733) (xy 357.190682 -265.472353) (xy 357.162829 -265.519274)
			(xy 357.128149 -265.561401) (xy 357.087451 -265.597747) (xy 357.041687 -265.627464) (xy 356.991928 -265.649856)
			(xy 356.965758 -265.657584) (xy 356.92842 -265.667998) (xy 356.92842 -265.792458) (xy 356.928888 -265.80704)
			(xy 356.937125 -265.835017) (xy 356.952939 -265.859521) (xy 356.975038 -265.878552) (xy 357.001617 -265.890555)
			(xy 357.030505 -265.894551) (xy 357.059345 -265.890213) (xy 357.08578 -265.877895) (xy 357.097076 -265.868658)
			(xy 357.117006 -265.850632) (xy 357.161272 -265.820166) (xy 357.209609 -265.796689) (xy 357.260921 -265.780731)
			(xy 357.314048 -265.772654) (xy 357.340916 -265.772138) (xy 357.367561 -265.772637) (xy 357.420256 -265.780582)
			(xy 357.471178 -265.796291) (xy 357.51919 -265.819414) (xy 357.563219 -265.849435) (xy 357.602283 -265.885683)
			(xy 357.635508 -265.927347) (xy 357.662152 -265.973498) (xy 357.681621 -266.023105) (xy 357.693479 -266.075059)
			(xy 357.697461 -266.1282) (xy 357.695461 -266.154895) (xy 361.684052 -266.154895) (xy 361.684052 -266.101597)
			(xy 361.691995 -266.048893) (xy 361.707705 -265.997963) (xy 361.730831 -265.949942) (xy 361.760855 -265.905905)
			(xy 361.797107 -265.866834) (xy 361.838778 -265.833603) (xy 361.884936 -265.806954) (xy 361.93455 -265.787482)
			(xy 361.986512 -265.775622) (xy 362.039662 -265.771639) (xy 362.092812 -265.775622) (xy 362.144774 -265.787482)
			(xy 362.194388 -265.806954) (xy 362.240546 -265.833603) (xy 362.282217 -265.866834) (xy 362.318469 -265.905905)
			(xy 362.348493 -265.949942) (xy 362.371619 -265.997963) (xy 362.387329 -266.048893) (xy 362.395272 -266.101597)
			(xy 362.39577 -266.128246) (xy 362.395272 -266.154895) (xy 362.623852 -266.154895) (xy 362.623852 -266.101597)
			(xy 362.631795 -266.048893) (xy 362.647505 -265.997963) (xy 362.670631 -265.949942) (xy 362.700655 -265.905905)
			(xy 362.736907 -265.866834) (xy 362.778578 -265.833603) (xy 362.824736 -265.806954) (xy 362.87435 -265.787482)
			(xy 362.926312 -265.775622) (xy 362.979462 -265.771639) (xy 363.032612 -265.775622) (xy 363.084574 -265.787482)
			(xy 363.134188 -265.806954) (xy 363.180346 -265.833603) (xy 363.222017 -265.866834) (xy 363.258269 -265.905905)
			(xy 363.288293 -265.949942) (xy 363.311419 -265.997963) (xy 363.327129 -266.048893) (xy 363.335072 -266.101597)
			(xy 363.33557 -266.128246) (xy 363.335072 -266.154895) (xy 363.563652 -266.154895) (xy 363.563652 -266.101597)
			(xy 363.571595 -266.048893) (xy 363.587305 -265.997963) (xy 363.610431 -265.949942) (xy 363.640455 -265.905905)
			(xy 363.676707 -265.866834) (xy 363.718378 -265.833603) (xy 363.764536 -265.806954) (xy 363.81415 -265.787482)
			(xy 363.866112 -265.775622) (xy 363.919262 -265.771639) (xy 363.972412 -265.775622) (xy 364.024374 -265.787482)
			(xy 364.073988 -265.806954) (xy 364.120146 -265.833603) (xy 364.161817 -265.866834) (xy 364.198069 -265.905905)
			(xy 364.228093 -265.949942) (xy 364.251219 -265.997963) (xy 364.266929 -266.048893) (xy 364.274872 -266.101597)
			(xy 364.27537 -266.128246) (xy 364.274872 -266.154895) (xy 364.274834 -266.155149) (xy 364.503452 -266.155149)
			(xy 364.503452 -266.101851) (xy 364.511395 -266.049147) (xy 364.527105 -265.998217) (xy 364.550231 -265.950196)
			(xy 364.580255 -265.906159) (xy 364.616507 -265.867088) (xy 364.658178 -265.833857) (xy 364.704336 -265.807208)
			(xy 364.75395 -265.787736) (xy 364.805912 -265.775876) (xy 364.859062 -265.771893) (xy 364.912212 -265.775876)
			(xy 364.964174 -265.787736) (xy 365.013788 -265.807208) (xy 365.059946 -265.833857) (xy 365.101617 -265.867088)
			(xy 365.137869 -265.906159) (xy 365.167893 -265.950196) (xy 365.191019 -265.998217) (xy 365.206729 -266.049147)
			(xy 365.214672 -266.101851) (xy 365.21517 -266.1285) (xy 365.214672 -266.155149) (xy 365.206729 -266.207853)
			(xy 365.191019 -266.258783) (xy 365.167893 -266.306804) (xy 365.137869 -266.350841) (xy 365.101617 -266.389912)
			(xy 365.059946 -266.423143) (xy 365.013788 -266.449792) (xy 364.964174 -266.469264) (xy 364.912212 -266.481124)
			(xy 364.859062 -266.485108) (xy 364.805912 -266.481124) (xy 364.75395 -266.469264) (xy 364.704336 -266.449792)
			(xy 364.658178 -266.423143) (xy 364.616507 -266.389912) (xy 364.580255 -266.350841) (xy 364.550231 -266.306804)
			(xy 364.527105 -266.258783) (xy 364.511395 -266.207853) (xy 364.503452 -266.155149) (xy 364.274834 -266.155149)
			(xy 364.266929 -266.207599) (xy 364.251219 -266.258529) (xy 364.228093 -266.30655) (xy 364.198069 -266.350587)
			(xy 364.161817 -266.389658) (xy 364.120146 -266.422889) (xy 364.073988 -266.449538) (xy 364.024374 -266.46901)
			(xy 363.972412 -266.48087) (xy 363.919262 -266.484854) (xy 363.866112 -266.48087) (xy 363.81415 -266.46901)
			(xy 363.764536 -266.449538) (xy 363.718378 -266.422889) (xy 363.676707 -266.389658) (xy 363.640455 -266.350587)
			(xy 363.610431 -266.30655) (xy 363.587305 -266.258529) (xy 363.571595 -266.207599) (xy 363.563652 -266.154895)
			(xy 363.335072 -266.154895) (xy 363.327129 -266.207599) (xy 363.311419 -266.258529) (xy 363.288293 -266.30655)
			(xy 363.258269 -266.350587) (xy 363.222017 -266.389658) (xy 363.180346 -266.422889) (xy 363.134188 -266.449538)
			(xy 363.084574 -266.46901) (xy 363.032612 -266.48087) (xy 362.979462 -266.484854) (xy 362.926312 -266.48087)
			(xy 362.87435 -266.46901) (xy 362.824736 -266.449538) (xy 362.778578 -266.422889) (xy 362.736907 -266.389658)
			(xy 362.700655 -266.350587) (xy 362.670631 -266.30655) (xy 362.647505 -266.258529) (xy 362.631795 -266.207599)
			(xy 362.623852 -266.154895) (xy 362.395272 -266.154895) (xy 362.387329 -266.207599) (xy 362.371619 -266.258529)
			(xy 362.348493 -266.30655) (xy 362.318469 -266.350587) (xy 362.282217 -266.389658) (xy 362.240546 -266.422889)
			(xy 362.194388 -266.449538) (xy 362.144774 -266.46901) (xy 362.092812 -266.48087) (xy 362.039662 -266.484854)
			(xy 361.986512 -266.48087) (xy 361.93455 -266.46901) (xy 361.884936 -266.449538) (xy 361.838778 -266.422889)
			(xy 361.797107 -266.389658) (xy 361.760855 -266.350587) (xy 361.730831 -266.30655) (xy 361.707705 -266.258529)
			(xy 361.691995 -266.207599) (xy 361.684052 -266.154895) (xy 357.695461 -266.154895) (xy 357.693479 -266.181341)
			(xy 357.681621 -266.233295) (xy 357.662152 -266.282902) (xy 357.635508 -266.329053) (xy 357.602283 -266.370717)
			(xy 357.563219 -266.406965) (xy 357.51919 -266.436986) (xy 357.471178 -266.460109) (xy 357.420256 -266.475818)
			(xy 357.367561 -266.483763) (xy 357.340916 -266.484354) (xy 357.314046 -266.483866) (xy 357.260916 -266.475794)
			(xy 357.209602 -266.459832) (xy 357.161268 -266.436342) (xy 357.117012 -266.405857) (xy 357.097076 -266.387834)
			(xy 357.085817 -266.378561) (xy 357.059375 -266.366275) (xy 357.030539 -266.361962) (xy 357.001659 -266.365971)
			(xy 356.975088 -266.377977) (xy 356.952992 -266.397001) (xy 356.937172 -266.421492) (xy 356.928916 -266.449456)
			(xy 356.92842 -266.464034) (xy 356.92842 -266.58824) (xy 356.966012 -266.5984) (xy 356.992164 -266.606175)
			(xy 357.041913 -266.628569) (xy 357.087667 -266.658285) (xy 357.128355 -266.69463) (xy 357.163027 -266.736752)
			(xy 357.190873 -266.783667) (xy 357.211241 -266.834279) (xy 357.223656 -266.887405) (xy 357.227826 -266.941802)
			(xy 357.225782 -266.968457) (xy 357.454952 -266.968457) (xy 357.454952 -266.915159) (xy 357.462895 -266.862455)
			(xy 357.478605 -266.811525) (xy 357.501731 -266.763504) (xy 357.531755 -266.719467) (xy 357.568007 -266.680396)
			(xy 357.609678 -266.647165) (xy 357.655836 -266.620516) (xy 357.70545 -266.601044) (xy 357.757412 -266.589184)
			(xy 357.810562 -266.585201) (xy 357.863712 -266.589184) (xy 357.915674 -266.601044) (xy 357.965288 -266.620516)
			(xy 358.011446 -266.647165) (xy 358.053117 -266.680396) (xy 358.089369 -266.719467) (xy 358.119393 -266.763504)
			(xy 358.142519 -266.811525) (xy 358.158229 -266.862455) (xy 358.166172 -266.915159) (xy 358.16667 -266.941808)
			(xy 358.166172 -266.968457) (xy 361.214152 -266.968457) (xy 361.214152 -266.915159) (xy 361.222095 -266.862455)
			(xy 361.237805 -266.811525) (xy 361.260931 -266.763504) (xy 361.290955 -266.719467) (xy 361.327207 -266.680396)
			(xy 361.368878 -266.647165) (xy 361.415036 -266.620516) (xy 361.46465 -266.601044) (xy 361.516612 -266.589184)
			(xy 361.569762 -266.585201) (xy 361.622912 -266.589184) (xy 361.674874 -266.601044) (xy 361.724488 -266.620516)
			(xy 361.770646 -266.647165) (xy 361.812317 -266.680396) (xy 361.848569 -266.719467) (xy 361.878593 -266.763504)
			(xy 361.901719 -266.811525) (xy 361.917429 -266.862455) (xy 361.925372 -266.915159) (xy 361.92587 -266.941808)
			(xy 361.925372 -266.968457) (xy 362.153952 -266.968457) (xy 362.153952 -266.915159) (xy 362.161895 -266.862455)
			(xy 362.177605 -266.811525) (xy 362.200731 -266.763504) (xy 362.230755 -266.719467) (xy 362.267007 -266.680396)
			(xy 362.308678 -266.647165) (xy 362.354836 -266.620516) (xy 362.40445 -266.601044) (xy 362.456412 -266.589184)
			(xy 362.509562 -266.585201) (xy 362.562712 -266.589184) (xy 362.614674 -266.601044) (xy 362.664288 -266.620516)
			(xy 362.710446 -266.647165) (xy 362.752117 -266.680396) (xy 362.788369 -266.719467) (xy 362.818393 -266.763504)
			(xy 362.841519 -266.811525) (xy 362.857229 -266.862455) (xy 362.865172 -266.915159) (xy 362.86567 -266.941808)
			(xy 362.865172 -266.968457) (xy 363.093752 -266.968457) (xy 363.093752 -266.915159) (xy 363.101695 -266.862455)
			(xy 363.117405 -266.811525) (xy 363.140531 -266.763504) (xy 363.170555 -266.719467) (xy 363.206807 -266.680396)
			(xy 363.248478 -266.647165) (xy 363.294636 -266.620516) (xy 363.34425 -266.601044) (xy 363.396212 -266.589184)
			(xy 363.449362 -266.585201) (xy 363.502512 -266.589184) (xy 363.554474 -266.601044) (xy 363.604088 -266.620516)
			(xy 363.650246 -266.647165) (xy 363.691917 -266.680396) (xy 363.728169 -266.719467) (xy 363.758193 -266.763504)
			(xy 363.781319 -266.811525) (xy 363.797029 -266.862455) (xy 363.804972 -266.915159) (xy 363.80547 -266.941808)
			(xy 363.804972 -266.968457) (xy 364.033552 -266.968457) (xy 364.033552 -266.915159) (xy 364.041495 -266.862455)
			(xy 364.057205 -266.811525) (xy 364.080331 -266.763504) (xy 364.110355 -266.719467) (xy 364.146607 -266.680396)
			(xy 364.188278 -266.647165) (xy 364.234436 -266.620516) (xy 364.28405 -266.601044) (xy 364.336012 -266.589184)
			(xy 364.389162 -266.585201) (xy 364.442312 -266.589184) (xy 364.494274 -266.601044) (xy 364.543888 -266.620516)
			(xy 364.590046 -266.647165) (xy 364.631717 -266.680396) (xy 364.667969 -266.719467) (xy 364.697993 -266.763504)
			(xy 364.721119 -266.811525) (xy 364.736829 -266.862455) (xy 364.744772 -266.915159) (xy 364.74527 -266.941808)
			(xy 364.744772 -266.968457) (xy 364.973606 -266.968457) (xy 364.973606 -266.915159) (xy 364.981549 -266.862455)
			(xy 364.997259 -266.811525) (xy 365.020385 -266.763504) (xy 365.050409 -266.719467) (xy 365.086661 -266.680396)
			(xy 365.128332 -266.647165) (xy 365.17449 -266.620516) (xy 365.224104 -266.601044) (xy 365.276066 -266.589184)
			(xy 365.329216 -266.585201) (xy 365.382366 -266.589184) (xy 365.434328 -266.601044) (xy 365.483942 -266.620516)
			(xy 365.5301 -266.647165) (xy 365.571771 -266.680396) (xy 365.608023 -266.719467) (xy 365.638047 -266.763504)
			(xy 365.661173 -266.811525) (xy 365.676883 -266.862455) (xy 365.684826 -266.915159) (xy 365.685324 -266.941808)
			(xy 365.684826 -266.968457) (xy 365.676883 -267.021161) (xy 365.661173 -267.072091) (xy 365.638047 -267.120112)
			(xy 365.608023 -267.164149) (xy 365.571771 -267.20322) (xy 365.5301 -267.236451) (xy 365.483942 -267.2631)
			(xy 365.434328 -267.282572) (xy 365.382366 -267.294432) (xy 365.329216 -267.298416) (xy 365.276066 -267.294432)
			(xy 365.224104 -267.282572) (xy 365.17449 -267.2631) (xy 365.128332 -267.236451) (xy 365.086661 -267.20322)
			(xy 365.050409 -267.164149) (xy 365.020385 -267.120112) (xy 364.997259 -267.072091) (xy 364.981549 -267.021161)
			(xy 364.973606 -266.968457) (xy 364.744772 -266.968457) (xy 364.736829 -267.021161) (xy 364.721119 -267.072091)
			(xy 364.697993 -267.120112) (xy 364.667969 -267.164149) (xy 364.631717 -267.20322) (xy 364.590046 -267.236451)
			(xy 364.543888 -267.2631) (xy 364.494274 -267.282572) (xy 364.442312 -267.294432) (xy 364.389162 -267.298416)
			(xy 364.336012 -267.294432) (xy 364.28405 -267.282572) (xy 364.234436 -267.2631) (xy 364.188278 -267.236451)
			(xy 364.146607 -267.20322) (xy 364.110355 -267.164149) (xy 364.080331 -267.120112) (xy 364.057205 -267.072091)
			(xy 364.041495 -267.021161) (xy 364.033552 -266.968457) (xy 363.804972 -266.968457) (xy 363.797029 -267.021161)
			(xy 363.781319 -267.072091) (xy 363.758193 -267.120112) (xy 363.728169 -267.164149) (xy 363.691917 -267.20322)
			(xy 363.650246 -267.236451) (xy 363.604088 -267.2631) (xy 363.554474 -267.282572) (xy 363.502512 -267.294432)
			(xy 363.449362 -267.298416) (xy 363.396212 -267.294432) (xy 363.34425 -267.282572) (xy 363.294636 -267.2631)
			(xy 363.248478 -267.236451) (xy 363.206807 -267.20322) (xy 363.170555 -267.164149) (xy 363.140531 -267.120112)
			(xy 363.117405 -267.072091) (xy 363.101695 -267.021161) (xy 363.093752 -266.968457) (xy 362.865172 -266.968457)
			(xy 362.857229 -267.021161) (xy 362.841519 -267.072091) (xy 362.818393 -267.120112) (xy 362.788369 -267.164149)
			(xy 362.752117 -267.20322) (xy 362.710446 -267.236451) (xy 362.664288 -267.2631) (xy 362.614674 -267.282572)
			(xy 362.562712 -267.294432) (xy 362.509562 -267.298416) (xy 362.456412 -267.294432) (xy 362.40445 -267.282572)
			(xy 362.354836 -267.2631) (xy 362.308678 -267.236451) (xy 362.267007 -267.20322) (xy 362.230755 -267.164149)
			(xy 362.200731 -267.120112) (xy 362.177605 -267.072091) (xy 362.161895 -267.021161) (xy 362.153952 -266.968457)
			(xy 361.925372 -266.968457) (xy 361.917429 -267.021161) (xy 361.901719 -267.072091) (xy 361.878593 -267.120112)
			(xy 361.848569 -267.164149) (xy 361.812317 -267.20322) (xy 361.770646 -267.236451) (xy 361.724488 -267.2631)
			(xy 361.674874 -267.282572) (xy 361.622912 -267.294432) (xy 361.569762 -267.298416) (xy 361.516612 -267.294432)
			(xy 361.46465 -267.282572) (xy 361.415036 -267.2631) (xy 361.368878 -267.236451) (xy 361.327207 -267.20322)
			(xy 361.290955 -267.164149) (xy 361.260931 -267.120112) (xy 361.237805 -267.072091) (xy 361.222095 -267.021161)
			(xy 361.214152 -266.968457) (xy 358.166172 -266.968457) (xy 358.158229 -267.021161) (xy 358.142519 -267.072091)
			(xy 358.119393 -267.120112) (xy 358.089369 -267.164149) (xy 358.053117 -267.20322) (xy 358.011446 -267.236451)
			(xy 357.965288 -267.2631) (xy 357.915674 -267.282572) (xy 357.863712 -267.294432) (xy 357.810562 -267.298416)
			(xy 357.757412 -267.294432) (xy 357.70545 -267.282572) (xy 357.655836 -267.2631) (xy 357.609678 -267.236451)
			(xy 357.568007 -267.20322) (xy 357.531755 -267.164149) (xy 357.501731 -267.120112) (xy 357.478605 -267.072091)
			(xy 357.462895 -267.021161) (xy 357.454952 -266.968457) (xy 357.225782 -266.968457) (xy 357.223655 -266.996199)
			(xy 357.21124 -267.049325) (xy 357.190871 -267.099937) (xy 357.163025 -267.146852) (xy 357.128352 -267.188974)
			(xy 357.087663 -267.225317) (xy 357.041909 -267.255033) (xy 356.99216 -267.277426) (xy 356.966012 -267.285216)
			(xy 356.92842 -267.295376) (xy 356.92842 -267.419836) (xy 356.928963 -267.434312) (xy 356.937155 -267.462083)
			(xy 356.952813 -267.486437) (xy 356.974679 -267.505417) (xy 357.000993 -267.517496) (xy 357.029639 -267.521702)
			(xy 357.058315 -267.517698) (xy 357.084714 -267.505805) (xy 357.09606 -267.496798) (xy 357.0986 -267.494512)
			(xy 357.098854 -267.494258) (xy 357.118702 -267.476602) (xy 357.162651 -267.446763) (xy 357.210543 -267.423782)
			(xy 357.261318 -267.408167) (xy 357.313848 -267.400265) (xy 357.340408 -267.39977) (xy 357.349298 -267.39977)
			(xy 357.375529 -267.400871) (xy 357.427259 -267.409827) (xy 357.477114 -267.426279) (xy 357.524015 -267.44987)
			(xy 357.566945 -267.480089) (xy 357.604975 -267.516281) (xy 357.637282 -267.557664) (xy 357.663165 -267.603339)
			(xy 357.682064 -267.652319) (xy 357.69357 -267.703542) (xy 357.697433 -267.755899) (xy 357.695468 -267.782527)
			(xy 357.924852 -267.782527) (xy 357.924852 -267.729229) (xy 357.932795 -267.676525) (xy 357.948505 -267.625595)
			(xy 357.971631 -267.577574) (xy 358.001655 -267.533537) (xy 358.037907 -267.494466) (xy 358.079578 -267.461235)
			(xy 358.125736 -267.434586) (xy 358.17535 -267.415114) (xy 358.227312 -267.403254) (xy 358.280462 -267.399271)
			(xy 358.333612 -267.403254) (xy 358.385574 -267.415114) (xy 358.435188 -267.434586) (xy 358.481346 -267.461235)
			(xy 358.523017 -267.494466) (xy 358.559269 -267.533537) (xy 358.589293 -267.577574) (xy 358.612419 -267.625595)
			(xy 358.628129 -267.676525) (xy 358.636072 -267.729229) (xy 358.63657 -267.755878) (xy 358.636072 -267.782527)
			(xy 361.684052 -267.782527) (xy 361.684052 -267.729229) (xy 361.691995 -267.676525) (xy 361.707705 -267.625595)
			(xy 361.730831 -267.577574) (xy 361.760855 -267.533537) (xy 361.797107 -267.494466) (xy 361.838778 -267.461235)
			(xy 361.884936 -267.434586) (xy 361.93455 -267.415114) (xy 361.986512 -267.403254) (xy 362.039662 -267.399271)
			(xy 362.092812 -267.403254) (xy 362.144774 -267.415114) (xy 362.194388 -267.434586) (xy 362.240546 -267.461235)
			(xy 362.282217 -267.494466) (xy 362.318469 -267.533537) (xy 362.348493 -267.577574) (xy 362.371619 -267.625595)
			(xy 362.387329 -267.676525) (xy 362.395272 -267.729229) (xy 362.39577 -267.755878) (xy 362.395272 -267.782527)
			(xy 362.623852 -267.782527) (xy 362.623852 -267.729229) (xy 362.631795 -267.676525) (xy 362.647505 -267.625595)
			(xy 362.670631 -267.577574) (xy 362.700655 -267.533537) (xy 362.736907 -267.494466) (xy 362.778578 -267.461235)
			(xy 362.824736 -267.434586) (xy 362.87435 -267.415114) (xy 362.926312 -267.403254) (xy 362.979462 -267.399271)
			(xy 363.032612 -267.403254) (xy 363.084574 -267.415114) (xy 363.134188 -267.434586) (xy 363.180346 -267.461235)
			(xy 363.222017 -267.494466) (xy 363.258269 -267.533537) (xy 363.288293 -267.577574) (xy 363.311419 -267.625595)
			(xy 363.327129 -267.676525) (xy 363.335072 -267.729229) (xy 363.33557 -267.755878) (xy 363.335072 -267.782527)
			(xy 363.563652 -267.782527) (xy 363.563652 -267.729229) (xy 363.571595 -267.676525) (xy 363.587305 -267.625595)
			(xy 363.610431 -267.577574) (xy 363.640455 -267.533537) (xy 363.676707 -267.494466) (xy 363.718378 -267.461235)
			(xy 363.764536 -267.434586) (xy 363.81415 -267.415114) (xy 363.866112 -267.403254) (xy 363.919262 -267.399271)
			(xy 363.972412 -267.403254) (xy 364.024374 -267.415114) (xy 364.073988 -267.434586) (xy 364.120146 -267.461235)
			(xy 364.161817 -267.494466) (xy 364.198069 -267.533537) (xy 364.228093 -267.577574) (xy 364.251219 -267.625595)
			(xy 364.266929 -267.676525) (xy 364.274872 -267.729229) (xy 364.27537 -267.755878) (xy 364.274872 -267.782527)
			(xy 364.503706 -267.782527) (xy 364.503706 -267.729229) (xy 364.511649 -267.676525) (xy 364.527359 -267.625595)
			(xy 364.550485 -267.577574) (xy 364.580509 -267.533537) (xy 364.616761 -267.494466) (xy 364.658432 -267.461235)
			(xy 364.70459 -267.434586) (xy 364.754204 -267.415114) (xy 364.806166 -267.403254) (xy 364.859316 -267.399271)
			(xy 364.912466 -267.403254) (xy 364.964428 -267.415114) (xy 365.014042 -267.434586) (xy 365.0602 -267.461235)
			(xy 365.101871 -267.494466) (xy 365.138123 -267.533537) (xy 365.168147 -267.577574) (xy 365.191273 -267.625595)
			(xy 365.206983 -267.676525) (xy 365.214926 -267.729229) (xy 365.215424 -267.755878) (xy 365.214926 -267.782527)
			(xy 365.206983 -267.835231) (xy 365.191273 -267.886161) (xy 365.168147 -267.934182) (xy 365.138123 -267.978219)
			(xy 365.101871 -268.01729) (xy 365.0602 -268.050521) (xy 365.014042 -268.07717) (xy 364.964428 -268.096642)
			(xy 364.912466 -268.108502) (xy 364.859316 -268.112486) (xy 364.806166 -268.108502) (xy 364.754204 -268.096642)
			(xy 364.70459 -268.07717) (xy 364.658432 -268.050521) (xy 364.616761 -268.01729) (xy 364.580509 -267.978219)
			(xy 364.550485 -267.934182) (xy 364.527359 -267.886161) (xy 364.511649 -267.835231) (xy 364.503706 -267.782527)
			(xy 364.274872 -267.782527) (xy 364.266929 -267.835231) (xy 364.251219 -267.886161) (xy 364.228093 -267.934182)
			(xy 364.198069 -267.978219) (xy 364.161817 -268.01729) (xy 364.120146 -268.050521) (xy 364.073988 -268.07717)
			(xy 364.024374 -268.096642) (xy 363.972412 -268.108502) (xy 363.919262 -268.112486) (xy 363.866112 -268.108502)
			(xy 363.81415 -268.096642) (xy 363.764536 -268.07717) (xy 363.718378 -268.050521) (xy 363.676707 -268.01729)
			(xy 363.640455 -267.978219) (xy 363.610431 -267.934182) (xy 363.587305 -267.886161) (xy 363.571595 -267.835231)
			(xy 363.563652 -267.782527) (xy 363.335072 -267.782527) (xy 363.327129 -267.835231) (xy 363.311419 -267.886161)
			(xy 363.288293 -267.934182) (xy 363.258269 -267.978219) (xy 363.222017 -268.01729) (xy 363.180346 -268.050521)
			(xy 363.134188 -268.07717) (xy 363.084574 -268.096642) (xy 363.032612 -268.108502) (xy 362.979462 -268.112486)
			(xy 362.926312 -268.108502) (xy 362.87435 -268.096642) (xy 362.824736 -268.07717) (xy 362.778578 -268.050521)
			(xy 362.736907 -268.01729) (xy 362.700655 -267.978219) (xy 362.670631 -267.934182) (xy 362.647505 -267.886161)
			(xy 362.631795 -267.835231) (xy 362.623852 -267.782527) (xy 362.395272 -267.782527) (xy 362.387329 -267.835231)
			(xy 362.371619 -267.886161) (xy 362.348493 -267.934182) (xy 362.318469 -267.978219) (xy 362.282217 -268.01729)
			(xy 362.240546 -268.050521) (xy 362.194388 -268.07717) (xy 362.144774 -268.096642) (xy 362.092812 -268.108502)
			(xy 362.039662 -268.112486) (xy 361.986512 -268.108502) (xy 361.93455 -268.096642) (xy 361.884936 -268.07717)
			(xy 361.838778 -268.050521) (xy 361.797107 -268.01729) (xy 361.760855 -267.978219) (xy 361.730831 -267.934182)
			(xy 361.707705 -267.886161) (xy 361.691995 -267.835231) (xy 361.684052 -267.782527) (xy 358.636072 -267.782527)
			(xy 358.628129 -267.835231) (xy 358.612419 -267.886161) (xy 358.589293 -267.934182) (xy 358.559269 -267.978219)
			(xy 358.523017 -268.01729) (xy 358.481346 -268.050521) (xy 358.435188 -268.07717) (xy 358.385574 -268.096642)
			(xy 358.333612 -268.108502) (xy 358.280462 -268.112486) (xy 358.227312 -268.108502) (xy 358.17535 -268.096642)
			(xy 358.125736 -268.07717) (xy 358.079578 -268.050521) (xy 358.037907 -268.01729) (xy 358.001655 -267.978219)
			(xy 357.971631 -267.934182) (xy 357.948505 -267.886161) (xy 357.932795 -267.835231) (xy 357.924852 -267.782527)
			(xy 357.695468 -267.782527) (xy 357.69357 -267.808257) (xy 357.682065 -267.85948) (xy 357.663166 -267.90846)
			(xy 357.637283 -267.954136) (xy 357.604976 -267.995518) (xy 357.566946 -268.03171) (xy 357.524016 -268.061929)
			(xy 357.477115 -268.08552) (xy 357.42726 -268.101972) (xy 357.37553 -268.110929) (xy 357.349298 -268.111986)
			(xy 357.340408 -268.111986) (xy 357.313847 -268.111494) (xy 357.261316 -268.1036) (xy 357.210542 -268.087984)
			(xy 357.162653 -268.064995) (xy 357.118713 -268.035143) (xy 357.098854 -268.017498) (xy 357.0986 -268.017244)
			(xy 357.09606 -268.014958) (xy 357.084724 -268.005933) (xy 357.058317 -267.994042) (xy 357.029633 -267.99004)
			(xy 357.000979 -267.994248) (xy 356.974658 -268.006328) (xy 356.952784 -268.025309) (xy 356.937115 -268.049666)
			(xy 356.928911 -268.077441) (xy 356.92842 -268.09192) (xy 356.92842 -268.216126) (xy 356.965758 -268.22654)
			(xy 356.991891 -268.23431) (xy 357.041603 -268.25669) (xy 357.087323 -268.286386) (xy 357.127981 -268.322704)
			(xy 357.162628 -268.364796) (xy 357.190453 -268.411678) (xy 357.210807 -268.462253) (xy 357.223212 -268.515341)
			(xy 357.22738 -268.569698) (xy 357.225337 -268.596343) (xy 357.454952 -268.596343) (xy 357.454952 -268.543045)
			(xy 357.462895 -268.490341) (xy 357.478605 -268.439411) (xy 357.501731 -268.39139) (xy 357.531755 -268.347353)
			(xy 357.568007 -268.308282) (xy 357.609678 -268.275051) (xy 357.655836 -268.248402) (xy 357.70545 -268.22893)
			(xy 357.757412 -268.21707) (xy 357.810562 -268.213087) (xy 357.863712 -268.21707) (xy 357.915674 -268.22893)
			(xy 357.965288 -268.248402) (xy 358.011446 -268.275051) (xy 358.053117 -268.308282) (xy 358.089369 -268.347353)
			(xy 358.119393 -268.39139) (xy 358.142519 -268.439411) (xy 358.158229 -268.490341) (xy 358.166172 -268.543045)
			(xy 358.16667 -268.569694) (xy 358.166172 -268.596343) (xy 361.214152 -268.596343) (xy 361.214152 -268.543045)
			(xy 361.222095 -268.490341) (xy 361.237805 -268.439411) (xy 361.260931 -268.39139) (xy 361.290955 -268.347353)
			(xy 361.327207 -268.308282) (xy 361.368878 -268.275051) (xy 361.415036 -268.248402) (xy 361.46465 -268.22893)
			(xy 361.516612 -268.21707) (xy 361.569762 -268.213087) (xy 361.622912 -268.21707) (xy 361.674874 -268.22893)
			(xy 361.724488 -268.248402) (xy 361.770646 -268.275051) (xy 361.812317 -268.308282) (xy 361.848569 -268.347353)
			(xy 361.878593 -268.39139) (xy 361.901719 -268.439411) (xy 361.917429 -268.490341) (xy 361.925372 -268.543045)
			(xy 361.92587 -268.569694) (xy 361.925372 -268.596343) (xy 362.154206 -268.596343) (xy 362.154206 -268.543045)
			(xy 362.162149 -268.490341) (xy 362.177859 -268.439411) (xy 362.200985 -268.39139) (xy 362.231009 -268.347353)
			(xy 362.267261 -268.308282) (xy 362.308932 -268.275051) (xy 362.35509 -268.248402) (xy 362.404704 -268.22893)
			(xy 362.456666 -268.21707) (xy 362.509816 -268.213087) (xy 362.562966 -268.21707) (xy 362.614928 -268.22893)
			(xy 362.664542 -268.248402) (xy 362.7107 -268.275051) (xy 362.752371 -268.308282) (xy 362.788623 -268.347353)
			(xy 362.818647 -268.39139) (xy 362.841773 -268.439411) (xy 362.857483 -268.490341) (xy 362.865426 -268.543045)
			(xy 362.865924 -268.569694) (xy 362.865426 -268.596343) (xy 363.094006 -268.596343) (xy 363.094006 -268.543045)
			(xy 363.101949 -268.490341) (xy 363.117659 -268.439411) (xy 363.140785 -268.39139) (xy 363.170809 -268.347353)
			(xy 363.207061 -268.308282) (xy 363.248732 -268.275051) (xy 363.29489 -268.248402) (xy 363.344504 -268.22893)
			(xy 363.396466 -268.21707) (xy 363.449616 -268.213087) (xy 363.502766 -268.21707) (xy 363.554728 -268.22893)
			(xy 363.604342 -268.248402) (xy 363.6505 -268.275051) (xy 363.692171 -268.308282) (xy 363.728423 -268.347353)
			(xy 363.758447 -268.39139) (xy 363.781573 -268.439411) (xy 363.797283 -268.490341) (xy 363.805226 -268.543045)
			(xy 363.805724 -268.569694) (xy 363.805226 -268.596343) (xy 364.033806 -268.596343) (xy 364.033806 -268.543045)
			(xy 364.041749 -268.490341) (xy 364.057459 -268.439411) (xy 364.080585 -268.39139) (xy 364.110609 -268.347353)
			(xy 364.146861 -268.308282) (xy 364.188532 -268.275051) (xy 364.23469 -268.248402) (xy 364.284304 -268.22893)
			(xy 364.336266 -268.21707) (xy 364.389416 -268.213087) (xy 364.442566 -268.21707) (xy 364.494528 -268.22893)
			(xy 364.544142 -268.248402) (xy 364.5903 -268.275051) (xy 364.631971 -268.308282) (xy 364.668223 -268.347353)
			(xy 364.698247 -268.39139) (xy 364.721373 -268.439411) (xy 364.737083 -268.490341) (xy 364.745026 -268.543045)
			(xy 364.745524 -268.569694) (xy 364.745026 -268.596343) (xy 364.973352 -268.596343) (xy 364.973352 -268.543045)
			(xy 364.981295 -268.490341) (xy 364.997005 -268.439411) (xy 365.020131 -268.39139) (xy 365.050155 -268.347353)
			(xy 365.086407 -268.308282) (xy 365.128078 -268.275051) (xy 365.174236 -268.248402) (xy 365.22385 -268.22893)
			(xy 365.275812 -268.21707) (xy 365.328962 -268.213087) (xy 365.382112 -268.21707) (xy 365.434074 -268.22893)
			(xy 365.483688 -268.248402) (xy 365.529846 -268.275051) (xy 365.571517 -268.308282) (xy 365.607769 -268.347353)
			(xy 365.637793 -268.39139) (xy 365.660919 -268.439411) (xy 365.676629 -268.490341) (xy 365.684572 -268.543045)
			(xy 365.68507 -268.569694) (xy 365.684572 -268.596343) (xy 365.676629 -268.649047) (xy 365.660919 -268.699977)
			(xy 365.637793 -268.747998) (xy 365.607769 -268.792035) (xy 365.571517 -268.831106) (xy 365.529846 -268.864337)
			(xy 365.483688 -268.890986) (xy 365.434074 -268.910458) (xy 365.382112 -268.922318) (xy 365.328962 -268.926302)
			(xy 365.275812 -268.922318) (xy 365.22385 -268.910458) (xy 365.174236 -268.890986) (xy 365.128078 -268.864337)
			(xy 365.086407 -268.831106) (xy 365.050155 -268.792035) (xy 365.020131 -268.747998) (xy 364.997005 -268.699977)
			(xy 364.981295 -268.649047) (xy 364.973352 -268.596343) (xy 364.745026 -268.596343) (xy 364.737083 -268.649047)
			(xy 364.721373 -268.699977) (xy 364.698247 -268.747998) (xy 364.668223 -268.792035) (xy 364.631971 -268.831106)
			(xy 364.5903 -268.864337) (xy 364.544142 -268.890986) (xy 364.494528 -268.910458) (xy 364.442566 -268.922318)
			(xy 364.389416 -268.926302) (xy 364.336266 -268.922318) (xy 364.284304 -268.910458) (xy 364.23469 -268.890986)
			(xy 364.188532 -268.864337) (xy 364.146861 -268.831106) (xy 364.110609 -268.792035) (xy 364.080585 -268.747998)
			(xy 364.057459 -268.699977) (xy 364.041749 -268.649047) (xy 364.033806 -268.596343) (xy 363.805226 -268.596343)
			(xy 363.797283 -268.649047) (xy 363.781573 -268.699977) (xy 363.758447 -268.747998) (xy 363.728423 -268.792035)
			(xy 363.692171 -268.831106) (xy 363.6505 -268.864337) (xy 363.604342 -268.890986) (xy 363.554728 -268.910458)
			(xy 363.502766 -268.922318) (xy 363.449616 -268.926302) (xy 363.396466 -268.922318) (xy 363.344504 -268.910458)
			(xy 363.29489 -268.890986) (xy 363.248732 -268.864337) (xy 363.207061 -268.831106) (xy 363.170809 -268.792035)
			(xy 363.140785 -268.747998) (xy 363.117659 -268.699977) (xy 363.101949 -268.649047) (xy 363.094006 -268.596343)
			(xy 362.865426 -268.596343) (xy 362.857483 -268.649047) (xy 362.841773 -268.699977) (xy 362.818647 -268.747998)
			(xy 362.788623 -268.792035) (xy 362.752371 -268.831106) (xy 362.7107 -268.864337) (xy 362.664542 -268.890986)
			(xy 362.614928 -268.910458) (xy 362.562966 -268.922318) (xy 362.509816 -268.926302) (xy 362.456666 -268.922318)
			(xy 362.404704 -268.910458) (xy 362.35509 -268.890986) (xy 362.308932 -268.864337) (xy 362.267261 -268.831106)
			(xy 362.231009 -268.792035) (xy 362.200985 -268.747998) (xy 362.177859 -268.699977) (xy 362.162149 -268.649047)
			(xy 362.154206 -268.596343) (xy 361.925372 -268.596343) (xy 361.917429 -268.649047) (xy 361.901719 -268.699977)
			(xy 361.878593 -268.747998) (xy 361.848569 -268.792035) (xy 361.812317 -268.831106) (xy 361.770646 -268.864337)
			(xy 361.724488 -268.890986) (xy 361.674874 -268.910458) (xy 361.622912 -268.922318) (xy 361.569762 -268.926302)
			(xy 361.516612 -268.922318) (xy 361.46465 -268.910458) (xy 361.415036 -268.890986) (xy 361.368878 -268.864337)
			(xy 361.327207 -268.831106) (xy 361.290955 -268.792035) (xy 361.260931 -268.747998) (xy 361.237805 -268.699977)
			(xy 361.222095 -268.649047) (xy 361.214152 -268.596343) (xy 358.166172 -268.596343) (xy 358.158229 -268.649047)
			(xy 358.142519 -268.699977) (xy 358.119393 -268.747998) (xy 358.089369 -268.792035) (xy 358.053117 -268.831106)
			(xy 358.011446 -268.864337) (xy 357.965288 -268.890986) (xy 357.915674 -268.910458) (xy 357.863712 -268.922318)
			(xy 357.810562 -268.926302) (xy 357.757412 -268.922318) (xy 357.70545 -268.910458) (xy 357.655836 -268.890986)
			(xy 357.609678 -268.864337) (xy 357.568007 -268.831106) (xy 357.531755 -268.792035) (xy 357.501731 -268.747998)
			(xy 357.478605 -268.699977) (xy 357.462895 -268.649047) (xy 357.454952 -268.596343) (xy 357.225337 -268.596343)
			(xy 357.223213 -268.624056) (xy 357.210808 -268.677144) (xy 357.190455 -268.727719) (xy 357.16263 -268.774601)
			(xy 357.127984 -268.816694) (xy 357.087325 -268.853012) (xy 357.041606 -268.882709) (xy 356.991894 -268.905089)
			(xy 356.965758 -268.912848) (xy 356.92842 -268.923262) (xy 356.92842 -269.047468) (xy 356.928967 -269.06194)
			(xy 356.937164 -269.089703) (xy 356.952823 -269.114049) (xy 356.974686 -269.133022) (xy 357.000995 -269.145096)
			(xy 357.029635 -269.149302) (xy 357.058305 -269.145301) (xy 357.084699 -269.133415) (xy 357.09606 -269.12443)
			(xy 357.0986 -269.122144) (xy 357.098854 -269.12189) (xy 357.118704 -269.104237) (xy 357.162654 -269.074404)
			(xy 357.210547 -269.051427) (xy 357.26132 -269.035815) (xy 357.313849 -269.027915) (xy 357.340408 -269.027402)
			(xy 357.349298 -269.027402) (xy 357.375526 -269.028503) (xy 357.427252 -269.037459) (xy 357.477102 -269.053909)
			(xy 357.523999 -269.077498) (xy 357.566925 -269.107714) (xy 357.604952 -269.143903) (xy 357.637256 -269.185282)
			(xy 357.663137 -269.230954) (xy 357.682034 -269.279929) (xy 357.693539 -269.331148) (xy 357.697401 -269.3835)
			(xy 357.695434 -269.410159) (xy 357.924852 -269.410159) (xy 357.924852 -269.356861) (xy 357.932795 -269.304157)
			(xy 357.948505 -269.253227) (xy 357.971631 -269.205206) (xy 358.001655 -269.161169) (xy 358.037907 -269.122098)
			(xy 358.079578 -269.088867) (xy 358.125736 -269.062218) (xy 358.17535 -269.042746) (xy 358.227312 -269.030886)
			(xy 358.280462 -269.026903) (xy 358.333612 -269.030886) (xy 358.385574 -269.042746) (xy 358.435188 -269.062218)
			(xy 358.481346 -269.088867) (xy 358.523017 -269.122098) (xy 358.559269 -269.161169) (xy 358.589293 -269.205206)
			(xy 358.612419 -269.253227) (xy 358.628129 -269.304157) (xy 358.636072 -269.356861) (xy 358.63657 -269.38351)
			(xy 358.636072 -269.410159) (xy 361.68456 -269.410159) (xy 361.68456 -269.356861) (xy 361.692503 -269.304157)
			(xy 361.708213 -269.253227) (xy 361.731339 -269.205206) (xy 361.761363 -269.161169) (xy 361.797615 -269.122098)
			(xy 361.839286 -269.088867) (xy 361.885444 -269.062218) (xy 361.935058 -269.042746) (xy 361.98702 -269.030886)
			(xy 362.04017 -269.026903) (xy 362.09332 -269.030886) (xy 362.145282 -269.042746) (xy 362.194896 -269.062218)
			(xy 362.241054 -269.088867) (xy 362.282725 -269.122098) (xy 362.318977 -269.161169) (xy 362.349001 -269.205206)
			(xy 362.372127 -269.253227) (xy 362.387837 -269.304157) (xy 362.39578 -269.356861) (xy 362.396278 -269.38351)
			(xy 362.39578 -269.410159) (xy 362.623852 -269.410159) (xy 362.623852 -269.356861) (xy 362.631795 -269.304157)
			(xy 362.647505 -269.253227) (xy 362.670631 -269.205206) (xy 362.700655 -269.161169) (xy 362.736907 -269.122098)
			(xy 362.778578 -269.088867) (xy 362.824736 -269.062218) (xy 362.87435 -269.042746) (xy 362.926312 -269.030886)
			(xy 362.979462 -269.026903) (xy 363.032612 -269.030886) (xy 363.084574 -269.042746) (xy 363.134188 -269.062218)
			(xy 363.180346 -269.088867) (xy 363.222017 -269.122098) (xy 363.258269 -269.161169) (xy 363.288293 -269.205206)
			(xy 363.311419 -269.253227) (xy 363.327129 -269.304157) (xy 363.335072 -269.356861) (xy 363.33557 -269.38351)
			(xy 363.335072 -269.410159) (xy 363.563652 -269.410159) (xy 363.563652 -269.356861) (xy 363.571595 -269.304157)
			(xy 363.587305 -269.253227) (xy 363.610431 -269.205206) (xy 363.640455 -269.161169) (xy 363.676707 -269.122098)
			(xy 363.718378 -269.088867) (xy 363.764536 -269.062218) (xy 363.81415 -269.042746) (xy 363.866112 -269.030886)
			(xy 363.919262 -269.026903) (xy 363.972412 -269.030886) (xy 364.024374 -269.042746) (xy 364.073988 -269.062218)
			(xy 364.120146 -269.088867) (xy 364.161817 -269.122098) (xy 364.198069 -269.161169) (xy 364.228093 -269.205206)
			(xy 364.251219 -269.253227) (xy 364.266929 -269.304157) (xy 364.274872 -269.356861) (xy 364.27537 -269.38351)
			(xy 364.274872 -269.410159) (xy 364.503452 -269.410159) (xy 364.503452 -269.356861) (xy 364.511395 -269.304157)
			(xy 364.527105 -269.253227) (xy 364.550231 -269.205206) (xy 364.580255 -269.161169) (xy 364.616507 -269.122098)
			(xy 364.658178 -269.088867) (xy 364.704336 -269.062218) (xy 364.75395 -269.042746) (xy 364.805912 -269.030886)
			(xy 364.859062 -269.026903) (xy 364.912212 -269.030886) (xy 364.964174 -269.042746) (xy 365.013788 -269.062218)
			(xy 365.059946 -269.088867) (xy 365.101617 -269.122098) (xy 365.137869 -269.161169) (xy 365.167893 -269.205206)
			(xy 365.191019 -269.253227) (xy 365.206729 -269.304157) (xy 365.214672 -269.356861) (xy 365.21517 -269.38351)
			(xy 365.214672 -269.410159) (xy 365.206729 -269.462863) (xy 365.191019 -269.513793) (xy 365.167893 -269.561814)
			(xy 365.137869 -269.605851) (xy 365.101617 -269.644922) (xy 365.059946 -269.678153) (xy 365.013788 -269.704802)
			(xy 364.964174 -269.724274) (xy 364.912212 -269.736134) (xy 364.859062 -269.740118) (xy 364.805912 -269.736134)
			(xy 364.75395 -269.724274) (xy 364.704336 -269.704802) (xy 364.658178 -269.678153) (xy 364.616507 -269.644922)
			(xy 364.580255 -269.605851) (xy 364.550231 -269.561814) (xy 364.527105 -269.513793) (xy 364.511395 -269.462863)
			(xy 364.503452 -269.410159) (xy 364.274872 -269.410159) (xy 364.266929 -269.462863) (xy 364.251219 -269.513793)
			(xy 364.228093 -269.561814) (xy 364.198069 -269.605851) (xy 364.161817 -269.644922) (xy 364.120146 -269.678153)
			(xy 364.073988 -269.704802) (xy 364.024374 -269.724274) (xy 363.972412 -269.736134) (xy 363.919262 -269.740118)
			(xy 363.866112 -269.736134) (xy 363.81415 -269.724274) (xy 363.764536 -269.704802) (xy 363.718378 -269.678153)
			(xy 363.676707 -269.644922) (xy 363.640455 -269.605851) (xy 363.610431 -269.561814) (xy 363.587305 -269.513793)
			(xy 363.571595 -269.462863) (xy 363.563652 -269.410159) (xy 363.335072 -269.410159) (xy 363.327129 -269.462863)
			(xy 363.311419 -269.513793) (xy 363.288293 -269.561814) (xy 363.258269 -269.605851) (xy 363.222017 -269.644922)
			(xy 363.180346 -269.678153) (xy 363.134188 -269.704802) (xy 363.084574 -269.724274) (xy 363.032612 -269.736134)
			(xy 362.979462 -269.740118) (xy 362.926312 -269.736134) (xy 362.87435 -269.724274) (xy 362.824736 -269.704802)
			(xy 362.778578 -269.678153) (xy 362.736907 -269.644922) (xy 362.700655 -269.605851) (xy 362.670631 -269.561814)
			(xy 362.647505 -269.513793) (xy 362.631795 -269.462863) (xy 362.623852 -269.410159) (xy 362.39578 -269.410159)
			(xy 362.387837 -269.462863) (xy 362.372127 -269.513793) (xy 362.349001 -269.561814) (xy 362.318977 -269.605851)
			(xy 362.282725 -269.644922) (xy 362.241054 -269.678153) (xy 362.194896 -269.704802) (xy 362.145282 -269.724274)
			(xy 362.09332 -269.736134) (xy 362.04017 -269.740118) (xy 361.98702 -269.736134) (xy 361.935058 -269.724274)
			(xy 361.885444 -269.704802) (xy 361.839286 -269.678153) (xy 361.797615 -269.644922) (xy 361.761363 -269.605851)
			(xy 361.731339 -269.561814) (xy 361.708213 -269.513793) (xy 361.692503 -269.462863) (xy 361.68456 -269.410159)
			(xy 358.636072 -269.410159) (xy 358.628129 -269.462863) (xy 358.612419 -269.513793) (xy 358.589293 -269.561814)
			(xy 358.559269 -269.605851) (xy 358.523017 -269.644922) (xy 358.481346 -269.678153) (xy 358.435188 -269.704802)
			(xy 358.385574 -269.724274) (xy 358.333612 -269.736134) (xy 358.280462 -269.740118) (xy 358.227312 -269.736134)
			(xy 358.17535 -269.724274) (xy 358.125736 -269.704802) (xy 358.079578 -269.678153) (xy 358.037907 -269.644922)
			(xy 358.001655 -269.605851) (xy 357.971631 -269.561814) (xy 357.948505 -269.513793) (xy 357.932795 -269.462863)
			(xy 357.924852 -269.410159) (xy 357.695434 -269.410159) (xy 357.693538 -269.435853) (xy 357.682034 -269.487071)
			(xy 357.663136 -269.536047) (xy 357.637256 -269.581718) (xy 357.604952 -269.623097) (xy 357.566925 -269.659286)
			(xy 357.523998 -269.689502) (xy 357.477102 -269.713091) (xy 357.427251 -269.729541) (xy 357.375526 -269.738497)
			(xy 357.349298 -269.739618) (xy 357.340408 -269.739618) (xy 357.313847 -269.739127) (xy 357.261315 -269.731232)
			(xy 357.21054 -269.715618) (xy 357.16265 -269.692631) (xy 357.118708 -269.66278) (xy 357.098854 -269.64513)
			(xy 357.0986 -269.644876) (xy 357.09606 -269.64259) (xy 357.084726 -269.633563) (xy 357.05832 -269.621669)
			(xy 357.029638 -269.617665) (xy 357.000984 -269.621872) (xy 356.974664 -269.633953) (xy 356.952792 -269.652937)
			(xy 356.937128 -269.677296) (xy 356.928931 -269.705073) (xy 356.92842 -269.719552) (xy 356.92842 -269.844012)
			(xy 356.965758 -269.854426) (xy 356.991892 -269.862196) (xy 357.041606 -269.884576) (xy 357.087328 -269.914273)
			(xy 357.127988 -269.950592) (xy 357.162637 -269.992685) (xy 357.190464 -270.039569) (xy 357.210818 -270.090146)
			(xy 357.223225 -270.143235) (xy 357.227393 -270.197595) (xy 357.225351 -270.224229) (xy 357.454952 -270.224229)
			(xy 357.454952 -270.170931) (xy 357.462895 -270.118227) (xy 357.478605 -270.067297) (xy 357.501731 -270.019276)
			(xy 357.531755 -269.975239) (xy 357.568007 -269.936168) (xy 357.609678 -269.902937) (xy 357.655836 -269.876288)
			(xy 357.70545 -269.856816) (xy 357.757412 -269.844956) (xy 357.810562 -269.840973) (xy 357.863712 -269.844956)
			(xy 357.915674 -269.856816) (xy 357.965288 -269.876288) (xy 358.011446 -269.902937) (xy 358.053117 -269.936168)
			(xy 358.089369 -269.975239) (xy 358.119393 -270.019276) (xy 358.142519 -270.067297) (xy 358.158229 -270.118227)
			(xy 358.166172 -270.170931) (xy 358.16667 -270.19758) (xy 358.166172 -270.224229) (xy 361.214152 -270.224229)
			(xy 361.214152 -270.170931) (xy 361.222095 -270.118227) (xy 361.237805 -270.067297) (xy 361.260931 -270.019276)
			(xy 361.290955 -269.975239) (xy 361.327207 -269.936168) (xy 361.368878 -269.902937) (xy 361.415036 -269.876288)
			(xy 361.46465 -269.856816) (xy 361.516612 -269.844956) (xy 361.569762 -269.840973) (xy 361.622912 -269.844956)
			(xy 361.674874 -269.856816) (xy 361.724488 -269.876288) (xy 361.770646 -269.902937) (xy 361.812317 -269.936168)
			(xy 361.848569 -269.975239) (xy 361.878593 -270.019276) (xy 361.901719 -270.067297) (xy 361.917429 -270.118227)
			(xy 361.925372 -270.170931) (xy 361.92587 -270.19758) (xy 361.925372 -270.224229) (xy 362.153952 -270.224229)
			(xy 362.153952 -270.170931) (xy 362.161895 -270.118227) (xy 362.177605 -270.067297) (xy 362.200731 -270.019276)
			(xy 362.230755 -269.975239) (xy 362.267007 -269.936168) (xy 362.308678 -269.902937) (xy 362.354836 -269.876288)
			(xy 362.40445 -269.856816) (xy 362.456412 -269.844956) (xy 362.509562 -269.840973) (xy 362.562712 -269.844956)
			(xy 362.614674 -269.856816) (xy 362.664288 -269.876288) (xy 362.710446 -269.902937) (xy 362.752117 -269.936168)
			(xy 362.788369 -269.975239) (xy 362.818393 -270.019276) (xy 362.841519 -270.067297) (xy 362.857229 -270.118227)
			(xy 362.865172 -270.170931) (xy 362.86567 -270.19758) (xy 362.865172 -270.224229) (xy 363.093752 -270.224229)
			(xy 363.093752 -270.170931) (xy 363.101695 -270.118227) (xy 363.117405 -270.067297) (xy 363.140531 -270.019276)
			(xy 363.170555 -269.975239) (xy 363.206807 -269.936168) (xy 363.248478 -269.902937) (xy 363.294636 -269.876288)
			(xy 363.34425 -269.856816) (xy 363.396212 -269.844956) (xy 363.449362 -269.840973) (xy 363.502512 -269.844956)
			(xy 363.554474 -269.856816) (xy 363.604088 -269.876288) (xy 363.650246 -269.902937) (xy 363.691917 -269.936168)
			(xy 363.728169 -269.975239) (xy 363.758193 -270.019276) (xy 363.781319 -270.067297) (xy 363.797029 -270.118227)
			(xy 363.804972 -270.170931) (xy 363.80547 -270.19758) (xy 363.804972 -270.224229) (xy 364.033806 -270.224229)
			(xy 364.033806 -270.170931) (xy 364.041749 -270.118227) (xy 364.057459 -270.067297) (xy 364.080585 -270.019276)
			(xy 364.110609 -269.975239) (xy 364.146861 -269.936168) (xy 364.188532 -269.902937) (xy 364.23469 -269.876288)
			(xy 364.284304 -269.856816) (xy 364.336266 -269.844956) (xy 364.389416 -269.840973) (xy 364.442566 -269.844956)
			(xy 364.494528 -269.856816) (xy 364.544142 -269.876288) (xy 364.5903 -269.902937) (xy 364.631971 -269.936168)
			(xy 364.668223 -269.975239) (xy 364.698247 -270.019276) (xy 364.721373 -270.067297) (xy 364.737083 -270.118227)
			(xy 364.745026 -270.170931) (xy 364.745524 -270.19758) (xy 364.745026 -270.224229) (xy 364.973352 -270.224229)
			(xy 364.973352 -270.170931) (xy 364.981295 -270.118227) (xy 364.997005 -270.067297) (xy 365.020131 -270.019276)
			(xy 365.050155 -269.975239) (xy 365.086407 -269.936168) (xy 365.128078 -269.902937) (xy 365.174236 -269.876288)
			(xy 365.22385 -269.856816) (xy 365.275812 -269.844956) (xy 365.328962 -269.840973) (xy 365.382112 -269.844956)
			(xy 365.434074 -269.856816) (xy 365.483688 -269.876288) (xy 365.529846 -269.902937) (xy 365.571517 -269.936168)
			(xy 365.607769 -269.975239) (xy 365.637793 -270.019276) (xy 365.660919 -270.067297) (xy 365.676629 -270.118227)
			(xy 365.684572 -270.170931) (xy 365.68507 -270.19758) (xy 365.684572 -270.224229) (xy 365.676629 -270.276933)
			(xy 365.660919 -270.327863) (xy 365.637793 -270.375884) (xy 365.607769 -270.419921) (xy 365.571517 -270.458992)
			(xy 365.529846 -270.492223) (xy 365.483688 -270.518872) (xy 365.434074 -270.538344) (xy 365.382112 -270.550204)
			(xy 365.328962 -270.554188) (xy 365.275812 -270.550204) (xy 365.22385 -270.538344) (xy 365.174236 -270.518872)
			(xy 365.128078 -270.492223) (xy 365.086407 -270.458992) (xy 365.050155 -270.419921) (xy 365.020131 -270.375884)
			(xy 364.997005 -270.327863) (xy 364.981295 -270.276933) (xy 364.973352 -270.224229) (xy 364.745026 -270.224229)
			(xy 364.737083 -270.276933) (xy 364.721373 -270.327863) (xy 364.698247 -270.375884) (xy 364.668223 -270.419921)
			(xy 364.631971 -270.458992) (xy 364.5903 -270.492223) (xy 364.544142 -270.518872) (xy 364.494528 -270.538344)
			(xy 364.442566 -270.550204) (xy 364.389416 -270.554188) (xy 364.336266 -270.550204) (xy 364.284304 -270.538344)
			(xy 364.23469 -270.518872) (xy 364.188532 -270.492223) (xy 364.146861 -270.458992) (xy 364.110609 -270.419921)
			(xy 364.080585 -270.375884) (xy 364.057459 -270.327863) (xy 364.041749 -270.276933) (xy 364.033806 -270.224229)
			(xy 363.804972 -270.224229) (xy 363.797029 -270.276933) (xy 363.781319 -270.327863) (xy 363.758193 -270.375884)
			(xy 363.728169 -270.419921) (xy 363.691917 -270.458992) (xy 363.650246 -270.492223) (xy 363.604088 -270.518872)
			(xy 363.554474 -270.538344) (xy 363.502512 -270.550204) (xy 363.449362 -270.554188) (xy 363.396212 -270.550204)
			(xy 363.34425 -270.538344) (xy 363.294636 -270.518872) (xy 363.248478 -270.492223) (xy 363.206807 -270.458992)
			(xy 363.170555 -270.419921) (xy 363.140531 -270.375884) (xy 363.117405 -270.327863) (xy 363.101695 -270.276933)
			(xy 363.093752 -270.224229) (xy 362.865172 -270.224229) (xy 362.857229 -270.276933) (xy 362.841519 -270.327863)
			(xy 362.818393 -270.375884) (xy 362.788369 -270.419921) (xy 362.752117 -270.458992) (xy 362.710446 -270.492223)
			(xy 362.664288 -270.518872) (xy 362.614674 -270.538344) (xy 362.562712 -270.550204) (xy 362.509562 -270.554188)
			(xy 362.456412 -270.550204) (xy 362.40445 -270.538344) (xy 362.354836 -270.518872) (xy 362.308678 -270.492223)
			(xy 362.267007 -270.458992) (xy 362.230755 -270.419921) (xy 362.200731 -270.375884) (xy 362.177605 -270.327863)
			(xy 362.161895 -270.276933) (xy 362.153952 -270.224229) (xy 361.925372 -270.224229) (xy 361.917429 -270.276933)
			(xy 361.901719 -270.327863) (xy 361.878593 -270.375884) (xy 361.848569 -270.419921) (xy 361.812317 -270.458992)
			(xy 361.770646 -270.492223) (xy 361.724488 -270.518872) (xy 361.674874 -270.538344) (xy 361.622912 -270.550204)
			(xy 361.569762 -270.554188) (xy 361.516612 -270.550204) (xy 361.46465 -270.538344) (xy 361.415036 -270.518872)
			(xy 361.368878 -270.492223) (xy 361.327207 -270.458992) (xy 361.290955 -270.419921) (xy 361.260931 -270.375884)
			(xy 361.237805 -270.327863) (xy 361.222095 -270.276933) (xy 361.214152 -270.224229) (xy 358.166172 -270.224229)
			(xy 358.158229 -270.276933) (xy 358.142519 -270.327863) (xy 358.119393 -270.375884) (xy 358.089369 -270.419921)
			(xy 358.053117 -270.458992) (xy 358.011446 -270.492223) (xy 357.965288 -270.518872) (xy 357.915674 -270.538344)
			(xy 357.863712 -270.550204) (xy 357.810562 -270.554188) (xy 357.757412 -270.550204) (xy 357.70545 -270.538344)
			(xy 357.655836 -270.518872) (xy 357.609678 -270.492223) (xy 357.568007 -270.458992) (xy 357.531755 -270.419921)
			(xy 357.501731 -270.375884) (xy 357.478605 -270.327863) (xy 357.462895 -270.276933) (xy 357.454952 -270.224229)
			(xy 357.225351 -270.224229) (xy 357.223226 -270.251955) (xy 357.210822 -270.305044) (xy 357.190468 -270.355622)
			(xy 357.162643 -270.402506) (xy 357.127996 -270.4446) (xy 357.087337 -270.480921) (xy 357.041616 -270.510619)
			(xy 356.991902 -270.533) (xy 356.965758 -270.540734) (xy 356.92842 -270.551148) (xy 356.92842 -270.675354)
			(xy 356.928965 -270.689828) (xy 356.93716 -270.717594) (xy 356.952819 -270.741944) (xy 356.974683 -270.76092)
			(xy 357.000994 -270.772996) (xy 357.029637 -270.777202) (xy 357.058309 -270.7732) (xy 357.084706 -270.761311)
			(xy 357.09606 -270.752316) (xy 357.0986 -270.75003) (xy 357.098854 -270.749776) (xy 357.118704 -270.732123)
			(xy 357.162655 -270.702291) (xy 357.210547 -270.679315) (xy 357.261321 -270.663704) (xy 357.313849 -270.655804)
			(xy 357.340408 -270.655288) (xy 357.349298 -270.655288) (xy 357.375528 -270.656389) (xy 357.427255 -270.665345)
			(xy 357.477107 -270.681796) (xy 357.524006 -270.705386) (xy 357.566934 -270.735603) (xy 357.604962 -270.771794)
			(xy 357.637267 -270.813174) (xy 357.663149 -270.858847) (xy 357.682047 -270.907825) (xy 357.693552 -270.959045)
			(xy 357.697415 -271.0114) (xy 357.695449 -271.038045) (xy 357.924852 -271.038045) (xy 357.924852 -270.984747)
			(xy 357.932795 -270.932043) (xy 357.948505 -270.881113) (xy 357.971631 -270.833092) (xy 358.001655 -270.789055)
			(xy 358.037907 -270.749984) (xy 358.079578 -270.716753) (xy 358.125736 -270.690104) (xy 358.17535 -270.670632)
			(xy 358.227312 -270.658772) (xy 358.280462 -270.654789) (xy 358.333612 -270.658772) (xy 358.385574 -270.670632)
			(xy 358.435188 -270.690104) (xy 358.481346 -270.716753) (xy 358.523017 -270.749984) (xy 358.559269 -270.789055)
			(xy 358.589293 -270.833092) (xy 358.612419 -270.881113) (xy 358.628129 -270.932043) (xy 358.636072 -270.984747)
			(xy 358.63657 -271.011396) (xy 358.636072 -271.038045) (xy 361.684052 -271.038045) (xy 361.684052 -270.984747)
			(xy 361.691995 -270.932043) (xy 361.707705 -270.881113) (xy 361.730831 -270.833092) (xy 361.760855 -270.789055)
			(xy 361.797107 -270.749984) (xy 361.838778 -270.716753) (xy 361.884936 -270.690104) (xy 361.93455 -270.670632)
			(xy 361.986512 -270.658772) (xy 362.039662 -270.654789) (xy 362.092812 -270.658772) (xy 362.144774 -270.670632)
			(xy 362.194388 -270.690104) (xy 362.240546 -270.716753) (xy 362.282217 -270.749984) (xy 362.318469 -270.789055)
			(xy 362.348493 -270.833092) (xy 362.371619 -270.881113) (xy 362.387329 -270.932043) (xy 362.395272 -270.984747)
			(xy 362.39577 -271.011396) (xy 362.395272 -271.038045) (xy 362.623852 -271.038045) (xy 362.623852 -270.984747)
			(xy 362.631795 -270.932043) (xy 362.647505 -270.881113) (xy 362.670631 -270.833092) (xy 362.700655 -270.789055)
			(xy 362.736907 -270.749984) (xy 362.778578 -270.716753) (xy 362.824736 -270.690104) (xy 362.87435 -270.670632)
			(xy 362.926312 -270.658772) (xy 362.979462 -270.654789) (xy 363.032612 -270.658772) (xy 363.084574 -270.670632)
			(xy 363.134188 -270.690104) (xy 363.180346 -270.716753) (xy 363.222017 -270.749984) (xy 363.258269 -270.789055)
			(xy 363.288293 -270.833092) (xy 363.311419 -270.881113) (xy 363.327129 -270.932043) (xy 363.335072 -270.984747)
			(xy 363.33557 -271.011396) (xy 363.335072 -271.038045) (xy 363.563652 -271.038045) (xy 363.563652 -270.984747)
			(xy 363.571595 -270.932043) (xy 363.587305 -270.881113) (xy 363.610431 -270.833092) (xy 363.640455 -270.789055)
			(xy 363.676707 -270.749984) (xy 363.718378 -270.716753) (xy 363.764536 -270.690104) (xy 363.81415 -270.670632)
			(xy 363.866112 -270.658772) (xy 363.919262 -270.654789) (xy 363.972412 -270.658772) (xy 364.024374 -270.670632)
			(xy 364.073988 -270.690104) (xy 364.120146 -270.716753) (xy 364.161817 -270.749984) (xy 364.198069 -270.789055)
			(xy 364.228093 -270.833092) (xy 364.251219 -270.881113) (xy 364.266929 -270.932043) (xy 364.274872 -270.984747)
			(xy 364.27537 -271.011396) (xy 364.274872 -271.038045) (xy 364.503452 -271.038045) (xy 364.503452 -270.984747)
			(xy 364.511395 -270.932043) (xy 364.527105 -270.881113) (xy 364.550231 -270.833092) (xy 364.580255 -270.789055)
			(xy 364.616507 -270.749984) (xy 364.658178 -270.716753) (xy 364.704336 -270.690104) (xy 364.75395 -270.670632)
			(xy 364.805912 -270.658772) (xy 364.859062 -270.654789) (xy 364.912212 -270.658772) (xy 364.964174 -270.670632)
			(xy 365.013788 -270.690104) (xy 365.059946 -270.716753) (xy 365.101617 -270.749984) (xy 365.137869 -270.789055)
			(xy 365.167893 -270.833092) (xy 365.191019 -270.881113) (xy 365.206729 -270.932043) (xy 365.214672 -270.984747)
			(xy 365.21517 -271.011396) (xy 365.214672 -271.038045) (xy 365.206729 -271.090749) (xy 365.191019 -271.141679)
			(xy 365.167893 -271.1897) (xy 365.137869 -271.233737) (xy 365.101617 -271.272808) (xy 365.059946 -271.306039)
			(xy 365.013788 -271.332688) (xy 364.964174 -271.35216) (xy 364.912212 -271.36402) (xy 364.859062 -271.368004)
			(xy 364.805912 -271.36402) (xy 364.75395 -271.35216) (xy 364.704336 -271.332688) (xy 364.658178 -271.306039)
			(xy 364.616507 -271.272808) (xy 364.580255 -271.233737) (xy 364.550231 -271.1897) (xy 364.527105 -271.141679)
			(xy 364.511395 -271.090749) (xy 364.503452 -271.038045) (xy 364.274872 -271.038045) (xy 364.266929 -271.090749)
			(xy 364.251219 -271.141679) (xy 364.228093 -271.1897) (xy 364.198069 -271.233737) (xy 364.161817 -271.272808)
			(xy 364.120146 -271.306039) (xy 364.073988 -271.332688) (xy 364.024374 -271.35216) (xy 363.972412 -271.36402)
			(xy 363.919262 -271.368004) (xy 363.866112 -271.36402) (xy 363.81415 -271.35216) (xy 363.764536 -271.332688)
			(xy 363.718378 -271.306039) (xy 363.676707 -271.272808) (xy 363.640455 -271.233737) (xy 363.610431 -271.1897)
			(xy 363.587305 -271.141679) (xy 363.571595 -271.090749) (xy 363.563652 -271.038045) (xy 363.335072 -271.038045)
			(xy 363.327129 -271.090749) (xy 363.311419 -271.141679) (xy 363.288293 -271.1897) (xy 363.258269 -271.233737)
			(xy 363.222017 -271.272808) (xy 363.180346 -271.306039) (xy 363.134188 -271.332688) (xy 363.084574 -271.35216)
			(xy 363.032612 -271.36402) (xy 362.979462 -271.368004) (xy 362.926312 -271.36402) (xy 362.87435 -271.35216)
			(xy 362.824736 -271.332688) (xy 362.778578 -271.306039) (xy 362.736907 -271.272808) (xy 362.700655 -271.233737)
			(xy 362.670631 -271.1897) (xy 362.647505 -271.141679) (xy 362.631795 -271.090749) (xy 362.623852 -271.038045)
			(xy 362.395272 -271.038045) (xy 362.387329 -271.090749) (xy 362.371619 -271.141679) (xy 362.348493 -271.1897)
			(xy 362.318469 -271.233737) (xy 362.282217 -271.272808) (xy 362.240546 -271.306039) (xy 362.194388 -271.332688)
			(xy 362.144774 -271.35216) (xy 362.092812 -271.36402) (xy 362.039662 -271.368004) (xy 361.986512 -271.36402)
			(xy 361.93455 -271.35216) (xy 361.884936 -271.332688) (xy 361.838778 -271.306039) (xy 361.797107 -271.272808)
			(xy 361.760855 -271.233737) (xy 361.730831 -271.1897) (xy 361.707705 -271.141679) (xy 361.691995 -271.090749)
			(xy 361.684052 -271.038045) (xy 358.636072 -271.038045) (xy 358.628129 -271.090749) (xy 358.612419 -271.141679)
			(xy 358.589293 -271.1897) (xy 358.559269 -271.233737) (xy 358.523017 -271.272808) (xy 358.481346 -271.306039)
			(xy 358.435188 -271.332688) (xy 358.385574 -271.35216) (xy 358.333612 -271.36402) (xy 358.280462 -271.368004)
			(xy 358.227312 -271.36402) (xy 358.17535 -271.35216) (xy 358.125736 -271.332688) (xy 358.079578 -271.306039)
			(xy 358.037907 -271.272808) (xy 358.001655 -271.233737) (xy 357.971631 -271.1897) (xy 357.948505 -271.141679)
			(xy 357.932795 -271.090749) (xy 357.924852 -271.038045) (xy 357.695449 -271.038045) (xy 357.693552 -271.063754)
			(xy 357.682047 -271.114975) (xy 357.663149 -271.163953) (xy 357.637267 -271.209626) (xy 357.604963 -271.251006)
			(xy 357.566934 -271.287197) (xy 357.524006 -271.317414) (xy 357.477108 -271.341004) (xy 357.427255 -271.357455)
			(xy 357.375528 -271.366411) (xy 357.349298 -271.367504) (xy 357.340408 -271.367504) (xy 357.313847 -271.367013)
			(xy 357.261316 -271.359118) (xy 357.210541 -271.343503) (xy 357.162651 -271.320515) (xy 357.11871 -271.290664)
			(xy 357.098854 -271.273016) (xy 357.0986 -271.272762) (xy 357.09606 -271.270476) (xy 357.084725 -271.26145)
			(xy 357.058319 -271.249557) (xy 357.029636 -271.245554) (xy 357.000982 -271.249762) (xy 356.974661 -271.261842)
			(xy 356.952788 -271.280825) (xy 356.937123 -271.305183) (xy 356.928923 -271.332959) (xy 356.92842 -271.347438)
			(xy 356.92842 -271.471644) (xy 356.966012 -271.481804) (xy 356.992164 -271.489579) (xy 357.041912 -271.511973)
			(xy 357.087665 -271.541689) (xy 357.128353 -271.578033) (xy 357.163025 -271.620155) (xy 357.19087 -271.66707)
			(xy 357.211238 -271.717681) (xy 357.223652 -271.770807) (xy 357.227822 -271.825203) (xy 357.225778 -271.851861)
			(xy 357.454698 -271.851861) (xy 357.454698 -271.798563) (xy 357.462641 -271.745859) (xy 357.478351 -271.694929)
			(xy 357.501477 -271.646908) (xy 357.531501 -271.602871) (xy 357.567753 -271.5638) (xy 357.609424 -271.530569)
			(xy 357.655582 -271.50392) (xy 357.705196 -271.484448) (xy 357.757158 -271.472588) (xy 357.810308 -271.468605)
			(xy 357.863458 -271.472588) (xy 357.91542 -271.484448) (xy 357.965034 -271.50392) (xy 358.011192 -271.530569)
			(xy 358.052863 -271.5638) (xy 358.089115 -271.602871) (xy 358.119139 -271.646908) (xy 358.142265 -271.694929)
			(xy 358.157975 -271.745859) (xy 358.165918 -271.798563) (xy 358.166416 -271.825212) (xy 358.165918 -271.851861)
			(xy 361.214152 -271.851861) (xy 361.214152 -271.798563) (xy 361.222095 -271.745859) (xy 361.237805 -271.694929)
			(xy 361.260931 -271.646908) (xy 361.290955 -271.602871) (xy 361.327207 -271.5638) (xy 361.368878 -271.530569)
			(xy 361.415036 -271.50392) (xy 361.46465 -271.484448) (xy 361.516612 -271.472588) (xy 361.569762 -271.468605)
			(xy 361.622912 -271.472588) (xy 361.674874 -271.484448) (xy 361.724488 -271.50392) (xy 361.770646 -271.530569)
			(xy 361.812317 -271.5638) (xy 361.848569 -271.602871) (xy 361.878593 -271.646908) (xy 361.901719 -271.694929)
			(xy 361.917429 -271.745859) (xy 361.925372 -271.798563) (xy 361.92587 -271.825212) (xy 361.925372 -271.851861)
			(xy 362.154206 -271.851861) (xy 362.154206 -271.798563) (xy 362.162149 -271.745859) (xy 362.177859 -271.694929)
			(xy 362.200985 -271.646908) (xy 362.231009 -271.602871) (xy 362.267261 -271.5638) (xy 362.308932 -271.530569)
			(xy 362.35509 -271.50392) (xy 362.404704 -271.484448) (xy 362.456666 -271.472588) (xy 362.509816 -271.468605)
			(xy 362.562966 -271.472588) (xy 362.614928 -271.484448) (xy 362.664542 -271.50392) (xy 362.7107 -271.530569)
			(xy 362.752371 -271.5638) (xy 362.788623 -271.602871) (xy 362.818647 -271.646908) (xy 362.841773 -271.694929)
			(xy 362.857483 -271.745859) (xy 362.865426 -271.798563) (xy 362.865924 -271.825212) (xy 362.865426 -271.851861)
			(xy 363.094006 -271.851861) (xy 363.094006 -271.798563) (xy 363.101949 -271.745859) (xy 363.117659 -271.694929)
			(xy 363.140785 -271.646908) (xy 363.170809 -271.602871) (xy 363.207061 -271.5638) (xy 363.248732 -271.530569)
			(xy 363.29489 -271.50392) (xy 363.344504 -271.484448) (xy 363.396466 -271.472588) (xy 363.449616 -271.468605)
			(xy 363.502766 -271.472588) (xy 363.554728 -271.484448) (xy 363.604342 -271.50392) (xy 363.6505 -271.530569)
			(xy 363.692171 -271.5638) (xy 363.728423 -271.602871) (xy 363.758447 -271.646908) (xy 363.781573 -271.694929)
			(xy 363.797283 -271.745859) (xy 363.805226 -271.798563) (xy 363.805724 -271.825212) (xy 363.805226 -271.851861)
			(xy 364.033298 -271.851861) (xy 364.033298 -271.798563) (xy 364.041241 -271.745859) (xy 364.056951 -271.694929)
			(xy 364.080077 -271.646908) (xy 364.110101 -271.602871) (xy 364.146353 -271.5638) (xy 364.188024 -271.530569)
			(xy 364.234182 -271.50392) (xy 364.283796 -271.484448) (xy 364.335758 -271.472588) (xy 364.388908 -271.468605)
			(xy 364.442058 -271.472588) (xy 364.49402 -271.484448) (xy 364.543634 -271.50392) (xy 364.589792 -271.530569)
			(xy 364.631463 -271.5638) (xy 364.667715 -271.602871) (xy 364.697739 -271.646908) (xy 364.720865 -271.694929)
			(xy 364.736575 -271.745859) (xy 364.744518 -271.798563) (xy 364.745016 -271.825212) (xy 364.744518 -271.851861)
			(xy 364.973606 -271.851861) (xy 364.973606 -271.798563) (xy 364.981549 -271.745859) (xy 364.997259 -271.694929)
			(xy 365.020385 -271.646908) (xy 365.050409 -271.602871) (xy 365.086661 -271.5638) (xy 365.128332 -271.530569)
			(xy 365.17449 -271.50392) (xy 365.224104 -271.484448) (xy 365.276066 -271.472588) (xy 365.329216 -271.468605)
			(xy 365.382366 -271.472588) (xy 365.434328 -271.484448) (xy 365.483942 -271.50392) (xy 365.5301 -271.530569)
			(xy 365.571771 -271.5638) (xy 365.608023 -271.602871) (xy 365.638047 -271.646908) (xy 365.661173 -271.694929)
			(xy 365.676883 -271.745859) (xy 365.684826 -271.798563) (xy 365.685324 -271.825212) (xy 365.684826 -271.851861)
			(xy 365.676883 -271.904565) (xy 365.661173 -271.955495) (xy 365.638047 -272.003516) (xy 365.608023 -272.047553)
			(xy 365.571771 -272.086624) (xy 365.5301 -272.119855) (xy 365.483942 -272.146504) (xy 365.434328 -272.165976)
			(xy 365.382366 -272.177836) (xy 365.329216 -272.18182) (xy 365.276066 -272.177836) (xy 365.224104 -272.165976)
			(xy 365.17449 -272.146504) (xy 365.128332 -272.119855) (xy 365.086661 -272.086624) (xy 365.050409 -272.047553)
			(xy 365.020385 -272.003516) (xy 364.997259 -271.955495) (xy 364.981549 -271.904565) (xy 364.973606 -271.851861)
			(xy 364.744518 -271.851861) (xy 364.736575 -271.904565) (xy 364.720865 -271.955495) (xy 364.697739 -272.003516)
			(xy 364.667715 -272.047553) (xy 364.631463 -272.086624) (xy 364.589792 -272.119855) (xy 364.543634 -272.146504)
			(xy 364.49402 -272.165976) (xy 364.442058 -272.177836) (xy 364.388908 -272.18182) (xy 364.335758 -272.177836)
			(xy 364.283796 -272.165976) (xy 364.234182 -272.146504) (xy 364.188024 -272.119855) (xy 364.146353 -272.086624)
			(xy 364.110101 -272.047553) (xy 364.080077 -272.003516) (xy 364.056951 -271.955495) (xy 364.041241 -271.904565)
			(xy 364.033298 -271.851861) (xy 363.805226 -271.851861) (xy 363.797283 -271.904565) (xy 363.781573 -271.955495)
			(xy 363.758447 -272.003516) (xy 363.728423 -272.047553) (xy 363.692171 -272.086624) (xy 363.6505 -272.119855)
			(xy 363.604342 -272.146504) (xy 363.554728 -272.165976) (xy 363.502766 -272.177836) (xy 363.449616 -272.18182)
			(xy 363.396466 -272.177836) (xy 363.344504 -272.165976) (xy 363.29489 -272.146504) (xy 363.248732 -272.119855)
			(xy 363.207061 -272.086624) (xy 363.170809 -272.047553) (xy 363.140785 -272.003516) (xy 363.117659 -271.955495)
			(xy 363.101949 -271.904565) (xy 363.094006 -271.851861) (xy 362.865426 -271.851861) (xy 362.857483 -271.904565)
			(xy 362.841773 -271.955495) (xy 362.818647 -272.003516) (xy 362.788623 -272.047553) (xy 362.752371 -272.086624)
			(xy 362.7107 -272.119855) (xy 362.664542 -272.146504) (xy 362.614928 -272.165976) (xy 362.562966 -272.177836)
			(xy 362.509816 -272.18182) (xy 362.456666 -272.177836) (xy 362.404704 -272.165976) (xy 362.35509 -272.146504)
			(xy 362.308932 -272.119855) (xy 362.267261 -272.086624) (xy 362.231009 -272.047553) (xy 362.200985 -272.003516)
			(xy 362.177859 -271.955495) (xy 362.162149 -271.904565) (xy 362.154206 -271.851861) (xy 361.925372 -271.851861)
			(xy 361.917429 -271.904565) (xy 361.901719 -271.955495) (xy 361.878593 -272.003516) (xy 361.848569 -272.047553)
			(xy 361.812317 -272.086624) (xy 361.770646 -272.119855) (xy 361.724488 -272.146504) (xy 361.674874 -272.165976)
			(xy 361.622912 -272.177836) (xy 361.569762 -272.18182) (xy 361.516612 -272.177836) (xy 361.46465 -272.165976)
			(xy 361.415036 -272.146504) (xy 361.368878 -272.119855) (xy 361.327207 -272.086624) (xy 361.290955 -272.047553)
			(xy 361.260931 -272.003516) (xy 361.237805 -271.955495) (xy 361.222095 -271.904565) (xy 361.214152 -271.851861)
			(xy 358.165918 -271.851861) (xy 358.157975 -271.904565) (xy 358.142265 -271.955495) (xy 358.119139 -272.003516)
			(xy 358.089115 -272.047553) (xy 358.052863 -272.086624) (xy 358.011192 -272.119855) (xy 357.965034 -272.146504)
			(xy 357.91542 -272.165976) (xy 357.863458 -272.177836) (xy 357.810308 -272.18182) (xy 357.757158 -272.177836)
			(xy 357.705196 -272.165976) (xy 357.655582 -272.146504) (xy 357.609424 -272.119855) (xy 357.567753 -272.086624)
			(xy 357.531501 -272.047553) (xy 357.501477 -272.003516) (xy 357.478351 -271.955495) (xy 357.462641 -271.904565)
			(xy 357.454698 -271.851861) (xy 357.225778 -271.851861) (xy 357.223651 -271.8796) (xy 357.211236 -271.932725)
			(xy 357.190867 -271.983336) (xy 357.163021 -272.030251) (xy 357.128349 -272.072372) (xy 357.08766 -272.108715)
			(xy 357.041906 -272.13843) (xy 356.992158 -272.160823) (xy 356.966012 -272.16862) (xy 356.92842 -272.17878)
			(xy 356.92842 -272.30324) (xy 356.928963 -272.317715) (xy 356.937156 -272.345485) (xy 356.952815 -272.369839)
			(xy 356.97468 -272.388817) (xy 357.000993 -272.400896) (xy 357.029639 -272.405102) (xy 357.058314 -272.401098)
			(xy 357.084712 -272.389207) (xy 357.09606 -272.380202) (xy 357.0986 -272.377916) (xy 357.098854 -272.377662)
			(xy 357.118704 -272.36001) (xy 357.162655 -272.330179) (xy 357.210548 -272.307204) (xy 357.261321 -272.291594)
			(xy 357.313849 -272.283694) (xy 357.340408 -272.283174) (xy 357.349298 -272.283174) (xy 357.375529 -272.284275)
			(xy 357.427258 -272.293231) (xy 357.477113 -272.309683) (xy 357.524013 -272.333273) (xy 357.566943 -272.363492)
			(xy 357.604973 -272.399684) (xy 357.637279 -272.441066) (xy 357.663162 -272.486741) (xy 357.682061 -272.53572)
			(xy 357.693566 -272.586943) (xy 357.697429 -272.6393) (xy 357.695464 -272.665931) (xy 357.924852 -272.665931)
			(xy 357.924852 -272.612633) (xy 357.932795 -272.559929) (xy 357.948505 -272.508999) (xy 357.971631 -272.460978)
			(xy 358.001655 -272.416941) (xy 358.037907 -272.37787) (xy 358.079578 -272.344639) (xy 358.125736 -272.31799)
			(xy 358.17535 -272.298518) (xy 358.227312 -272.286658) (xy 358.280462 -272.282675) (xy 358.333612 -272.286658)
			(xy 358.385574 -272.298518) (xy 358.435188 -272.31799) (xy 358.481346 -272.344639) (xy 358.523017 -272.37787)
			(xy 358.559269 -272.416941) (xy 358.589293 -272.460978) (xy 358.612419 -272.508999) (xy 358.628129 -272.559929)
			(xy 358.636072 -272.612633) (xy 358.63657 -272.639282) (xy 358.636072 -272.665931) (xy 361.684052 -272.665931)
			(xy 361.684052 -272.612633) (xy 361.691995 -272.559929) (xy 361.707705 -272.508999) (xy 361.730831 -272.460978)
			(xy 361.760855 -272.416941) (xy 361.797107 -272.37787) (xy 361.838778 -272.344639) (xy 361.884936 -272.31799)
			(xy 361.93455 -272.298518) (xy 361.986512 -272.286658) (xy 362.039662 -272.282675) (xy 362.092812 -272.286658)
			(xy 362.144774 -272.298518) (xy 362.194388 -272.31799) (xy 362.240546 -272.344639) (xy 362.282217 -272.37787)
			(xy 362.318469 -272.416941) (xy 362.348493 -272.460978) (xy 362.371619 -272.508999) (xy 362.387329 -272.559929)
			(xy 362.395272 -272.612633) (xy 362.39577 -272.639282) (xy 362.395272 -272.665931) (xy 362.623852 -272.665931)
			(xy 362.623852 -272.612633) (xy 362.631795 -272.559929) (xy 362.647505 -272.508999) (xy 362.670631 -272.460978)
			(xy 362.700655 -272.416941) (xy 362.736907 -272.37787) (xy 362.778578 -272.344639) (xy 362.824736 -272.31799)
			(xy 362.87435 -272.298518) (xy 362.926312 -272.286658) (xy 362.979462 -272.282675) (xy 363.032612 -272.286658)
			(xy 363.084574 -272.298518) (xy 363.134188 -272.31799) (xy 363.180346 -272.344639) (xy 363.222017 -272.37787)
			(xy 363.258269 -272.416941) (xy 363.288293 -272.460978) (xy 363.311419 -272.508999) (xy 363.327129 -272.559929)
			(xy 363.335072 -272.612633) (xy 363.33557 -272.639282) (xy 363.335072 -272.665931) (xy 363.563652 -272.665931)
			(xy 363.563652 -272.612633) (xy 363.571595 -272.559929) (xy 363.587305 -272.508999) (xy 363.610431 -272.460978)
			(xy 363.640455 -272.416941) (xy 363.676707 -272.37787) (xy 363.718378 -272.344639) (xy 363.764536 -272.31799)
			(xy 363.81415 -272.298518) (xy 363.866112 -272.286658) (xy 363.919262 -272.282675) (xy 363.972412 -272.286658)
			(xy 364.024374 -272.298518) (xy 364.073988 -272.31799) (xy 364.120146 -272.344639) (xy 364.161817 -272.37787)
			(xy 364.198069 -272.416941) (xy 364.228093 -272.460978) (xy 364.251219 -272.508999) (xy 364.266929 -272.559929)
			(xy 364.274872 -272.612633) (xy 364.27537 -272.639282) (xy 364.274872 -272.665931) (xy 364.503452 -272.665931)
			(xy 364.503452 -272.612633) (xy 364.511395 -272.559929) (xy 364.527105 -272.508999) (xy 364.550231 -272.460978)
			(xy 364.580255 -272.416941) (xy 364.616507 -272.37787) (xy 364.658178 -272.344639) (xy 364.704336 -272.31799)
			(xy 364.75395 -272.298518) (xy 364.805912 -272.286658) (xy 364.859062 -272.282675) (xy 364.912212 -272.286658)
			(xy 364.964174 -272.298518) (xy 365.013788 -272.31799) (xy 365.059946 -272.344639) (xy 365.101617 -272.37787)
			(xy 365.137869 -272.416941) (xy 365.167893 -272.460978) (xy 365.191019 -272.508999) (xy 365.206729 -272.559929)
			(xy 365.214672 -272.612633) (xy 365.21517 -272.639282) (xy 365.214672 -272.665931) (xy 365.206729 -272.718635)
			(xy 365.191019 -272.769565) (xy 365.167893 -272.817586) (xy 365.137869 -272.861623) (xy 365.101617 -272.900694)
			(xy 365.059946 -272.933925) (xy 365.013788 -272.960574) (xy 364.964174 -272.980046) (xy 364.912212 -272.991906)
			(xy 364.859062 -272.99589) (xy 364.805912 -272.991906) (xy 364.75395 -272.980046) (xy 364.704336 -272.960574)
			(xy 364.658178 -272.933925) (xy 364.616507 -272.900694) (xy 364.580255 -272.861623) (xy 364.550231 -272.817586)
			(xy 364.527105 -272.769565) (xy 364.511395 -272.718635) (xy 364.503452 -272.665931) (xy 364.274872 -272.665931)
			(xy 364.266929 -272.718635) (xy 364.251219 -272.769565) (xy 364.228093 -272.817586) (xy 364.198069 -272.861623)
			(xy 364.161817 -272.900694) (xy 364.120146 -272.933925) (xy 364.073988 -272.960574) (xy 364.024374 -272.980046)
			(xy 363.972412 -272.991906) (xy 363.919262 -272.99589) (xy 363.866112 -272.991906) (xy 363.81415 -272.980046)
			(xy 363.764536 -272.960574) (xy 363.718378 -272.933925) (xy 363.676707 -272.900694) (xy 363.640455 -272.861623)
			(xy 363.610431 -272.817586) (xy 363.587305 -272.769565) (xy 363.571595 -272.718635) (xy 363.563652 -272.665931)
			(xy 363.335072 -272.665931) (xy 363.327129 -272.718635) (xy 363.311419 -272.769565) (xy 363.288293 -272.817586)
			(xy 363.258269 -272.861623) (xy 363.222017 -272.900694) (xy 363.180346 -272.933925) (xy 363.134188 -272.960574)
			(xy 363.084574 -272.980046) (xy 363.032612 -272.991906) (xy 362.979462 -272.99589) (xy 362.926312 -272.991906)
			(xy 362.87435 -272.980046) (xy 362.824736 -272.960574) (xy 362.778578 -272.933925) (xy 362.736907 -272.900694)
			(xy 362.700655 -272.861623) (xy 362.670631 -272.817586) (xy 362.647505 -272.769565) (xy 362.631795 -272.718635)
			(xy 362.623852 -272.665931) (xy 362.395272 -272.665931) (xy 362.387329 -272.718635) (xy 362.371619 -272.769565)
			(xy 362.348493 -272.817586) (xy 362.318469 -272.861623) (xy 362.282217 -272.900694) (xy 362.240546 -272.933925)
			(xy 362.194388 -272.960574) (xy 362.144774 -272.980046) (xy 362.092812 -272.991906) (xy 362.039662 -272.99589)
			(xy 361.986512 -272.991906) (xy 361.93455 -272.980046) (xy 361.884936 -272.960574) (xy 361.838778 -272.933925)
			(xy 361.797107 -272.900694) (xy 361.760855 -272.861623) (xy 361.730831 -272.817586) (xy 361.707705 -272.769565)
			(xy 361.691995 -272.718635) (xy 361.684052 -272.665931) (xy 358.636072 -272.665931) (xy 358.628129 -272.718635)
			(xy 358.612419 -272.769565) (xy 358.589293 -272.817586) (xy 358.559269 -272.861623) (xy 358.523017 -272.900694)
			(xy 358.481346 -272.933925) (xy 358.435188 -272.960574) (xy 358.385574 -272.980046) (xy 358.333612 -272.991906)
			(xy 358.280462 -272.99589) (xy 358.227312 -272.991906) (xy 358.17535 -272.980046) (xy 358.125736 -272.960574)
			(xy 358.079578 -272.933925) (xy 358.037907 -272.900694) (xy 358.001655 -272.861623) (xy 357.971631 -272.817586)
			(xy 357.948505 -272.769565) (xy 357.932795 -272.718635) (xy 357.924852 -272.665931) (xy 357.695464 -272.665931)
			(xy 357.693566 -272.691656) (xy 357.682061 -272.742879) (xy 357.663162 -272.791858) (xy 357.637279 -272.837533)
			(xy 357.604973 -272.878915) (xy 357.566943 -272.915107) (xy 357.524013 -272.945326) (xy 357.477113 -272.968917)
			(xy 357.427259 -272.985368) (xy 357.375529 -272.994325) (xy 357.349298 -272.99539) (xy 357.340408 -272.99539)
			(xy 357.313847 -272.994898) (xy 357.261316 -272.987004) (xy 357.210542 -272.971388) (xy 357.162653 -272.9484)
			(xy 357.118712 -272.918548) (xy 357.098854 -272.900902) (xy 357.0986 -272.900648) (xy 357.09606 -272.898362)
			(xy 357.084725 -272.889337) (xy 357.058317 -272.877446) (xy 357.029634 -272.873443) (xy 357.00098 -272.877651)
			(xy 356.974659 -272.889731) (xy 356.952785 -272.908713) (xy 356.937117 -272.93307) (xy 356.928914 -272.960845)
			(xy 356.92842 -272.975324) (xy 356.92842 -273.09953) (xy 356.965758 -273.109944) (xy 356.990446 -273.117252)
			(xy 357.037568 -273.137993) (xy 357.081214 -273.165303) (xy 357.120472 -273.198613) (xy 357.154525 -273.237228)
			(xy 357.182663 -273.280344) (xy 357.204301 -273.327062) (xy 357.218986 -273.376409) (xy 357.226414 -273.427355)
			(xy 357.22687 -273.453098) (xy 357.226478 -273.4763) (xy 357.226024 -273.479747) (xy 357.454952 -273.479747)
			(xy 357.454952 -273.426449) (xy 357.462895 -273.373745) (xy 357.478605 -273.322815) (xy 357.501731 -273.274794)
			(xy 357.531755 -273.230757) (xy 357.568007 -273.191686) (xy 357.609678 -273.158455) (xy 357.655836 -273.131806)
			(xy 357.70545 -273.112334) (xy 357.757412 -273.100474) (xy 357.810562 -273.096491) (xy 357.863712 -273.100474)
			(xy 357.915674 -273.112334) (xy 357.965288 -273.131806) (xy 358.011446 -273.158455) (xy 358.053117 -273.191686)
			(xy 358.089369 -273.230757) (xy 358.119393 -273.274794) (xy 358.142519 -273.322815) (xy 358.158229 -273.373745)
			(xy 358.166172 -273.426449) (xy 358.16667 -273.453098) (xy 358.166172 -273.479747) (xy 361.214152 -273.479747)
			(xy 361.214152 -273.426449) (xy 361.222095 -273.373745) (xy 361.237805 -273.322815) (xy 361.260931 -273.274794)
			(xy 361.290955 -273.230757) (xy 361.327207 -273.191686) (xy 361.368878 -273.158455) (xy 361.415036 -273.131806)
			(xy 361.46465 -273.112334) (xy 361.516612 -273.100474) (xy 361.569762 -273.096491) (xy 361.622912 -273.100474)
			(xy 361.674874 -273.112334) (xy 361.724488 -273.131806) (xy 361.770646 -273.158455) (xy 361.812317 -273.191686)
			(xy 361.848569 -273.230757) (xy 361.878593 -273.274794) (xy 361.901719 -273.322815) (xy 361.917429 -273.373745)
			(xy 361.925372 -273.426449) (xy 361.92587 -273.453098) (xy 361.925372 -273.479747) (xy 361.917429 -273.532451)
			(xy 361.901719 -273.583381) (xy 361.878593 -273.631402) (xy 361.848569 -273.675439) (xy 361.812317 -273.71451)
			(xy 361.770646 -273.747741) (xy 361.724488 -273.77439) (xy 361.674874 -273.793862) (xy 361.622912 -273.805722)
			(xy 361.569762 -273.809706) (xy 361.516612 -273.805722) (xy 361.46465 -273.793862) (xy 361.415036 -273.77439)
			(xy 361.368878 -273.747741) (xy 361.327207 -273.71451) (xy 361.290955 -273.675439) (xy 361.260931 -273.631402)
			(xy 361.237805 -273.583381) (xy 361.222095 -273.532451) (xy 361.214152 -273.479747) (xy 358.166172 -273.479747)
			(xy 358.158229 -273.532451) (xy 358.142519 -273.583381) (xy 358.119393 -273.631402) (xy 358.089369 -273.675439)
			(xy 358.053117 -273.71451) (xy 358.011446 -273.747741) (xy 357.965288 -273.77439) (xy 357.915674 -273.793862)
			(xy 357.863712 -273.805722) (xy 357.810562 -273.809706) (xy 357.757412 -273.805722) (xy 357.70545 -273.793862)
			(xy 357.655836 -273.77439) (xy 357.609678 -273.747741) (xy 357.568007 -273.71451) (xy 357.531755 -273.675439)
			(xy 357.501731 -273.631402) (xy 357.478605 -273.583381) (xy 357.462895 -273.532451) (xy 357.454952 -273.479747)
			(xy 357.226024 -273.479747) (xy 357.220422 -273.522308) (xy 357.208449 -273.567142) (xy 357.199946 -273.588734)
			(xy 357.190548 -273.611848) (xy 357.363014 -273.910552) (xy 357.387906 -273.913854) (xy 357.413241 -273.917686)
			(xy 357.462531 -273.931678) (xy 357.509306 -273.952592) (xy 357.5526 -273.979996) (xy 357.591517 -274.013324)
			(xy 357.625254 -274.051888) (xy 357.653113 -274.09489) (xy 357.67452 -274.141442) (xy 357.68903 -274.190582)
			(xy 357.696346 -274.241295) (xy 357.69677 -274.266914) (xy 357.696273 -274.293563) (xy 357.924852 -274.293563)
			(xy 357.924852 -274.240265) (xy 357.932795 -274.187561) (xy 357.948505 -274.136631) (xy 357.971631 -274.08861)
			(xy 358.001655 -274.044573) (xy 358.037907 -274.005502) (xy 358.079578 -273.972271) (xy 358.125736 -273.945622)
			(xy 358.17535 -273.92615) (xy 358.227312 -273.91429) (xy 358.280462 -273.910307) (xy 358.333612 -273.91429)
			(xy 358.385574 -273.92615) (xy 358.435188 -273.945622) (xy 358.481346 -273.972271) (xy 358.523017 -274.005502)
			(xy 358.559269 -274.044573) (xy 358.589293 -274.08861) (xy 358.612419 -274.136631) (xy 358.628129 -274.187561)
			(xy 358.636072 -274.240265) (xy 358.63657 -274.266914) (xy 358.636072 -274.293563) (xy 358.628129 -274.346267)
			(xy 358.612419 -274.397197) (xy 358.589293 -274.445218) (xy 358.559269 -274.489255) (xy 358.523017 -274.528326)
			(xy 358.481346 -274.561557) (xy 358.435188 -274.588206) (xy 358.385574 -274.607678) (xy 358.333612 -274.619538)
			(xy 358.280462 -274.623522) (xy 358.227312 -274.619538) (xy 358.17535 -274.607678) (xy 358.125736 -274.588206)
			(xy 358.079578 -274.561557) (xy 358.037907 -274.528326) (xy 358.001655 -274.489255) (xy 357.971631 -274.445218)
			(xy 357.948505 -274.397197) (xy 357.932795 -274.346267) (xy 357.924852 -274.293563) (xy 357.696273 -274.293563)
			(xy 357.696248 -274.294898) (xy 357.687491 -274.350175) (xy 357.670193 -274.403402) (xy 357.644782 -274.453268)
			(xy 357.611882 -274.498544) (xy 357.572304 -274.538116) (xy 357.527023 -274.571009) (xy 357.477154 -274.596413)
			(xy 357.423925 -274.613703) (xy 357.368646 -274.622452) (xy 357.340662 -274.623022) (xy 357.314771 -274.622561)
			(xy 357.263535 -274.615066) (xy 357.213925 -274.600226) (xy 357.16699 -274.578354) (xy 357.123719 -274.549911)
			(xy 357.085027 -274.515499) (xy 357.05173 -274.475843) (xy 357.02453 -274.43178) (xy 357.004003 -274.384241)
			(xy 356.990581 -274.334229) (xy 356.987094 -274.30857) (xy 356.98557 -274.29714) (xy 356.9843 -274.266914)
			(xy 356.984664 -274.243627) (xy 356.990703 -274.197447) (xy 357.002706 -274.152446) (xy 357.011224 -274.13077)
			(xy 357.020876 -274.107656) (xy 356.906576 -273.90979) (xy 356.848664 -273.80946) (xy 356.823772 -273.806158)
			(xy 356.812342 -273.80438) (xy 356.786434 -273.800062) (xy 356.630224 -273.956272) (xy 356.63505 -273.993102)
			(xy 356.654474 -274.010294) (xy 356.688669 -274.049299) (xy 356.716916 -274.092804) (xy 356.738632 -274.139911)
			(xy 356.753368 -274.189645) (xy 356.760819 -274.240978) (xy 356.761288 -274.266914) (xy 356.760828 -274.292641)
			(xy 356.753504 -274.343571) (xy 356.739007 -274.39294) (xy 356.717631 -274.439744) (xy 356.689813 -274.48303)
			(xy 356.656117 -274.521916) (xy 356.617231 -274.555611) (xy 356.573946 -274.58343) (xy 356.527142 -274.604806)
			(xy 356.477773 -274.619304) (xy 356.426843 -274.626628) (xy 356.401116 -274.627086) (xy 356.390956 -274.626832)
			(xy 356.378549 -274.6309) (xy 356.356201 -274.644384) (xy 356.33801 -274.663101) (xy 356.325168 -274.685824)
			(xy 356.318518 -274.711064) (xy 356.318058 -274.724114) (xy 356.318058 -275.107379) (xy 356.515152 -275.107379)
			(xy 356.515152 -275.054081) (xy 356.523095 -275.001377) (xy 356.538805 -274.950447) (xy 356.561931 -274.902426)
			(xy 356.591955 -274.858389) (xy 356.628207 -274.819318) (xy 356.669878 -274.786087) (xy 356.716036 -274.759438)
			(xy 356.76565 -274.739966) (xy 356.817612 -274.728106) (xy 356.870762 -274.724123) (xy 356.923912 -274.728106)
			(xy 356.975874 -274.739966) (xy 357.025488 -274.759438) (xy 357.071646 -274.786087) (xy 357.113317 -274.819318)
			(xy 357.149569 -274.858389) (xy 357.179593 -274.902426) (xy 357.202719 -274.950447) (xy 357.218429 -275.001377)
			(xy 357.226372 -275.054081) (xy 357.22687 -275.08073) (xy 357.226372 -275.107379) (xy 357.454952 -275.107379)
			(xy 357.454952 -275.054081) (xy 357.462895 -275.001377) (xy 357.478605 -274.950447) (xy 357.501731 -274.902426)
			(xy 357.531755 -274.858389) (xy 357.568007 -274.819318) (xy 357.609678 -274.786087) (xy 357.655836 -274.759438)
			(xy 357.70545 -274.739966) (xy 357.757412 -274.728106) (xy 357.810562 -274.724123) (xy 357.863712 -274.728106)
			(xy 357.915674 -274.739966) (xy 357.965288 -274.759438) (xy 358.011446 -274.786087) (xy 358.053117 -274.819318)
			(xy 358.089369 -274.858389) (xy 358.119393 -274.902426) (xy 358.142519 -274.950447) (xy 358.158229 -275.001377)
			(xy 358.166172 -275.054081) (xy 358.16667 -275.08073) (xy 358.166172 -275.107379) (xy 358.158229 -275.160083)
			(xy 358.142519 -275.211013) (xy 358.119393 -275.259034) (xy 358.089369 -275.303071) (xy 358.053117 -275.342142)
			(xy 358.011446 -275.375373) (xy 357.965288 -275.402022) (xy 357.915674 -275.421494) (xy 357.863712 -275.433354)
			(xy 357.810562 -275.437338) (xy 357.757412 -275.433354) (xy 357.70545 -275.421494) (xy 357.655836 -275.402022)
			(xy 357.609678 -275.375373) (xy 357.568007 -275.342142) (xy 357.531755 -275.303071) (xy 357.501731 -275.259034)
			(xy 357.478605 -275.211013) (xy 357.462895 -275.160083) (xy 357.454952 -275.107379) (xy 357.226372 -275.107379)
			(xy 357.218429 -275.160083) (xy 357.202719 -275.211013) (xy 357.179593 -275.259034) (xy 357.149569 -275.303071)
			(xy 357.113317 -275.342142) (xy 357.071646 -275.375373) (xy 357.025488 -275.402022) (xy 356.975874 -275.421494)
			(xy 356.923912 -275.433354) (xy 356.870762 -275.437338) (xy 356.817612 -275.433354) (xy 356.76565 -275.421494)
			(xy 356.716036 -275.402022) (xy 356.669878 -275.375373) (xy 356.628207 -275.342142) (xy 356.591955 -275.303071)
			(xy 356.561931 -275.259034) (xy 356.538805 -275.211013) (xy 356.523095 -275.160083) (xy 356.515152 -275.107379)
			(xy 356.318058 -275.107379) (xy 356.318058 -275.356066) (xy 356.423468 -275.538438) (xy 356.448106 -275.54174)
			(xy 356.473454 -275.545559) (xy 356.522774 -275.559529) (xy 356.569581 -275.580426) (xy 356.612907 -275.60782)
			(xy 356.651858 -275.641144) (xy 356.685627 -275.679709) (xy 356.713517 -275.722717) (xy 356.734952 -275.769281)
			(xy 356.749487 -275.818437) (xy 356.756824 -275.86917) (xy 356.757224 -275.8948) (xy 356.756705 -275.922061)
			(xy 356.748396 -275.975947) (xy 356.731974 -276.027937) (xy 356.70782 -276.076818) (xy 356.6765 -276.121447)
			(xy 356.638745 -276.160782) (xy 356.595437 -276.193904) (xy 356.547588 -276.22004) (xy 356.496314 -276.23858)
			(xy 356.442814 -276.249089) (xy 356.415594 -276.250654) (xy 356.400056 -276.251829) (xy 356.370751 -276.262378)
			(xy 356.345987 -276.281267) (xy 356.328065 -276.306739) (xy 356.318651 -276.336428) (xy 356.318058 -276.352)
			(xy 356.318058 -276.708616) (xy 356.514654 -276.708616) (xy 356.515088 -276.682987) (xy 356.522422 -276.632257)
			(xy 356.536954 -276.583103) (xy 356.558385 -276.53654) (xy 356.586271 -276.493532) (xy 356.620037 -276.454967)
			(xy 356.658983 -276.421643) (xy 356.702306 -276.394248) (xy 356.749109 -276.373348) (xy 356.798426 -276.359376)
			(xy 356.823772 -276.355556) (xy 356.84841 -276.352254) (xy 357.020876 -276.053804) (xy 357.011224 -276.03069)
			(xy 357.002708 -276.009058) (xy 356.99072 -275.96414) (xy 356.984676 -275.918045) (xy 356.9843 -275.8948)
			(xy 356.984798 -275.868151) (xy 356.992741 -275.815447) (xy 357.008451 -275.764517) (xy 357.031577 -275.716496)
			(xy 357.061601 -275.672459) (xy 357.097853 -275.633388) (xy 357.139524 -275.600157) (xy 357.185682 -275.573508)
			(xy 357.235296 -275.554036) (xy 357.287258 -275.542176) (xy 357.340408 -275.538193) (xy 357.393558 -275.542176)
			(xy 357.44552 -275.554036) (xy 357.495134 -275.573508) (xy 357.541292 -275.600157) (xy 357.582963 -275.633388)
			(xy 357.619215 -275.672459) (xy 357.649239 -275.716496) (xy 357.672365 -275.764517) (xy 357.688075 -275.815447)
			(xy 357.696018 -275.868151) (xy 357.696516 -275.8948) (xy 357.696065 -275.920418) (xy 357.695916 -275.921449)
			(xy 357.924852 -275.921449) (xy 357.924852 -275.868151) (xy 357.932795 -275.815447) (xy 357.948505 -275.764517)
			(xy 357.971631 -275.716496) (xy 358.001655 -275.672459) (xy 358.037907 -275.633388) (xy 358.079578 -275.600157)
			(xy 358.125736 -275.573508) (xy 358.17535 -275.554036) (xy 358.227312 -275.542176) (xy 358.280462 -275.538193)
			(xy 358.333612 -275.542176) (xy 358.385574 -275.554036) (xy 358.435188 -275.573508) (xy 358.481346 -275.600157)
			(xy 358.523017 -275.633388) (xy 358.559269 -275.672459) (xy 358.589293 -275.716496) (xy 358.612419 -275.764517)
			(xy 358.628129 -275.815447) (xy 358.636072 -275.868151) (xy 358.63657 -275.8948) (xy 358.636072 -275.921449)
			(xy 358.628129 -275.974153) (xy 358.612419 -276.025083) (xy 358.589293 -276.073104) (xy 358.559269 -276.117141)
			(xy 358.523017 -276.156212) (xy 358.481346 -276.189443) (xy 358.435188 -276.216092) (xy 358.385574 -276.235564)
			(xy 358.333612 -276.247424) (xy 358.280462 -276.251408) (xy 358.227312 -276.247424) (xy 358.17535 -276.235564)
			(xy 358.125736 -276.216092) (xy 358.079578 -276.189443) (xy 358.037907 -276.156212) (xy 358.001655 -276.117141)
			(xy 357.971631 -276.073104) (xy 357.948505 -276.025083) (xy 357.932795 -275.974153) (xy 357.924852 -275.921449)
			(xy 357.695916 -275.921449) (xy 357.688749 -275.971128) (xy 357.674238 -276.020265) (xy 357.652834 -276.066814)
			(xy 357.624977 -276.109815) (xy 357.591244 -276.148378) (xy 357.552331 -276.181706) (xy 357.509042 -276.209112)
			(xy 357.462271 -276.230029) (xy 357.412985 -276.244025) (xy 357.387652 -276.24786) (xy 357.36276 -276.251162)
			(xy 357.190294 -276.549612) (xy 357.199946 -276.572726) (xy 357.208466 -276.594357) (xy 357.220452 -276.639275)
			(xy 357.226495 -276.685371) (xy 357.22687 -276.708616) (xy 357.226372 -276.735265) (xy 357.454952 -276.735265)
			(xy 357.454952 -276.681967) (xy 357.462895 -276.629263) (xy 357.478605 -276.578333) (xy 357.501731 -276.530312)
			(xy 357.531755 -276.486275) (xy 357.568007 -276.447204) (xy 357.609678 -276.413973) (xy 357.655836 -276.387324)
			(xy 357.70545 -276.367852) (xy 357.757412 -276.355992) (xy 357.810562 -276.352009) (xy 357.863712 -276.355992)
			(xy 357.915674 -276.367852) (xy 357.965288 -276.387324) (xy 358.011446 -276.413973) (xy 358.053117 -276.447204)
			(xy 358.089369 -276.486275) (xy 358.119393 -276.530312) (xy 358.142519 -276.578333) (xy 358.158229 -276.629263)
			(xy 358.166172 -276.681967) (xy 358.16667 -276.708616) (xy 358.166172 -276.735265) (xy 358.158229 -276.787969)
			(xy 358.142519 -276.838899) (xy 358.119393 -276.88692) (xy 358.089369 -276.930957) (xy 358.053117 -276.970028)
			(xy 358.011446 -277.003259) (xy 357.965288 -277.029908) (xy 357.915674 -277.04938) (xy 357.863712 -277.06124)
			(xy 357.810562 -277.065224) (xy 357.757412 -277.06124) (xy 357.70545 -277.04938) (xy 357.655836 -277.029908)
			(xy 357.609678 -277.003259) (xy 357.568007 -276.970028) (xy 357.531755 -276.930957) (xy 357.501731 -276.88692)
			(xy 357.478605 -276.838899) (xy 357.462895 -276.787969) (xy 357.454952 -276.735265) (xy 357.226372 -276.735265)
			(xy 357.218429 -276.787969) (xy 357.202719 -276.838899) (xy 357.179593 -276.88692) (xy 357.149569 -276.930957)
			(xy 357.113317 -276.970028) (xy 357.071646 -277.003259) (xy 357.025488 -277.029908) (xy 356.975874 -277.04938)
			(xy 356.923912 -277.06124) (xy 356.870762 -277.065224) (xy 356.817612 -277.06124) (xy 356.76565 -277.04938)
			(xy 356.716036 -277.029908) (xy 356.669878 -277.003259) (xy 356.628207 -276.970028) (xy 356.591955 -276.930957)
			(xy 356.561931 -276.88692) (xy 356.538805 -276.838899) (xy 356.523095 -276.787969) (xy 356.515152 -276.735265)
			(xy 356.514654 -276.708616) (xy 356.318058 -276.708616) (xy 356.318058 -277.065232) (xy 356.318665 -277.080794)
			(xy 356.328116 -277.110453) (xy 356.346044 -277.1359) (xy 356.37079 -277.154783) (xy 356.400067 -277.165357)
			(xy 356.415594 -277.166578) (xy 356.443502 -277.16829) (xy 356.498313 -277.179317) (xy 356.550732 -277.198764)
			(xy 356.599473 -277.226154) (xy 356.64334 -277.260818) (xy 356.68126 -277.301903) (xy 356.69728 -277.32482)
			(xy 357.044244 -277.32482) (xy 357.058482 -277.304248) (xy 357.091802 -277.266929) (xy 357.130016 -277.234637)
			(xy 357.17237 -277.20801) (xy 357.218034 -277.187569) (xy 357.266108 -277.173717) (xy 357.315647 -277.166727)
			(xy 357.340662 -277.166324) (xy 357.367313 -277.166794) (xy 357.420019 -277.174733) (xy 357.470954 -277.19044)
			(xy 357.518978 -277.213563) (xy 357.563019 -277.243585) (xy 357.602094 -277.279837) (xy 357.635329 -277.321508)
			(xy 357.661981 -277.367667) (xy 357.681455 -277.417283) (xy 357.693317 -277.469248) (xy 357.6973 -277.5224)
			(xy 357.695301 -277.549081) (xy 357.924852 -277.549081) (xy 357.924852 -277.495783) (xy 357.932795 -277.443079)
			(xy 357.948505 -277.392149) (xy 357.971631 -277.344128) (xy 358.001655 -277.300091) (xy 358.037907 -277.26102)
			(xy 358.079578 -277.227789) (xy 358.125736 -277.20114) (xy 358.17535 -277.181668) (xy 358.227312 -277.169808)
			(xy 358.280462 -277.165825) (xy 358.333612 -277.169808) (xy 358.385574 -277.181668) (xy 358.435188 -277.20114)
			(xy 358.481346 -277.227789) (xy 358.523017 -277.26102) (xy 358.559269 -277.300091) (xy 358.589293 -277.344128)
			(xy 358.612419 -277.392149) (xy 358.628129 -277.443079) (xy 358.636072 -277.495783) (xy 358.63657 -277.522432)
			(xy 358.636072 -277.549081) (xy 358.628129 -277.601785) (xy 358.612419 -277.652715) (xy 358.589293 -277.700736)
			(xy 358.559269 -277.744773) (xy 358.523017 -277.783844) (xy 358.481346 -277.817075) (xy 358.435188 -277.843724)
			(xy 358.385574 -277.863196) (xy 358.333612 -277.875056) (xy 358.280462 -277.87904) (xy 358.227312 -277.875056)
			(xy 358.17535 -277.863196) (xy 358.125736 -277.843724) (xy 358.079578 -277.817075) (xy 358.037907 -277.783844)
			(xy 358.001655 -277.744773) (xy 357.971631 -277.700736) (xy 357.948505 -277.652715) (xy 357.932795 -277.601785)
			(xy 357.924852 -277.549081) (xy 357.695301 -277.549081) (xy 357.693317 -277.575552) (xy 357.681455 -277.627517)
			(xy 357.661981 -277.677133) (xy 357.635329 -277.723292) (xy 357.602094 -277.764963) (xy 357.563019 -277.801215)
			(xy 357.518978 -277.831237) (xy 357.470954 -277.85436) (xy 357.420019 -277.870067) (xy 357.367313 -277.878006)
			(xy 357.340662 -277.87854) (xy 357.31565 -277.878115) (xy 357.266117 -277.871115) (xy 357.21805 -277.857258)
			(xy 357.172392 -277.836817) (xy 357.130041 -277.810192) (xy 357.091829 -277.777907) (xy 357.058506 -277.740597)
			(xy 357.044244 -277.720044) (xy 356.69728 -277.720044) (xy 356.681317 -277.743005) (xy 356.643407 -277.784111)
			(xy 356.599533 -277.81878) (xy 356.550776 -277.84616) (xy 356.498337 -277.865576) (xy 356.443506 -277.87655)
			(xy 356.415594 -277.878286) (xy 356.400057 -277.879462) (xy 356.370757 -277.890012) (xy 356.345999 -277.908901)
			(xy 356.328084 -277.934374) (xy 356.318679 -277.964062) (xy 356.318058 -277.979632) (xy 356.318058 -278.363151)
			(xy 356.515152 -278.363151) (xy 356.515152 -278.309853) (xy 356.523095 -278.257149) (xy 356.538805 -278.206219)
			(xy 356.561931 -278.158198) (xy 356.591955 -278.114161) (xy 356.628207 -278.07509) (xy 356.669878 -278.041859)
			(xy 356.716036 -278.01521) (xy 356.76565 -277.995738) (xy 356.817612 -277.983878) (xy 356.870762 -277.979895)
			(xy 356.923912 -277.983878) (xy 356.975874 -277.995738) (xy 357.025488 -278.01521) (xy 357.071646 -278.041859)
			(xy 357.113317 -278.07509) (xy 357.149569 -278.114161) (xy 357.179593 -278.158198) (xy 357.202719 -278.206219)
			(xy 357.218429 -278.257149) (xy 357.226372 -278.309853) (xy 357.22687 -278.336502) (xy 357.226372 -278.363151)
			(xy 357.454952 -278.363151) (xy 357.454952 -278.309853) (xy 357.462895 -278.257149) (xy 357.478605 -278.206219)
			(xy 357.501731 -278.158198) (xy 357.531755 -278.114161) (xy 357.568007 -278.07509) (xy 357.609678 -278.041859)
			(xy 357.655836 -278.01521) (xy 357.70545 -277.995738) (xy 357.757412 -277.983878) (xy 357.810562 -277.979895)
			(xy 357.863712 -277.983878) (xy 357.915674 -277.995738) (xy 357.965288 -278.01521) (xy 358.011446 -278.041859)
			(xy 358.053117 -278.07509) (xy 358.089369 -278.114161) (xy 358.119393 -278.158198) (xy 358.142519 -278.206219)
			(xy 358.158229 -278.257149) (xy 358.166172 -278.309853) (xy 358.16667 -278.336502) (xy 358.166177 -278.362897)
			(xy 362.153952 -278.362897) (xy 362.153952 -278.309599) (xy 362.161895 -278.256895) (xy 362.177605 -278.205965)
			(xy 362.200731 -278.157944) (xy 362.230755 -278.113907) (xy 362.267007 -278.074836) (xy 362.308678 -278.041605)
			(xy 362.354836 -278.014956) (xy 362.40445 -277.995484) (xy 362.456412 -277.983624) (xy 362.509562 -277.979641)
			(xy 362.562712 -277.983624) (xy 362.614674 -277.995484) (xy 362.664288 -278.014956) (xy 362.710446 -278.041605)
			(xy 362.752117 -278.074836) (xy 362.788369 -278.113907) (xy 362.818393 -278.157944) (xy 362.841519 -278.205965)
			(xy 362.857229 -278.256895) (xy 362.865172 -278.309599) (xy 362.86567 -278.336248) (xy 362.865172 -278.362897)
			(xy 362.857229 -278.415601) (xy 362.841519 -278.466531) (xy 362.818393 -278.514552) (xy 362.788369 -278.558589)
			(xy 362.752117 -278.59766) (xy 362.710446 -278.630891) (xy 362.664288 -278.65754) (xy 362.614674 -278.677012)
			(xy 362.562712 -278.688872) (xy 362.509562 -278.692856) (xy 362.456412 -278.688872) (xy 362.40445 -278.677012)
			(xy 362.354836 -278.65754) (xy 362.308678 -278.630891) (xy 362.267007 -278.59766) (xy 362.230755 -278.558589)
			(xy 362.200731 -278.514552) (xy 362.177605 -278.466531) (xy 362.161895 -278.415601) (xy 362.153952 -278.362897)
			(xy 358.166177 -278.362897) (xy 358.166172 -278.363151) (xy 358.158229 -278.415855) (xy 358.142519 -278.466785)
			(xy 358.119393 -278.514806) (xy 358.089369 -278.558843) (xy 358.053117 -278.597914) (xy 358.011446 -278.631145)
			(xy 357.965288 -278.657794) (xy 357.915674 -278.677266) (xy 357.863712 -278.689126) (xy 357.810562 -278.69311)
			(xy 357.757412 -278.689126) (xy 357.70545 -278.677266) (xy 357.655836 -278.657794) (xy 357.609678 -278.631145)
			(xy 357.568007 -278.597914) (xy 357.531755 -278.558843) (xy 357.501731 -278.514806) (xy 357.478605 -278.466785)
			(xy 357.462895 -278.415855) (xy 357.454952 -278.363151) (xy 357.226372 -278.363151) (xy 357.218429 -278.415855)
			(xy 357.202719 -278.466785) (xy 357.179593 -278.514806) (xy 357.149569 -278.558843) (xy 357.113317 -278.597914)
			(xy 357.071646 -278.631145) (xy 357.025488 -278.657794) (xy 356.975874 -278.677266) (xy 356.923912 -278.689126)
			(xy 356.870762 -278.69311) (xy 356.817612 -278.689126) (xy 356.76565 -278.677266) (xy 356.716036 -278.657794)
			(xy 356.669878 -278.631145) (xy 356.628207 -278.597914) (xy 356.591955 -278.558843) (xy 356.561931 -278.514806)
			(xy 356.538805 -278.466785) (xy 356.523095 -278.415855) (xy 356.515152 -278.363151) (xy 356.318058 -278.363151)
			(xy 356.318058 -278.693118) (xy 356.318671 -278.708732) (xy 356.32818 -278.738481) (xy 356.346216 -278.763978)
			(xy 356.3711 -278.782852) (xy 356.400517 -278.793344) (xy 356.416102 -278.794464) (xy 356.443281 -278.796142)
			(xy 356.496696 -278.80672) (xy 356.547878 -278.825306) (xy 356.595635 -278.851465) (xy 356.638853 -278.884589)
			(xy 356.676526 -278.923906) (xy 356.707775 -278.968499) (xy 356.731872 -279.017328) (xy 356.748256 -279.069257)
			(xy 356.756544 -279.123075) (xy 356.756544 -279.176967) (xy 362.623852 -279.176967) (xy 362.623852 -279.123669)
			(xy 362.631795 -279.070965) (xy 362.647505 -279.020035) (xy 362.670631 -278.972014) (xy 362.700655 -278.927977)
			(xy 362.736907 -278.888906) (xy 362.778578 -278.855675) (xy 362.824736 -278.829026) (xy 362.87435 -278.809554)
			(xy 362.926312 -278.797694) (xy 362.979462 -278.793711) (xy 363.032612 -278.797694) (xy 363.084574 -278.809554)
			(xy 363.134188 -278.829026) (xy 363.180346 -278.855675) (xy 363.222017 -278.888906) (xy 363.258269 -278.927977)
			(xy 363.288293 -278.972014) (xy 363.311419 -279.020035) (xy 363.327129 -279.070965) (xy 363.335072 -279.123669)
			(xy 363.33557 -279.150318) (xy 363.335072 -279.176967) (xy 363.563652 -279.176967) (xy 363.563652 -279.123669)
			(xy 363.571595 -279.070965) (xy 363.587305 -279.020035) (xy 363.610431 -278.972014) (xy 363.640455 -278.927977)
			(xy 363.676707 -278.888906) (xy 363.718378 -278.855675) (xy 363.764536 -278.829026) (xy 363.81415 -278.809554)
			(xy 363.866112 -278.797694) (xy 363.919262 -278.793711) (xy 363.972412 -278.797694) (xy 364.024374 -278.809554)
			(xy 364.073988 -278.829026) (xy 364.120146 -278.855675) (xy 364.161817 -278.888906) (xy 364.198069 -278.927977)
			(xy 364.228093 -278.972014) (xy 364.251219 -279.020035) (xy 364.266929 -279.070965) (xy 364.274872 -279.123669)
			(xy 364.27537 -279.150318) (xy 364.274872 -279.176967) (xy 364.266929 -279.229671) (xy 364.251219 -279.280601)
			(xy 364.228093 -279.328622) (xy 364.198069 -279.372659) (xy 364.161817 -279.41173) (xy 364.120146 -279.444961)
			(xy 364.073988 -279.47161) (xy 364.024374 -279.491082) (xy 363.972412 -279.502942) (xy 363.919262 -279.506926)
			(xy 363.866112 -279.502942) (xy 363.81415 -279.491082) (xy 363.764536 -279.47161) (xy 363.718378 -279.444961)
			(xy 363.676707 -279.41173) (xy 363.640455 -279.372659) (xy 363.610431 -279.328622) (xy 363.587305 -279.280601)
			(xy 363.571595 -279.229671) (xy 363.563652 -279.176967) (xy 363.335072 -279.176967) (xy 363.327129 -279.229671)
			(xy 363.311419 -279.280601) (xy 363.288293 -279.328622) (xy 363.258269 -279.372659) (xy 363.222017 -279.41173)
			(xy 363.180346 -279.444961) (xy 363.134188 -279.47161) (xy 363.084574 -279.491082) (xy 363.032612 -279.502942)
			(xy 362.979462 -279.506926) (xy 362.926312 -279.502942) (xy 362.87435 -279.491082) (xy 362.824736 -279.47161)
			(xy 362.778578 -279.444961) (xy 362.736907 -279.41173) (xy 362.700655 -279.372659) (xy 362.670631 -279.328622)
			(xy 362.647505 -279.280601) (xy 362.631795 -279.229671) (xy 362.623852 -279.176967) (xy 356.756544 -279.176967)
			(xy 356.756544 -279.177527) (xy 356.748255 -279.231344) (xy 356.731871 -279.283273) (xy 356.707774 -279.332103)
			(xy 356.676525 -279.376695) (xy 356.638852 -279.416012) (xy 356.595633 -279.449136) (xy 356.547877 -279.475295)
			(xy 356.496694 -279.49388) (xy 356.44328 -279.504458) (xy 356.416102 -279.506172) (xy 356.400506 -279.507278)
			(xy 356.371059 -279.517739) (xy 356.346148 -279.536608) (xy 356.328103 -279.562121) (xy 356.318608 -279.591894)
			(xy 356.318058 -279.607518) (xy 356.318058 -279.82037) (xy 356.273862 -279.864566) (xy 356.27945 -279.89149)
			(xy 356.282978 -279.909445) (xy 356.286794 -279.945838) (xy 356.28707 -279.964134) (xy 356.286572 -279.990783)
			(xy 361.214152 -279.990783) (xy 361.214152 -279.937485) (xy 361.222095 -279.884781) (xy 361.237805 -279.833851)
			(xy 361.260931 -279.78583) (xy 361.290955 -279.741793) (xy 361.327207 -279.702722) (xy 361.368878 -279.669491)
			(xy 361.415036 -279.642842) (xy 361.46465 -279.62337) (xy 361.516612 -279.61151) (xy 361.569762 -279.607527)
			(xy 361.622912 -279.61151) (xy 361.674874 -279.62337) (xy 361.724488 -279.642842) (xy 361.770646 -279.669491)
			(xy 361.812317 -279.702722) (xy 361.848569 -279.741793) (xy 361.878593 -279.78583) (xy 361.901719 -279.833851)
			(xy 361.917429 -279.884781) (xy 361.925372 -279.937485) (xy 361.92587 -279.964134) (xy 361.925372 -279.990783)
			(xy 361.917429 -280.043487) (xy 361.901719 -280.094417) (xy 361.878593 -280.142438) (xy 361.848569 -280.186475)
			(xy 361.812317 -280.225546) (xy 361.770646 -280.258777) (xy 361.724488 -280.285426) (xy 361.674874 -280.304898)
			(xy 361.622912 -280.316758) (xy 361.569762 -280.320742) (xy 361.516612 -280.316758) (xy 361.46465 -280.304898)
			(xy 361.415036 -280.285426) (xy 361.368878 -280.258777) (xy 361.327207 -280.225546) (xy 361.290955 -280.186475)
			(xy 361.260931 -280.142438) (xy 361.237805 -280.094417) (xy 361.222095 -280.043487) (xy 361.214152 -279.990783)
			(xy 356.286572 -279.990783) (xy 356.286547 -279.992117) (xy 356.277787 -280.047392) (xy 356.260487 -280.100616)
			(xy 356.235075 -280.150479) (xy 356.202175 -280.195752) (xy 356.162597 -280.235322) (xy 356.117317 -280.268212)
			(xy 356.067449 -280.293615) (xy 356.014222 -280.310904) (xy 355.958945 -280.319653) (xy 355.930962 -280.320242)
			(xy 355.912664 -280.319994) (xy 355.876268 -280.316181) (xy 355.858318 -280.312622) (xy 355.831394 -280.307034)
			(xy 355.733604 -280.404824) (xy 355.723414 -280.415729) (xy 355.709296 -280.442008) (xy 355.703389 -280.471249)
			(xy 355.706198 -280.500947) (xy 355.717483 -280.528562) (xy 355.726492 -280.54046) (xy 355.729286 -280.544016)
			(xy 355.74575 -280.563551) (xy 355.773497 -280.606445) (xy 355.794834 -280.652862) (xy 355.809324 -280.701851)
			(xy 355.816669 -280.752407) (xy 355.81717 -280.77795) (xy 355.81717 -280.786586) (xy 355.816402 -280.804853)
			(xy 357.924852 -280.804853) (xy 357.924852 -280.751555) (xy 357.932795 -280.698851) (xy 357.948505 -280.647921)
			(xy 357.971631 -280.5999) (xy 358.001655 -280.555863) (xy 358.037907 -280.516792) (xy 358.079578 -280.483561)
			(xy 358.125736 -280.456912) (xy 358.17535 -280.43744) (xy 358.227312 -280.42558) (xy 358.280462 -280.421597)
			(xy 358.333612 -280.42558) (xy 358.385574 -280.43744) (xy 358.435188 -280.456912) (xy 358.481346 -280.483561)
			(xy 358.523017 -280.516792) (xy 358.559269 -280.555863) (xy 358.589293 -280.5999) (xy 358.612419 -280.647921)
			(xy 358.628129 -280.698851) (xy 358.636072 -280.751555) (xy 358.63657 -280.778204) (xy 358.636072 -280.804853)
			(xy 358.628129 -280.857557) (xy 358.612419 -280.908487) (xy 358.589293 -280.956508) (xy 358.559269 -281.000545)
			(xy 358.523017 -281.039616) (xy 358.481346 -281.072847) (xy 358.435188 -281.099496) (xy 358.385574 -281.118968)
			(xy 358.333612 -281.130828) (xy 358.280462 -281.134812) (xy 358.227312 -281.130828) (xy 358.17535 -281.118968)
			(xy 358.125736 -281.099496) (xy 358.079578 -281.072847) (xy 358.037907 -281.039616) (xy 358.001655 -281.000545)
			(xy 357.971631 -280.956508) (xy 357.948505 -280.908487) (xy 357.932795 -280.857557) (xy 357.924852 -280.804853)
			(xy 355.816402 -280.804853) (xy 355.816011 -280.81414) (xy 355.806244 -280.868414) (xy 355.788225 -280.920533)
			(xy 355.762387 -280.969251) (xy 355.729346 -281.013403) (xy 355.689893 -281.051933) (xy 355.644972 -281.08392)
			(xy 355.595656 -281.108599) (xy 355.543125 -281.125379) (xy 355.488635 -281.13386) (xy 355.461062 -281.134312)
			(xy 355.460808 -281.134312) (xy 355.435776 -281.133888) (xy 355.386205 -281.126879) (xy 355.338104 -281.112998)
			(xy 355.29242 -281.092519) (xy 355.250054 -281.065845) (xy 355.230684 -281.049984) (xy 355.227382 -281.04719)
			(xy 355.215551 -281.037231) (xy 355.187466 -281.024324) (xy 355.156805 -281.02042) (xy 355.126382 -281.025878)
			(xy 355.09899 -281.040198) (xy 355.087682 -281.050746) (xy 355.055424 -281.083004) (xy 355.045223 -281.093944)
			(xy 355.031099 -281.120294) (xy 355.025201 -281.149603) (xy 355.028034 -281.179365) (xy 355.039356 -281.207035)
			(xy 355.058198 -281.230247) (xy 355.082949 -281.247015) (xy 355.09708 -281.251914) (xy 355.123921 -281.260819)
			(xy 355.174596 -281.285916) (xy 355.220666 -281.318709) (xy 355.260973 -281.358373) (xy 355.294502 -281.40391)
			(xy 355.32041 -281.454175) (xy 355.338047 -281.507904) (xy 355.346968 -281.563745) (xy 355.347524 -281.59202)
			(xy 355.347 -281.618669) (xy 361.214152 -281.618669) (xy 361.214152 -281.565371) (xy 361.222095 -281.512667)
			(xy 361.237805 -281.461737) (xy 361.260931 -281.413716) (xy 361.290955 -281.369679) (xy 361.327207 -281.330608)
			(xy 361.368878 -281.297377) (xy 361.415036 -281.270728) (xy 361.46465 -281.251256) (xy 361.516612 -281.239396)
			(xy 361.569762 -281.235413) (xy 361.622912 -281.239396) (xy 361.674874 -281.251256) (xy 361.724488 -281.270728)
			(xy 361.770646 -281.297377) (xy 361.812317 -281.330608) (xy 361.848569 -281.369679) (xy 361.878593 -281.413716)
			(xy 361.901719 -281.461737) (xy 361.917429 -281.512667) (xy 361.925372 -281.565371) (xy 361.92587 -281.59202)
			(xy 361.925372 -281.618669) (xy 361.917429 -281.671373) (xy 361.901719 -281.722303) (xy 361.878593 -281.770324)
			(xy 361.848569 -281.814361) (xy 361.812317 -281.853432) (xy 361.770646 -281.886663) (xy 361.724488 -281.913312)
			(xy 361.674874 -281.932784) (xy 361.622912 -281.944644) (xy 361.569762 -281.948628) (xy 361.516612 -281.944644)
			(xy 361.46465 -281.932784) (xy 361.415036 -281.913312) (xy 361.368878 -281.886663) (xy 361.327207 -281.853432)
			(xy 361.290955 -281.814361) (xy 361.260931 -281.770324) (xy 361.237805 -281.722303) (xy 361.222095 -281.671373)
			(xy 361.214152 -281.618669) (xy 355.347 -281.618669) (xy 355.346974 -281.620003) (xy 355.338216 -281.675278)
			(xy 355.32092 -281.728504) (xy 355.295511 -281.778368) (xy 355.262615 -281.823644) (xy 355.223041 -281.863218)
			(xy 355.177765 -281.896113) (xy 355.1279 -281.921522) (xy 355.074674 -281.938817) (xy 355.019399 -281.947574)
			(xy 354.991416 -281.948128) (xy 354.96314 -281.947587) (xy 354.907298 -281.938654) (xy 354.853569 -281.921011)
			(xy 354.803302 -281.895101) (xy 354.75776 -281.861574) (xy 354.718088 -281.821273) (xy 354.685281 -281.77521)
			(xy 354.660164 -281.724542) (xy 354.65131 -281.697684) (xy 354.646366 -281.683575) (xy 354.629607 -281.658836)
			(xy 354.606406 -281.640003) (xy 354.57875 -281.628688) (xy 354.549003 -281.625857) (xy 354.519709 -281.631752)
			(xy 354.493373 -281.645871) (xy 354.4824 -281.656028) (xy 354.377244 -281.761184) (xy 354.543614 -282.049474)
			(xy 354.568506 -282.052776) (xy 354.59384 -282.056608) (xy 354.643129 -282.0706) (xy 354.689903 -282.091515)
			(xy 354.733195 -282.118919) (xy 354.77211 -282.152248) (xy 354.805845 -282.190812) (xy 354.833702 -282.233814)
			(xy 354.855105 -282.280366) (xy 354.869613 -282.329505) (xy 354.876926 -282.380217) (xy 354.87737 -282.405836)
			(xy 354.876872 -282.432485) (xy 355.105452 -282.432485) (xy 355.105452 -282.379187) (xy 355.113395 -282.326483)
			(xy 355.129105 -282.275553) (xy 355.152231 -282.227532) (xy 355.182255 -282.183495) (xy 355.218507 -282.144424)
			(xy 355.260178 -282.111193) (xy 355.306336 -282.084544) (xy 355.35595 -282.065072) (xy 355.407912 -282.053212)
			(xy 355.461062 -282.049229) (xy 355.514212 -282.053212) (xy 355.566174 -282.065072) (xy 355.615788 -282.084544)
			(xy 355.661946 -282.111193) (xy 355.703617 -282.144424) (xy 355.739869 -282.183495) (xy 355.769893 -282.227532)
			(xy 355.793019 -282.275553) (xy 355.808729 -282.326483) (xy 355.816672 -282.379187) (xy 355.81717 -282.405836)
			(xy 355.816672 -282.432485) (xy 357.924852 -282.432485) (xy 357.924852 -282.379187) (xy 357.932795 -282.326483)
			(xy 357.948505 -282.275553) (xy 357.971631 -282.227532) (xy 358.001655 -282.183495) (xy 358.037907 -282.144424)
			(xy 358.079578 -282.111193) (xy 358.125736 -282.084544) (xy 358.17535 -282.065072) (xy 358.227312 -282.053212)
			(xy 358.280462 -282.049229) (xy 358.333612 -282.053212) (xy 358.385574 -282.065072) (xy 358.435188 -282.084544)
			(xy 358.481346 -282.111193) (xy 358.523017 -282.144424) (xy 358.559269 -282.183495) (xy 358.589293 -282.227532)
			(xy 358.612419 -282.275553) (xy 358.628129 -282.326483) (xy 358.636072 -282.379187) (xy 358.63657 -282.405836)
			(xy 358.636072 -282.432485) (xy 358.628129 -282.485189) (xy 358.612419 -282.536119) (xy 358.589293 -282.58414)
			(xy 358.559269 -282.628177) (xy 358.523017 -282.667248) (xy 358.481346 -282.700479) (xy 358.435188 -282.727128)
			(xy 358.385574 -282.7466) (xy 358.333612 -282.75846) (xy 358.280462 -282.762444) (xy 358.227312 -282.75846)
			(xy 358.17535 -282.7466) (xy 358.125736 -282.727128) (xy 358.079578 -282.700479) (xy 358.037907 -282.667248)
			(xy 358.001655 -282.628177) (xy 357.971631 -282.58414) (xy 357.948505 -282.536119) (xy 357.932795 -282.485189)
			(xy 357.924852 -282.432485) (xy 355.816672 -282.432485) (xy 355.808729 -282.485189) (xy 355.793019 -282.536119)
			(xy 355.769893 -282.58414) (xy 355.739869 -282.628177) (xy 355.703617 -282.667248) (xy 355.661946 -282.700479)
			(xy 355.615788 -282.727128) (xy 355.566174 -282.7466) (xy 355.514212 -282.75846) (xy 355.461062 -282.762444)
			(xy 355.407912 -282.75846) (xy 355.35595 -282.7466) (xy 355.306336 -282.727128) (xy 355.260178 -282.700479)
			(xy 355.218507 -282.667248) (xy 355.182255 -282.628177) (xy 355.152231 -282.58414) (xy 355.129105 -282.536119)
			(xy 355.113395 -282.485189) (xy 355.105452 -282.432485) (xy 354.876872 -282.432485) (xy 354.876847 -282.433818)
			(xy 354.868086 -282.489093) (xy 354.850787 -282.542317) (xy 354.825374 -282.59218) (xy 354.792474 -282.637453)
			(xy 354.752897 -282.677022) (xy 354.707617 -282.709913) (xy 354.657749 -282.735315) (xy 354.604521 -282.752604)
			(xy 354.549245 -282.761353) (xy 354.521262 -282.761944) (xy 354.495371 -282.761483) (xy 354.444133 -282.753988)
			(xy 354.394523 -282.739149) (xy 354.347586 -282.717277) (xy 354.304314 -282.688835) (xy 354.26562 -282.654423)
			(xy 354.23232 -282.614767) (xy 354.205118 -282.570705) (xy 354.184588 -282.523166) (xy 354.171163 -282.473154)
			(xy 354.167694 -282.447492) (xy 354.16617 -282.436062) (xy 354.1649 -282.405836) (xy 354.165263 -282.382549)
			(xy 354.171299 -282.336368) (xy 354.183299 -282.291366) (xy 354.191824 -282.269692) (xy 354.201476 -282.246578)
			(xy 354.17887 -282.207208) (xy 354.154232 -282.165044) (xy 354.14719 -282.15374) (xy 354.128354 -282.134929)
			(xy 354.105297 -282.121623) (xy 354.079585 -282.114726) (xy 354.052964 -282.114706) (xy 354.027241 -282.121566)
			(xy 354.004165 -282.134838) (xy 353.994466 -282.143962) (xy 353.898454 -282.239974) (xy 353.911154 -282.271216)
			(xy 353.920426 -282.295103) (xy 353.932789 -282.344829) (xy 353.935792 -282.370276) (xy 353.93757 -282.405836)
			(xy 353.937123 -282.43145) (xy 353.929781 -282.48215) (xy 353.915252 -282.531276) (xy 353.893837 -282.577814)
			(xy 353.865977 -282.620804) (xy 353.832247 -282.659362) (xy 353.793342 -282.69269) (xy 353.750065 -282.720103)
			(xy 353.703308 -282.741035) (xy 353.654034 -282.755053) (xy 353.628706 -282.758896) (xy 353.604068 -282.762198)
			(xy 353.50958 -282.92552) (xy 353.431602 -283.060902) (xy 353.441 -283.084016) (xy 353.449517 -283.105648)
			(xy 353.461506 -283.150565) (xy 353.467552 -283.196661) (xy 353.467924 -283.219906) (xy 353.467401 -283.246555)
			(xy 353.695752 -283.246555) (xy 353.695752 -283.193257) (xy 353.703695 -283.140553) (xy 353.719405 -283.089623)
			(xy 353.742531 -283.041602) (xy 353.772555 -282.997565) (xy 353.808807 -282.958494) (xy 353.850478 -282.925263)
			(xy 353.896636 -282.898614) (xy 353.94625 -282.879142) (xy 353.998212 -282.867282) (xy 354.051362 -282.863299)
			(xy 354.104512 -282.867282) (xy 354.156474 -282.879142) (xy 354.206088 -282.898614) (xy 354.252246 -282.925263)
			(xy 354.293917 -282.958494) (xy 354.330169 -282.997565) (xy 354.360193 -283.041602) (xy 354.383319 -283.089623)
			(xy 354.399029 -283.140553) (xy 354.406972 -283.193257) (xy 354.40747 -283.219906) (xy 354.406972 -283.246555)
			(xy 354.635806 -283.246555) (xy 354.635806 -283.193257) (xy 354.643749 -283.140553) (xy 354.659459 -283.089623)
			(xy 354.682585 -283.041602) (xy 354.712609 -282.997565) (xy 354.748861 -282.958494) (xy 354.790532 -282.925263)
			(xy 354.83669 -282.898614) (xy 354.886304 -282.879142) (xy 354.938266 -282.867282) (xy 354.991416 -282.863299)
			(xy 355.044566 -282.867282) (xy 355.096528 -282.879142) (xy 355.146142 -282.898614) (xy 355.1923 -282.925263)
			(xy 355.233971 -282.958494) (xy 355.270223 -282.997565) (xy 355.300247 -283.041602) (xy 355.323373 -283.089623)
			(xy 355.339083 -283.140553) (xy 355.347026 -283.193257) (xy 355.347524 -283.219906) (xy 355.347026 -283.246555)
			(xy 361.214152 -283.246555) (xy 361.214152 -283.193257) (xy 361.222095 -283.140553) (xy 361.237805 -283.089623)
			(xy 361.260931 -283.041602) (xy 361.290955 -282.997565) (xy 361.327207 -282.958494) (xy 361.368878 -282.925263)
			(xy 361.415036 -282.898614) (xy 361.46465 -282.879142) (xy 361.516612 -282.867282) (xy 361.569762 -282.863299)
			(xy 361.622912 -282.867282) (xy 361.674874 -282.879142) (xy 361.724488 -282.898614) (xy 361.770646 -282.925263)
			(xy 361.812317 -282.958494) (xy 361.848569 -282.997565) (xy 361.878593 -283.041602) (xy 361.901719 -283.089623)
			(xy 361.917429 -283.140553) (xy 361.925372 -283.193257) (xy 361.92587 -283.219906) (xy 361.925372 -283.246555)
			(xy 364.033806 -283.246555) (xy 364.033806 -283.193257) (xy 364.041749 -283.140553) (xy 364.057459 -283.089623)
			(xy 364.080585 -283.041602) (xy 364.110609 -282.997565) (xy 364.146861 -282.958494) (xy 364.188532 -282.925263)
			(xy 364.23469 -282.898614) (xy 364.284304 -282.879142) (xy 364.336266 -282.867282) (xy 364.389416 -282.863299)
			(xy 364.442566 -282.867282) (xy 364.494528 -282.879142) (xy 364.544142 -282.898614) (xy 364.5903 -282.925263)
			(xy 364.631971 -282.958494) (xy 364.668223 -282.997565) (xy 364.698247 -283.041602) (xy 364.721373 -283.089623)
			(xy 364.737083 -283.140553) (xy 364.745026 -283.193257) (xy 364.745524 -283.219906) (xy 364.745026 -283.246555)
			(xy 364.737083 -283.299259) (xy 364.721373 -283.350189) (xy 364.698247 -283.39821) (xy 364.668223 -283.442247)
			(xy 364.631971 -283.481318) (xy 364.5903 -283.514549) (xy 364.544142 -283.541198) (xy 364.494528 -283.56067)
			(xy 364.442566 -283.57253) (xy 364.389416 -283.576514) (xy 364.336266 -283.57253) (xy 364.284304 -283.56067)
			(xy 364.23469 -283.541198) (xy 364.188532 -283.514549) (xy 364.146861 -283.481318) (xy 364.110609 -283.442247)
			(xy 364.080585 -283.39821) (xy 364.057459 -283.350189) (xy 364.041749 -283.299259) (xy 364.033806 -283.246555)
			(xy 361.925372 -283.246555) (xy 361.917429 -283.299259) (xy 361.901719 -283.350189) (xy 361.878593 -283.39821)
			(xy 361.848569 -283.442247) (xy 361.812317 -283.481318) (xy 361.770646 -283.514549) (xy 361.724488 -283.541198)
			(xy 361.674874 -283.56067) (xy 361.622912 -283.57253) (xy 361.569762 -283.576514) (xy 361.516612 -283.57253)
			(xy 361.46465 -283.56067) (xy 361.415036 -283.541198) (xy 361.368878 -283.514549) (xy 361.327207 -283.481318)
			(xy 361.290955 -283.442247) (xy 361.260931 -283.39821) (xy 361.237805 -283.350189) (xy 361.222095 -283.299259)
			(xy 361.214152 -283.246555) (xy 355.347026 -283.246555) (xy 355.339083 -283.299259) (xy 355.323373 -283.350189)
			(xy 355.300247 -283.39821) (xy 355.270223 -283.442247) (xy 355.233971 -283.481318) (xy 355.1923 -283.514549)
			(xy 355.146142 -283.541198) (xy 355.096528 -283.56067) (xy 355.044566 -283.57253) (xy 354.991416 -283.576514)
			(xy 354.938266 -283.57253) (xy 354.886304 -283.56067) (xy 354.83669 -283.541198) (xy 354.790532 -283.514549)
			(xy 354.748861 -283.481318) (xy 354.712609 -283.442247) (xy 354.682585 -283.39821) (xy 354.659459 -283.350189)
			(xy 354.643749 -283.299259) (xy 354.635806 -283.246555) (xy 354.406972 -283.246555) (xy 354.399029 -283.299259)
			(xy 354.383319 -283.350189) (xy 354.360193 -283.39821) (xy 354.330169 -283.442247) (xy 354.293917 -283.481318)
			(xy 354.252246 -283.514549) (xy 354.206088 -283.541198) (xy 354.156474 -283.56067) (xy 354.104512 -283.57253)
			(xy 354.051362 -283.576514) (xy 353.998212 -283.57253) (xy 353.94625 -283.56067) (xy 353.896636 -283.541198)
			(xy 353.850478 -283.514549) (xy 353.808807 -283.481318) (xy 353.772555 -283.442247) (xy 353.742531 -283.39821)
			(xy 353.719405 -283.350189) (xy 353.703695 -283.299259) (xy 353.695752 -283.246555) (xy 353.467401 -283.246555)
			(xy 353.467375 -283.247889) (xy 353.458619 -283.303167) (xy 353.441324 -283.356394) (xy 353.415916 -283.40626)
			(xy 353.38302 -283.451539) (xy 353.343446 -283.491113) (xy 353.298169 -283.524011) (xy 353.248303 -283.54942)
			(xy 353.195076 -283.566717) (xy 353.139799 -283.575474) (xy 353.111816 -283.576014) (xy 353.085966 -283.575552)
			(xy 353.03481 -283.568072) (xy 352.985275 -283.553267) (xy 352.938404 -283.531449) (xy 352.895184 -283.503078)
			(xy 352.856525 -283.46875) (xy 352.839528 -283.449268) (xy 352.829948 -283.439419) (xy 352.806712 -283.42478)
			(xy 352.780414 -283.416864) (xy 352.752957 -283.416243) (xy 352.726329 -283.422963) (xy 352.702455 -283.436538)
			(xy 352.692462 -283.445966) (xy 352.630232 -283.508196) (xy 352.62055 -283.518515) (xy 352.606789 -283.543228)
			(xy 352.600347 -283.570771) (xy 352.601719 -283.599023) (xy 352.610799 -283.625812) (xy 352.626888 -283.649076)
			(xy 352.64875 -283.667025) (xy 352.674701 -283.678277) (xy 352.688652 -283.680662) (xy 352.713997 -283.684484)
			(xy 352.76331 -283.698459) (xy 352.81011 -283.71936) (xy 352.85343 -283.746756) (xy 352.892373 -283.780081)
			(xy 352.926135 -283.818645) (xy 352.954019 -283.861652) (xy 352.975447 -283.908213) (xy 352.989978 -283.957366)
			(xy 352.99731 -284.008094) (xy 352.99777 -284.033722) (xy 352.997273 -284.060371) (xy 353.225852 -284.060371)
			(xy 353.225852 -284.007073) (xy 353.233795 -283.954369) (xy 353.249505 -283.903439) (xy 353.272631 -283.855418)
			(xy 353.302655 -283.811381) (xy 353.338907 -283.77231) (xy 353.380578 -283.739079) (xy 353.426736 -283.71243)
			(xy 353.47635 -283.692958) (xy 353.528312 -283.681098) (xy 353.581462 -283.677115) (xy 353.634612 -283.681098)
			(xy 353.686574 -283.692958) (xy 353.736188 -283.71243) (xy 353.782346 -283.739079) (xy 353.824017 -283.77231)
			(xy 353.860269 -283.811381) (xy 353.890293 -283.855418) (xy 353.913419 -283.903439) (xy 353.929129 -283.954369)
			(xy 353.937072 -284.007073) (xy 353.93757 -284.033722) (xy 353.937072 -284.060371) (xy 355.105452 -284.060371)
			(xy 355.105452 -284.007073) (xy 355.113395 -283.954369) (xy 355.129105 -283.903439) (xy 355.152231 -283.855418)
			(xy 355.182255 -283.811381) (xy 355.218507 -283.77231) (xy 355.260178 -283.739079) (xy 355.306336 -283.71243)
			(xy 355.35595 -283.692958) (xy 355.407912 -283.681098) (xy 355.461062 -283.677115) (xy 355.514212 -283.681098)
			(xy 355.566174 -283.692958) (xy 355.615788 -283.71243) (xy 355.661946 -283.739079) (xy 355.703617 -283.77231)
			(xy 355.739869 -283.811381) (xy 355.769893 -283.855418) (xy 355.793019 -283.903439) (xy 355.808729 -283.954369)
			(xy 355.816672 -284.007073) (xy 355.81717 -284.033722) (xy 355.816672 -284.060371) (xy 357.924852 -284.060371)
			(xy 357.924852 -284.007073) (xy 357.932795 -283.954369) (xy 357.948505 -283.903439) (xy 357.971631 -283.855418)
			(xy 358.001655 -283.811381) (xy 358.037907 -283.77231) (xy 358.079578 -283.739079) (xy 358.125736 -283.71243)
			(xy 358.17535 -283.692958) (xy 358.227312 -283.681098) (xy 358.280462 -283.677115) (xy 358.333612 -283.681098)
			(xy 358.385574 -283.692958) (xy 358.435188 -283.71243) (xy 358.481346 -283.739079) (xy 358.523017 -283.77231)
			(xy 358.559269 -283.811381) (xy 358.589293 -283.855418) (xy 358.612419 -283.903439) (xy 358.628129 -283.954369)
			(xy 358.636072 -284.007073) (xy 358.63657 -284.033722) (xy 358.636072 -284.060371) (xy 358.628129 -284.113075)
			(xy 358.612419 -284.164005) (xy 358.589293 -284.212026) (xy 358.559269 -284.256063) (xy 358.523017 -284.295134)
			(xy 358.481346 -284.328365) (xy 358.435188 -284.355014) (xy 358.385574 -284.374486) (xy 358.333612 -284.386346)
			(xy 358.280462 -284.39033) (xy 358.227312 -284.386346) (xy 358.17535 -284.374486) (xy 358.125736 -284.355014)
			(xy 358.079578 -284.328365) (xy 358.037907 -284.295134) (xy 358.001655 -284.256063) (xy 357.971631 -284.212026)
			(xy 357.948505 -284.164005) (xy 357.932795 -284.113075) (xy 357.924852 -284.060371) (xy 355.816672 -284.060371)
			(xy 355.808729 -284.113075) (xy 355.793019 -284.164005) (xy 355.769893 -284.212026) (xy 355.739869 -284.256063)
			(xy 355.703617 -284.295134) (xy 355.661946 -284.328365) (xy 355.615788 -284.355014) (xy 355.566174 -284.374486)
			(xy 355.514212 -284.386346) (xy 355.461062 -284.39033) (xy 355.407912 -284.386346) (xy 355.35595 -284.374486)
			(xy 355.306336 -284.355014) (xy 355.260178 -284.328365) (xy 355.218507 -284.295134) (xy 355.182255 -284.256063)
			(xy 355.152231 -284.212026) (xy 355.129105 -284.164005) (xy 355.113395 -284.113075) (xy 355.105452 -284.060371)
			(xy 353.937072 -284.060371) (xy 353.929129 -284.113075) (xy 353.913419 -284.164005) (xy 353.890293 -284.212026)
			(xy 353.860269 -284.256063) (xy 353.824017 -284.295134) (xy 353.782346 -284.328365) (xy 353.736188 -284.355014)
			(xy 353.686574 -284.374486) (xy 353.634612 -284.386346) (xy 353.581462 -284.39033) (xy 353.528312 -284.386346)
			(xy 353.47635 -284.374486) (xy 353.426736 -284.355014) (xy 353.380578 -284.328365) (xy 353.338907 -284.295134)
			(xy 353.302655 -284.256063) (xy 353.272631 -284.212026) (xy 353.249505 -284.164005) (xy 353.233795 -284.113075)
			(xy 353.225852 -284.060371) (xy 352.997273 -284.060371) (xy 352.997248 -284.061705) (xy 352.988489 -284.116982)
			(xy 352.971191 -284.170208) (xy 352.945779 -284.220072) (xy 352.912879 -284.265347) (xy 352.873302 -284.304918)
			(xy 352.828021 -284.33781) (xy 352.778152 -284.363214) (xy 352.724923 -284.380503) (xy 352.669645 -284.389252)
			(xy 352.641662 -284.38983) (xy 352.615246 -284.388814) (xy 352.601312 -284.388239) (xy 352.574 -284.39382)
			(xy 352.549215 -284.406582) (xy 352.528808 -284.425574) (xy 352.5143 -284.449379) (xy 352.506774 -284.476221)
			(xy 352.50628 -284.49016) (xy 352.50628 -284.724348) (xy 352.509074 -284.732476) (xy 352.517958 -284.760409)
			(xy 352.527533 -284.818233) (xy 352.528124 -284.847538) (xy 352.527604 -284.874187) (xy 352.755952 -284.874187)
			(xy 352.755952 -284.820889) (xy 352.763895 -284.768185) (xy 352.779605 -284.717255) (xy 352.802731 -284.669234)
			(xy 352.832755 -284.625197) (xy 352.869007 -284.586126) (xy 352.910678 -284.552895) (xy 352.956836 -284.526246)
			(xy 353.00645 -284.506774) (xy 353.058412 -284.494914) (xy 353.111562 -284.490931) (xy 353.164712 -284.494914)
			(xy 353.216674 -284.506774) (xy 353.266288 -284.526246) (xy 353.312446 -284.552895) (xy 353.354117 -284.586126)
			(xy 353.390369 -284.625197) (xy 353.420393 -284.669234) (xy 353.443519 -284.717255) (xy 353.459229 -284.768185)
			(xy 353.467172 -284.820889) (xy 353.46767 -284.847538) (xy 353.467172 -284.874187) (xy 361.214152 -284.874187)
			(xy 361.214152 -284.820889) (xy 361.222095 -284.768185) (xy 361.237805 -284.717255) (xy 361.260931 -284.669234)
			(xy 361.290955 -284.625197) (xy 361.327207 -284.586126) (xy 361.368878 -284.552895) (xy 361.415036 -284.526246)
			(xy 361.46465 -284.506774) (xy 361.516612 -284.494914) (xy 361.569762 -284.490931) (xy 361.622912 -284.494914)
			(xy 361.674874 -284.506774) (xy 361.724488 -284.526246) (xy 361.770646 -284.552895) (xy 361.812317 -284.586126)
			(xy 361.848569 -284.625197) (xy 361.878593 -284.669234) (xy 361.901719 -284.717255) (xy 361.917429 -284.768185)
			(xy 361.925372 -284.820889) (xy 361.92587 -284.847538) (xy 361.925372 -284.874187) (xy 364.033806 -284.874187)
			(xy 364.033806 -284.820889) (xy 364.041749 -284.768185) (xy 364.057459 -284.717255) (xy 364.080585 -284.669234)
			(xy 364.110609 -284.625197) (xy 364.146861 -284.586126) (xy 364.188532 -284.552895) (xy 364.23469 -284.526246)
			(xy 364.284304 -284.506774) (xy 364.336266 -284.494914) (xy 364.389416 -284.490931) (xy 364.442566 -284.494914)
			(xy 364.494528 -284.506774) (xy 364.544142 -284.526246) (xy 364.5903 -284.552895) (xy 364.631971 -284.586126)
			(xy 364.668223 -284.625197) (xy 364.698247 -284.669234) (xy 364.721373 -284.717255) (xy 364.737083 -284.768185)
			(xy 364.745026 -284.820889) (xy 364.745524 -284.847538) (xy 364.745026 -284.874187) (xy 364.737083 -284.926891)
			(xy 364.721373 -284.977821) (xy 364.698247 -285.025842) (xy 364.668223 -285.069879) (xy 364.631971 -285.10895)
			(xy 364.5903 -285.142181) (xy 364.544142 -285.16883) (xy 364.494528 -285.188302) (xy 364.442566 -285.200162)
			(xy 364.389416 -285.204146) (xy 364.336266 -285.200162) (xy 364.284304 -285.188302) (xy 364.23469 -285.16883)
			(xy 364.188532 -285.142181) (xy 364.146861 -285.10895) (xy 364.110609 -285.069879) (xy 364.080585 -285.025842)
			(xy 364.057459 -284.977821) (xy 364.041749 -284.926891) (xy 364.033806 -284.874187) (xy 361.925372 -284.874187)
			(xy 361.917429 -284.926891) (xy 361.901719 -284.977821) (xy 361.878593 -285.025842) (xy 361.848569 -285.069879)
			(xy 361.812317 -285.10895) (xy 361.770646 -285.142181) (xy 361.724488 -285.16883) (xy 361.674874 -285.188302)
			(xy 361.622912 -285.200162) (xy 361.569762 -285.204146) (xy 361.516612 -285.200162) (xy 361.46465 -285.188302)
			(xy 361.415036 -285.16883) (xy 361.368878 -285.142181) (xy 361.327207 -285.10895) (xy 361.290955 -285.069879)
			(xy 361.260931 -285.025842) (xy 361.237805 -284.977821) (xy 361.222095 -284.926891) (xy 361.214152 -284.874187)
			(xy 353.467172 -284.874187) (xy 353.459229 -284.926891) (xy 353.443519 -284.977821) (xy 353.420393 -285.025842)
			(xy 353.390369 -285.069879) (xy 353.354117 -285.10895) (xy 353.312446 -285.142181) (xy 353.266288 -285.16883)
			(xy 353.216674 -285.188302) (xy 353.164712 -285.200162) (xy 353.111562 -285.204146) (xy 353.058412 -285.200162)
			(xy 353.00645 -285.188302) (xy 352.956836 -285.16883) (xy 352.910678 -285.142181) (xy 352.869007 -285.10895)
			(xy 352.832755 -285.069879) (xy 352.802731 -285.025842) (xy 352.779605 -284.977821) (xy 352.763895 -284.926891)
			(xy 352.755952 -284.874187) (xy 352.527604 -284.874187) (xy 352.527552 -284.876846) (xy 352.517981 -284.934673)
			(xy 352.509074 -284.9626) (xy 352.50628 -284.970728) (xy 352.50628 -285.204916) (xy 352.506716 -285.218857)
			(xy 352.51426 -285.2457) (xy 352.528782 -285.269502) (xy 352.549199 -285.28849) (xy 352.573991 -285.30125)
			(xy 352.601309 -285.30683) (xy 352.615246 -285.306262) (xy 352.641662 -285.305246) (xy 352.668318 -285.305717)
			(xy 352.721037 -285.313657) (xy 352.771982 -285.329367) (xy 352.820017 -285.352495) (xy 352.864068 -285.382524)
			(xy 352.903151 -285.418784) (xy 352.936393 -285.460464) (xy 352.963051 -285.506633) (xy 352.98253 -285.55626)
			(xy 352.994394 -285.608236) (xy 352.998378 -285.6614) (xy 352.996384 -285.688003) (xy 355.105452 -285.688003)
			(xy 355.105452 -285.634705) (xy 355.113395 -285.582001) (xy 355.129105 -285.531071) (xy 355.152231 -285.48305)
			(xy 355.182255 -285.439013) (xy 355.218507 -285.399942) (xy 355.260178 -285.366711) (xy 355.306336 -285.340062)
			(xy 355.35595 -285.32059) (xy 355.407912 -285.30873) (xy 355.461062 -285.304747) (xy 355.514212 -285.30873)
			(xy 355.566174 -285.32059) (xy 355.615788 -285.340062) (xy 355.661946 -285.366711) (xy 355.703617 -285.399942)
			(xy 355.739869 -285.439013) (xy 355.769893 -285.48305) (xy 355.793019 -285.531071) (xy 355.808729 -285.582001)
			(xy 355.816672 -285.634705) (xy 355.81717 -285.661354) (xy 355.816672 -285.688003) (xy 357.924852 -285.688003)
			(xy 357.924852 -285.634705) (xy 357.932795 -285.582001) (xy 357.948505 -285.531071) (xy 357.971631 -285.48305)
			(xy 358.001655 -285.439013) (xy 358.037907 -285.399942) (xy 358.079578 -285.366711) (xy 358.125736 -285.340062)
			(xy 358.17535 -285.32059) (xy 358.227312 -285.30873) (xy 358.280462 -285.304747) (xy 358.333612 -285.30873)
			(xy 358.385574 -285.32059) (xy 358.435188 -285.340062) (xy 358.481346 -285.366711) (xy 358.523017 -285.399942)
			(xy 358.559269 -285.439013) (xy 358.589293 -285.48305) (xy 358.612419 -285.531071) (xy 358.628129 -285.582001)
			(xy 358.636072 -285.634705) (xy 358.63657 -285.661354) (xy 358.636072 -285.688003) (xy 358.628129 -285.740707)
			(xy 358.612419 -285.791637) (xy 358.589293 -285.839658) (xy 358.559269 -285.883695) (xy 358.523017 -285.922766)
			(xy 358.481346 -285.955997) (xy 358.435188 -285.982646) (xy 358.385574 -286.002118) (xy 358.333612 -286.013978)
			(xy 358.280462 -286.017962) (xy 358.227312 -286.013978) (xy 358.17535 -286.002118) (xy 358.125736 -285.982646)
			(xy 358.079578 -285.955997) (xy 358.037907 -285.922766) (xy 358.001655 -285.883695) (xy 357.971631 -285.839658)
			(xy 357.948505 -285.791637) (xy 357.932795 -285.740707) (xy 357.924852 -285.688003) (xy 355.816672 -285.688003)
			(xy 355.808729 -285.740707) (xy 355.793019 -285.791637) (xy 355.769893 -285.839658) (xy 355.739869 -285.883695)
			(xy 355.703617 -285.922766) (xy 355.661946 -285.955997) (xy 355.615788 -285.982646) (xy 355.566174 -286.002118)
			(xy 355.514212 -286.013978) (xy 355.461062 -286.017962) (xy 355.407912 -286.013978) (xy 355.35595 -286.002118)
			(xy 355.306336 -285.982646) (xy 355.260178 -285.955997) (xy 355.218507 -285.922766) (xy 355.182255 -285.883695)
			(xy 355.152231 -285.839658) (xy 355.129105 -285.791637) (xy 355.113395 -285.740707) (xy 355.105452 -285.688003)
			(xy 352.996384 -285.688003) (xy 352.994394 -285.714564) (xy 352.98253 -285.76654) (xy 352.963051 -285.816167)
			(xy 352.936393 -285.862336) (xy 352.903151 -285.904016) (xy 352.864068 -285.940276) (xy 352.820017 -285.970305)
			(xy 352.771982 -285.993433) (xy 352.721037 -286.009143) (xy 352.668318 -286.017083) (xy 352.641662 -286.017462)
			(xy 352.615246 -286.016446) (xy 352.601309 -286.01587) (xy 352.573989 -286.021451) (xy 352.549197 -286.034212)
			(xy 352.528779 -286.053202) (xy 352.514258 -286.077006) (xy 352.506715 -286.10385) (xy 352.50628 -286.117792)
			(xy 352.50628 -286.352742) (xy 352.509074 -286.360616) (xy 352.517851 -286.388307) (xy 352.527293 -286.445619)
			(xy 352.52787 -286.474662) (xy 352.52787 -286.475424) (xy 352.52787 -286.476186) (xy 352.527338 -286.502073)
			(xy 352.756206 -286.502073) (xy 352.756206 -286.448775) (xy 352.764149 -286.396071) (xy 352.779859 -286.345141)
			(xy 352.802985 -286.29712) (xy 352.833009 -286.253083) (xy 352.869261 -286.214012) (xy 352.910932 -286.180781)
			(xy 352.95709 -286.154132) (xy 353.006704 -286.13466) (xy 353.058666 -286.1228) (xy 353.111816 -286.118817)
			(xy 353.164966 -286.1228) (xy 353.216928 -286.13466) (xy 353.266542 -286.154132) (xy 353.3127 -286.180781)
			(xy 353.354371 -286.214012) (xy 353.390623 -286.253083) (xy 353.420647 -286.29712) (xy 353.443773 -286.345141)
			(xy 353.459483 -286.396071) (xy 353.467426 -286.448775) (xy 353.467924 -286.475424) (xy 353.467426 -286.502073)
			(xy 361.214152 -286.502073) (xy 361.214152 -286.448775) (xy 361.222095 -286.396071) (xy 361.237805 -286.345141)
			(xy 361.260931 -286.29712) (xy 361.290955 -286.253083) (xy 361.327207 -286.214012) (xy 361.368878 -286.180781)
			(xy 361.415036 -286.154132) (xy 361.46465 -286.13466) (xy 361.516612 -286.1228) (xy 361.569762 -286.118817)
			(xy 361.622912 -286.1228) (xy 361.674874 -286.13466) (xy 361.724488 -286.154132) (xy 361.770646 -286.180781)
			(xy 361.812317 -286.214012) (xy 361.848569 -286.253083) (xy 361.878593 -286.29712) (xy 361.901719 -286.345141)
			(xy 361.917429 -286.396071) (xy 361.925372 -286.448775) (xy 361.92587 -286.475424) (xy 361.925372 -286.502073)
			(xy 364.033806 -286.502073) (xy 364.033806 -286.448775) (xy 364.041749 -286.396071) (xy 364.057459 -286.345141)
			(xy 364.080585 -286.29712) (xy 364.110609 -286.253083) (xy 364.146861 -286.214012) (xy 364.188532 -286.180781)
			(xy 364.23469 -286.154132) (xy 364.284304 -286.13466) (xy 364.336266 -286.1228) (xy 364.389416 -286.118817)
			(xy 364.442566 -286.1228) (xy 364.494528 -286.13466) (xy 364.544142 -286.154132) (xy 364.5903 -286.180781)
			(xy 364.631971 -286.214012) (xy 364.668223 -286.253083) (xy 364.698247 -286.29712) (xy 364.721373 -286.345141)
			(xy 364.737083 -286.396071) (xy 364.745026 -286.448775) (xy 364.745524 -286.475424) (xy 364.745026 -286.502073)
			(xy 364.737083 -286.554777) (xy 364.721373 -286.605707) (xy 364.698247 -286.653728) (xy 364.668223 -286.697765)
			(xy 364.631971 -286.736836) (xy 364.5903 -286.770067) (xy 364.544142 -286.796716) (xy 364.494528 -286.816188)
			(xy 364.442566 -286.828048) (xy 364.389416 -286.832032) (xy 364.336266 -286.828048) (xy 364.284304 -286.816188)
			(xy 364.23469 -286.796716) (xy 364.188532 -286.770067) (xy 364.146861 -286.736836) (xy 364.110609 -286.697765)
			(xy 364.080585 -286.653728) (xy 364.057459 -286.605707) (xy 364.041749 -286.554777) (xy 364.033806 -286.502073)
			(xy 361.925372 -286.502073) (xy 361.917429 -286.554777) (xy 361.901719 -286.605707) (xy 361.878593 -286.653728)
			(xy 361.848569 -286.697765) (xy 361.812317 -286.736836) (xy 361.770646 -286.770067) (xy 361.724488 -286.796716)
			(xy 361.674874 -286.816188) (xy 361.622912 -286.828048) (xy 361.569762 -286.832032) (xy 361.516612 -286.828048)
			(xy 361.46465 -286.816188) (xy 361.415036 -286.796716) (xy 361.368878 -286.770067) (xy 361.327207 -286.736836)
			(xy 361.290955 -286.697765) (xy 361.260931 -286.653728) (xy 361.237805 -286.605707) (xy 361.222095 -286.554777)
			(xy 361.214152 -286.502073) (xy 353.467426 -286.502073) (xy 353.459483 -286.554777) (xy 353.443773 -286.605707)
			(xy 353.420647 -286.653728) (xy 353.390623 -286.697765) (xy 353.354371 -286.736836) (xy 353.3127 -286.770067)
			(xy 353.266542 -286.796716) (xy 353.216928 -286.816188) (xy 353.164966 -286.828048) (xy 353.111816 -286.832032)
			(xy 353.058666 -286.828048) (xy 353.006704 -286.816188) (xy 352.95709 -286.796716) (xy 352.910932 -286.770067)
			(xy 352.869261 -286.736836) (xy 352.833009 -286.697765) (xy 352.802985 -286.653728) (xy 352.779859 -286.605707)
			(xy 352.764149 -286.554777) (xy 352.756206 -286.502073) (xy 352.527338 -286.502073) (xy 352.527273 -286.505227)
			(xy 352.517829 -286.562536) (xy 352.509074 -286.590232) (xy 352.50628 -286.598106) (xy 352.50628 -286.832802)
			(xy 352.506717 -286.846765) (xy 352.514281 -286.873649) (xy 352.528844 -286.897478) (xy 352.549317 -286.916472)
			(xy 352.574169 -286.929212) (xy 352.601542 -286.934744) (xy 352.6155 -286.934148) (xy 352.641916 -286.933132)
			(xy 352.668562 -286.933631) (xy 352.721257 -286.941576) (xy 352.77218 -286.957286) (xy 352.820193 -286.980409)
			(xy 352.864223 -287.01043) (xy 352.903287 -287.046678) (xy 352.936513 -287.088344) (xy 352.963158 -287.134496)
			(xy 352.982627 -287.184103) (xy 352.994485 -287.236058) (xy 352.998467 -287.2892) (xy 352.996467 -287.315889)
			(xy 355.105452 -287.315889) (xy 355.105452 -287.262591) (xy 355.113395 -287.209887) (xy 355.129105 -287.158957)
			(xy 355.152231 -287.110936) (xy 355.182255 -287.066899) (xy 355.218507 -287.027828) (xy 355.260178 -286.994597)
			(xy 355.306336 -286.967948) (xy 355.35595 -286.948476) (xy 355.407912 -286.936616) (xy 355.461062 -286.932633)
			(xy 355.514212 -286.936616) (xy 355.566174 -286.948476) (xy 355.615788 -286.967948) (xy 355.661946 -286.994597)
			(xy 355.703617 -287.027828) (xy 355.739869 -287.066899) (xy 355.769893 -287.110936) (xy 355.793019 -287.158957)
			(xy 355.808729 -287.209887) (xy 355.816672 -287.262591) (xy 355.81717 -287.28924) (xy 355.816672 -287.315889)
			(xy 357.924852 -287.315889) (xy 357.924852 -287.262591) (xy 357.932795 -287.209887) (xy 357.948505 -287.158957)
			(xy 357.971631 -287.110936) (xy 358.001655 -287.066899) (xy 358.037907 -287.027828) (xy 358.079578 -286.994597)
			(xy 358.125736 -286.967948) (xy 358.17535 -286.948476) (xy 358.227312 -286.936616) (xy 358.280462 -286.932633)
			(xy 358.333612 -286.936616) (xy 358.385574 -286.948476) (xy 358.435188 -286.967948) (xy 358.481346 -286.994597)
			(xy 358.523017 -287.027828) (xy 358.559269 -287.066899) (xy 358.589293 -287.110936) (xy 358.612419 -287.158957)
			(xy 358.628129 -287.209887) (xy 358.636072 -287.262591) (xy 358.63657 -287.28924) (xy 358.636072 -287.315889)
			(xy 358.628129 -287.368593) (xy 358.612419 -287.419523) (xy 358.589293 -287.467544) (xy 358.559269 -287.511581)
			(xy 358.523017 -287.550652) (xy 358.481346 -287.583883) (xy 358.435188 -287.610532) (xy 358.385574 -287.630004)
			(xy 358.333612 -287.641864) (xy 358.280462 -287.645848) (xy 358.227312 -287.641864) (xy 358.17535 -287.630004)
			(xy 358.125736 -287.610532) (xy 358.079578 -287.583883) (xy 358.037907 -287.550652) (xy 358.001655 -287.511581)
			(xy 357.971631 -287.467544) (xy 357.948505 -287.419523) (xy 357.932795 -287.368593) (xy 357.924852 -287.315889)
			(xy 355.816672 -287.315889) (xy 355.808729 -287.368593) (xy 355.793019 -287.419523) (xy 355.769893 -287.467544)
			(xy 355.739869 -287.511581) (xy 355.703617 -287.550652) (xy 355.661946 -287.583883) (xy 355.615788 -287.610532)
			(xy 355.566174 -287.630004) (xy 355.514212 -287.641864) (xy 355.461062 -287.645848) (xy 355.407912 -287.641864)
			(xy 355.35595 -287.630004) (xy 355.306336 -287.610532) (xy 355.260178 -287.583883) (xy 355.218507 -287.550652)
			(xy 355.182255 -287.511581) (xy 355.152231 -287.467544) (xy 355.129105 -287.419523) (xy 355.113395 -287.368593)
			(xy 355.105452 -287.315889) (xy 352.996467 -287.315889) (xy 352.994485 -287.342342) (xy 352.982627 -287.394297)
			(xy 352.963158 -287.443905) (xy 352.936513 -287.490056) (xy 352.903287 -287.531722) (xy 352.864223 -287.56797)
			(xy 352.820193 -287.597991) (xy 352.77218 -287.621114) (xy 352.721257 -287.636824) (xy 352.668561 -287.644769)
			(xy 352.641916 -287.645348) (xy 352.6155 -287.644332) (xy 352.601545 -287.643723) (xy 352.574176 -287.649257)
			(xy 352.549331 -287.662) (xy 352.528868 -287.680999) (xy 352.51432 -287.704832) (xy 352.506774 -287.731716)
			(xy 352.50628 -287.745678) (xy 352.50628 -287.979866) (xy 352.509074 -287.987994) (xy 352.517957 -288.015927)
			(xy 352.527529 -288.073751) (xy 352.528124 -288.103056) (xy 352.527602 -288.129705) (xy 352.756206 -288.129705)
			(xy 352.756206 -288.076407) (xy 352.764149 -288.023703) (xy 352.779859 -287.972773) (xy 352.802985 -287.924752)
			(xy 352.833009 -287.880715) (xy 352.869261 -287.841644) (xy 352.910932 -287.808413) (xy 352.95709 -287.781764)
			(xy 353.006704 -287.762292) (xy 353.058666 -287.750432) (xy 353.111816 -287.746449) (xy 353.164966 -287.750432)
			(xy 353.216928 -287.762292) (xy 353.266542 -287.781764) (xy 353.3127 -287.808413) (xy 353.354371 -287.841644)
			(xy 353.390623 -287.880715) (xy 353.420647 -287.924752) (xy 353.443773 -287.972773) (xy 353.459483 -288.023703)
			(xy 353.467426 -288.076407) (xy 353.467924 -288.103056) (xy 353.467426 -288.129705) (xy 361.214152 -288.129705)
			(xy 361.214152 -288.076407) (xy 361.222095 -288.023703) (xy 361.237805 -287.972773) (xy 361.260931 -287.924752)
			(xy 361.290955 -287.880715) (xy 361.327207 -287.841644) (xy 361.368878 -287.808413) (xy 361.415036 -287.781764)
			(xy 361.46465 -287.762292) (xy 361.516612 -287.750432) (xy 361.569762 -287.746449) (xy 361.622912 -287.750432)
			(xy 361.674874 -287.762292) (xy 361.724488 -287.781764) (xy 361.770646 -287.808413) (xy 361.812317 -287.841644)
			(xy 361.848569 -287.880715) (xy 361.878593 -287.924752) (xy 361.901719 -287.972773) (xy 361.917429 -288.023703)
			(xy 361.925372 -288.076407) (xy 361.92587 -288.103056) (xy 361.925372 -288.129705) (xy 364.033806 -288.129705)
			(xy 364.033806 -288.076407) (xy 364.041749 -288.023703) (xy 364.057459 -287.972773) (xy 364.080585 -287.924752)
			(xy 364.110609 -287.880715) (xy 364.146861 -287.841644) (xy 364.188532 -287.808413) (xy 364.23469 -287.781764)
			(xy 364.284304 -287.762292) (xy 364.336266 -287.750432) (xy 364.389416 -287.746449) (xy 364.442566 -287.750432)
			(xy 364.494528 -287.762292) (xy 364.544142 -287.781764) (xy 364.5903 -287.808413) (xy 364.631971 -287.841644)
			(xy 364.668223 -287.880715) (xy 364.698247 -287.924752) (xy 364.721373 -287.972773) (xy 364.737083 -288.023703)
			(xy 364.745026 -288.076407) (xy 364.745524 -288.103056) (xy 364.745026 -288.129705) (xy 367.792752 -288.129705)
			(xy 367.792752 -288.076407) (xy 367.800695 -288.023703) (xy 367.816405 -287.972773) (xy 367.839531 -287.924752)
			(xy 367.869555 -287.880715) (xy 367.905807 -287.841644) (xy 367.947478 -287.808413) (xy 367.993636 -287.781764)
			(xy 368.04325 -287.762292) (xy 368.095212 -287.750432) (xy 368.148362 -287.746449) (xy 368.201512 -287.750432)
			(xy 368.253474 -287.762292) (xy 368.303088 -287.781764) (xy 368.349246 -287.808413) (xy 368.390917 -287.841644)
			(xy 368.427169 -287.880715) (xy 368.457193 -287.924752) (xy 368.480319 -287.972773) (xy 368.496029 -288.023703)
			(xy 368.503972 -288.076407) (xy 368.50447 -288.103056) (xy 368.503972 -288.129705) (xy 368.496029 -288.182409)
			(xy 368.480319 -288.233339) (xy 368.457193 -288.28136) (xy 368.427169 -288.325397) (xy 368.390917 -288.364468)
			(xy 368.349246 -288.397699) (xy 368.303088 -288.424348) (xy 368.253474 -288.44382) (xy 368.201512 -288.45568)
			(xy 368.148362 -288.459664) (xy 368.095212 -288.45568) (xy 368.04325 -288.44382) (xy 367.993636 -288.424348)
			(xy 367.947478 -288.397699) (xy 367.905807 -288.364468) (xy 367.869555 -288.325397) (xy 367.839531 -288.28136)
			(xy 367.816405 -288.233339) (xy 367.800695 -288.182409) (xy 367.792752 -288.129705) (xy 364.745026 -288.129705)
			(xy 364.737083 -288.182409) (xy 364.721373 -288.233339) (xy 364.698247 -288.28136) (xy 364.668223 -288.325397)
			(xy 364.631971 -288.364468) (xy 364.5903 -288.397699) (xy 364.544142 -288.424348) (xy 364.494528 -288.44382)
			(xy 364.442566 -288.45568) (xy 364.389416 -288.459664) (xy 364.336266 -288.45568) (xy 364.284304 -288.44382)
			(xy 364.23469 -288.424348) (xy 364.188532 -288.397699) (xy 364.146861 -288.364468) (xy 364.110609 -288.325397)
			(xy 364.080585 -288.28136) (xy 364.057459 -288.233339) (xy 364.041749 -288.182409) (xy 364.033806 -288.129705)
			(xy 361.925372 -288.129705) (xy 361.917429 -288.182409) (xy 361.901719 -288.233339) (xy 361.878593 -288.28136)
			(xy 361.848569 -288.325397) (xy 361.812317 -288.364468) (xy 361.770646 -288.397699) (xy 361.724488 -288.424348)
			(xy 361.674874 -288.44382) (xy 361.622912 -288.45568) (xy 361.569762 -288.459664) (xy 361.516612 -288.45568)
			(xy 361.46465 -288.44382) (xy 361.415036 -288.424348) (xy 361.368878 -288.397699) (xy 361.327207 -288.364468)
			(xy 361.290955 -288.325397) (xy 361.260931 -288.28136) (xy 361.237805 -288.233339) (xy 361.222095 -288.182409)
			(xy 361.214152 -288.129705) (xy 353.467426 -288.129705) (xy 353.459483 -288.182409) (xy 353.443773 -288.233339)
			(xy 353.420647 -288.28136) (xy 353.390623 -288.325397) (xy 353.354371 -288.364468) (xy 353.3127 -288.397699)
			(xy 353.266542 -288.424348) (xy 353.216928 -288.44382) (xy 353.164966 -288.45568) (xy 353.111816 -288.459664)
			(xy 353.058666 -288.45568) (xy 353.006704 -288.44382) (xy 352.95709 -288.424348) (xy 352.910932 -288.397699)
			(xy 352.869261 -288.364468) (xy 352.833009 -288.325397) (xy 352.802985 -288.28136) (xy 352.779859 -288.233339)
			(xy 352.764149 -288.182409) (xy 352.756206 -288.129705) (xy 352.527602 -288.129705) (xy 352.52755 -288.132363)
			(xy 352.517976 -288.19019) (xy 352.509074 -288.218118) (xy 352.50628 -288.226246) (xy 352.50628 -288.460688)
			(xy 352.506715 -288.474653) (xy 352.514277 -288.501539) (xy 352.528839 -288.525372) (xy 352.549312 -288.544369)
			(xy 352.574166 -288.557111) (xy 352.601542 -288.562644) (xy 352.6155 -288.562034) (xy 352.641916 -288.561018)
			(xy 352.668563 -288.561517) (xy 352.72126 -288.569462) (xy 352.772185 -288.585173) (xy 352.8202 -288.608297)
			(xy 352.864232 -288.638319) (xy 352.903298 -288.674569) (xy 352.936524 -288.716236) (xy 352.96317 -288.762389)
			(xy 352.98264 -288.811999) (xy 352.994499 -288.863956) (xy 352.998481 -288.9171) (xy 352.996482 -288.943775)
			(xy 355.105706 -288.943775) (xy 355.105706 -288.890477) (xy 355.113649 -288.837773) (xy 355.129359 -288.786843)
			(xy 355.152485 -288.738822) (xy 355.182509 -288.694785) (xy 355.218761 -288.655714) (xy 355.260432 -288.622483)
			(xy 355.30659 -288.595834) (xy 355.356204 -288.576362) (xy 355.408166 -288.564502) (xy 355.461316 -288.560519)
			(xy 355.514466 -288.564502) (xy 355.566428 -288.576362) (xy 355.616042 -288.595834) (xy 355.6622 -288.622483)
			(xy 355.703871 -288.655714) (xy 355.740123 -288.694785) (xy 355.770147 -288.738822) (xy 355.793273 -288.786843)
			(xy 355.808983 -288.837773) (xy 355.816926 -288.890477) (xy 355.817424 -288.917126) (xy 355.816926 -288.943775)
			(xy 355.808983 -288.996479) (xy 355.801735 -289.019975) (xy 357.925106 -289.019975) (xy 357.925106 -288.966677)
			(xy 357.933049 -288.913973) (xy 357.948759 -288.863043) (xy 357.971885 -288.815022) (xy 358.001909 -288.770985)
			(xy 358.038161 -288.731914) (xy 358.079832 -288.698683) (xy 358.12599 -288.672034) (xy 358.175604 -288.652562)
			(xy 358.227566 -288.640702) (xy 358.280716 -288.636719) (xy 358.333866 -288.640702) (xy 358.385828 -288.652562)
			(xy 358.435442 -288.672034) (xy 358.4816 -288.698683) (xy 358.523271 -288.731914) (xy 358.559523 -288.770985)
			(xy 358.589547 -288.815022) (xy 358.612673 -288.863043) (xy 358.628383 -288.913973) (xy 358.632874 -288.943775)
			(xy 367.323106 -288.943775) (xy 367.323106 -288.890477) (xy 367.331049 -288.837773) (xy 367.346759 -288.786843)
			(xy 367.369885 -288.738822) (xy 367.399909 -288.694785) (xy 367.436161 -288.655714) (xy 367.477832 -288.622483)
			(xy 367.52399 -288.595834) (xy 367.573604 -288.576362) (xy 367.625566 -288.564502) (xy 367.678716 -288.560519)
			(xy 367.731866 -288.564502) (xy 367.783828 -288.576362) (xy 367.833442 -288.595834) (xy 367.8796 -288.622483)
			(xy 367.921271 -288.655714) (xy 367.957523 -288.694785) (xy 367.987547 -288.738822) (xy 368.010673 -288.786843)
			(xy 368.026383 -288.837773) (xy 368.034326 -288.890477) (xy 368.034824 -288.917126) (xy 368.034326 -288.943775)
			(xy 368.026383 -288.996479) (xy 368.010673 -289.047409) (xy 367.987547 -289.09543) (xy 367.957523 -289.139467)
			(xy 367.921271 -289.178538) (xy 367.8796 -289.211769) (xy 367.833442 -289.238418) (xy 367.783828 -289.25789)
			(xy 367.731866 -289.26975) (xy 367.678716 -289.273734) (xy 367.625566 -289.26975) (xy 367.573604 -289.25789)
			(xy 367.52399 -289.238418) (xy 367.477832 -289.211769) (xy 367.436161 -289.178538) (xy 367.399909 -289.139467)
			(xy 367.369885 -289.09543) (xy 367.346759 -289.047409) (xy 367.331049 -288.996479) (xy 367.323106 -288.943775)
			(xy 358.632874 -288.943775) (xy 358.636326 -288.966677) (xy 358.636824 -288.993326) (xy 358.636326 -289.019975)
			(xy 358.628383 -289.072679) (xy 358.612673 -289.123609) (xy 358.589547 -289.17163) (xy 358.559523 -289.215667)
			(xy 358.523271 -289.254738) (xy 358.4816 -289.287969) (xy 358.435442 -289.314618) (xy 358.385828 -289.33409)
			(xy 358.333866 -289.34595) (xy 358.280716 -289.349934) (xy 358.227566 -289.34595) (xy 358.175604 -289.33409)
			(xy 358.12599 -289.314618) (xy 358.079832 -289.287969) (xy 358.038161 -289.254738) (xy 358.001909 -289.215667)
			(xy 357.971885 -289.17163) (xy 357.948759 -289.123609) (xy 357.933049 -289.072679) (xy 357.925106 -289.019975)
			(xy 355.801735 -289.019975) (xy 355.793273 -289.047409) (xy 355.770147 -289.09543) (xy 355.740123 -289.139467)
			(xy 355.703871 -289.178538) (xy 355.6622 -289.211769) (xy 355.616042 -289.238418) (xy 355.566428 -289.25789)
			(xy 355.514466 -289.26975) (xy 355.461316 -289.273734) (xy 355.408166 -289.26975) (xy 355.356204 -289.25789)
			(xy 355.30659 -289.238418) (xy 355.260432 -289.211769) (xy 355.218761 -289.178538) (xy 355.182509 -289.139467)
			(xy 355.152485 -289.09543) (xy 355.129359 -289.047409) (xy 355.113649 -288.996479) (xy 355.105706 -288.943775)
			(xy 352.996482 -288.943775) (xy 352.994499 -288.970244) (xy 352.98264 -289.022201) (xy 352.96317 -289.071811)
			(xy 352.936524 -289.117964) (xy 352.903298 -289.159631) (xy 352.864232 -289.195881) (xy 352.8202 -289.225903)
			(xy 352.772185 -289.249027) (xy 352.72126 -289.264738) (xy 352.668563 -289.272683) (xy 352.641916 -289.273234)
			(xy 352.641662 -289.273234) (xy 352.617518 -289.272834) (xy 352.569672 -289.266311) (xy 352.523148 -289.253374)
			(xy 352.478802 -289.234264) (xy 352.437449 -289.20933) (xy 352.418396 -289.194494) (xy 352.386392 -289.183064)
			(xy 352.376404 -289.183602) (xy 352.357971 -289.191313) (xy 352.350578 -289.19805) (xy 352.246692 -289.301936)
			(xy 352.236646 -289.312732) (xy 352.222682 -289.338694) (xy 352.216713 -289.367561) (xy 352.219234 -289.396931)
			(xy 352.230036 -289.424359) (xy 352.248219 -289.447561) (xy 352.27227 -289.464606) (xy 352.286062 -289.46983)
			(xy 352.312131 -289.479221) (xy 352.36122 -289.504921) (xy 352.405734 -289.537915) (xy 352.444599 -289.577408)
			(xy 352.476875 -289.622445) (xy 352.501785 -289.671939) (xy 352.518726 -289.724694) (xy 352.527288 -289.779437)
			(xy 352.52787 -289.807142) (xy 352.527344 -289.833791) (xy 366.852952 -289.833791) (xy 366.852952 -289.780493)
			(xy 366.860895 -289.727789) (xy 366.876605 -289.676859) (xy 366.899731 -289.628838) (xy 366.929755 -289.584801)
			(xy 366.966007 -289.54573) (xy 367.007678 -289.512499) (xy 367.053836 -289.48585) (xy 367.10345 -289.466378)
			(xy 367.155412 -289.454518) (xy 367.208562 -289.450535) (xy 367.261712 -289.454518) (xy 367.313674 -289.466378)
			(xy 367.363288 -289.48585) (xy 367.409446 -289.512499) (xy 367.451117 -289.54573) (xy 367.487369 -289.584801)
			(xy 367.517393 -289.628838) (xy 367.540519 -289.676859) (xy 367.556229 -289.727789) (xy 367.564172 -289.780493)
			(xy 367.56467 -289.807142) (xy 367.792254 -289.807142) (xy 367.792654 -289.781501) (xy 367.800004 -289.730748)
			(xy 367.814559 -289.681575) (xy 367.836017 -289.634998) (xy 367.863935 -289.591981) (xy 367.897735 -289.553414)
			(xy 367.936717 -289.520094) (xy 367.980076 -289.492711) (xy 368.026915 -289.471831) (xy 368.076265 -289.457886)
			(xy 368.101626 -289.454082) (xy 368.127534 -289.45078) (xy 368.312446 -289.101022) (xy 368.300508 -289.077654)
			(xy 368.288512 -289.052703) (xy 368.271552 -289.000003) (xy 368.262951 -288.945314) (xy 368.262408 -288.917634)
			(xy 368.262408 -288.917126) (xy 368.262906 -288.890477) (xy 368.270849 -288.837773) (xy 368.286559 -288.786843)
			(xy 368.309685 -288.738822) (xy 368.339709 -288.694785) (xy 368.375961 -288.655714) (xy 368.417632 -288.622483)
			(xy 368.46379 -288.595834) (xy 368.513404 -288.576362) (xy 368.565366 -288.564502) (xy 368.618516 -288.560519)
			(xy 368.671666 -288.564502) (xy 368.723628 -288.576362) (xy 368.773242 -288.595834) (xy 368.8194 -288.622483)
			(xy 368.861071 -288.655714) (xy 368.897323 -288.694785) (xy 368.927347 -288.738822) (xy 368.950473 -288.786843)
			(xy 368.966183 -288.837773) (xy 368.974126 -288.890477) (xy 368.974624 -288.917126) (xy 368.974127 -288.942763)
			(xy 368.966783 -288.993508) (xy 368.952236 -289.042676) (xy 368.930788 -289.089248) (xy 368.902881 -289.132262)
			(xy 368.869092 -289.170829) (xy 368.830122 -289.20415) (xy 368.786774 -289.231537) (xy 368.739947 -289.252423)
			(xy 368.690608 -289.266377) (xy 368.665252 -289.270186) (xy 368.639344 -289.273488) (xy 368.454432 -289.623246)
			(xy 368.46637 -289.646614) (xy 368.478354 -289.671571) (xy 368.495318 -289.724268) (xy 368.503924 -289.778954)
			(xy 368.50447 -289.806634) (xy 368.50447 -289.807142) (xy 368.503972 -289.833791) (xy 368.732552 -289.833791)
			(xy 368.732552 -289.780493) (xy 368.740495 -289.727789) (xy 368.756205 -289.676859) (xy 368.779331 -289.628838)
			(xy 368.809355 -289.584801) (xy 368.845607 -289.54573) (xy 368.887278 -289.512499) (xy 368.933436 -289.48585)
			(xy 368.98305 -289.466378) (xy 369.035012 -289.454518) (xy 369.088162 -289.450535) (xy 369.141312 -289.454518)
			(xy 369.193274 -289.466378) (xy 369.242888 -289.48585) (xy 369.289046 -289.512499) (xy 369.330717 -289.54573)
			(xy 369.366969 -289.584801) (xy 369.396993 -289.628838) (xy 369.420119 -289.676859) (xy 369.435829 -289.727789)
			(xy 369.443772 -289.780493) (xy 369.44427 -289.807142) (xy 369.443772 -289.833791) (xy 369.435829 -289.886495)
			(xy 369.420119 -289.937425) (xy 369.396993 -289.985446) (xy 369.366969 -290.029483) (xy 369.330717 -290.068554)
			(xy 369.289046 -290.101785) (xy 369.242888 -290.128434) (xy 369.193274 -290.147906) (xy 369.141312 -290.159766)
			(xy 369.088162 -290.16375) (xy 369.035012 -290.159766) (xy 368.98305 -290.147906) (xy 368.933436 -290.128434)
			(xy 368.887278 -290.101785) (xy 368.845607 -290.068554) (xy 368.809355 -290.029483) (xy 368.779331 -289.985446)
			(xy 368.756205 -289.937425) (xy 368.740495 -289.886495) (xy 368.732552 -289.833791) (xy 368.503972 -289.833791)
			(xy 368.496029 -289.886495) (xy 368.480319 -289.937425) (xy 368.457193 -289.985446) (xy 368.427169 -290.029483)
			(xy 368.390917 -290.068554) (xy 368.349246 -290.101785) (xy 368.303088 -290.128434) (xy 368.253474 -290.147906)
			(xy 368.201512 -290.159766) (xy 368.148362 -290.16375) (xy 368.095212 -290.159766) (xy 368.04325 -290.147906)
			(xy 367.993636 -290.128434) (xy 367.947478 -290.101785) (xy 367.905807 -290.068554) (xy 367.869555 -290.029483)
			(xy 367.839531 -289.985446) (xy 367.816405 -289.937425) (xy 367.800695 -289.886495) (xy 367.792752 -289.833791)
			(xy 367.792254 -289.807142) (xy 367.56467 -289.807142) (xy 367.564172 -289.833791) (xy 367.556229 -289.886495)
			(xy 367.540519 -289.937425) (xy 367.517393 -289.985446) (xy 367.487369 -290.029483) (xy 367.451117 -290.068554)
			(xy 367.409446 -290.101785) (xy 367.363288 -290.128434) (xy 367.313674 -290.147906) (xy 367.261712 -290.159766)
			(xy 367.208562 -290.16375) (xy 367.155412 -290.159766) (xy 367.10345 -290.147906) (xy 367.053836 -290.128434)
			(xy 367.007678 -290.101785) (xy 366.966007 -290.068554) (xy 366.929755 -290.029483) (xy 366.899731 -289.985446)
			(xy 366.876605 -289.937425) (xy 366.860895 -289.886495) (xy 366.852952 -289.833791) (xy 352.527344 -289.833791)
			(xy 352.527318 -289.835122) (xy 352.518557 -289.890392) (xy 352.501259 -289.943611) (xy 352.475848 -289.993468)
			(xy 352.44295 -290.038737) (xy 352.403376 -290.078302) (xy 352.3581 -290.11119) (xy 352.308237 -290.136589)
			(xy 352.255014 -290.153876) (xy 352.199742 -290.162624) (xy 352.171762 -290.16325) (xy 352.144057 -290.162721)
			(xy 352.089316 -290.154136) (xy 352.036564 -290.137179) (xy 351.987073 -290.112259) (xy 351.942038 -290.079977)
			(xy 351.902544 -290.041111) (xy 351.869543 -289.996599) (xy 351.843833 -289.947515) (xy 351.83445 -289.921442)
			(xy 351.829271 -289.907618) (xy 351.81225 -289.883516) (xy 351.789043 -289.865292) (xy 351.761591 -289.854472)
			(xy 351.732191 -289.851961) (xy 351.703302 -289.857969) (xy 351.677341 -289.871993) (xy 351.666556 -289.882072)
			(xy 351.00768 -290.540948) (xy 335.18348 -290.540948) (xy 334.04048 -291.683948) (xy 334.04048 -292.982951)
			(xy 351.177581 -292.982951) (xy 351.177581 -292.928449) (xy 351.185338 -292.874501) (xy 351.200693 -292.822206)
			(xy 351.223335 -292.772629) (xy 351.252801 -292.726779) (xy 351.288493 -292.685589) (xy 351.329684 -292.649898)
			(xy 351.375534 -292.620432) (xy 351.425112 -292.597791) (xy 351.477407 -292.582437) (xy 351.531355 -292.574681)
			(xy 351.558606 -292.574218) (xy 351.586683 -292.574702) (xy 351.642232 -292.582918) (xy 351.695978 -292.599186)
			(xy 351.746759 -292.623155) (xy 351.793479 -292.654308) (xy 351.814638 -292.67277) (xy 351.826251 -292.682602)
			(xy 351.85379 -292.695511) (xy 351.883911 -292.699721) (xy 351.913933 -292.694856) (xy 351.941183 -292.681349)
			(xy 351.95256 -292.671246) (xy 351.973928 -292.651755) (xy 352.021446 -292.618785) (xy 352.0734 -292.593376)
			(xy 352.128597 -292.576109) (xy 352.18577 -292.567382) (xy 352.214688 -292.566852) (xy 352.214942 -292.566852)
			(xy 352.242188 -292.567421) (xy 352.296126 -292.575182) (xy 352.34841 -292.590539) (xy 352.397977 -292.61318)
			(xy 352.443817 -292.642644) (xy 352.484998 -292.678332) (xy 352.520681 -292.719517) (xy 352.55014 -292.76536)
			(xy 352.572776 -292.814929) (xy 352.588127 -292.867215) (xy 352.595882 -292.921154) (xy 352.595882 -292.975646)
			(xy 352.594832 -292.982951) (xy 357.228881 -292.982951) (xy 357.228881 -292.928449) (xy 357.236638 -292.874501)
			(xy 357.251993 -292.822207) (xy 357.274634 -292.77263) (xy 357.3041 -292.72678) (xy 357.339792 -292.68559)
			(xy 357.380982 -292.649899) (xy 357.426832 -292.620433) (xy 357.476409 -292.597792) (xy 357.528703 -292.582437)
			(xy 357.582651 -292.574681) (xy 357.609902 -292.574218) (xy 357.637272 -292.574679) (xy 357.691452 -292.582497)
			(xy 357.743955 -292.597987) (xy 357.793702 -292.62083) (xy 357.839669 -292.650556) (xy 357.8606 -292.668198)
			(xy 357.871928 -292.677434) (xy 357.898485 -292.68961) (xy 357.927402 -292.693783) (xy 357.956319 -292.68961)
			(xy 357.982876 -292.677434) (xy 357.994204 -292.668198) (xy 358.015123 -292.650543) (xy 358.0611 -292.620834)
			(xy 358.11085 -292.598001) (xy 358.163354 -292.582514) (xy 358.217532 -292.57469) (xy 358.244902 -292.574218)
			(xy 358.272155 -292.574652) (xy 358.326106 -292.582409) (xy 358.378404 -292.597766) (xy 358.427985 -292.620408)
			(xy 358.473838 -292.649877) (xy 358.515031 -292.685571) (xy 358.550724 -292.726764) (xy 358.580193 -292.772617)
			(xy 358.602835 -292.822198) (xy 358.618191 -292.874496) (xy 358.625948 -292.928447) (xy 358.625948 -292.982949)
			(xy 363.686604 -292.982949) (xy 363.686604 -292.928451) (xy 363.69436 -292.874507) (xy 363.709714 -292.822216)
			(xy 363.732354 -292.772642) (xy 363.761818 -292.726795) (xy 363.797506 -292.685608) (xy 363.838694 -292.649919)
			(xy 363.884541 -292.620454) (xy 363.934114 -292.597815) (xy 363.986405 -292.582461) (xy 364.040349 -292.574704)
			(xy 364.067598 -292.574218) (xy 364.094968 -292.574681) (xy 364.149148 -292.582499) (xy 364.201651 -292.597988)
			(xy 364.251398 -292.620831) (xy 364.297365 -292.650556) (xy 364.318296 -292.668198) (xy 364.329624 -292.677434)
			(xy 364.356181 -292.68961) (xy 364.385098 -292.693783) (xy 364.414015 -292.68961) (xy 364.440572 -292.677434)
			(xy 364.4519 -292.668198) (xy 364.472821 -292.650545) (xy 364.518797 -292.620835) (xy 364.568547 -292.598002)
			(xy 364.62105 -292.582514) (xy 364.675228 -292.57469) (xy 364.702598 -292.574218) (xy 364.729853 -292.574629)
			(xy 364.783808 -292.582386) (xy 364.836109 -292.597743) (xy 364.885693 -292.620387) (xy 364.93155 -292.649857)
			(xy 364.972746 -292.685553) (xy 365.008442 -292.726749) (xy 365.037912 -292.772605) (xy 365.060556 -292.822189)
			(xy 365.075914 -292.87449) (xy 365.083671 -292.928445) (xy 365.083671 -292.982955) (xy 365.075914 -293.03691)
			(xy 365.060556 -293.089211) (xy 365.037912 -293.138795) (xy 365.008442 -293.184651) (xy 364.972746 -293.225847)
			(xy 364.93155 -293.261543) (xy 364.885693 -293.291013) (xy 364.836109 -293.313657) (xy 364.783808 -293.329014)
			(xy 364.729853 -293.336771) (xy 364.702598 -293.337234) (xy 364.675227 -293.336785) (xy 364.621046 -293.328966)
			(xy 364.568543 -293.313473) (xy 364.518796 -293.290627) (xy 364.47283 -293.260898) (xy 364.4519 -293.243254)
			(xy 364.440572 -293.234018) (xy 364.414015 -293.221842) (xy 364.385098 -293.217669) (xy 364.356181 -293.221842)
			(xy 364.329624 -293.234018) (xy 364.318296 -293.243254) (xy 364.29737 -293.260901) (xy 364.251397 -293.290613)
			(xy 364.201647 -293.313449) (xy 364.149145 -293.328938) (xy 364.094968 -293.336762) (xy 364.067598 -293.337234)
			(xy 364.040349 -293.336696) (xy 363.986405 -293.328939) (xy 363.934114 -293.313585) (xy 363.884541 -293.290946)
			(xy 363.838694 -293.261481) (xy 363.797506 -293.225792) (xy 363.761818 -293.184605) (xy 363.732354 -293.138758)
			(xy 363.709714 -293.089184) (xy 363.69436 -293.036893) (xy 363.686604 -292.982949) (xy 358.625948 -292.982949)
			(xy 358.625948 -292.982953) (xy 358.618191 -293.036904) (xy 358.602835 -293.089202) (xy 358.580193 -293.138783)
			(xy 358.550724 -293.184636) (xy 358.515031 -293.225829) (xy 358.473838 -293.261523) (xy 358.427985 -293.290992)
			(xy 358.378404 -293.313634) (xy 358.326106 -293.328991) (xy 358.272155 -293.336748) (xy 358.244902 -293.337234)
			(xy 358.217531 -293.336783) (xy 358.163351 -293.328964) (xy 358.110847 -293.313472) (xy 358.0611 -293.290627)
			(xy 358.015135 -293.260898) (xy 357.994204 -293.243254) (xy 357.982876 -293.234018) (xy 357.956319 -293.221842)
			(xy 357.927402 -293.217669) (xy 357.898485 -293.221842) (xy 357.871928 -293.234018) (xy 357.8606 -293.243254)
			(xy 357.839673 -293.260899) (xy 357.793699 -293.290612) (xy 357.743951 -293.313447) (xy 357.691449 -293.328937)
			(xy 357.637272 -293.336762) (xy 357.609902 -293.337234) (xy 357.582651 -293.336719) (xy 357.528703 -293.328963)
			(xy 357.476409 -293.313608) (xy 357.426832 -293.290967) (xy 357.380982 -293.261501) (xy 357.339792 -293.22581)
			(xy 357.3041 -293.18462) (xy 357.274634 -293.13877) (xy 357.251993 -293.089193) (xy 357.236638 -293.036899)
			(xy 357.228881 -292.982951) (xy 352.594832 -292.982951) (xy 352.588127 -293.029585) (xy 352.572776 -293.081871)
			(xy 352.55014 -293.13144) (xy 352.520681 -293.177283) (xy 352.484998 -293.218468) (xy 352.443817 -293.254156)
			(xy 352.397977 -293.28362) (xy 352.34841 -293.306261) (xy 352.296126 -293.321618) (xy 352.242188 -293.329379)
			(xy 352.214942 -293.329868) (xy 352.186864 -293.329419) (xy 352.131313 -293.321195) (xy 352.077567 -293.304919)
			(xy 352.026786 -293.280942) (xy 351.980068 -293.249782) (xy 351.95891 -293.231316) (xy 351.947336 -293.221434)
			(xy 351.919783 -293.208533) (xy 351.889651 -293.204334) (xy 351.85962 -293.209211) (xy 351.832366 -293.22273)
			(xy 351.820988 -293.23284) (xy 351.799613 -293.252323) (xy 351.752096 -293.285291) (xy 351.700143 -293.3107)
			(xy 351.644948 -293.327969) (xy 351.587777 -293.336701) (xy 351.55886 -293.337234) (xy 351.558606 -293.337234)
			(xy 351.531355 -293.336719) (xy 351.477407 -293.328963) (xy 351.425112 -293.313609) (xy 351.375534 -293.290968)
			(xy 351.329684 -293.261502) (xy 351.288493 -293.225811) (xy 351.252801 -293.184621) (xy 351.223335 -293.138771)
			(xy 351.200693 -293.089194) (xy 351.185338 -293.036899) (xy 351.177581 -292.982951) (xy 334.04048 -292.982951)
			(xy 334.04048 -295.060651) (xy 351.198901 -295.060651) (xy 351.198901 -295.006149) (xy 351.206658 -294.9522)
			(xy 351.222015 -294.899906) (xy 351.244658 -294.850329) (xy 351.274126 -294.804479) (xy 351.30982 -294.76329)
			(xy 351.351013 -294.727601) (xy 351.396865 -294.698137) (xy 351.446445 -294.6755) (xy 351.498742 -294.66015)
			(xy 351.55269 -294.652398) (xy 351.579942 -294.651938) (xy 351.606876 -294.652417) (xy 351.660206 -294.660004)
			(xy 351.711939 -294.675019) (xy 351.761043 -294.697165) (xy 351.806543 -294.726001) (xy 351.827338 -294.743124)
			(xy 351.838806 -294.752175) (xy 351.865494 -294.764022) (xy 351.89444 -294.767861) (xy 351.923294 -294.763379)
			(xy 351.949712 -294.750941) (xy 351.960942 -294.7416) (xy 351.982009 -294.723433) (xy 352.028438 -294.692794)
			(xy 352.078823 -294.669218) (xy 352.132095 -294.653205) (xy 352.187129 -294.645094) (xy 352.214942 -294.644572)
			(xy 352.24219 -294.645101) (xy 352.29613 -294.652862) (xy 352.348417 -294.66822) (xy 352.397986 -294.690862)
			(xy 352.443829 -294.720328) (xy 352.485012 -294.756018) (xy 352.520697 -294.797205) (xy 352.550158 -294.843051)
			(xy 352.572795 -294.892622) (xy 352.588147 -294.944911) (xy 352.595902 -294.998852) (xy 352.595902 -295.053348)
			(xy 352.594119 -295.065751) (xy 357.228881 -295.065751) (xy 357.228881 -295.011249) (xy 357.236638 -294.957301)
			(xy 357.251993 -294.905007) (xy 357.274634 -294.85543) (xy 357.3041 -294.80958) (xy 357.339792 -294.76839)
			(xy 357.380982 -294.732699) (xy 357.426832 -294.703233) (xy 357.476409 -294.680592) (xy 357.528703 -294.665237)
			(xy 357.582651 -294.657481) (xy 357.609902 -294.657018) (xy 357.640025 -294.657597) (xy 357.699521 -294.667077)
			(xy 357.756788 -294.685787) (xy 357.810405 -294.713261) (xy 357.85904 -294.748816) (xy 357.880666 -294.769794)
			(xy 357.890388 -294.779012) (xy 357.91355 -294.792457) (xy 357.939411 -294.799419) (xy 357.966193 -294.799419)
			(xy 357.992054 -294.792457) (xy 358.015216 -294.779012) (xy 358.024938 -294.769794) (xy 358.046566 -294.748817)
			(xy 358.095194 -294.713249) (xy 358.14881 -294.685768) (xy 358.206079 -294.667059) (xy 358.265578 -294.657587)
			(xy 358.295702 -294.657018) (xy 358.322955 -294.657452) (xy 358.376906 -294.665209) (xy 358.429204 -294.680566)
			(xy 358.478785 -294.703208) (xy 358.524638 -294.732677) (xy 358.565831 -294.768371) (xy 358.601524 -294.809564)
			(xy 358.630993 -294.855417) (xy 358.653635 -294.904998) (xy 358.668991 -294.957296) (xy 358.676748 -295.011247)
			(xy 358.676748 -295.065749) (xy 363.572304 -295.065749) (xy 363.572304 -295.011251) (xy 363.58006 -294.957307)
			(xy 363.595414 -294.905016) (xy 363.618054 -294.855442) (xy 363.647518 -294.809595) (xy 363.683206 -294.768408)
			(xy 363.724394 -294.732719) (xy 363.770241 -294.703254) (xy 363.819814 -294.680615) (xy 363.872105 -294.665261)
			(xy 363.926049 -294.657504) (xy 363.953298 -294.657018) (xy 363.980668 -294.657481) (xy 364.034848 -294.665299)
			(xy 364.087351 -294.680788) (xy 364.137098 -294.703631) (xy 364.183065 -294.733356) (xy 364.203996 -294.750998)
			(xy 364.215324 -294.760234) (xy 364.241881 -294.77241) (xy 364.270798 -294.776583) (xy 364.299715 -294.77241)
			(xy 364.326272 -294.760234) (xy 364.3376 -294.750998) (xy 364.358521 -294.733345) (xy 364.404497 -294.703635)
			(xy 364.454247 -294.680802) (xy 364.50675 -294.665314) (xy 364.560928 -294.65749) (xy 364.588298 -294.657018)
			(xy 364.615553 -294.657429) (xy 364.669508 -294.665186) (xy 364.721809 -294.680543) (xy 364.771393 -294.703187)
			(xy 364.81725 -294.732657) (xy 364.858446 -294.768353) (xy 364.894142 -294.809549) (xy 364.923612 -294.855405)
			(xy 364.946256 -294.904989) (xy 364.961614 -294.95729) (xy 364.969371 -295.011245) (xy 364.969371 -295.038526)
			(xy 370.181376 -295.038526) (xy 370.185447 -294.982904) (xy 370.197573 -294.928467) (xy 370.217496 -294.876376)
			(xy 370.244792 -294.827741) (xy 370.278878 -294.783598) (xy 370.319027 -294.744889) (xy 370.364385 -294.712438)
			(xy 370.413985 -294.686937) (xy 370.466769 -294.66893) (xy 370.521612 -294.6588) (xy 370.577346 -294.656763)
			(xy 370.632783 -294.662863) (xy 370.68674 -294.676969) (xy 370.738069 -294.698781) (xy 370.785675 -294.727835)
			(xy 370.828543 -294.76351) (xy 370.86576 -294.805047) (xy 370.896533 -294.85156) (xy 370.920205 -294.902057)
			(xy 370.936273 -294.955464) (xy 370.944393 -295.01064) (xy 370.944902 -295.038526) (xy 370.944393 -295.066412)
			(xy 370.936273 -295.121588) (xy 370.920205 -295.174995) (xy 370.896533 -295.225492) (xy 370.86576 -295.272005)
			(xy 370.828543 -295.313542) (xy 370.785675 -295.349217) (xy 370.738069 -295.378271) (xy 370.68674 -295.400083)
			(xy 370.632783 -295.414189) (xy 370.577346 -295.420289) (xy 370.521612 -295.418252) (xy 370.466769 -295.408122)
			(xy 370.413985 -295.390115) (xy 370.364385 -295.364614) (xy 370.319027 -295.332163) (xy 370.278878 -295.293454)
			(xy 370.244792 -295.249311) (xy 370.217496 -295.200676) (xy 370.197573 -295.148585) (xy 370.185447 -295.094148)
			(xy 370.181376 -295.038526) (xy 364.969371 -295.038526) (xy 364.969371 -295.065755) (xy 364.961614 -295.11971)
			(xy 364.946256 -295.172011) (xy 364.923612 -295.221595) (xy 364.894142 -295.267451) (xy 364.858446 -295.308647)
			(xy 364.81725 -295.344343) (xy 364.771393 -295.373813) (xy 364.721809 -295.396457) (xy 364.669508 -295.411814)
			(xy 364.615553 -295.419571) (xy 364.588298 -295.420034) (xy 364.560927 -295.419585) (xy 364.506746 -295.411766)
			(xy 364.454243 -295.396273) (xy 364.404496 -295.373427) (xy 364.35853 -295.343698) (xy 364.3376 -295.326054)
			(xy 364.326272 -295.316818) (xy 364.299715 -295.304642) (xy 364.270798 -295.300469) (xy 364.241881 -295.304642)
			(xy 364.215324 -295.316818) (xy 364.203996 -295.326054) (xy 364.18307 -295.343701) (xy 364.137097 -295.373413)
			(xy 364.087347 -295.396249) (xy 364.034845 -295.411738) (xy 363.980668 -295.419562) (xy 363.953298 -295.420034)
			(xy 363.926049 -295.419496) (xy 363.872105 -295.411739) (xy 363.819814 -295.396385) (xy 363.770241 -295.373746)
			(xy 363.724394 -295.344281) (xy 363.683206 -295.308592) (xy 363.647518 -295.267405) (xy 363.618054 -295.221558)
			(xy 363.595414 -295.171984) (xy 363.58006 -295.119693) (xy 363.572304 -295.065749) (xy 358.676748 -295.065749)
			(xy 358.676748 -295.065753) (xy 358.668991 -295.119704) (xy 358.653635 -295.172002) (xy 358.630993 -295.221583)
			(xy 358.601524 -295.267436) (xy 358.565831 -295.308629) (xy 358.524638 -295.344323) (xy 358.478785 -295.373792)
			(xy 358.429204 -295.396434) (xy 358.376906 -295.411791) (xy 358.322955 -295.419548) (xy 358.295702 -295.420034)
			(xy 358.265578 -295.419467) (xy 358.206082 -295.409986) (xy 358.148813 -295.391274) (xy 358.095196 -295.363797)
			(xy 358.046562 -295.328238) (xy 358.024938 -295.307258) (xy 358.015216 -295.29804) (xy 357.992054 -295.284595)
			(xy 357.966193 -295.277633) (xy 357.939411 -295.277633) (xy 357.91355 -295.284595) (xy 357.890388 -295.29804)
			(xy 357.880666 -295.307258) (xy 357.859028 -295.328224) (xy 357.810404 -295.363796) (xy 357.756791 -295.39128)
			(xy 357.699523 -295.409991) (xy 357.640025 -295.419465) (xy 357.609902 -295.420034) (xy 357.582651 -295.419519)
			(xy 357.528703 -295.411763) (xy 357.476409 -295.396408) (xy 357.426832 -295.373767) (xy 357.380982 -295.344301)
			(xy 357.339792 -295.30861) (xy 357.3041 -295.26742) (xy 357.274634 -295.22157) (xy 357.251993 -295.171993)
			(xy 357.236638 -295.119699) (xy 357.228881 -295.065751) (xy 352.594119 -295.065751) (xy 352.588147 -295.107289)
			(xy 352.572795 -295.159578) (xy 352.550158 -295.209149) (xy 352.520697 -295.254995) (xy 352.485012 -295.296182)
			(xy 352.443829 -295.331872) (xy 352.397986 -295.361338) (xy 352.348417 -295.38398) (xy 352.29613 -295.399338)
			(xy 352.24219 -295.407099) (xy 352.214942 -295.407588) (xy 352.188008 -295.407112) (xy 352.134678 -295.399524)
			(xy 352.082946 -295.384507) (xy 352.033841 -295.362361) (xy 351.988342 -295.333525) (xy 351.967546 -295.316402)
			(xy 351.956087 -295.307342) (xy 351.929394 -295.295506) (xy 351.900448 -295.291673) (xy 351.871595 -295.296155)
			(xy 351.845175 -295.308589) (xy 351.833942 -295.317926) (xy 351.812846 -295.336057) (xy 351.766425 -295.366701)
			(xy 351.716047 -295.390283) (xy 351.662781 -295.406305) (xy 351.607753 -295.414427) (xy 351.579942 -295.414954)
			(xy 351.55269 -295.414402) (xy 351.498741 -295.40665) (xy 351.446445 -295.3913) (xy 351.396865 -295.368663)
			(xy 351.351013 -295.339199) (xy 351.30982 -295.30351) (xy 351.274126 -295.262321) (xy 351.244658 -295.216471)
			(xy 351.222015 -295.166894) (xy 351.206658 -295.1146) (xy 351.198901 -295.060651) (xy 334.04048 -295.060651)
			(xy 334.04048 -297.515026) (xy 336.155548 -297.515026) (xy 336.159529 -297.382006) (xy 336.171458 -297.249461)
			(xy 336.191293 -297.117868) (xy 336.218962 -296.987696) (xy 336.254366 -296.859411) (xy 336.297379 -296.733474)
			(xy 336.347846 -296.610335) (xy 336.405587 -296.490434) (xy 336.470396 -296.374201) (xy 336.54204 -296.262051)
			(xy 336.620262 -296.154387) (xy 336.704783 -296.051594) (xy 336.795301 -295.954039) (xy 336.89149 -295.862073)
			(xy 336.993008 -295.776023) (xy 337.099489 -295.696199) (xy 337.210554 -295.622886) (xy 337.325805 -295.556346)
			(xy 337.444829 -295.496817) (xy 337.5672 -295.444513) (xy 337.692479 -295.399621) (xy 337.82022 -295.362302)
			(xy 337.949963 -295.332689) (xy 338.081245 -295.310888) (xy 338.213596 -295.296978) (xy 338.346542 -295.291007)
			(xy 338.479607 -295.292998) (xy 338.612315 -295.302943) (xy 338.744191 -295.320807) (xy 338.874762 -295.346525)
			(xy 339.003562 -295.380006) (xy 339.130128 -295.42113) (xy 339.254009 -295.46975) (xy 339.37476 -295.525691)
			(xy 339.49195 -295.588753) (xy 339.605159 -295.658711) (xy 339.713981 -295.735315) (xy 339.818027 -295.818289)
			(xy 339.916925 -295.907337) (xy 340.01032 -296.00214) (xy 340.097878 -296.102358) (xy 340.179287 -296.207634)
			(xy 340.254253 -296.31759) (xy 340.32251 -296.431832) (xy 340.383812 -296.549952) (xy 340.437941 -296.671527)
			(xy 340.484702 -296.796121) (xy 340.523928 -296.923289) (xy 340.555478 -297.052575) (xy 340.565056 -297.105351)
			(xy 351.198901 -297.105351) (xy 351.198901 -297.050849) (xy 351.206658 -296.9969) (xy 351.222015 -296.944606)
			(xy 351.244658 -296.895029) (xy 351.274126 -296.849179) (xy 351.30982 -296.80799) (xy 351.351013 -296.772301)
			(xy 351.396865 -296.742837) (xy 351.446445 -296.7202) (xy 351.498742 -296.70485) (xy 351.55269 -296.697098)
			(xy 351.579942 -296.696638) (xy 351.606876 -296.697117) (xy 351.660206 -296.704704) (xy 351.711939 -296.719719)
			(xy 351.761043 -296.741865) (xy 351.806543 -296.770701) (xy 351.827338 -296.787824) (xy 351.838806 -296.796875)
			(xy 351.865494 -296.808722) (xy 351.89444 -296.812561) (xy 351.923294 -296.808079) (xy 351.949712 -296.795641)
			(xy 351.960942 -296.7863) (xy 351.982009 -296.768133) (xy 352.028438 -296.737494) (xy 352.078823 -296.713918)
			(xy 352.132095 -296.697905) (xy 352.187129 -296.689794) (xy 352.214942 -296.689272) (xy 352.24219 -296.689801)
			(xy 352.29613 -296.697562) (xy 352.348417 -296.71292) (xy 352.397986 -296.735562) (xy 352.443829 -296.765028)
			(xy 352.485012 -296.800718) (xy 352.520697 -296.841905) (xy 352.550158 -296.887751) (xy 352.572795 -296.937322)
			(xy 352.588147 -296.989611) (xy 352.595902 -297.043552) (xy 352.595902 -297.098048) (xy 352.588147 -297.151989)
			(xy 352.572795 -297.204278) (xy 352.563446 -297.224751) (xy 357.228881 -297.224751) (xy 357.228881 -297.170249)
			(xy 357.236638 -297.116301) (xy 357.251993 -297.064007) (xy 357.274634 -297.01443) (xy 357.3041 -296.96858)
			(xy 357.339792 -296.92739) (xy 357.380982 -296.891699) (xy 357.426832 -296.862233) (xy 357.476409 -296.839592)
			(xy 357.528703 -296.824237) (xy 357.582651 -296.816481) (xy 357.609902 -296.816018) (xy 357.640025 -296.816597)
			(xy 357.699521 -296.826077) (xy 357.756788 -296.844787) (xy 357.810405 -296.872261) (xy 357.85904 -296.907816)
			(xy 357.880666 -296.928794) (xy 357.890388 -296.938012) (xy 357.91355 -296.951457) (xy 357.939411 -296.958419)
			(xy 357.966193 -296.958419) (xy 357.992054 -296.951457) (xy 358.015216 -296.938012) (xy 358.024938 -296.928794)
			(xy 358.046566 -296.907817) (xy 358.095194 -296.872249) (xy 358.14881 -296.844768) (xy 358.206079 -296.826059)
			(xy 358.265578 -296.816587) (xy 358.295702 -296.816018) (xy 358.322955 -296.816452) (xy 358.376906 -296.824209)
			(xy 358.429204 -296.839566) (xy 358.478785 -296.862208) (xy 358.524638 -296.891677) (xy 358.565831 -296.927371)
			(xy 358.601524 -296.968564) (xy 358.630993 -297.014417) (xy 358.653635 -297.063998) (xy 358.668991 -297.116296)
			(xy 358.676748 -297.170247) (xy 358.676748 -297.224749) (xy 363.572304 -297.224749) (xy 363.572304 -297.170251)
			(xy 363.58006 -297.116307) (xy 363.595414 -297.064016) (xy 363.618054 -297.014442) (xy 363.647518 -296.968595)
			(xy 363.683206 -296.927408) (xy 363.724394 -296.891719) (xy 363.770241 -296.862254) (xy 363.819814 -296.839615)
			(xy 363.872105 -296.824261) (xy 363.926049 -296.816504) (xy 363.953298 -296.816018) (xy 363.980668 -296.816481)
			(xy 364.034848 -296.824299) (xy 364.087351 -296.839788) (xy 364.137098 -296.862631) (xy 364.183065 -296.892356)
			(xy 364.203996 -296.909998) (xy 364.215324 -296.919234) (xy 364.241881 -296.93141) (xy 364.270798 -296.935583)
			(xy 364.299715 -296.93141) (xy 364.326272 -296.919234) (xy 364.3376 -296.909998) (xy 364.358521 -296.892345)
			(xy 364.404497 -296.862635) (xy 364.454247 -296.839802) (xy 364.50675 -296.824314) (xy 364.560928 -296.81649)
			(xy 364.588298 -296.816018) (xy 364.615553 -296.816429) (xy 364.669508 -296.824186) (xy 364.721809 -296.839543)
			(xy 364.771393 -296.862187) (xy 364.81725 -296.891657) (xy 364.858446 -296.927353) (xy 364.894142 -296.968549)
			(xy 364.923612 -297.014405) (xy 364.946256 -297.063989) (xy 364.961614 -297.11629) (xy 364.969371 -297.170245)
			(xy 364.969371 -297.197526) (xy 370.181376 -297.197526) (xy 370.185447 -297.141904) (xy 370.197573 -297.087467)
			(xy 370.217496 -297.035376) (xy 370.244792 -296.986741) (xy 370.278878 -296.942598) (xy 370.319027 -296.903889)
			(xy 370.364385 -296.871438) (xy 370.413985 -296.845937) (xy 370.466769 -296.82793) (xy 370.521612 -296.8178)
			(xy 370.577346 -296.815763) (xy 370.632783 -296.821863) (xy 370.68674 -296.835969) (xy 370.738069 -296.857781)
			(xy 370.785675 -296.886835) (xy 370.828543 -296.92251) (xy 370.86576 -296.964047) (xy 370.896533 -297.01056)
			(xy 370.920205 -297.061057) (xy 370.936273 -297.114464) (xy 370.944393 -297.16964) (xy 370.944902 -297.197526)
			(xy 370.944393 -297.225412) (xy 370.936273 -297.280588) (xy 370.920205 -297.333995) (xy 370.896533 -297.384492)
			(xy 370.86576 -297.431005) (xy 370.828543 -297.472542) (xy 370.785675 -297.508217) (xy 370.774518 -297.515026)
			(xy 379.13565 -297.515026) (xy 379.139631 -297.382006) (xy 379.15156 -297.249461) (xy 379.171395 -297.117868)
			(xy 379.199064 -296.987696) (xy 379.234468 -296.859411) (xy 379.277481 -296.733474) (xy 379.327948 -296.610335)
			(xy 379.385689 -296.490434) (xy 379.450498 -296.374201) (xy 379.522142 -296.262051) (xy 379.600364 -296.154387)
			(xy 379.684885 -296.051594) (xy 379.775403 -295.954039) (xy 379.871592 -295.862073) (xy 379.97311 -295.776023)
			(xy 380.079591 -295.696199) (xy 380.190656 -295.622886) (xy 380.305907 -295.556346) (xy 380.424931 -295.496817)
			(xy 380.547302 -295.444513) (xy 380.672581 -295.399621) (xy 380.800322 -295.362302) (xy 380.930065 -295.332689)
			(xy 381.061347 -295.310888) (xy 381.193698 -295.296978) (xy 381.326644 -295.291007) (xy 381.459709 -295.292998)
			(xy 381.592417 -295.302943) (xy 381.724293 -295.320807) (xy 381.854864 -295.346525) (xy 381.983664 -295.380006)
			(xy 382.11023 -295.42113) (xy 382.234111 -295.46975) (xy 382.354862 -295.525691) (xy 382.472052 -295.588753)
			(xy 382.585261 -295.658711) (xy 382.694083 -295.735315) (xy 382.798129 -295.818289) (xy 382.897027 -295.907337)
			(xy 382.990422 -296.00214) (xy 383.07798 -296.102358) (xy 383.159389 -296.207634) (xy 383.234355 -296.31759)
			(xy 383.302612 -296.431832) (xy 383.363914 -296.549952) (xy 383.418043 -296.671527) (xy 383.464804 -296.796121)
			(xy 383.50403 -296.923289) (xy 383.53558 -297.052575) (xy 383.559343 -297.183516) (xy 383.575232 -297.315644)
			(xy 383.58319 -297.448486) (xy 383.583688 -297.515026) (xy 383.58319 -297.581566) (xy 383.575232 -297.714408)
			(xy 383.559343 -297.846536) (xy 383.53558 -297.977477) (xy 383.50403 -298.106763) (xy 383.464804 -298.233931)
			(xy 383.418043 -298.358525) (xy 383.363914 -298.4801) (xy 383.302612 -298.59822) (xy 383.234355 -298.712462)
			(xy 383.159389 -298.822418) (xy 383.07798 -298.927694) (xy 382.990422 -299.027912) (xy 382.897027 -299.122715)
			(xy 382.798129 -299.211763) (xy 382.694083 -299.294737) (xy 382.585261 -299.371341) (xy 382.472052 -299.441299)
			(xy 382.354862 -299.504361) (xy 382.234111 -299.560302) (xy 382.11023 -299.608922) (xy 381.983664 -299.650046)
			(xy 381.854864 -299.683527) (xy 381.724293 -299.709245) (xy 381.592417 -299.727109) (xy 381.459709 -299.737054)
			(xy 381.326644 -299.739045) (xy 381.193698 -299.733074) (xy 381.061347 -299.719164) (xy 380.930065 -299.697363)
			(xy 380.800322 -299.66775) (xy 380.672581 -299.630431) (xy 380.547302 -299.585539) (xy 380.424931 -299.533235)
			(xy 380.305907 -299.473706) (xy 380.190656 -299.407166) (xy 380.079591 -299.333853) (xy 379.97311 -299.254029)
			(xy 379.871592 -299.167979) (xy 379.775403 -299.076013) (xy 379.684885 -298.978458) (xy 379.600364 -298.875665)
			(xy 379.522142 -298.768001) (xy 379.450498 -298.655851) (xy 379.385689 -298.539618) (xy 379.327948 -298.419717)
			(xy 379.277481 -298.296578) (xy 379.234468 -298.170641) (xy 379.199064 -298.042356) (xy 379.171395 -297.912184)
			(xy 379.15156 -297.780591) (xy 379.139631 -297.648046) (xy 379.13565 -297.515026) (xy 370.774518 -297.515026)
			(xy 370.738069 -297.537271) (xy 370.68674 -297.559083) (xy 370.632783 -297.573189) (xy 370.577346 -297.579289)
			(xy 370.521612 -297.577252) (xy 370.466769 -297.567122) (xy 370.413985 -297.549115) (xy 370.364385 -297.523614)
			(xy 370.319027 -297.491163) (xy 370.278878 -297.452454) (xy 370.244792 -297.408311) (xy 370.217496 -297.359676)
			(xy 370.197573 -297.307585) (xy 370.185447 -297.253148) (xy 370.181376 -297.197526) (xy 364.969371 -297.197526)
			(xy 364.969371 -297.224755) (xy 364.961614 -297.27871) (xy 364.946256 -297.331011) (xy 364.923612 -297.380595)
			(xy 364.894142 -297.426451) (xy 364.858446 -297.467647) (xy 364.81725 -297.503343) (xy 364.771393 -297.532813)
			(xy 364.721809 -297.555457) (xy 364.669508 -297.570814) (xy 364.615553 -297.578571) (xy 364.588298 -297.579034)
			(xy 364.560927 -297.578585) (xy 364.506746 -297.570766) (xy 364.454243 -297.555273) (xy 364.404496 -297.532427)
			(xy 364.35853 -297.502698) (xy 364.3376 -297.485054) (xy 364.326272 -297.475818) (xy 364.299715 -297.463642)
			(xy 364.270798 -297.459469) (xy 364.241881 -297.463642) (xy 364.215324 -297.475818) (xy 364.203996 -297.485054)
			(xy 364.18307 -297.502701) (xy 364.137097 -297.532413) (xy 364.087347 -297.555249) (xy 364.034845 -297.570738)
			(xy 363.980668 -297.578562) (xy 363.953298 -297.579034) (xy 363.926049 -297.578496) (xy 363.872105 -297.570739)
			(xy 363.819814 -297.555385) (xy 363.770241 -297.532746) (xy 363.724394 -297.503281) (xy 363.683206 -297.467592)
			(xy 363.647518 -297.426405) (xy 363.618054 -297.380558) (xy 363.595414 -297.330984) (xy 363.58006 -297.278693)
			(xy 363.572304 -297.224749) (xy 358.676748 -297.224749) (xy 358.676748 -297.224753) (xy 358.668991 -297.278704)
			(xy 358.653635 -297.331002) (xy 358.630993 -297.380583) (xy 358.601524 -297.426436) (xy 358.565831 -297.467629)
			(xy 358.524638 -297.503323) (xy 358.478785 -297.532792) (xy 358.429204 -297.555434) (xy 358.376906 -297.570791)
			(xy 358.322955 -297.578548) (xy 358.295702 -297.579034) (xy 358.265578 -297.578467) (xy 358.206082 -297.568986)
			(xy 358.148813 -297.550274) (xy 358.095196 -297.522797) (xy 358.046562 -297.487238) (xy 358.024938 -297.466258)
			(xy 358.015216 -297.45704) (xy 357.992054 -297.443595) (xy 357.966193 -297.436633) (xy 357.939411 -297.436633)
			(xy 357.91355 -297.443595) (xy 357.890388 -297.45704) (xy 357.880666 -297.466258) (xy 357.859028 -297.487224)
			(xy 357.810404 -297.522796) (xy 357.756791 -297.55028) (xy 357.699523 -297.568991) (xy 357.640025 -297.578465)
			(xy 357.609902 -297.579034) (xy 357.582651 -297.578519) (xy 357.528703 -297.570763) (xy 357.476409 -297.555408)
			(xy 357.426832 -297.532767) (xy 357.380982 -297.503301) (xy 357.339792 -297.46761) (xy 357.3041 -297.42642)
			(xy 357.274634 -297.38057) (xy 357.251993 -297.330993) (xy 357.236638 -297.278699) (xy 357.228881 -297.224751)
			(xy 352.563446 -297.224751) (xy 352.550158 -297.253849) (xy 352.520697 -297.299695) (xy 352.485012 -297.340882)
			(xy 352.443829 -297.376572) (xy 352.397986 -297.406038) (xy 352.348417 -297.42868) (xy 352.29613 -297.444038)
			(xy 352.24219 -297.451799) (xy 352.214942 -297.452288) (xy 352.188008 -297.451812) (xy 352.134678 -297.444224)
			(xy 352.082946 -297.429207) (xy 352.033841 -297.407061) (xy 351.988342 -297.378225) (xy 351.967546 -297.361102)
			(xy 351.956087 -297.352042) (xy 351.929394 -297.340206) (xy 351.900448 -297.336373) (xy 351.871595 -297.340855)
			(xy 351.845175 -297.353289) (xy 351.833942 -297.362626) (xy 351.812846 -297.380757) (xy 351.766425 -297.411401)
			(xy 351.716047 -297.434983) (xy 351.662781 -297.451005) (xy 351.607753 -297.459127) (xy 351.579942 -297.459654)
			(xy 351.55269 -297.459102) (xy 351.498741 -297.45135) (xy 351.446445 -297.436) (xy 351.396865 -297.413363)
			(xy 351.351013 -297.383899) (xy 351.30982 -297.34821) (xy 351.274126 -297.307021) (xy 351.244658 -297.261171)
			(xy 351.222015 -297.211594) (xy 351.206658 -297.1593) (xy 351.198901 -297.105351) (xy 340.565056 -297.105351)
			(xy 340.579241 -297.183516) (xy 340.59513 -297.315644) (xy 340.603088 -297.448486) (xy 340.603586 -297.515026)
			(xy 340.603088 -297.581566) (xy 340.59513 -297.714408) (xy 340.579241 -297.846536) (xy 340.555478 -297.977477)
			(xy 340.523928 -298.106763) (xy 340.484702 -298.233931) (xy 340.437941 -298.358525) (xy 340.383812 -298.4801)
			(xy 340.32251 -298.59822) (xy 340.254253 -298.712462) (xy 340.179287 -298.822418) (xy 340.097878 -298.927694)
			(xy 340.01032 -299.027912) (xy 339.916925 -299.122715) (xy 339.818027 -299.211763) (xy 339.713981 -299.294737)
			(xy 339.605159 -299.371341) (xy 339.49195 -299.441299) (xy 339.37476 -299.504361) (xy 339.254009 -299.560302)
			(xy 339.130128 -299.608922) (xy 339.003562 -299.650046) (xy 338.874762 -299.683527) (xy 338.744191 -299.709245)
			(xy 338.612315 -299.727109) (xy 338.479607 -299.737054) (xy 338.346542 -299.739045) (xy 338.213596 -299.733074)
			(xy 338.081245 -299.719164) (xy 337.949963 -299.697363) (xy 337.82022 -299.66775) (xy 337.692479 -299.630431)
			(xy 337.5672 -299.585539) (xy 337.444829 -299.533235) (xy 337.325805 -299.473706) (xy 337.210554 -299.407166)
			(xy 337.099489 -299.333853) (xy 336.993008 -299.254029) (xy 336.89149 -299.167979) (xy 336.795301 -299.076013)
			(xy 336.704783 -298.978458) (xy 336.620262 -298.875665) (xy 336.54204 -298.768001) (xy 336.470396 -298.655851)
			(xy 336.405587 -298.539618) (xy 336.347846 -298.419717) (xy 336.297379 -298.296578) (xy 336.254366 -298.170641)
			(xy 336.218962 -298.042356) (xy 336.191293 -297.912184) (xy 336.171458 -297.780591) (xy 336.159529 -297.648046)
			(xy 336.155548 -297.515026) (xy 334.04048 -297.515026) (xy 334.04048 -312.740548) (xy 333.480336 -315.709738)
			(xy 345.576648 -315.709738) (xy 345.576648 -315.625042) (xy 345.584699 -315.540728) (xy 345.600728 -315.457562)
			(xy 345.624589 -315.376295) (xy 345.656068 -315.297665) (xy 345.694879 -315.222384) (xy 345.740669 -315.151132)
			(xy 345.793025 -315.084556) (xy 345.851473 -315.023258) (xy 345.915483 -314.967793) (xy 345.984475 -314.918664)
			(xy 346.057825 -314.876315) (xy 346.134868 -314.841131) (xy 346.214907 -314.813429) (xy 346.297216 -314.793461)
			(xy 346.381051 -314.781408) (xy 346.465652 -314.777378) (xy 346.550253 -314.781408) (xy 346.634088 -314.793461)
			(xy 346.716397 -314.813429) (xy 346.796436 -314.841131) (xy 346.873479 -314.876315) (xy 346.946829 -314.918664)
			(xy 347.015821 -314.967793) (xy 347.079831 -315.023258) (xy 347.138279 -315.084556) (xy 347.190635 -315.151132)
			(xy 347.236425 -315.222384) (xy 347.275236 -315.297665) (xy 347.306715 -315.376295) (xy 347.330576 -315.457562)
			(xy 347.346605 -315.540728) (xy 347.354656 -315.625042) (xy 347.35516 -315.66739) (xy 347.550237 -315.66739)
			(xy 347.554259 -315.58167) (xy 347.56629 -315.496702) (xy 347.586226 -315.413235) (xy 347.613889 -315.332001)
			(xy 347.649038 -315.253715) (xy 347.691364 -315.179064) (xy 347.740493 -315.108705) (xy 347.795996 -315.043255)
			(xy 347.857383 -314.983291) (xy 347.924116 -314.929338) (xy 347.995608 -314.881871) (xy 348.07123 -314.841307)
			(xy 348.150319 -314.808003) (xy 348.232179 -314.782251) (xy 348.31609 -314.764278) (xy 348.401316 -314.754242)
			(xy 348.487108 -314.75223) (xy 348.57271 -314.758261) (xy 348.657372 -314.772281) (xy 348.740349 -314.794167)
			(xy 348.820912 -314.823728) (xy 348.898352 -314.860702) (xy 348.971991 -314.904766) (xy 349.041179 -314.955532)
			(xy 349.10531 -315.012553) (xy 349.163819 -315.075329) (xy 349.216192 -315.143309) (xy 349.26197 -315.215894)
			(xy 349.30075 -315.292446) (xy 349.332191 -315.372294) (xy 349.356017 -315.454735) (xy 349.372018 -315.539045)
			(xy 349.380053 -315.624483) (xy 349.380556 -315.66739) (xy 349.38006 -315.709738) (xy 351.774248 -315.709738)
			(xy 351.774248 -315.625042) (xy 351.782299 -315.540728) (xy 351.798328 -315.457562) (xy 351.822189 -315.376295)
			(xy 351.853668 -315.297665) (xy 351.892479 -315.222384) (xy 351.938269 -315.151132) (xy 351.990625 -315.084556)
			(xy 352.049073 -315.023258) (xy 352.113083 -314.967793) (xy 352.182075 -314.918664) (xy 352.255425 -314.876315)
			(xy 352.332468 -314.841131) (xy 352.412507 -314.813429) (xy 352.494816 -314.793461) (xy 352.578651 -314.781408)
			(xy 352.663252 -314.777378) (xy 352.747853 -314.781408) (xy 352.831688 -314.793461) (xy 352.913997 -314.813429)
			(xy 352.994036 -314.841131) (xy 353.071079 -314.876315) (xy 353.144429 -314.918664) (xy 353.213421 -314.967793)
			(xy 353.277431 -315.023258) (xy 353.335879 -315.084556) (xy 353.388235 -315.151132) (xy 353.434025 -315.222384)
			(xy 353.472836 -315.297665) (xy 353.504315 -315.376295) (xy 353.528176 -315.457562) (xy 353.544205 -315.540728)
			(xy 353.552256 -315.625042) (xy 353.55276 -315.66739) (xy 353.747837 -315.66739) (xy 353.751859 -315.58167)
			(xy 353.76389 -315.496702) (xy 353.783826 -315.413235) (xy 353.811489 -315.332001) (xy 353.846638 -315.253715)
			(xy 353.888964 -315.179064) (xy 353.938093 -315.108705) (xy 353.993596 -315.043255) (xy 354.054983 -314.983291)
			(xy 354.121716 -314.929338) (xy 354.193208 -314.881871) (xy 354.26883 -314.841307) (xy 354.347919 -314.808003)
			(xy 354.429779 -314.782251) (xy 354.51369 -314.764278) (xy 354.598916 -314.754242) (xy 354.684708 -314.75223)
			(xy 354.77031 -314.758261) (xy 354.854972 -314.772281) (xy 354.937949 -314.794167) (xy 355.018512 -314.823728)
			(xy 355.095952 -314.860702) (xy 355.169591 -314.904766) (xy 355.238779 -314.955532) (xy 355.30291 -315.012553)
			(xy 355.361419 -315.075329) (xy 355.413792 -315.143309) (xy 355.45957 -315.215894) (xy 355.49835 -315.292446)
			(xy 355.529791 -315.372294) (xy 355.553617 -315.454735) (xy 355.569618 -315.539045) (xy 355.577653 -315.624483)
			(xy 355.578156 -315.66739) (xy 355.57766 -315.709738) (xy 357.952036 -315.709738) (xy 357.952036 -315.625042)
			(xy 357.960087 -315.540728) (xy 357.976116 -315.457562) (xy 357.999977 -315.376295) (xy 358.031456 -315.297665)
			(xy 358.070267 -315.222384) (xy 358.116057 -315.151132) (xy 358.168413 -315.084556) (xy 358.226861 -315.023258)
			(xy 358.290871 -314.967793) (xy 358.359863 -314.918664) (xy 358.433213 -314.876315) (xy 358.510256 -314.841131)
			(xy 358.590295 -314.813429) (xy 358.672604 -314.793461) (xy 358.756439 -314.781408) (xy 358.84104 -314.777378)
			(xy 358.925641 -314.781408) (xy 359.009476 -314.793461) (xy 359.091785 -314.813429) (xy 359.171824 -314.841131)
			(xy 359.248867 -314.876315) (xy 359.322217 -314.918664) (xy 359.391209 -314.967793) (xy 359.455219 -315.023258)
			(xy 359.513667 -315.084556) (xy 359.566023 -315.151132) (xy 359.611813 -315.222384) (xy 359.650624 -315.297665)
			(xy 359.682103 -315.376295) (xy 359.705964 -315.457562) (xy 359.721993 -315.540728) (xy 359.730044 -315.625042)
			(xy 359.730548 -315.66739) (xy 359.925625 -315.66739) (xy 359.929647 -315.58167) (xy 359.941678 -315.496702)
			(xy 359.961614 -315.413235) (xy 359.989277 -315.332001) (xy 360.024426 -315.253715) (xy 360.066752 -315.179064)
			(xy 360.115881 -315.108705) (xy 360.171384 -315.043255) (xy 360.232771 -314.983291) (xy 360.299504 -314.929338)
			(xy 360.370996 -314.881871) (xy 360.446618 -314.841307) (xy 360.525707 -314.808003) (xy 360.607567 -314.782251)
			(xy 360.691478 -314.764278) (xy 360.776704 -314.754242) (xy 360.862496 -314.75223) (xy 360.948098 -314.758261)
			(xy 361.03276 -314.772281) (xy 361.115737 -314.794167) (xy 361.1963 -314.823728) (xy 361.27374 -314.860702)
			(xy 361.347379 -314.904766) (xy 361.416567 -314.955532) (xy 361.480698 -315.012553) (xy 361.539207 -315.075329)
			(xy 361.59158 -315.143309) (xy 361.637358 -315.215894) (xy 361.676138 -315.292446) (xy 361.707579 -315.372294)
			(xy 361.731405 -315.454735) (xy 361.747406 -315.539045) (xy 361.755441 -315.624483) (xy 361.755944 -315.66739)
			(xy 361.755448 -315.709738) (xy 364.149636 -315.709738) (xy 364.149636 -315.625042) (xy 364.157687 -315.540728)
			(xy 364.173716 -315.457562) (xy 364.197577 -315.376295) (xy 364.229056 -315.297665) (xy 364.267867 -315.222384)
			(xy 364.313657 -315.151132) (xy 364.366013 -315.084556) (xy 364.424461 -315.023258) (xy 364.488471 -314.967793)
			(xy 364.557463 -314.918664) (xy 364.630813 -314.876315) (xy 364.707856 -314.841131) (xy 364.787895 -314.813429)
			(xy 364.870204 -314.793461) (xy 364.954039 -314.781408) (xy 365.03864 -314.777378) (xy 365.123241 -314.781408)
			(xy 365.207076 -314.793461) (xy 365.289385 -314.813429) (xy 365.369424 -314.841131) (xy 365.446467 -314.876315)
			(xy 365.519817 -314.918664) (xy 365.588809 -314.967793) (xy 365.652819 -315.023258) (xy 365.711267 -315.084556)
			(xy 365.763623 -315.151132) (xy 365.809413 -315.222384) (xy 365.848224 -315.297665) (xy 365.879703 -315.376295)
			(xy 365.903564 -315.457562) (xy 365.919593 -315.540728) (xy 365.927644 -315.625042) (xy 365.928148 -315.66739)
			(xy 366.123225 -315.66739) (xy 366.127247 -315.58167) (xy 366.139278 -315.496702) (xy 366.159214 -315.413235)
			(xy 366.186877 -315.332001) (xy 366.222026 -315.253715) (xy 366.264352 -315.179064) (xy 366.313481 -315.108705)
			(xy 366.368984 -315.043255) (xy 366.430371 -314.983291) (xy 366.497104 -314.929338) (xy 366.568596 -314.881871)
			(xy 366.644218 -314.841307) (xy 366.723307 -314.808003) (xy 366.805167 -314.782251) (xy 366.889078 -314.764278)
			(xy 366.974304 -314.754242) (xy 367.060096 -314.75223) (xy 367.145698 -314.758261) (xy 367.23036 -314.772281)
			(xy 367.313337 -314.794167) (xy 367.3939 -314.823728) (xy 367.47134 -314.860702) (xy 367.544979 -314.904766)
			(xy 367.614167 -314.955532) (xy 367.678298 -315.012553) (xy 367.736807 -315.075329) (xy 367.78918 -315.143309)
			(xy 367.834958 -315.215894) (xy 367.873738 -315.292446) (xy 367.905179 -315.372294) (xy 367.929005 -315.454735)
			(xy 367.945006 -315.539045) (xy 367.953041 -315.624483) (xy 367.953544 -315.66739) (xy 367.953048 -315.709738)
			(xy 370.347236 -315.709738) (xy 370.347236 -315.625042) (xy 370.355287 -315.540728) (xy 370.371316 -315.457562)
			(xy 370.395177 -315.376295) (xy 370.426656 -315.297665) (xy 370.465467 -315.222384) (xy 370.511257 -315.151132)
			(xy 370.563613 -315.084556) (xy 370.622061 -315.023258) (xy 370.686071 -314.967793) (xy 370.755063 -314.918664)
			(xy 370.828413 -314.876315) (xy 370.905456 -314.841131) (xy 370.985495 -314.813429) (xy 371.067804 -314.793461)
			(xy 371.151639 -314.781408) (xy 371.23624 -314.777378) (xy 371.320841 -314.781408) (xy 371.404676 -314.793461)
			(xy 371.486985 -314.813429) (xy 371.567024 -314.841131) (xy 371.644067 -314.876315) (xy 371.717417 -314.918664)
			(xy 371.786409 -314.967793) (xy 371.850419 -315.023258) (xy 371.908867 -315.084556) (xy 371.961223 -315.151132)
			(xy 372.007013 -315.222384) (xy 372.045824 -315.297665) (xy 372.077303 -315.376295) (xy 372.101164 -315.457562)
			(xy 372.117193 -315.540728) (xy 372.125244 -315.625042) (xy 372.125748 -315.66739) (xy 372.320825 -315.66739)
			(xy 372.324847 -315.58167) (xy 372.336878 -315.496702) (xy 372.356814 -315.413235) (xy 372.384477 -315.332001)
			(xy 372.419626 -315.253715) (xy 372.461952 -315.179064) (xy 372.511081 -315.108705) (xy 372.566584 -315.043255)
			(xy 372.627971 -314.983291) (xy 372.694704 -314.929338) (xy 372.766196 -314.881871) (xy 372.841818 -314.841307)
			(xy 372.920907 -314.808003) (xy 373.002767 -314.782251) (xy 373.086678 -314.764278) (xy 373.171904 -314.754242)
			(xy 373.257696 -314.75223) (xy 373.343298 -314.758261) (xy 373.42796 -314.772281) (xy 373.510937 -314.794167)
			(xy 373.5915 -314.823728) (xy 373.66894 -314.860702) (xy 373.742579 -314.904766) (xy 373.811767 -314.955532)
			(xy 373.875898 -315.012553) (xy 373.934407 -315.075329) (xy 373.98678 -315.143309) (xy 374.032558 -315.215894)
			(xy 374.071338 -315.292446) (xy 374.102779 -315.372294) (xy 374.126605 -315.454735) (xy 374.142606 -315.539045)
			(xy 374.150641 -315.624483) (xy 374.151144 -315.66739) (xy 374.150641 -315.710297) (xy 374.142606 -315.795735)
			(xy 374.126605 -315.880045) (xy 374.102779 -315.962486) (xy 374.071338 -316.042334) (xy 374.032558 -316.118886)
			(xy 373.98678 -316.191471) (xy 373.934407 -316.259451) (xy 373.875898 -316.322227) (xy 373.811767 -316.379248)
			(xy 373.742579 -316.430014) (xy 373.66894 -316.474078) (xy 373.5915 -316.511052) (xy 373.510937 -316.540613)
			(xy 373.42796 -316.562499) (xy 373.343298 -316.576519) (xy 373.257696 -316.58255) (xy 373.171904 -316.580538)
			(xy 373.086678 -316.570502) (xy 373.002767 -316.552529) (xy 372.920907 -316.526777) (xy 372.841818 -316.493473)
			(xy 372.766196 -316.452909) (xy 372.694704 -316.405442) (xy 372.627971 -316.351489) (xy 372.566584 -316.291525)
			(xy 372.511081 -316.226075) (xy 372.461952 -316.155716) (xy 372.419626 -316.081065) (xy 372.384477 -316.002779)
			(xy 372.356814 -315.921545) (xy 372.336878 -315.838078) (xy 372.324847 -315.75311) (xy 372.320825 -315.66739)
			(xy 372.125748 -315.66739) (xy 372.125244 -315.709738) (xy 372.117193 -315.794052) (xy 372.101164 -315.877218)
			(xy 372.077303 -315.958485) (xy 372.045824 -316.037115) (xy 372.007013 -316.112396) (xy 371.961223 -316.183648)
			(xy 371.908867 -316.250224) (xy 371.850419 -316.311522) (xy 371.786409 -316.366987) (xy 371.717417 -316.416116)
			(xy 371.644067 -316.458465) (xy 371.567024 -316.493649) (xy 371.486985 -316.521351) (xy 371.404676 -316.541319)
			(xy 371.320841 -316.553372) (xy 371.23624 -316.557403) (xy 371.151639 -316.553372) (xy 371.067804 -316.541319)
			(xy 370.985495 -316.521351) (xy 370.905456 -316.493649) (xy 370.828413 -316.458465) (xy 370.755063 -316.416116)
			(xy 370.686071 -316.366987) (xy 370.622061 -316.311522) (xy 370.563613 -316.250224) (xy 370.511257 -316.183648)
			(xy 370.465467 -316.112396) (xy 370.426656 -316.037115) (xy 370.395177 -315.958485) (xy 370.371316 -315.877218)
			(xy 370.355287 -315.794052) (xy 370.347236 -315.709738) (xy 367.953048 -315.709738) (xy 367.953041 -315.710297)
			(xy 367.945006 -315.795735) (xy 367.929005 -315.880045) (xy 367.905179 -315.962486) (xy 367.873738 -316.042334)
			(xy 367.834958 -316.118886) (xy 367.78918 -316.191471) (xy 367.736807 -316.259451) (xy 367.678298 -316.322227)
			(xy 367.614167 -316.379248) (xy 367.544979 -316.430014) (xy 367.47134 -316.474078) (xy 367.3939 -316.511052)
			(xy 367.313337 -316.540613) (xy 367.23036 -316.562499) (xy 367.145698 -316.576519) (xy 367.060096 -316.58255)
			(xy 366.974304 -316.580538) (xy 366.889078 -316.570502) (xy 366.805167 -316.552529) (xy 366.723307 -316.526777)
			(xy 366.644218 -316.493473) (xy 366.568596 -316.452909) (xy 366.497104 -316.405442) (xy 366.430371 -316.351489)
			(xy 366.368984 -316.291525) (xy 366.313481 -316.226075) (xy 366.264352 -316.155716) (xy 366.222026 -316.081065)
			(xy 366.186877 -316.002779) (xy 366.159214 -315.921545) (xy 366.139278 -315.838078) (xy 366.127247 -315.75311)
			(xy 366.123225 -315.66739) (xy 365.928148 -315.66739) (xy 365.927644 -315.709738) (xy 365.919593 -315.794052)
			(xy 365.903564 -315.877218) (xy 365.879703 -315.958485) (xy 365.848224 -316.037115) (xy 365.809413 -316.112396)
			(xy 365.763623 -316.183648) (xy 365.711267 -316.250224) (xy 365.652819 -316.311522) (xy 365.588809 -316.366987)
			(xy 365.519817 -316.416116) (xy 365.446467 -316.458465) (xy 365.369424 -316.493649) (xy 365.289385 -316.521351)
			(xy 365.207076 -316.541319) (xy 365.123241 -316.553372) (xy 365.03864 -316.557403) (xy 364.954039 -316.553372)
			(xy 364.870204 -316.541319) (xy 364.787895 -316.521351) (xy 364.707856 -316.493649) (xy 364.630813 -316.458465)
			(xy 364.557463 -316.416116) (xy 364.488471 -316.366987) (xy 364.424461 -316.311522) (xy 364.366013 -316.250224)
			(xy 364.313657 -316.183648) (xy 364.267867 -316.112396) (xy 364.229056 -316.037115) (xy 364.197577 -315.958485)
			(xy 364.173716 -315.877218) (xy 364.157687 -315.794052) (xy 364.149636 -315.709738) (xy 361.755448 -315.709738)
			(xy 361.755441 -315.710297) (xy 361.747406 -315.795735) (xy 361.731405 -315.880045) (xy 361.707579 -315.962486)
			(xy 361.676138 -316.042334) (xy 361.637358 -316.118886) (xy 361.59158 -316.191471) (xy 361.539207 -316.259451)
			(xy 361.480698 -316.322227) (xy 361.416567 -316.379248) (xy 361.347379 -316.430014) (xy 361.27374 -316.474078)
			(xy 361.1963 -316.511052) (xy 361.115737 -316.540613) (xy 361.03276 -316.562499) (xy 360.948098 -316.576519)
			(xy 360.862496 -316.58255) (xy 360.776704 -316.580538) (xy 360.691478 -316.570502) (xy 360.607567 -316.552529)
			(xy 360.525707 -316.526777) (xy 360.446618 -316.493473) (xy 360.370996 -316.452909) (xy 360.299504 -316.405442)
			(xy 360.232771 -316.351489) (xy 360.171384 -316.291525) (xy 360.115881 -316.226075) (xy 360.066752 -316.155716)
			(xy 360.024426 -316.081065) (xy 359.989277 -316.002779) (xy 359.961614 -315.921545) (xy 359.941678 -315.838078)
			(xy 359.929647 -315.75311) (xy 359.925625 -315.66739) (xy 359.730548 -315.66739) (xy 359.730044 -315.709738)
			(xy 359.721993 -315.794052) (xy 359.705964 -315.877218) (xy 359.682103 -315.958485) (xy 359.650624 -316.037115)
			(xy 359.611813 -316.112396) (xy 359.566023 -316.183648) (xy 359.513667 -316.250224) (xy 359.455219 -316.311522)
			(xy 359.391209 -316.366987) (xy 359.322217 -316.416116) (xy 359.248867 -316.458465) (xy 359.171824 -316.493649)
			(xy 359.091785 -316.521351) (xy 359.009476 -316.541319) (xy 358.925641 -316.553372) (xy 358.84104 -316.557403)
			(xy 358.756439 -316.553372) (xy 358.672604 -316.541319) (xy 358.590295 -316.521351) (xy 358.510256 -316.493649)
			(xy 358.433213 -316.458465) (xy 358.359863 -316.416116) (xy 358.290871 -316.366987) (xy 358.226861 -316.311522)
			(xy 358.168413 -316.250224) (xy 358.116057 -316.183648) (xy 358.070267 -316.112396) (xy 358.031456 -316.037115)
			(xy 357.999977 -315.958485) (xy 357.976116 -315.877218) (xy 357.960087 -315.794052) (xy 357.952036 -315.709738)
			(xy 355.57766 -315.709738) (xy 355.577653 -315.710297) (xy 355.569618 -315.795735) (xy 355.553617 -315.880045)
			(xy 355.529791 -315.962486) (xy 355.49835 -316.042334) (xy 355.45957 -316.118886) (xy 355.413792 -316.191471)
			(xy 355.361419 -316.259451) (xy 355.30291 -316.322227) (xy 355.238779 -316.379248) (xy 355.169591 -316.430014)
			(xy 355.095952 -316.474078) (xy 355.018512 -316.511052) (xy 354.937949 -316.540613) (xy 354.854972 -316.562499)
			(xy 354.77031 -316.576519) (xy 354.684708 -316.58255) (xy 354.598916 -316.580538) (xy 354.51369 -316.570502)
			(xy 354.429779 -316.552529) (xy 354.347919 -316.526777) (xy 354.26883 -316.493473) (xy 354.193208 -316.452909)
			(xy 354.121716 -316.405442) (xy 354.054983 -316.351489) (xy 353.993596 -316.291525) (xy 353.938093 -316.226075)
			(xy 353.888964 -316.155716) (xy 353.846638 -316.081065) (xy 353.811489 -316.002779) (xy 353.783826 -315.921545)
			(xy 353.76389 -315.838078) (xy 353.751859 -315.75311) (xy 353.747837 -315.66739) (xy 353.55276 -315.66739)
			(xy 353.552256 -315.709738) (xy 353.544205 -315.794052) (xy 353.528176 -315.877218) (xy 353.504315 -315.958485)
			(xy 353.472836 -316.037115) (xy 353.434025 -316.112396) (xy 353.388235 -316.183648) (xy 353.335879 -316.250224)
			(xy 353.277431 -316.311522) (xy 353.213421 -316.366987) (xy 353.144429 -316.416116) (xy 353.071079 -316.458465)
			(xy 352.994036 -316.493649) (xy 352.913997 -316.521351) (xy 352.831688 -316.541319) (xy 352.747853 -316.553372)
			(xy 352.663252 -316.557403) (xy 352.578651 -316.553372) (xy 352.494816 -316.541319) (xy 352.412507 -316.521351)
			(xy 352.332468 -316.493649) (xy 352.255425 -316.458465) (xy 352.182075 -316.416116) (xy 352.113083 -316.366987)
			(xy 352.049073 -316.311522) (xy 351.990625 -316.250224) (xy 351.938269 -316.183648) (xy 351.892479 -316.112396)
			(xy 351.853668 -316.037115) (xy 351.822189 -315.958485) (xy 351.798328 -315.877218) (xy 351.782299 -315.794052)
			(xy 351.774248 -315.709738) (xy 349.38006 -315.709738) (xy 349.380053 -315.710297) (xy 349.372018 -315.795735)
			(xy 349.356017 -315.880045) (xy 349.332191 -315.962486) (xy 349.30075 -316.042334) (xy 349.26197 -316.118886)
			(xy 349.216192 -316.191471) (xy 349.163819 -316.259451) (xy 349.10531 -316.322227) (xy 349.041179 -316.379248)
			(xy 348.971991 -316.430014) (xy 348.898352 -316.474078) (xy 348.820912 -316.511052) (xy 348.740349 -316.540613)
			(xy 348.657372 -316.562499) (xy 348.57271 -316.576519) (xy 348.487108 -316.58255) (xy 348.401316 -316.580538)
			(xy 348.31609 -316.570502) (xy 348.232179 -316.552529) (xy 348.150319 -316.526777) (xy 348.07123 -316.493473)
			(xy 347.995608 -316.452909) (xy 347.924116 -316.405442) (xy 347.857383 -316.351489) (xy 347.795996 -316.291525)
			(xy 347.740493 -316.226075) (xy 347.691364 -316.155716) (xy 347.649038 -316.081065) (xy 347.613889 -316.002779)
			(xy 347.586226 -315.921545) (xy 347.56629 -315.838078) (xy 347.554259 -315.75311) (xy 347.550237 -315.66739)
			(xy 347.35516 -315.66739) (xy 347.354656 -315.709738) (xy 347.346605 -315.794052) (xy 347.330576 -315.877218)
			(xy 347.306715 -315.958485) (xy 347.275236 -316.037115) (xy 347.236425 -316.112396) (xy 347.190635 -316.183648)
			(xy 347.138279 -316.250224) (xy 347.079831 -316.311522) (xy 347.015821 -316.366987) (xy 346.946829 -316.416116)
			(xy 346.873479 -316.458465) (xy 346.796436 -316.493649) (xy 346.716397 -316.521351) (xy 346.634088 -316.541319)
			(xy 346.550253 -316.553372) (xy 346.465652 -316.557403) (xy 346.381051 -316.553372) (xy 346.297216 -316.541319)
			(xy 346.214907 -316.521351) (xy 346.134868 -316.493649) (xy 346.057825 -316.458465) (xy 345.984475 -316.416116)
			(xy 345.915483 -316.366987) (xy 345.851473 -316.311522) (xy 345.793025 -316.250224) (xy 345.740669 -316.183648)
			(xy 345.694879 -316.112396) (xy 345.656068 -316.037115) (xy 345.624589 -315.958485) (xy 345.600728 -315.877218)
			(xy 345.584699 -315.794052) (xy 345.576648 -315.709738) (xy 333.480336 -315.709738) (xy 332.311756 -321.904106)
			(xy 328.24928 -327.472548) (xy 328.24928 -332.273402) (xy 328.55408 -332.578202) (xy 331.709776 -332.578202)
		)
		(stroke
			(width 0)
			(type solid)
		)
		(fill yes)
		(layer "In15.Cu")
		(net "PVCCIN_CPU0")
	)
	(gr_poly
		(pts
			(xy 102.912672 -365.776002) (xy 100.379276 -363.242352) (xy 100.359153 -363.221501) (xy 100.325057 -363.17465)
			(xy 100.298712 -363.12304) (xy 100.280765 -363.067945) (xy 100.271661 -363.01072) (xy 100.271072 -362.981748)
			(xy 100.271072 -355.644704) (xy 100.271635 -355.615732) (xy 100.280749 -355.558508) (xy 100.298705 -355.503416)
			(xy 100.325063 -355.451812) (xy 100.359171 -355.404969) (xy 100.379276 -355.3841) (xy 101.495352 -354.26777)
			(xy 101.498654 -354.262436) (xy 101.513546 -354.238647) (xy 101.549209 -354.195313) (xy 101.590833 -354.157668)
			(xy 101.637522 -354.126525) (xy 101.688268 -354.102554) (xy 101.741977 -354.086273) (xy 101.797491 -354.078033)
			(xy 101.825552 -354.077524) (xy 101.852806 -354.077984) (xy 101.906761 -354.085736) (xy 101.959062 -354.101088)
			(xy 102.008647 -354.123728) (xy 102.054503 -354.153195) (xy 102.095699 -354.188889) (xy 102.131395 -354.230084)
			(xy 102.160864 -354.275939) (xy 102.183507 -354.325523) (xy 102.198861 -354.377824) (xy 102.206615 -354.431778)
			(xy 102.20706 -354.459032) (xy 102.206567 -354.487097) (xy 102.205082 -354.497132) (xy 105.004868 -354.497132)
			(xy 105.008939 -354.44151) (xy 105.021065 -354.387073) (xy 105.040988 -354.334982) (xy 105.068284 -354.286347)
			(xy 105.10237 -354.242204) (xy 105.142519 -354.203495) (xy 105.187877 -354.171044) (xy 105.237477 -354.145543)
			(xy 105.290261 -354.127536) (xy 105.345104 -354.117406) (xy 105.400838 -354.115369) (xy 105.456275 -354.121469)
			(xy 105.510232 -354.135575) (xy 105.525446 -354.14204) (xy 111.725708 -354.14204) (xy 111.729779 -354.086418)
			(xy 111.741905 -354.031981) (xy 111.761828 -353.97989) (xy 111.789124 -353.931255) (xy 111.82321 -353.887112)
			(xy 111.863359 -353.848403) (xy 111.908717 -353.815952) (xy 111.958317 -353.790451) (xy 112.011101 -353.772444)
			(xy 112.065944 -353.762314) (xy 112.121678 -353.760277) (xy 112.177115 -353.766377) (xy 112.231072 -353.780483)
			(xy 112.282401 -353.802295) (xy 112.330007 -353.831349) (xy 112.372875 -353.867024) (xy 112.410092 -353.908561)
			(xy 112.440865 -353.955074) (xy 112.464537 -354.005571) (xy 112.480605 -354.058978) (xy 112.488725 -354.114154)
			(xy 112.489234 -354.14204) (xy 112.488725 -354.169926) (xy 112.480605 -354.225102) (xy 112.464537 -354.278509)
			(xy 112.440865 -354.329006) (xy 112.410092 -354.375519) (xy 112.372875 -354.417056) (xy 112.330007 -354.452731)
			(xy 112.282401 -354.481785) (xy 112.231072 -354.503597) (xy 112.177115 -354.517703) (xy 112.121678 -354.523803)
			(xy 112.065944 -354.521766) (xy 112.011101 -354.511636) (xy 111.958317 -354.493629) (xy 111.908717 -354.468128)
			(xy 111.863359 -354.435677) (xy 111.82321 -354.396968) (xy 111.789124 -354.352825) (xy 111.761828 -354.30419)
			(xy 111.741905 -354.252099) (xy 111.729779 -354.197662) (xy 111.725708 -354.14204) (xy 105.525446 -354.14204)
			(xy 105.561561 -354.157387) (xy 105.609167 -354.186441) (xy 105.652035 -354.222116) (xy 105.689252 -354.263653)
			(xy 105.720025 -354.310166) (xy 105.743697 -354.360663) (xy 105.759765 -354.41407) (xy 105.767885 -354.469246)
			(xy 105.768394 -354.497132) (xy 105.767885 -354.525018) (xy 105.759765 -354.580194) (xy 105.743697 -354.633601)
			(xy 105.720025 -354.684098) (xy 105.689252 -354.730611) (xy 105.652035 -354.772148) (xy 105.609167 -354.807823)
			(xy 105.561561 -354.836877) (xy 105.510232 -354.858689) (xy 105.456275 -354.872795) (xy 105.400838 -354.878895)
			(xy 105.345104 -354.876858) (xy 105.290261 -354.866728) (xy 105.237477 -354.848721) (xy 105.187877 -354.82322)
			(xy 105.142519 -354.790769) (xy 105.10237 -354.75206) (xy 105.068284 -354.707917) (xy 105.040988 -354.659282)
			(xy 105.021065 -354.607191) (xy 105.008939 -354.552754) (xy 105.004868 -354.497132) (xy 102.205082 -354.497132)
			(xy 102.198349 -354.542622) (xy 102.182082 -354.596343) (xy 102.158115 -354.647099) (xy 102.126968 -354.693793)
			(xy 102.089313 -354.735418) (xy 102.045963 -354.771074) (xy 102.022148 -354.78593) (xy 102.016814 -354.789232)
			(xy 101.94163 -354.864416) (xy 101.931397 -354.875401) (xy 101.917251 -354.901866) (xy 101.911399 -354.931298)
			(xy 101.914346 -354.96116) (xy 101.925837 -354.988881) (xy 101.944882 -355.01207) (xy 101.96984 -355.028731)
			(xy 101.984048 -355.03358) (xy 102.009864 -355.041851) (xy 102.059035 -355.06467) (xy 102.104483 -355.094218)
			(xy 102.145292 -355.129899) (xy 102.170808 -355.159564) (xy 111.223296 -355.159564) (xy 111.227367 -355.103942)
			(xy 111.239493 -355.049505) (xy 111.259416 -354.997414) (xy 111.286712 -354.948779) (xy 111.320798 -354.904636)
			(xy 111.360947 -354.865927) (xy 111.406305 -354.833476) (xy 111.455905 -354.807975) (xy 111.508689 -354.789968)
			(xy 111.563532 -354.779838) (xy 111.619266 -354.777801) (xy 111.674703 -354.783901) (xy 111.72866 -354.798007)
			(xy 111.779989 -354.819819) (xy 111.827595 -354.848873) (xy 111.870463 -354.884548) (xy 111.90768 -354.926085)
			(xy 111.938453 -354.972598) (xy 111.962125 -355.023095) (xy 111.972845 -355.058726) (xy 112.247678 -355.058726)
			(xy 112.251749 -355.003104) (xy 112.263875 -354.948667) (xy 112.283798 -354.896576) (xy 112.311094 -354.847941)
			(xy 112.34518 -354.803798) (xy 112.385329 -354.765089) (xy 112.430687 -354.732638) (xy 112.480287 -354.707137)
			(xy 112.533071 -354.68913) (xy 112.587914 -354.679) (xy 112.643648 -354.676963) (xy 112.699085 -354.683063)
			(xy 112.753042 -354.697169) (xy 112.804371 -354.718981) (xy 112.851977 -354.748035) (xy 112.894845 -354.78371)
			(xy 112.900703 -354.790248) (xy 113.438938 -354.790248) (xy 113.443009 -354.734626) (xy 113.455135 -354.680189)
			(xy 113.475058 -354.628098) (xy 113.502354 -354.579463) (xy 113.53644 -354.53532) (xy 113.576589 -354.496611)
			(xy 113.621947 -354.46416) (xy 113.671547 -354.438659) (xy 113.724331 -354.420652) (xy 113.779174 -354.410522)
			(xy 113.834908 -354.408485) (xy 113.890345 -354.414585) (xy 113.944302 -354.428691) (xy 113.995631 -354.450503)
			(xy 114.043237 -354.479557) (xy 114.086105 -354.515232) (xy 114.123322 -354.556769) (xy 114.154095 -354.603282)
			(xy 114.177767 -354.653779) (xy 114.188028 -354.687886) (xy 116.286026 -354.687886) (xy 116.286472 -354.661506)
			(xy 116.293727 -354.609248) (xy 116.30811 -354.558488) (xy 116.329348 -354.510192) (xy 116.357036 -354.465282)
			(xy 116.390646 -354.424613) (xy 116.429536 -354.388961) (xy 116.472967 -354.359006) (xy 116.496338 -354.346764)
			(xy 116.508712 -354.340085) (xy 116.529447 -354.321108) (xy 116.544213 -354.29719) (xy 116.551887 -354.270148)
			(xy 116.551885 -354.242039) (xy 116.544208 -354.214999) (xy 116.529439 -354.191082) (xy 116.508701 -354.172108)
			(xy 116.496338 -354.165408) (xy 116.472948 -354.153203) (xy 116.429525 -354.123234) (xy 116.390642 -354.087572)
			(xy 116.357039 -354.046897) (xy 116.329355 -354.001983) (xy 116.308118 -353.953686) (xy 116.293731 -353.902924)
			(xy 116.28647 -353.850666) (xy 116.286026 -353.824286) (xy 116.286512 -353.797035) (xy 116.294268 -353.743087)
			(xy 116.309623 -353.690792) (xy 116.332265 -353.641215) (xy 116.361731 -353.595365) (xy 116.397422 -353.554174)
			(xy 116.438613 -353.518483) (xy 116.484463 -353.489017) (xy 116.53404 -353.466375) (xy 116.586335 -353.45102)
			(xy 116.640283 -353.443264) (xy 116.694785 -353.443264) (xy 116.748733 -353.45102) (xy 116.801028 -353.466375)
			(xy 116.850605 -353.489017) (xy 116.896455 -353.518483) (xy 116.937646 -353.554174) (xy 116.973337 -353.595365)
			(xy 117.002803 -353.641215) (xy 117.025445 -353.690792) (xy 117.0408 -353.743087) (xy 117.048556 -353.797035)
			(xy 117.049042 -353.824286) (xy 117.048618 -353.850666) (xy 117.041355 -353.902923) (xy 117.026965 -353.953683)
			(xy 117.005723 -354.001977) (xy 116.978032 -354.046886) (xy 116.944421 -354.087554) (xy 116.90553 -354.123207)
			(xy 116.862101 -354.153164) (xy 116.83873 -354.165408) (xy 116.826384 -354.172131) (xy 116.805657 -354.191103)
			(xy 116.790897 -354.215013) (xy 116.783225 -354.242044) (xy 116.783223 -354.270143) (xy 116.790892 -354.297175)
			(xy 116.805649 -354.321087) (xy 116.826374 -354.340062) (xy 116.83873 -354.346764) (xy 116.862101 -354.359004)
			(xy 116.905524 -354.388967) (xy 116.944409 -354.424623) (xy 116.978014 -354.465293) (xy 117.005701 -354.510202)
			(xy 117.026941 -354.558495) (xy 117.041331 -354.609252) (xy 117.048596 -354.661507) (xy 117.049042 -354.687886)
			(xy 117.048556 -354.715137) (xy 117.0408 -354.769085) (xy 117.025445 -354.82138) (xy 117.002803 -354.870957)
			(xy 116.973337 -354.916807) (xy 116.937646 -354.957998) (xy 116.896455 -354.993689) (xy 116.850605 -355.023155)
			(xy 116.801028 -355.045797) (xy 116.748733 -355.061152) (xy 116.694785 -355.068908) (xy 116.640283 -355.068908)
			(xy 116.586335 -355.061152) (xy 116.53404 -355.045797) (xy 116.484463 -355.023155) (xy 116.438613 -354.993689)
			(xy 116.397422 -354.957998) (xy 116.361731 -354.916807) (xy 116.332265 -354.870957) (xy 116.309623 -354.82138)
			(xy 116.294268 -354.769085) (xy 116.286512 -354.715137) (xy 116.286026 -354.687886) (xy 114.188028 -354.687886)
			(xy 114.193835 -354.707186) (xy 114.201955 -354.762362) (xy 114.202464 -354.790248) (xy 114.201955 -354.818134)
			(xy 114.193835 -354.87331) (xy 114.177767 -354.926717) (xy 114.154095 -354.977214) (xy 114.123322 -355.023727)
			(xy 114.086105 -355.065264) (xy 114.043237 -355.100939) (xy 113.995631 -355.129993) (xy 113.944302 -355.151805)
			(xy 113.890345 -355.165911) (xy 113.834908 -355.172011) (xy 113.779174 -355.169974) (xy 113.724331 -355.159844)
			(xy 113.671547 -355.141837) (xy 113.621947 -355.116336) (xy 113.576589 -355.083885) (xy 113.53644 -355.045176)
			(xy 113.502354 -355.001033) (xy 113.475058 -354.952398) (xy 113.455135 -354.900307) (xy 113.443009 -354.84587)
			(xy 113.438938 -354.790248) (xy 112.900703 -354.790248) (xy 112.932062 -354.825247) (xy 112.962835 -354.87176)
			(xy 112.986507 -354.922257) (xy 113.002575 -354.975664) (xy 113.010695 -355.03084) (xy 113.011204 -355.058726)
			(xy 113.010695 -355.086612) (xy 113.002575 -355.141788) (xy 112.990426 -355.18217) (xy 117.96852 -355.18217)
			(xy 117.972591 -355.126548) (xy 117.984717 -355.072111) (xy 118.00464 -355.02002) (xy 118.031936 -354.971385)
			(xy 118.066022 -354.927242) (xy 118.106171 -354.888533) (xy 118.151529 -354.856082) (xy 118.201129 -354.830581)
			(xy 118.253913 -354.812574) (xy 118.308756 -354.802444) (xy 118.36449 -354.800407) (xy 118.419927 -354.806507)
			(xy 118.473884 -354.820613) (xy 118.525213 -354.842425) (xy 118.572819 -354.871479) (xy 118.615687 -354.907154)
			(xy 118.652904 -354.948691) (xy 118.683677 -354.995204) (xy 118.707349 -355.045701) (xy 118.723417 -355.099108)
			(xy 118.731537 -355.154284) (xy 118.732046 -355.18217) (xy 118.731537 -355.210056) (xy 118.723417 -355.265232)
			(xy 118.707349 -355.318639) (xy 118.683677 -355.369136) (xy 118.652904 -355.415649) (xy 118.615687 -355.457186)
			(xy 118.572819 -355.492861) (xy 118.525213 -355.521915) (xy 118.473884 -355.543727) (xy 118.419927 -355.557833)
			(xy 118.36449 -355.563933) (xy 118.308756 -355.561896) (xy 118.253913 -355.551766) (xy 118.201129 -355.533759)
			(xy 118.151529 -355.508258) (xy 118.106171 -355.475807) (xy 118.066022 -355.437098) (xy 118.031936 -355.392955)
			(xy 118.00464 -355.34432) (xy 117.984717 -355.292229) (xy 117.972591 -355.237792) (xy 117.96852 -355.18217)
			(xy 112.990426 -355.18217) (xy 112.986507 -355.195195) (xy 112.962835 -355.245692) (xy 112.932062 -355.292205)
			(xy 112.894845 -355.333742) (xy 112.851977 -355.369417) (xy 112.804371 -355.398471) (xy 112.753042 -355.420283)
			(xy 112.699085 -355.434389) (xy 112.643648 -355.440489) (xy 112.587914 -355.438452) (xy 112.533071 -355.428322)
			(xy 112.480287 -355.410315) (xy 112.430687 -355.384814) (xy 112.385329 -355.352363) (xy 112.34518 -355.313654)
			(xy 112.311094 -355.269511) (xy 112.283798 -355.220876) (xy 112.263875 -355.168785) (xy 112.251749 -355.114348)
			(xy 112.247678 -355.058726) (xy 111.972845 -355.058726) (xy 111.978193 -355.076502) (xy 111.986313 -355.131678)
			(xy 111.986822 -355.159564) (xy 111.986313 -355.18745) (xy 111.978193 -355.242626) (xy 111.962125 -355.296033)
			(xy 111.938453 -355.34653) (xy 111.90768 -355.393043) (xy 111.870463 -355.43458) (xy 111.827595 -355.470255)
			(xy 111.779989 -355.499309) (xy 111.72866 -355.521121) (xy 111.674703 -355.535227) (xy 111.619266 -355.541327)
			(xy 111.563532 -355.53929) (xy 111.508689 -355.52916) (xy 111.455905 -355.511153) (xy 111.406305 -355.485652)
			(xy 111.360947 -355.453201) (xy 111.320798 -355.414492) (xy 111.286712 -355.370349) (xy 111.259416 -355.321714)
			(xy 111.239493 -355.269623) (xy 111.227367 -355.215186) (xy 111.223296 -355.159564) (xy 102.170808 -355.159564)
			(xy 102.180642 -355.170997) (xy 102.20982 -355.216682) (xy 102.23224 -355.266037) (xy 102.24745 -355.318068)
			(xy 102.255144 -355.371728) (xy 102.255574 -355.398832) (xy 102.255108 -355.426082) (xy 102.247348 -355.480028)
			(xy 102.231988 -355.53232) (xy 102.209344 -355.581894) (xy 102.179874 -355.627741) (xy 102.14418 -355.668927)
			(xy 102.102988 -355.704614) (xy 102.057136 -355.734075) (xy 102.007558 -355.756712) (xy 101.955264 -355.772062)
			(xy 101.901317 -355.779813) (xy 101.874066 -355.78034) (xy 101.846961 -355.779868) (xy 101.793295 -355.7722)
			(xy 101.741257 -355.75701) (xy 101.691894 -355.734603) (xy 101.646202 -355.705431) (xy 101.605101 -355.670082)
			(xy 101.569421 -355.629269) (xy 101.539881 -355.583814) (xy 101.517075 -355.534634) (xy 101.508814 -355.508814)
			(xy 101.503954 -355.494609) (xy 101.487291 -355.469653) (xy 101.464101 -355.450609) (xy 101.436381 -355.439116)
			(xy 101.406519 -355.436164) (xy 101.377085 -355.442008) (xy 101.350616 -355.456143) (xy 101.33965 -355.466396)
			(xy 101.008688 -355.797358) (xy 101.008688 -356.261924) (xy 103.482392 -356.261924) (xy 103.486463 -356.206302)
			(xy 103.498589 -356.151865) (xy 103.518512 -356.099774) (xy 103.545808 -356.051139) (xy 103.579894 -356.006996)
			(xy 103.620043 -355.968287) (xy 103.665401 -355.935836) (xy 103.715001 -355.910335) (xy 103.767785 -355.892328)
			(xy 103.822628 -355.882198) (xy 103.878362 -355.880161) (xy 103.933799 -355.886261) (xy 103.987756 -355.900367)
			(xy 104.039085 -355.922179) (xy 104.086691 -355.951233) (xy 104.129559 -355.986908) (xy 104.166776 -356.028445)
			(xy 104.197549 -356.074958) (xy 104.221221 -356.125455) (xy 104.228884 -356.150926) (xy 110.986314 -356.150926)
			(xy 110.990385 -356.095304) (xy 111.002511 -356.040867) (xy 111.022434 -355.988776) (xy 111.04973 -355.940141)
			(xy 111.083816 -355.895998) (xy 111.123965 -355.857289) (xy 111.169323 -355.824838) (xy 111.218923 -355.799337)
			(xy 111.271707 -355.78133) (xy 111.32655 -355.7712) (xy 111.382284 -355.769163) (xy 111.437721 -355.775263)
			(xy 111.491678 -355.789369) (xy 111.543007 -355.811181) (xy 111.590613 -355.840235) (xy 111.633481 -355.87591)
			(xy 111.670698 -355.917447) (xy 111.687202 -355.942392) (xy 116.343682 -355.942392) (xy 116.347753 -355.88677)
			(xy 116.359879 -355.832333) (xy 116.379802 -355.780242) (xy 116.407098 -355.731607) (xy 116.441184 -355.687464)
			(xy 116.481333 -355.648755) (xy 116.526691 -355.616304) (xy 116.576291 -355.590803) (xy 116.629075 -355.572796)
			(xy 116.683918 -355.562666) (xy 116.739652 -355.560629) (xy 116.795089 -355.566729) (xy 116.849046 -355.580835)
			(xy 116.900375 -355.602647) (xy 116.947981 -355.631701) (xy 116.990849 -355.667376) (xy 117.0181 -355.69779)
			(xy 120.263664 -355.69779) (xy 120.267735 -355.642168) (xy 120.279861 -355.587731) (xy 120.299784 -355.53564)
			(xy 120.32708 -355.487005) (xy 120.361166 -355.442862) (xy 120.401315 -355.404153) (xy 120.446673 -355.371702)
			(xy 120.496273 -355.346201) (xy 120.549057 -355.328194) (xy 120.6039 -355.318064) (xy 120.659634 -355.316027)
			(xy 120.715071 -355.322127) (xy 120.769028 -355.336233) (xy 120.820357 -355.358045) (xy 120.867963 -355.387099)
			(xy 120.910831 -355.422774) (xy 120.948048 -355.464311) (xy 120.978821 -355.510824) (xy 121.002493 -355.561321)
			(xy 121.018561 -355.614728) (xy 121.026681 -355.669904) (xy 121.02719 -355.69779) (xy 121.026681 -355.725676)
			(xy 121.018561 -355.780852) (xy 121.002493 -355.834259) (xy 120.978821 -355.884756) (xy 120.948048 -355.931269)
			(xy 120.910831 -355.972806) (xy 120.867963 -356.008481) (xy 120.82476 -356.034848) (xy 122.442222 -356.034848)
			(xy 122.446293 -355.979226) (xy 122.458419 -355.924789) (xy 122.478342 -355.872698) (xy 122.505638 -355.824063)
			(xy 122.539724 -355.77992) (xy 122.579873 -355.741211) (xy 122.625231 -355.70876) (xy 122.674831 -355.683259)
			(xy 122.727615 -355.665252) (xy 122.782458 -355.655122) (xy 122.838192 -355.653085) (xy 122.893629 -355.659185)
			(xy 122.947586 -355.673291) (xy 122.998915 -355.695103) (xy 123.046521 -355.724157) (xy 123.089389 -355.759832)
			(xy 123.126606 -355.801369) (xy 123.157379 -355.847882) (xy 123.181051 -355.898379) (xy 123.197119 -355.951786)
			(xy 123.205239 -356.006962) (xy 123.205748 -356.034848) (xy 123.205239 -356.062734) (xy 123.197119 -356.11791)
			(xy 123.181051 -356.171317) (xy 123.157379 -356.221814) (xy 123.126606 -356.268327) (xy 123.089389 -356.309864)
			(xy 123.046521 -356.345539) (xy 122.998915 -356.374593) (xy 122.947586 -356.396405) (xy 122.893629 -356.410511)
			(xy 122.838192 -356.416611) (xy 122.782458 -356.414574) (xy 122.727615 -356.404444) (xy 122.674831 -356.386437)
			(xy 122.625231 -356.360936) (xy 122.579873 -356.328485) (xy 122.539724 -356.289776) (xy 122.505638 -356.245633)
			(xy 122.478342 -356.196998) (xy 122.458419 -356.144907) (xy 122.446293 -356.09047) (xy 122.442222 -356.034848)
			(xy 120.82476 -356.034848) (xy 120.820357 -356.037535) (xy 120.769028 -356.059347) (xy 120.715071 -356.073453)
			(xy 120.659634 -356.079553) (xy 120.6039 -356.077516) (xy 120.549057 -356.067386) (xy 120.496273 -356.049379)
			(xy 120.446673 -356.023878) (xy 120.401315 -355.991427) (xy 120.361166 -355.952718) (xy 120.32708 -355.908575)
			(xy 120.299784 -355.85994) (xy 120.279861 -355.807849) (xy 120.267735 -355.753412) (xy 120.263664 -355.69779)
			(xy 117.0181 -355.69779) (xy 117.028066 -355.708913) (xy 117.058839 -355.755426) (xy 117.082511 -355.805923)
			(xy 117.098579 -355.85933) (xy 117.106699 -355.914506) (xy 117.107208 -355.942392) (xy 117.106699 -355.970278)
			(xy 117.098579 -356.025454) (xy 117.082511 -356.078861) (xy 117.058839 -356.129358) (xy 117.028066 -356.175871)
			(xy 116.990849 -356.217408) (xy 116.947981 -356.253083) (xy 116.900375 -356.282137) (xy 116.849046 -356.303949)
			(xy 116.795089 -356.318055) (xy 116.739652 -356.324155) (xy 116.683918 -356.322118) (xy 116.629075 -356.311988)
			(xy 116.576291 -356.293981) (xy 116.526691 -356.26848) (xy 116.481333 -356.236029) (xy 116.441184 -356.19732)
			(xy 116.407098 -356.153177) (xy 116.379802 -356.104542) (xy 116.359879 -356.052451) (xy 116.347753 -355.998014)
			(xy 116.343682 -355.942392) (xy 111.687202 -355.942392) (xy 111.701471 -355.96396) (xy 111.725143 -356.014457)
			(xy 111.741211 -356.067864) (xy 111.749331 -356.12304) (xy 111.74984 -356.150926) (xy 111.749331 -356.178812)
			(xy 111.741211 -356.233988) (xy 111.725143 -356.287395) (xy 111.701471 -356.337892) (xy 111.670698 -356.384405)
			(xy 111.633481 -356.425942) (xy 111.590613 -356.461617) (xy 111.543007 -356.490671) (xy 111.491678 -356.512483)
			(xy 111.437721 -356.526589) (xy 111.382284 -356.532689) (xy 111.32655 -356.530652) (xy 111.271707 -356.520522)
			(xy 111.218923 -356.502515) (xy 111.169323 -356.477014) (xy 111.123965 -356.444563) (xy 111.083816 -356.405854)
			(xy 111.04973 -356.361711) (xy 111.022434 -356.313076) (xy 111.002511 -356.260985) (xy 110.990385 -356.206548)
			(xy 110.986314 -356.150926) (xy 104.228884 -356.150926) (xy 104.237289 -356.178862) (xy 104.245409 -356.234038)
			(xy 104.245918 -356.261924) (xy 104.245409 -356.28981) (xy 104.237289 -356.344986) (xy 104.221221 -356.398393)
			(xy 104.197549 -356.44889) (xy 104.166776 -356.495403) (xy 104.129559 -356.53694) (xy 104.091938 -356.568248)
			(xy 113.183922 -356.568248) (xy 113.187993 -356.512626) (xy 113.200119 -356.458189) (xy 113.220042 -356.406098)
			(xy 113.247338 -356.357463) (xy 113.281424 -356.31332) (xy 113.321573 -356.274611) (xy 113.366931 -356.24216)
			(xy 113.416531 -356.216659) (xy 113.469315 -356.198652) (xy 113.524158 -356.188522) (xy 113.579892 -356.186485)
			(xy 113.635329 -356.192585) (xy 113.689286 -356.206691) (xy 113.740615 -356.228503) (xy 113.788221 -356.257557)
			(xy 113.831089 -356.293232) (xy 113.868306 -356.334769) (xy 113.899079 -356.381282) (xy 113.922751 -356.431779)
			(xy 113.938819 -356.485186) (xy 113.946939 -356.540362) (xy 113.947448 -356.568248) (xy 113.946939 -356.596134)
			(xy 113.938819 -356.65131) (xy 113.922751 -356.704717) (xy 113.899079 -356.755214) (xy 113.868306 -356.801727)
			(xy 113.831089 -356.843264) (xy 113.825211 -356.848156) (xy 114.184174 -356.848156) (xy 114.188245 -356.792534)
			(xy 114.200371 -356.738097) (xy 114.220294 -356.686006) (xy 114.24759 -356.637371) (xy 114.281676 -356.593228)
			(xy 114.321825 -356.554519) (xy 114.367183 -356.522068) (xy 114.416783 -356.496567) (xy 114.469567 -356.47856)
			(xy 114.52441 -356.46843) (xy 114.580144 -356.466393) (xy 114.635581 -356.472493) (xy 114.689538 -356.486599)
			(xy 114.740867 -356.508411) (xy 114.788473 -356.537465) (xy 114.831341 -356.57314) (xy 114.868558 -356.614677)
			(xy 114.899331 -356.66119) (xy 114.923003 -356.711687) (xy 114.939071 -356.765094) (xy 114.947191 -356.82027)
			(xy 114.9477 -356.848156) (xy 114.947191 -356.876042) (xy 114.939071 -356.931218) (xy 114.924629 -356.97922)
			(xy 122.843796 -356.97922) (xy 122.847867 -356.923598) (xy 122.859993 -356.869161) (xy 122.879916 -356.81707)
			(xy 122.907212 -356.768435) (xy 122.941298 -356.724292) (xy 122.981447 -356.685583) (xy 123.026805 -356.653132)
			(xy 123.076405 -356.627631) (xy 123.129189 -356.609624) (xy 123.184032 -356.599494) (xy 123.239766 -356.597457)
			(xy 123.295203 -356.603557) (xy 123.34916 -356.617663) (xy 123.400489 -356.639475) (xy 123.448095 -356.668529)
			(xy 123.490963 -356.704204) (xy 123.52818 -356.745741) (xy 123.558953 -356.792254) (xy 123.582625 -356.842751)
			(xy 123.598693 -356.896158) (xy 123.606813 -356.951334) (xy 123.607322 -356.97922) (xy 123.606813 -357.007106)
			(xy 123.598693 -357.062282) (xy 123.582625 -357.115689) (xy 123.558953 -357.166186) (xy 123.52818 -357.212699)
			(xy 123.490963 -357.254236) (xy 123.448095 -357.289911) (xy 123.400489 -357.318965) (xy 123.34916 -357.340777)
			(xy 123.295203 -357.354883) (xy 123.239766 -357.360983) (xy 123.184032 -357.358946) (xy 123.129189 -357.348816)
			(xy 123.076405 -357.330809) (xy 123.026805 -357.305308) (xy 122.981447 -357.272857) (xy 122.941298 -357.234148)
			(xy 122.907212 -357.190005) (xy 122.879916 -357.14137) (xy 122.859993 -357.089279) (xy 122.847867 -357.034842)
			(xy 122.843796 -356.97922) (xy 114.924629 -356.97922) (xy 114.923003 -356.984625) (xy 114.899331 -357.035122)
			(xy 114.868558 -357.081635) (xy 114.831341 -357.123172) (xy 114.788473 -357.158847) (xy 114.740867 -357.187901)
			(xy 114.689538 -357.209713) (xy 114.635581 -357.223819) (xy 114.580144 -357.229919) (xy 114.52441 -357.227882)
			(xy 114.469567 -357.217752) (xy 114.416783 -357.199745) (xy 114.367183 -357.174244) (xy 114.321825 -357.141793)
			(xy 114.281676 -357.103084) (xy 114.24759 -357.058941) (xy 114.220294 -357.010306) (xy 114.200371 -356.958215)
			(xy 114.188245 -356.903778) (xy 114.184174 -356.848156) (xy 113.825211 -356.848156) (xy 113.788221 -356.878939)
			(xy 113.740615 -356.907993) (xy 113.689286 -356.929805) (xy 113.635329 -356.943911) (xy 113.579892 -356.950011)
			(xy 113.524158 -356.947974) (xy 113.469315 -356.937844) (xy 113.416531 -356.919837) (xy 113.366931 -356.894336)
			(xy 113.321573 -356.861885) (xy 113.281424 -356.823176) (xy 113.247338 -356.779033) (xy 113.220042 -356.730398)
			(xy 113.200119 -356.678307) (xy 113.187993 -356.62387) (xy 113.183922 -356.568248) (xy 104.091938 -356.568248)
			(xy 104.086691 -356.572615) (xy 104.039085 -356.601669) (xy 103.987756 -356.623481) (xy 103.933799 -356.637587)
			(xy 103.878362 -356.643687) (xy 103.822628 -356.64165) (xy 103.767785 -356.63152) (xy 103.715001 -356.613513)
			(xy 103.665401 -356.588012) (xy 103.620043 -356.555561) (xy 103.579894 -356.516852) (xy 103.545808 -356.472709)
			(xy 103.518512 -356.424074) (xy 103.498589 -356.371983) (xy 103.486463 -356.317546) (xy 103.482392 -356.261924)
			(xy 101.008688 -356.261924) (xy 101.008688 -356.795578) (xy 101.453186 -356.795578) (xy 101.457257 -356.739956)
			(xy 101.469383 -356.685519) (xy 101.489306 -356.633428) (xy 101.516602 -356.584793) (xy 101.550688 -356.54065)
			(xy 101.590837 -356.501941) (xy 101.636195 -356.46949) (xy 101.685795 -356.443989) (xy 101.738579 -356.425982)
			(xy 101.793422 -356.415852) (xy 101.849156 -356.413815) (xy 101.904593 -356.419915) (xy 101.95855 -356.434021)
			(xy 102.009879 -356.455833) (xy 102.057485 -356.484887) (xy 102.100353 -356.520562) (xy 102.13757 -356.562099)
			(xy 102.168343 -356.608612) (xy 102.192015 -356.659109) (xy 102.208083 -356.712516) (xy 102.216203 -356.767692)
			(xy 102.216712 -356.795578) (xy 102.216203 -356.823464) (xy 102.208083 -356.87864) (xy 102.192015 -356.932047)
			(xy 102.168343 -356.982544) (xy 102.13757 -357.029057) (xy 102.100353 -357.070594) (xy 102.057485 -357.106269)
			(xy 102.009879 -357.135323) (xy 101.95855 -357.157135) (xy 101.904593 -357.171241) (xy 101.849156 -357.177341)
			(xy 101.793422 -357.175304) (xy 101.738579 -357.165174) (xy 101.685795 -357.147167) (xy 101.636195 -357.121666)
			(xy 101.590837 -357.089215) (xy 101.550688 -357.050506) (xy 101.516602 -357.006363) (xy 101.489306 -356.957728)
			(xy 101.469383 -356.905637) (xy 101.457257 -356.8512) (xy 101.453186 -356.795578) (xy 101.008688 -356.795578)
			(xy 101.008688 -357.689658) (xy 101.452678 -357.689658) (xy 101.456749 -357.634036) (xy 101.468875 -357.579599)
			(xy 101.488798 -357.527508) (xy 101.516094 -357.478873) (xy 101.55018 -357.43473) (xy 101.590329 -357.396021)
			(xy 101.635687 -357.36357) (xy 101.685287 -357.338069) (xy 101.738071 -357.320062) (xy 101.792914 -357.309932)
			(xy 101.848648 -357.307895) (xy 101.904085 -357.313995) (xy 101.958042 -357.328101) (xy 102.009371 -357.349913)
			(xy 102.056977 -357.378967) (xy 102.099845 -357.414642) (xy 102.137062 -357.456179) (xy 102.167835 -357.502692)
			(xy 102.191507 -357.553189) (xy 102.207575 -357.606596) (xy 102.215695 -357.661772) (xy 102.216204 -357.689658)
			(xy 102.215695 -357.717544) (xy 102.207575 -357.77272) (xy 102.191507 -357.826127) (xy 102.167835 -357.876624)
			(xy 102.137062 -357.923137) (xy 102.099845 -357.964674) (xy 102.056977 -358.000349) (xy 102.009371 -358.029403)
			(xy 101.958042 -358.051215) (xy 101.904085 -358.065321) (xy 101.848648 -358.071421) (xy 101.792914 -358.069384)
			(xy 101.738071 -358.059254) (xy 101.685287 -358.041247) (xy 101.635687 -358.015746) (xy 101.590329 -357.983295)
			(xy 101.55018 -357.944586) (xy 101.516094 -357.900443) (xy 101.488798 -357.851808) (xy 101.468875 -357.799717)
			(xy 101.456749 -357.74528) (xy 101.452678 -357.689658) (xy 101.008688 -357.689658) (xy 101.008688 -358.221277)
			(xy 103.496811 -358.221277) (xy 103.504564 -358.167319) (xy 103.519917 -358.115013) (xy 103.542559 -358.065425)
			(xy 103.572026 -358.019564) (xy 103.607721 -357.978364) (xy 103.648916 -357.942663) (xy 103.694772 -357.913188)
			(xy 103.744356 -357.890539) (xy 103.796659 -357.875177) (xy 103.850616 -357.867415) (xy 103.877872 -357.86695)
			(xy 103.894015 -357.867093) (xy 103.926189 -357.869764) (xy 103.942134 -357.872284) (xy 103.956157 -357.874251)
			(xy 103.9843 -357.871191) (xy 104.01052 -357.860522) (xy 104.032803 -357.843063) (xy 104.049435 -357.820157)
			(xy 104.059139 -357.793564) (xy 104.061168 -357.765328) (xy 104.05872 -357.75138) (xy 104.054913 -357.732111)
			(xy 104.050845 -357.693042) (xy 104.050592 -357.673402) (xy 104.051053 -357.646149) (xy 104.05881 -357.592198)
			(xy 104.074166 -357.539899) (xy 104.096808 -357.490319) (xy 104.126276 -357.444465) (xy 104.16197 -357.403272)
			(xy 104.203163 -357.367578) (xy 104.249016 -357.33811) (xy 104.298596 -357.315467) (xy 104.350894 -357.300111)
			(xy 104.404846 -357.292353) (xy 104.459352 -357.292353) (xy 104.513303 -357.30011) (xy 104.565601 -357.315466)
			(xy 104.615182 -357.338109) (xy 104.661035 -357.367577) (xy 104.702228 -357.40327) (xy 104.737922 -357.444463)
			(xy 104.767391 -357.490317) (xy 104.790033 -357.539897) (xy 104.796343 -357.561388) (xy 112.960402 -357.561388)
			(xy 112.964473 -357.505766) (xy 112.976599 -357.451329) (xy 112.996522 -357.399238) (xy 113.023818 -357.350603)
			(xy 113.057904 -357.30646) (xy 113.098053 -357.267751) (xy 113.143411 -357.2353) (xy 113.193011 -357.209799)
			(xy 113.245795 -357.191792) (xy 113.300638 -357.181662) (xy 113.356372 -357.179625) (xy 113.411809 -357.185725)
			(xy 113.465766 -357.199831) (xy 113.517095 -357.221643) (xy 113.564701 -357.250697) (xy 113.607569 -357.286372)
			(xy 113.644786 -357.327909) (xy 113.675559 -357.374422) (xy 113.699231 -357.424919) (xy 113.715299 -357.478326)
			(xy 113.723419 -357.533502) (xy 113.723928 -357.561388) (xy 113.723419 -357.589274) (xy 113.715299 -357.64445)
			(xy 113.699231 -357.697857) (xy 113.675559 -357.748354) (xy 113.644786 -357.794867) (xy 113.607569 -357.836404)
			(xy 113.564701 -357.872079) (xy 113.517095 -357.901133) (xy 113.465766 -357.922945) (xy 113.411809 -357.937051)
			(xy 113.356372 -357.943151) (xy 113.300638 -357.941114) (xy 113.245795 -357.930984) (xy 113.193011 -357.912977)
			(xy 113.143411 -357.887476) (xy 113.098053 -357.855025) (xy 113.057904 -357.816316) (xy 113.023818 -357.772173)
			(xy 112.996522 -357.723538) (xy 112.976599 -357.671447) (xy 112.964473 -357.61701) (xy 112.960402 -357.561388)
			(xy 104.796343 -357.561388) (xy 104.805389 -357.592195) (xy 104.813147 -357.646146) (xy 104.813147 -357.700652)
			(xy 104.80539 -357.754604) (xy 104.790034 -357.806902) (xy 104.767391 -357.856482) (xy 104.737923 -357.902336)
			(xy 104.702229 -357.943529) (xy 104.661036 -357.979223) (xy 104.615183 -358.008691) (xy 104.565602 -358.031333)
			(xy 104.513304 -358.04669) (xy 104.459353 -358.054447) (xy 104.4321 -358.05491) (xy 104.415957 -358.054772)
			(xy 104.383783 -358.052097) (xy 104.367838 -358.049576) (xy 104.353814 -358.047629) (xy 104.325679 -358.050694)
			(xy 104.299465 -358.061365) (xy 104.277187 -358.07882) (xy 104.260555 -358.10172) (xy 104.250848 -358.128305)
			(xy 104.250646 -358.13111) (xy 119.248426 -358.13111) (xy 119.252499 -358.075451) (xy 119.264634 -358.020978)
			(xy 119.28457 -357.968852) (xy 119.311884 -357.920184) (xy 119.345992 -357.876012) (xy 119.386169 -357.837277)
			(xy 119.431557 -357.804805) (xy 119.481189 -357.779287) (xy 119.534009 -357.761268) (xy 119.588888 -357.751131)
			(xy 119.644659 -357.749093) (xy 119.700133 -357.755196) (xy 119.754126 -357.769312) (xy 119.805489 -357.791139)
			(xy 119.853127 -357.820212) (xy 119.896023 -357.855911) (xy 119.933265 -357.897475) (xy 119.964059 -357.944019)
			(xy 119.987747 -357.99455) (xy 120.003825 -358.047992) (xy 120.011951 -358.103206) (xy 120.012414 -358.12857)
			(xy 122.04522 -358.12857) (xy 122.049291 -358.072948) (xy 122.061417 -358.018511) (xy 122.08134 -357.96642)
			(xy 122.108636 -357.917785) (xy 122.142722 -357.873642) (xy 122.182871 -357.834933) (xy 122.228229 -357.802482)
			(xy 122.277829 -357.776981) (xy 122.330613 -357.758974) (xy 122.385456 -357.748844) (xy 122.44119 -357.746807)
			(xy 122.496627 -357.752907) (xy 122.550584 -357.767013) (xy 122.601913 -357.788825) (xy 122.649519 -357.817879)
			(xy 122.692387 -357.853554) (xy 122.729604 -357.895091) (xy 122.760377 -357.941604) (xy 122.784049 -357.992101)
			(xy 122.800117 -358.045508) (xy 122.808237 -358.100684) (xy 122.808746 -358.12857) (xy 122.808237 -358.156456)
			(xy 122.800117 -358.211632) (xy 122.784049 -358.265039) (xy 122.760377 -358.315536) (xy 122.729604 -358.362049)
			(xy 122.692387 -358.403586) (xy 122.649519 -358.439261) (xy 122.601913 -358.468315) (xy 122.550584 -358.490127)
			(xy 122.496627 -358.504233) (xy 122.44119 -358.510333) (xy 122.385456 -358.508296) (xy 122.330613 -358.498166)
			(xy 122.277829 -358.480159) (xy 122.228229 -358.454658) (xy 122.182871 -358.422207) (xy 122.142722 -358.383498)
			(xy 122.108636 -358.339355) (xy 122.08134 -358.29072) (xy 122.061417 -358.238629) (xy 122.049291 -358.184192)
			(xy 122.04522 -358.12857) (xy 120.012414 -358.12857) (xy 120.01246 -358.13111) (xy 120.011951 -358.159014)
			(xy 120.003825 -358.214228) (xy 119.987747 -358.26767) (xy 119.964059 -358.318201) (xy 119.933265 -358.364745)
			(xy 119.896023 -358.406309) (xy 119.853127 -358.442008) (xy 119.805489 -358.471081) (xy 119.754126 -358.492908)
			(xy 119.700133 -358.507024) (xy 119.644659 -358.513127) (xy 119.588888 -358.511089) (xy 119.534009 -358.500952)
			(xy 119.481189 -358.482933) (xy 119.431557 -358.457415) (xy 119.386169 -358.424943) (xy 119.345992 -358.386208)
			(xy 119.311884 -358.342036) (xy 119.28457 -358.293368) (xy 119.264634 -358.241242) (xy 119.252499 -358.186769)
			(xy 119.248426 -358.13111) (xy 104.250646 -358.13111) (xy 104.248811 -358.156533) (xy 104.251252 -358.17048)
			(xy 104.255053 -358.18975) (xy 104.259125 -358.228818) (xy 104.25938 -358.248458) (xy 104.25899 -358.275714)
			(xy 104.251238 -358.329672) (xy 104.235886 -358.381978) (xy 104.213246 -358.431566) (xy 104.183779 -358.477428)
			(xy 104.148086 -358.518629) (xy 104.106892 -358.554332) (xy 104.072209 -358.576626) (xy 112.706402 -358.576626)
			(xy 112.710473 -358.521004) (xy 112.722599 -358.466567) (xy 112.742522 -358.414476) (xy 112.769818 -358.365841)
			(xy 112.803904 -358.321698) (xy 112.844053 -358.282989) (xy 112.889411 -358.250538) (xy 112.939011 -358.225037)
			(xy 112.991795 -358.20703) (xy 113.046638 -358.1969) (xy 113.102372 -358.194863) (xy 113.157809 -358.200963)
			(xy 113.211766 -358.215069) (xy 113.263095 -358.236881) (xy 113.310701 -358.265935) (xy 113.353569 -358.30161)
			(xy 113.390786 -358.343147) (xy 113.421559 -358.38966) (xy 113.445231 -358.440157) (xy 113.461299 -358.493564)
			(xy 113.469419 -358.54874) (xy 113.469928 -358.576626) (xy 113.469419 -358.604512) (xy 113.461299 -358.659688)
			(xy 113.445231 -358.713095) (xy 113.421559 -358.763592) (xy 113.390786 -358.810105) (xy 113.353569 -358.851642)
			(xy 113.310701 -358.887317) (xy 113.263095 -358.916371) (xy 113.211766 -358.938183) (xy 113.157809 -358.952289)
			(xy 113.102372 -358.958389) (xy 113.046638 -358.956352) (xy 112.991795 -358.946222) (xy 112.939011 -358.928215)
			(xy 112.889411 -358.902714) (xy 112.844053 -358.870263) (xy 112.803904 -358.831554) (xy 112.769818 -358.787411)
			(xy 112.742522 -358.738776) (xy 112.722599 -358.686685) (xy 112.710473 -358.632248) (xy 112.706402 -358.576626)
			(xy 104.072209 -358.576626) (xy 104.061036 -358.583808) (xy 104.011452 -358.606458) (xy 103.95915 -358.621821)
			(xy 103.905193 -358.629584) (xy 103.850681 -358.62959) (xy 103.796723 -358.621837) (xy 103.744418 -358.606484)
			(xy 103.694829 -358.583844) (xy 103.648968 -358.554376) (xy 103.607767 -358.518682) (xy 103.572066 -358.477488)
			(xy 103.54259 -358.431632) (xy 103.51994 -358.382048) (xy 103.504578 -358.329745) (xy 103.496815 -358.275789)
			(xy 103.496811 -358.221277) (xy 101.008688 -358.221277) (xy 101.008688 -359.188004) (xy 104.05313 -359.188004)
			(xy 104.057201 -359.132382) (xy 104.069327 -359.077945) (xy 104.08925 -359.025854) (xy 104.116546 -358.977219)
			(xy 104.150632 -358.933076) (xy 104.190781 -358.894367) (xy 104.236139 -358.861916) (xy 104.285739 -358.836415)
			(xy 104.338523 -358.818408) (xy 104.393366 -358.808278) (xy 104.4491 -358.806241) (xy 104.504537 -358.812341)
			(xy 104.558494 -358.826447) (xy 104.609823 -358.848259) (xy 104.657429 -358.877313) (xy 104.700297 -358.912988)
			(xy 104.737514 -358.954525) (xy 104.744103 -358.964484) (xy 122.787916 -358.964484) (xy 122.791987 -358.908862)
			(xy 122.804113 -358.854425) (xy 122.824036 -358.802334) (xy 122.851332 -358.753699) (xy 122.885418 -358.709556)
			(xy 122.925567 -358.670847) (xy 122.970925 -358.638396) (xy 123.020525 -358.612895) (xy 123.073309 -358.594888)
			(xy 123.128152 -358.584758) (xy 123.183886 -358.582721) (xy 123.239323 -358.588821) (xy 123.29328 -358.602927)
			(xy 123.344609 -358.624739) (xy 123.392215 -358.653793) (xy 123.435083 -358.689468) (xy 123.4723 -358.731005)
			(xy 123.503073 -358.777518) (xy 123.526745 -358.828015) (xy 123.542813 -358.881422) (xy 123.550933 -358.936598)
			(xy 123.551442 -358.964484) (xy 123.550933 -358.99237) (xy 123.542813 -359.047546) (xy 123.526745 -359.100953)
			(xy 123.503073 -359.15145) (xy 123.4723 -359.197963) (xy 123.435083 -359.2395) (xy 123.392215 -359.275175)
			(xy 123.344609 -359.304229) (xy 123.29328 -359.326041) (xy 123.239323 -359.340147) (xy 123.183886 -359.346247)
			(xy 123.128152 -359.34421) (xy 123.073309 -359.33408) (xy 123.020525 -359.316073) (xy 122.970925 -359.290572)
			(xy 122.925567 -359.258121) (xy 122.885418 -359.219412) (xy 122.851332 -359.175269) (xy 122.824036 -359.126634)
			(xy 122.804113 -359.074543) (xy 122.791987 -359.020106) (xy 122.787916 -358.964484) (xy 104.744103 -358.964484)
			(xy 104.768287 -359.001038) (xy 104.791959 -359.051535) (xy 104.808027 -359.104942) (xy 104.816147 -359.160118)
			(xy 104.816656 -359.188004) (xy 104.816147 -359.21589) (xy 104.808027 -359.271066) (xy 104.791959 -359.324473)
			(xy 104.768287 -359.37497) (xy 104.737514 -359.421483) (xy 104.700297 -359.46302) (xy 104.657429 -359.498695)
			(xy 104.609823 -359.527749) (xy 104.558494 -359.549561) (xy 104.504537 -359.563667) (xy 104.4491 -359.569767)
			(xy 104.393366 -359.56773) (xy 104.338523 -359.5576) (xy 104.285739 -359.539593) (xy 104.236139 -359.514092)
			(xy 104.190781 -359.481641) (xy 104.150632 -359.442932) (xy 104.116546 -359.398789) (xy 104.08925 -359.350154)
			(xy 104.069327 -359.298063) (xy 104.057201 -359.243626) (xy 104.05313 -359.188004) (xy 101.008688 -359.188004)
			(xy 101.008688 -359.595674) (xy 112.734088 -359.595674) (xy 112.738159 -359.540052) (xy 112.750285 -359.485615)
			(xy 112.770208 -359.433524) (xy 112.797504 -359.384889) (xy 112.83159 -359.340746) (xy 112.871739 -359.302037)
			(xy 112.917097 -359.269586) (xy 112.966697 -359.244085) (xy 113.019481 -359.226078) (xy 113.074324 -359.215948)
			(xy 113.130058 -359.213911) (xy 113.185495 -359.220011) (xy 113.239452 -359.234117) (xy 113.290781 -359.255929)
			(xy 113.338387 -359.284983) (xy 113.381255 -359.320658) (xy 113.418472 -359.362195) (xy 113.432119 -359.382822)
			(xy 116.061996 -359.382822) (xy 116.066067 -359.3272) (xy 116.078193 -359.272763) (xy 116.098116 -359.220672)
			(xy 116.125412 -359.172037) (xy 116.159498 -359.127894) (xy 116.199647 -359.089185) (xy 116.245005 -359.056734)
			(xy 116.294605 -359.031233) (xy 116.347389 -359.013226) (xy 116.402232 -359.003096) (xy 116.457966 -359.001059)
			(xy 116.513403 -359.007159) (xy 116.56736 -359.021265) (xy 116.618689 -359.043077) (xy 116.666295 -359.072131)
			(xy 116.709163 -359.107806) (xy 116.74638 -359.149343) (xy 116.777153 -359.195856) (xy 116.800825 -359.246353)
			(xy 116.816893 -359.29976) (xy 116.825013 -359.354936) (xy 116.825522 -359.382822) (xy 116.825013 -359.410708)
			(xy 116.816893 -359.465884) (xy 116.800825 -359.519291) (xy 116.777153 -359.569788) (xy 116.74638 -359.616301)
			(xy 116.709163 -359.657838) (xy 116.666295 -359.693513) (xy 116.618689 -359.722567) (xy 116.56736 -359.744379)
			(xy 116.513403 -359.758485) (xy 116.457966 -359.764585) (xy 116.402232 -359.762548) (xy 116.347389 -359.752418)
			(xy 116.294605 -359.734411) (xy 116.245005 -359.70891) (xy 116.199647 -359.676459) (xy 116.159498 -359.63775)
			(xy 116.125412 -359.593607) (xy 116.098116 -359.544972) (xy 116.078193 -359.492881) (xy 116.066067 -359.438444)
			(xy 116.061996 -359.382822) (xy 113.432119 -359.382822) (xy 113.449245 -359.408708) (xy 113.472917 -359.459205)
			(xy 113.488985 -359.512612) (xy 113.497105 -359.567788) (xy 113.497614 -359.595674) (xy 113.497105 -359.62356)
			(xy 113.488985 -359.678736) (xy 113.472917 -359.732143) (xy 113.449245 -359.78264) (xy 113.418472 -359.829153)
			(xy 113.381255 -359.87069) (xy 113.338387 -359.906365) (xy 113.290781 -359.935419) (xy 113.239452 -359.957231)
			(xy 113.185495 -359.971337) (xy 113.130058 -359.977437) (xy 113.074324 -359.9754) (xy 113.019481 -359.96527)
			(xy 112.966697 -359.947263) (xy 112.917097 -359.921762) (xy 112.871739 -359.889311) (xy 112.83159 -359.850602)
			(xy 112.797504 -359.806459) (xy 112.770208 -359.757824) (xy 112.750285 -359.705733) (xy 112.738159 -359.651296)
			(xy 112.734088 -359.595674) (xy 101.008688 -359.595674) (xy 101.008688 -359.985056) (xy 101.469696 -359.985056)
			(xy 101.473767 -359.929434) (xy 101.485893 -359.874997) (xy 101.505816 -359.822906) (xy 101.533112 -359.774271)
			(xy 101.567198 -359.730128) (xy 101.607347 -359.691419) (xy 101.652705 -359.658968) (xy 101.702305 -359.633467)
			(xy 101.755089 -359.61546) (xy 101.809932 -359.60533) (xy 101.865666 -359.603293) (xy 101.921103 -359.609393)
			(xy 101.97506 -359.623499) (xy 102.026389 -359.645311) (xy 102.073995 -359.674365) (xy 102.116863 -359.71004)
			(xy 102.15408 -359.751577) (xy 102.184853 -359.79809) (xy 102.208525 -359.848587) (xy 102.224593 -359.901994)
			(xy 102.232713 -359.95717) (xy 102.233222 -359.985056) (xy 102.232713 -360.012942) (xy 102.224593 -360.068118)
			(xy 102.208525 -360.121525) (xy 102.184853 -360.172022) (xy 102.155123 -360.216958) (xy 103.98963 -360.216958)
			(xy 103.993701 -360.161336) (xy 104.005827 -360.106899) (xy 104.02575 -360.054808) (xy 104.053046 -360.006173)
			(xy 104.087132 -359.96203) (xy 104.127281 -359.923321) (xy 104.172639 -359.89087) (xy 104.222239 -359.865369)
			(xy 104.275023 -359.847362) (xy 104.329866 -359.837232) (xy 104.3856 -359.835195) (xy 104.441037 -359.841295)
			(xy 104.494994 -359.855401) (xy 104.546323 -359.877213) (xy 104.593929 -359.906267) (xy 104.636797 -359.941942)
			(xy 104.674014 -359.983479) (xy 104.704787 -360.029992) (xy 104.728459 -360.080489) (xy 104.744527 -360.133896)
			(xy 104.752647 -360.189072) (xy 104.753156 -360.216958) (xy 104.752647 -360.244844) (xy 104.744527 -360.30002)
			(xy 104.728459 -360.353427) (xy 104.704787 -360.403924) (xy 104.674014 -360.450437) (xy 104.636797 -360.491974)
			(xy 104.593929 -360.527649) (xy 104.546323 -360.556703) (xy 104.494994 -360.578515) (xy 104.441037 -360.592621)
			(xy 104.3856 -360.598721) (xy 104.329866 -360.596684) (xy 104.275023 -360.586554) (xy 104.222239 -360.568547)
			(xy 104.172639 -360.543046) (xy 104.127281 -360.510595) (xy 104.087132 -360.471886) (xy 104.053046 -360.427743)
			(xy 104.02575 -360.379108) (xy 104.005827 -360.327017) (xy 103.993701 -360.27258) (xy 103.98963 -360.216958)
			(xy 102.155123 -360.216958) (xy 102.15408 -360.218535) (xy 102.116863 -360.260072) (xy 102.073995 -360.295747)
			(xy 102.026389 -360.324801) (xy 101.97506 -360.346613) (xy 101.921103 -360.360719) (xy 101.865666 -360.366819)
			(xy 101.809932 -360.364782) (xy 101.755089 -360.354652) (xy 101.702305 -360.336645) (xy 101.652705 -360.311144)
			(xy 101.607347 -360.278693) (xy 101.567198 -360.239984) (xy 101.533112 -360.195841) (xy 101.505816 -360.147206)
			(xy 101.485893 -360.095115) (xy 101.473767 -360.040678) (xy 101.469696 -359.985056) (xy 101.008688 -359.985056)
			(xy 101.008688 -360.61142) (xy 112.831624 -360.61142) (xy 112.835695 -360.555798) (xy 112.847821 -360.501361)
			(xy 112.867744 -360.44927) (xy 112.89504 -360.400635) (xy 112.929126 -360.356492) (xy 112.969275 -360.317783)
			(xy 113.014633 -360.285332) (xy 113.064233 -360.259831) (xy 113.117017 -360.241824) (xy 113.17186 -360.231694)
			(xy 113.227594 -360.229657) (xy 113.283031 -360.235757) (xy 113.336988 -360.249863) (xy 113.388317 -360.271675)
			(xy 113.391471 -360.2736) (xy 118.713248 -360.2736) (xy 118.717321 -360.217941) (xy 118.729456 -360.163468)
			(xy 118.749392 -360.111342) (xy 118.776706 -360.062674) (xy 118.810814 -360.018502) (xy 118.850991 -359.979767)
			(xy 118.896379 -359.947295) (xy 118.946011 -359.921777) (xy 118.998831 -359.903758) (xy 119.05371 -359.893621)
			(xy 119.109481 -359.891583) (xy 119.164955 -359.897686) (xy 119.218948 -359.911802) (xy 119.270311 -359.933629)
			(xy 119.317949 -359.962702) (xy 119.360845 -359.998401) (xy 119.398087 -360.039965) (xy 119.428881 -360.086509)
			(xy 119.452569 -360.13704) (xy 119.468647 -360.190482) (xy 119.476773 -360.245696) (xy 119.477282 -360.2736)
			(xy 119.476773 -360.301504) (xy 119.468647 -360.356718) (xy 119.452569 -360.41016) (xy 119.428881 -360.460691)
			(xy 119.398087 -360.507235) (xy 119.360845 -360.548799) (xy 119.317949 -360.584498) (xy 119.270311 -360.613571)
			(xy 119.218948 -360.635398) (xy 119.164955 -360.649514) (xy 119.109481 -360.655617) (xy 119.05371 -360.653579)
			(xy 118.998831 -360.643442) (xy 118.946011 -360.625423) (xy 118.896379 -360.599905) (xy 118.850991 -360.567433)
			(xy 118.810814 -360.528698) (xy 118.776706 -360.484526) (xy 118.749392 -360.435858) (xy 118.729456 -360.383732)
			(xy 118.717321 -360.329259) (xy 118.713248 -360.2736) (xy 113.391471 -360.2736) (xy 113.435923 -360.300729)
			(xy 113.478791 -360.336404) (xy 113.516008 -360.377941) (xy 113.546781 -360.424454) (xy 113.570453 -360.474951)
			(xy 113.586521 -360.528358) (xy 113.594641 -360.583534) (xy 113.59515 -360.61142) (xy 113.594641 -360.639306)
			(xy 113.588577 -360.680508) (xy 128.966466 -360.680508) (xy 128.970537 -360.624886) (xy 128.982663 -360.570449)
			(xy 129.002586 -360.518358) (xy 129.029882 -360.469723) (xy 129.063968 -360.42558) (xy 129.104117 -360.386871)
			(xy 129.149475 -360.35442) (xy 129.199075 -360.328919) (xy 129.251859 -360.310912) (xy 129.306702 -360.300782)
			(xy 129.362436 -360.298745) (xy 129.417873 -360.304845) (xy 129.47183 -360.318951) (xy 129.523159 -360.340763)
			(xy 129.570765 -360.369817) (xy 129.613633 -360.405492) (xy 129.65085 -360.447029) (xy 129.681623 -360.493542)
			(xy 129.705295 -360.544039) (xy 129.721363 -360.597446) (xy 129.729483 -360.652622) (xy 129.729992 -360.680508)
			(xy 129.729483 -360.708394) (xy 129.721363 -360.76357) (xy 129.705295 -360.816977) (xy 129.681623 -360.867474)
			(xy 129.65085 -360.913987) (xy 129.613633 -360.955524) (xy 129.570765 -360.991199) (xy 129.523159 -361.020253)
			(xy 129.47183 -361.042065) (xy 129.417873 -361.056171) (xy 129.362436 -361.062271) (xy 129.306702 -361.060234)
			(xy 129.251859 -361.050104) (xy 129.199075 -361.032097) (xy 129.149475 -361.006596) (xy 129.104117 -360.974145)
			(xy 129.063968 -360.935436) (xy 129.029882 -360.891293) (xy 129.002586 -360.842658) (xy 128.982663 -360.790567)
			(xy 128.970537 -360.73613) (xy 128.966466 -360.680508) (xy 113.588577 -360.680508) (xy 113.586521 -360.694482)
			(xy 113.570453 -360.747889) (xy 113.546781 -360.798386) (xy 113.516008 -360.844899) (xy 113.478791 -360.886436)
			(xy 113.435923 -360.922111) (xy 113.388317 -360.951165) (xy 113.336988 -360.972977) (xy 113.283031 -360.987083)
			(xy 113.227594 -360.993183) (xy 113.17186 -360.991146) (xy 113.117017 -360.981016) (xy 113.064233 -360.963009)
			(xy 113.014633 -360.937508) (xy 112.969275 -360.905057) (xy 112.929126 -360.866348) (xy 112.89504 -360.822205)
			(xy 112.867744 -360.77357) (xy 112.847821 -360.721479) (xy 112.835695 -360.667042) (xy 112.831624 -360.61142)
			(xy 101.008688 -360.61142) (xy 101.008688 -361.133136) (xy 121.446286 -361.133136) (xy 121.450375 -361.077254)
			(xy 121.462558 -361.022564) (xy 121.482574 -360.97023) (xy 121.509997 -360.921368) (xy 121.544242 -360.87702)
			(xy 121.584578 -360.83813) (xy 121.630148 -360.805528) (xy 121.679979 -360.779909) (xy 121.733009 -360.761817)
			(xy 121.788107 -360.75164) (xy 121.844101 -360.749594) (xy 121.899796 -360.755722) (xy 121.954005 -360.769894)
			(xy 122.005573 -360.791808) (xy 122.053401 -360.820997) (xy 122.096469 -360.856838) (xy 122.133859 -360.898568)
			(xy 122.164775 -360.945298) (xy 122.188558 -360.996031) (xy 122.2047 -361.049687) (xy 122.212859 -361.105121)
			(xy 122.21337 -361.133136) (xy 122.212859 -361.161151) (xy 122.2047 -361.216585) (xy 122.188558 -361.270241)
			(xy 122.164775 -361.320974) (xy 122.133859 -361.367704) (xy 122.096469 -361.409434) (xy 122.053401 -361.445275)
			(xy 122.005573 -361.474464) (xy 121.954005 -361.496378) (xy 121.899796 -361.51055) (xy 121.844101 -361.516678)
			(xy 121.788107 -361.514632) (xy 121.733009 -361.504455) (xy 121.679979 -361.486363) (xy 121.630148 -361.460744)
			(xy 121.584578 -361.428142) (xy 121.544242 -361.389252) (xy 121.509997 -361.344904) (xy 121.482574 -361.296042)
			(xy 121.462558 -361.243708) (xy 121.450375 -361.189018) (xy 121.446286 -361.133136) (xy 101.008688 -361.133136)
			(xy 101.008688 -361.544616) (xy 112.355882 -361.544616) (xy 112.359953 -361.488994) (xy 112.372079 -361.434557)
			(xy 112.392002 -361.382466) (xy 112.419298 -361.333831) (xy 112.453384 -361.289688) (xy 112.493533 -361.250979)
			(xy 112.538891 -361.218528) (xy 112.588491 -361.193027) (xy 112.641275 -361.17502) (xy 112.696118 -361.16489)
			(xy 112.751852 -361.162853) (xy 112.807289 -361.168953) (xy 112.861246 -361.183059) (xy 112.912575 -361.204871)
			(xy 112.960181 -361.233925) (xy 113.003049 -361.2696) (xy 113.040266 -361.311137) (xy 113.071039 -361.35765)
			(xy 113.094711 -361.408147) (xy 113.110779 -361.461554) (xy 113.118899 -361.51673) (xy 113.119408 -361.544616)
			(xy 113.118899 -361.572502) (xy 113.110779 -361.627678) (xy 113.094711 -361.681085) (xy 113.071039 -361.731582)
			(xy 113.040266 -361.778095) (xy 113.003049 -361.819632) (xy 112.960181 -361.855307) (xy 112.912575 -361.884361)
			(xy 112.861246 -361.906173) (xy 112.807289 -361.920279) (xy 112.751852 -361.926379) (xy 112.696118 -361.924342)
			(xy 112.641275 -361.914212) (xy 112.588491 -361.896205) (xy 112.538891 -361.870704) (xy 112.493533 -361.838253)
			(xy 112.453384 -361.799544) (xy 112.419298 -361.755401) (xy 112.392002 -361.706766) (xy 112.372079 -361.654675)
			(xy 112.359953 -361.600238) (xy 112.355882 -361.544616) (xy 101.008688 -361.544616) (xy 101.008688 -361.952032)
			(xy 102.011732 -361.952032) (xy 102.015803 -361.89641) (xy 102.027929 -361.841973) (xy 102.047852 -361.789882)
			(xy 102.075148 -361.741247) (xy 102.109234 -361.697104) (xy 102.149383 -361.658395) (xy 102.194741 -361.625944)
			(xy 102.244341 -361.600443) (xy 102.297125 -361.582436) (xy 102.351968 -361.572306) (xy 102.407702 -361.570269)
			(xy 102.463139 -361.576369) (xy 102.517096 -361.590475) (xy 102.568425 -361.612287) (xy 102.616031 -361.641341)
			(xy 102.658899 -361.677016) (xy 102.696116 -361.718553) (xy 102.726889 -361.765066) (xy 102.750561 -361.815563)
			(xy 102.766629 -361.86897) (xy 102.774749 -361.924146) (xy 102.775188 -361.948222) (xy 103.776778 -361.948222)
			(xy 103.780849 -361.8926) (xy 103.792975 -361.838163) (xy 103.812898 -361.786072) (xy 103.840194 -361.737437)
			(xy 103.87428 -361.693294) (xy 103.914429 -361.654585) (xy 103.959787 -361.622134) (xy 104.009387 -361.596633)
			(xy 104.062171 -361.578626) (xy 104.117014 -361.568496) (xy 104.172748 -361.566459) (xy 104.228185 -361.572559)
			(xy 104.282142 -361.586665) (xy 104.333471 -361.608477) (xy 104.381077 -361.637531) (xy 104.423945 -361.673206)
			(xy 104.461162 -361.714743) (xy 104.491935 -361.761256) (xy 104.515607 -361.811753) (xy 104.531675 -361.86516)
			(xy 104.539795 -361.920336) (xy 104.540304 -361.948222) (xy 104.539795 -361.976108) (xy 104.531675 -362.031284)
			(xy 104.515607 -362.084691) (xy 104.491935 -362.135188) (xy 104.461162 -362.181701) (xy 104.423945 -362.223238)
			(xy 104.381077 -362.258913) (xy 104.333471 -362.287967) (xy 104.282142 -362.309779) (xy 104.229145 -362.323634)
			(xy 105.517186 -362.323634) (xy 105.521257 -362.268012) (xy 105.533383 -362.213575) (xy 105.553306 -362.161484)
			(xy 105.580602 -362.112849) (xy 105.614688 -362.068706) (xy 105.654837 -362.029997) (xy 105.700195 -361.997546)
			(xy 105.749795 -361.972045) (xy 105.802579 -361.954038) (xy 105.857422 -361.943908) (xy 105.913156 -361.941871)
			(xy 105.968593 -361.947971) (xy 106.02255 -361.962077) (xy 106.073879 -361.983889) (xy 106.121485 -362.012943)
			(xy 106.164353 -362.048618) (xy 106.20157 -362.090155) (xy 106.232343 -362.136668) (xy 106.256015 -362.187165)
			(xy 106.272083 -362.240572) (xy 106.280203 -362.295748) (xy 106.280712 -362.323634) (xy 106.280203 -362.35152)
			(xy 106.272083 -362.406696) (xy 106.265054 -362.43006) (xy 111.033812 -362.43006) (xy 111.037883 -362.374438)
			(xy 111.050009 -362.320001) (xy 111.069932 -362.26791) (xy 111.097228 -362.219275) (xy 111.131314 -362.175132)
			(xy 111.171463 -362.136423) (xy 111.216821 -362.103972) (xy 111.266421 -362.078471) (xy 111.319205 -362.060464)
			(xy 111.374048 -362.050334) (xy 111.429782 -362.048297) (xy 111.485219 -362.054397) (xy 111.539176 -362.068503)
			(xy 111.590505 -362.090315) (xy 111.601567 -362.097066) (xy 128.08534 -362.097066) (xy 128.089411 -362.041444)
			(xy 128.101537 -361.987007) (xy 128.12146 -361.934916) (xy 128.148756 -361.886281) (xy 128.182842 -361.842138)
			(xy 128.222991 -361.803429) (xy 128.268349 -361.770978) (xy 128.317949 -361.745477) (xy 128.370733 -361.72747)
			(xy 128.425576 -361.71734) (xy 128.48131 -361.715303) (xy 128.536747 -361.721403) (xy 128.590704 -361.735509)
			(xy 128.642033 -361.757321) (xy 128.689639 -361.786375) (xy 128.731207 -361.820968) (xy 144.809462 -361.820968)
			(xy 144.813533 -361.765346) (xy 144.825659 -361.710909) (xy 144.845582 -361.658818) (xy 144.872878 -361.610183)
			(xy 144.906964 -361.56604) (xy 144.947113 -361.527331) (xy 144.992471 -361.49488) (xy 145.042071 -361.469379)
			(xy 145.094855 -361.451372) (xy 145.149698 -361.441242) (xy 145.205432 -361.439205) (xy 145.260869 -361.445305)
			(xy 145.314826 -361.459411) (xy 145.366155 -361.481223) (xy 145.413761 -361.510277) (xy 145.456629 -361.545952)
			(xy 145.493846 -361.587489) (xy 145.524619 -361.634002) (xy 145.537251 -361.660948) (xy 145.977862 -361.660948)
			(xy 145.981933 -361.605326) (xy 145.994059 -361.550889) (xy 146.013982 -361.498798) (xy 146.041278 -361.450163)
			(xy 146.075364 -361.40602) (xy 146.115513 -361.367311) (xy 146.160871 -361.33486) (xy 146.210471 -361.309359)
			(xy 146.263255 -361.291352) (xy 146.318098 -361.281222) (xy 146.373832 -361.279185) (xy 146.429269 -361.285285)
			(xy 146.483226 -361.299391) (xy 146.534555 -361.321203) (xy 146.582161 -361.350257) (xy 146.625029 -361.385932)
			(xy 146.662246 -361.427469) (xy 146.693019 -361.473982) (xy 146.716691 -361.524479) (xy 146.732759 -361.577886)
			(xy 146.740879 -361.633062) (xy 146.741388 -361.660948) (xy 146.740879 -361.688834) (xy 146.732759 -361.74401)
			(xy 146.716691 -361.797417) (xy 146.693019 -361.847914) (xy 146.662246 -361.894427) (xy 146.625029 -361.935964)
			(xy 146.582161 -361.971639) (xy 146.534555 -362.000693) (xy 146.483226 -362.022505) (xy 146.429269 -362.036611)
			(xy 146.373832 -362.042711) (xy 146.318098 -362.040674) (xy 146.263255 -362.030544) (xy 146.210471 -362.012537)
			(xy 146.160871 -361.987036) (xy 146.115513 -361.954585) (xy 146.075364 -361.915876) (xy 146.041278 -361.871733)
			(xy 146.013982 -361.823098) (xy 145.994059 -361.771007) (xy 145.981933 -361.71657) (xy 145.977862 -361.660948)
			(xy 145.537251 -361.660948) (xy 145.548291 -361.684499) (xy 145.564359 -361.737906) (xy 145.572479 -361.793082)
			(xy 145.572988 -361.820968) (xy 145.572479 -361.848854) (xy 145.564359 -361.90403) (xy 145.548291 -361.957437)
			(xy 145.524619 -362.007934) (xy 145.493846 -362.054447) (xy 145.456629 -362.095984) (xy 145.413761 -362.131659)
			(xy 145.366155 -362.160713) (xy 145.314826 -362.182525) (xy 145.260869 -362.196631) (xy 145.205432 -362.202731)
			(xy 145.149698 -362.200694) (xy 145.094855 -362.190564) (xy 145.042071 -362.172557) (xy 144.992471 -362.147056)
			(xy 144.947113 -362.114605) (xy 144.906964 -362.075896) (xy 144.872878 -362.031753) (xy 144.845582 -361.983118)
			(xy 144.825659 -361.931027) (xy 144.813533 -361.87659) (xy 144.809462 -361.820968) (xy 128.731207 -361.820968)
			(xy 128.732507 -361.82205) (xy 128.769724 -361.863587) (xy 128.800497 -361.9101) (xy 128.824169 -361.960597)
			(xy 128.840237 -362.014004) (xy 128.848357 -362.06918) (xy 128.848866 -362.097066) (xy 128.848357 -362.124952)
			(xy 128.840237 -362.180128) (xy 128.824169 -362.233535) (xy 128.800497 -362.284032) (xy 128.769724 -362.330545)
			(xy 128.732507 -362.372082) (xy 128.689639 -362.407757) (xy 128.642033 -362.436811) (xy 128.590704 -362.458623)
			(xy 128.536747 -362.472729) (xy 128.48131 -362.478829) (xy 128.425576 -362.476792) (xy 128.370733 -362.466662)
			(xy 128.317949 -362.448655) (xy 128.268349 -362.423154) (xy 128.222991 -362.390703) (xy 128.182842 -362.351994)
			(xy 128.148756 -362.307851) (xy 128.12146 -362.259216) (xy 128.101537 -362.207125) (xy 128.089411 -362.152688)
			(xy 128.08534 -362.097066) (xy 111.601567 -362.097066) (xy 111.638111 -362.119369) (xy 111.680979 -362.155044)
			(xy 111.718196 -362.196581) (xy 111.748969 -362.243094) (xy 111.772641 -362.293591) (xy 111.788709 -362.346998)
			(xy 111.796829 -362.402174) (xy 111.797338 -362.43006) (xy 111.796829 -362.457946) (xy 111.788709 -362.513122)
			(xy 111.772641 -362.566529) (xy 111.748969 -362.617026) (xy 111.718196 -362.663539) (xy 111.680979 -362.705076)
			(xy 111.638111 -362.740751) (xy 111.590505 -362.769805) (xy 111.539176 -362.791617) (xy 111.485219 -362.805723)
			(xy 111.429782 -362.811823) (xy 111.374048 -362.809786) (xy 111.319205 -362.799656) (xy 111.266421 -362.781649)
			(xy 111.216821 -362.756148) (xy 111.171463 -362.723697) (xy 111.131314 -362.684988) (xy 111.097228 -362.640845)
			(xy 111.069932 -362.59221) (xy 111.050009 -362.540119) (xy 111.037883 -362.485682) (xy 111.033812 -362.43006)
			(xy 106.265054 -362.43006) (xy 106.256015 -362.460103) (xy 106.232343 -362.5106) (xy 106.20157 -362.557113)
			(xy 106.164353 -362.59865) (xy 106.121485 -362.634325) (xy 106.073879 -362.663379) (xy 106.02255 -362.685191)
			(xy 105.968593 -362.699297) (xy 105.913156 -362.705397) (xy 105.857422 -362.70336) (xy 105.802579 -362.69323)
			(xy 105.749795 -362.675223) (xy 105.700195 -362.649722) (xy 105.654837 -362.617271) (xy 105.614688 -362.578562)
			(xy 105.580602 -362.534419) (xy 105.553306 -362.485784) (xy 105.533383 -362.433693) (xy 105.521257 -362.379256)
			(xy 105.517186 -362.323634) (xy 104.229145 -362.323634) (xy 104.228185 -362.323885) (xy 104.172748 -362.329985)
			(xy 104.117014 -362.327948) (xy 104.062171 -362.317818) (xy 104.009387 -362.299811) (xy 103.959787 -362.27431)
			(xy 103.914429 -362.241859) (xy 103.87428 -362.20315) (xy 103.840194 -362.159007) (xy 103.812898 -362.110372)
			(xy 103.792975 -362.058281) (xy 103.780849 -362.003844) (xy 103.776778 -361.948222) (xy 102.775188 -361.948222)
			(xy 102.775258 -361.952032) (xy 102.774749 -361.979918) (xy 102.766629 -362.035094) (xy 102.750561 -362.088501)
			(xy 102.726889 -362.138998) (xy 102.696116 -362.185511) (xy 102.658899 -362.227048) (xy 102.616031 -362.262723)
			(xy 102.568425 -362.291777) (xy 102.517096 -362.313589) (xy 102.463139 -362.327695) (xy 102.407702 -362.333795)
			(xy 102.351968 -362.331758) (xy 102.297125 -362.321628) (xy 102.244341 -362.303621) (xy 102.194741 -362.27812)
			(xy 102.149383 -362.245669) (xy 102.109234 -362.20696) (xy 102.075148 -362.162817) (xy 102.047852 -362.114182)
			(xy 102.027929 -362.062091) (xy 102.015803 -362.007654) (xy 102.011732 -361.952032) (xy 101.008688 -361.952032)
			(xy 101.008688 -362.829094) (xy 101.327934 -363.148372) (xy 106.262676 -363.148372) (xy 106.266747 -363.09275)
			(xy 106.278873 -363.038313) (xy 106.298796 -362.986222) (xy 106.326092 -362.937587) (xy 106.360178 -362.893444)
			(xy 106.400327 -362.854735) (xy 106.445685 -362.822284) (xy 106.495285 -362.796783) (xy 106.548069 -362.778776)
			(xy 106.602912 -362.768646) (xy 106.658646 -362.766609) (xy 106.714083 -362.772709) (xy 106.76804 -362.786815)
			(xy 106.819369 -362.808627) (xy 106.866975 -362.837681) (xy 106.909843 -362.873356) (xy 106.94706 -362.914893)
			(xy 106.977833 -362.961406) (xy 107.001505 -363.011903) (xy 107.017573 -363.06531) (xy 107.025693 -363.120486)
			(xy 107.026202 -363.148372) (xy 107.025693 -363.176258) (xy 107.017573 -363.231434) (xy 107.001505 -363.284841)
			(xy 106.977833 -363.335338) (xy 106.951128 -363.375702) (xy 109.736888 -363.375702) (xy 109.740959 -363.32008)
			(xy 109.753085 -363.265643) (xy 109.773008 -363.213552) (xy 109.800304 -363.164917) (xy 109.83439 -363.120774)
			(xy 109.874539 -363.082065) (xy 109.919897 -363.049614) (xy 109.969497 -363.024113) (xy 110.022281 -363.006106)
			(xy 110.077124 -362.995976) (xy 110.132858 -362.993939) (xy 110.188295 -363.000039) (xy 110.242252 -363.014145)
			(xy 110.293581 -363.035957) (xy 110.341187 -363.065011) (xy 110.384055 -363.100686) (xy 110.421272 -363.142223)
			(xy 110.452045 -363.188736) (xy 110.475717 -363.239233) (xy 110.491785 -363.29264) (xy 110.496608 -363.32541)
			(xy 112.722658 -363.32541) (xy 112.726729 -363.269788) (xy 112.738855 -363.215351) (xy 112.758778 -363.16326)
			(xy 112.786074 -363.114625) (xy 112.82016 -363.070482) (xy 112.860309 -363.031773) (xy 112.905667 -362.999322)
			(xy 112.955267 -362.973821) (xy 113.008051 -362.955814) (xy 113.062894 -362.945684) (xy 113.118628 -362.943647)
			(xy 113.174065 -362.949747) (xy 113.228022 -362.963853) (xy 113.279351 -362.985665) (xy 113.326957 -363.014719)
			(xy 113.369825 -363.050394) (xy 113.407042 -363.091931) (xy 113.437815 -363.138444) (xy 113.461487 -363.188941)
			(xy 113.477555 -363.242348) (xy 113.485675 -363.297524) (xy 113.486184 -363.32541) (xy 113.485675 -363.353296)
			(xy 113.477555 -363.408472) (xy 113.461487 -363.461879) (xy 113.437815 -363.512376) (xy 113.431444 -363.522006)
			(xy 115.599208 -363.522006) (xy 115.603279 -363.466384) (xy 115.615405 -363.411947) (xy 115.635328 -363.359856)
			(xy 115.662624 -363.311221) (xy 115.69671 -363.267078) (xy 115.736859 -363.228369) (xy 115.782217 -363.195918)
			(xy 115.831817 -363.170417) (xy 115.884601 -363.15241) (xy 115.939444 -363.14228) (xy 115.995178 -363.140243)
			(xy 116.050615 -363.146343) (xy 116.104572 -363.160449) (xy 116.155901 -363.182261) (xy 116.203507 -363.211315)
			(xy 116.246375 -363.24699) (xy 116.283592 -363.288527) (xy 116.314365 -363.33504) (xy 116.338037 -363.385537)
			(xy 116.354105 -363.438944) (xy 116.362225 -363.49412) (xy 116.362734 -363.522006) (xy 116.362225 -363.549892)
			(xy 116.354105 -363.605068) (xy 116.338037 -363.658475) (xy 116.314365 -363.708972) (xy 116.283592 -363.755485)
			(xy 116.246375 -363.797022) (xy 116.203507 -363.832697) (xy 116.155901 -363.861751) (xy 116.104572 -363.883563)
			(xy 116.050615 -363.897669) (xy 115.995178 -363.903769) (xy 115.939444 -363.901732) (xy 115.884601 -363.891602)
			(xy 115.831817 -363.873595) (xy 115.782217 -363.848094) (xy 115.736859 -363.815643) (xy 115.69671 -363.776934)
			(xy 115.662624 -363.732791) (xy 115.635328 -363.684156) (xy 115.615405 -363.632065) (xy 115.603279 -363.577628)
			(xy 115.599208 -363.522006) (xy 113.431444 -363.522006) (xy 113.407042 -363.558889) (xy 113.369825 -363.600426)
			(xy 113.326957 -363.636101) (xy 113.279351 -363.665155) (xy 113.228022 -363.686967) (xy 113.174065 -363.701073)
			(xy 113.118628 -363.707173) (xy 113.062894 -363.705136) (xy 113.008051 -363.695006) (xy 112.955267 -363.676999)
			(xy 112.905667 -363.651498) (xy 112.860309 -363.619047) (xy 112.82016 -363.580338) (xy 112.786074 -363.536195)
			(xy 112.758778 -363.48756) (xy 112.738855 -363.435469) (xy 112.726729 -363.381032) (xy 112.722658 -363.32541)
			(xy 110.496608 -363.32541) (xy 110.499905 -363.347816) (xy 110.500414 -363.375702) (xy 110.499905 -363.403588)
			(xy 110.491785 -363.458764) (xy 110.475717 -363.512171) (xy 110.452045 -363.562668) (xy 110.421272 -363.609181)
			(xy 110.384055 -363.650718) (xy 110.341187 -363.686393) (xy 110.293581 -363.715447) (xy 110.242252 -363.737259)
			(xy 110.188295 -363.751365) (xy 110.132858 -363.757465) (xy 110.077124 -363.755428) (xy 110.022281 -363.745298)
			(xy 109.969497 -363.727291) (xy 109.919897 -363.70179) (xy 109.874539 -363.669339) (xy 109.83439 -363.63063)
			(xy 109.800304 -363.586487) (xy 109.773008 -363.537852) (xy 109.753085 -363.485761) (xy 109.740959 -363.431324)
			(xy 109.736888 -363.375702) (xy 106.951128 -363.375702) (xy 106.94706 -363.381851) (xy 106.909843 -363.423388)
			(xy 106.866975 -363.459063) (xy 106.819369 -363.488117) (xy 106.76804 -363.509929) (xy 106.714083 -363.524035)
			(xy 106.658646 -363.530135) (xy 106.602912 -363.528098) (xy 106.548069 -363.517968) (xy 106.495285 -363.499961)
			(xy 106.445685 -363.47446) (xy 106.400327 -363.442009) (xy 106.360178 -363.4033) (xy 106.326092 -363.359157)
			(xy 106.298796 -363.310522) (xy 106.278873 -363.258431) (xy 106.266747 -363.203994) (xy 106.262676 -363.148372)
			(xy 101.327934 -363.148372) (xy 101.817343 -363.63783) (xy 104.371646 -363.63783) (xy 104.375717 -363.582208)
			(xy 104.387843 -363.527771) (xy 104.407766 -363.47568) (xy 104.435062 -363.427045) (xy 104.469148 -363.382902)
			(xy 104.509297 -363.344193) (xy 104.554655 -363.311742) (xy 104.604255 -363.286241) (xy 104.657039 -363.268234)
			(xy 104.711882 -363.258104) (xy 104.767616 -363.256067) (xy 104.823053 -363.262167) (xy 104.87701 -363.276273)
			(xy 104.928339 -363.298085) (xy 104.975945 -363.327139) (xy 105.018813 -363.362814) (xy 105.05603 -363.404351)
			(xy 105.086803 -363.450864) (xy 105.110475 -363.501361) (xy 105.126543 -363.554768) (xy 105.134663 -363.609944)
			(xy 105.135172 -363.63783) (xy 105.134663 -363.665716) (xy 105.126543 -363.720892) (xy 105.110475 -363.774299)
			(xy 105.086803 -363.824796) (xy 105.05603 -363.871309) (xy 105.018813 -363.912846) (xy 104.975945 -363.948521)
			(xy 104.928339 -363.977575) (xy 104.87701 -363.999387) (xy 104.823053 -364.013493) (xy 104.767616 -364.019593)
			(xy 104.711882 -364.017556) (xy 104.657039 -364.007426) (xy 104.604255 -363.989419) (xy 104.554655 -363.963918)
			(xy 104.509297 -363.931467) (xy 104.469148 -363.892758) (xy 104.435062 -363.848615) (xy 104.407766 -363.79998)
			(xy 104.387843 -363.747889) (xy 104.375717 -363.693452) (xy 104.371646 -363.63783) (xy 101.817343 -363.63783)
			(xy 102.593235 -364.4138) (xy 106.12069 -364.4138) (xy 106.124761 -364.358178) (xy 106.136887 -364.303741)
			(xy 106.15681 -364.25165) (xy 106.184106 -364.203015) (xy 106.218192 -364.158872) (xy 106.258341 -364.120163)
			(xy 106.303699 -364.087712) (xy 106.353299 -364.062211) (xy 106.406083 -364.044204) (xy 106.460926 -364.034074)
			(xy 106.51666 -364.032037) (xy 106.572097 -364.038137) (xy 106.626054 -364.052243) (xy 106.677383 -364.074055)
			(xy 106.724989 -364.103109) (xy 106.767857 -364.138784) (xy 106.805074 -364.180321) (xy 106.835847 -364.226834)
			(xy 106.859519 -364.277331) (xy 106.869398 -364.310168) (xy 107.575602 -364.310168) (xy 107.579673 -364.254546)
			(xy 107.591799 -364.200109) (xy 107.611722 -364.148018) (xy 107.639018 -364.099383) (xy 107.673104 -364.05524)
			(xy 107.713253 -364.016531) (xy 107.758611 -363.98408) (xy 107.808211 -363.958579) (xy 107.860995 -363.940572)
			(xy 107.915838 -363.930442) (xy 107.971572 -363.928405) (xy 108.027009 -363.934505) (xy 108.080966 -363.948611)
			(xy 108.132295 -363.970423) (xy 108.179901 -363.999477) (xy 108.222769 -364.035152) (xy 108.259986 -364.076689)
			(xy 108.290759 -364.123202) (xy 108.314431 -364.173699) (xy 108.330499 -364.227106) (xy 108.338619 -364.282282)
			(xy 108.339128 -364.310168) (xy 108.338619 -364.338054) (xy 108.330499 -364.39323) (xy 108.326603 -364.40618)
			(xy 109.82782 -364.40618) (xy 109.831891 -364.350558) (xy 109.844017 -364.296121) (xy 109.86394 -364.24403)
			(xy 109.891236 -364.195395) (xy 109.925322 -364.151252) (xy 109.965471 -364.112543) (xy 110.010829 -364.080092)
			(xy 110.060429 -364.054591) (xy 110.113213 -364.036584) (xy 110.168056 -364.026454) (xy 110.22379 -364.024417)
			(xy 110.279227 -364.030517) (xy 110.333184 -364.044623) (xy 110.384513 -364.066435) (xy 110.432119 -364.095489)
			(xy 110.474987 -364.131164) (xy 110.512204 -364.172701) (xy 110.542977 -364.219214) (xy 110.548703 -364.231428)
			(xy 111.419638 -364.231428) (xy 111.423709 -364.175806) (xy 111.435835 -364.121369) (xy 111.455758 -364.069278)
			(xy 111.483054 -364.020643) (xy 111.51714 -363.9765) (xy 111.557289 -363.937791) (xy 111.602647 -363.90534)
			(xy 111.652247 -363.879839) (xy 111.705031 -363.861832) (xy 111.759874 -363.851702) (xy 111.815608 -363.849665)
			(xy 111.871045 -363.855765) (xy 111.925002 -363.869871) (xy 111.976331 -363.891683) (xy 112.023937 -363.920737)
			(xy 112.066805 -363.956412) (xy 112.104022 -363.997949) (xy 112.134795 -364.044462) (xy 112.158467 -364.094959)
			(xy 112.174535 -364.148366) (xy 112.177713 -364.16996) (xy 114.192048 -364.16996) (xy 114.196121 -364.114301)
			(xy 114.208256 -364.059828) (xy 114.228192 -364.007702) (xy 114.255506 -363.959034) (xy 114.289614 -363.914862)
			(xy 114.329791 -363.876127) (xy 114.375179 -363.843655) (xy 114.424811 -363.818137) (xy 114.477631 -363.800118)
			(xy 114.53251 -363.789981) (xy 114.588281 -363.787943) (xy 114.643755 -363.794046) (xy 114.697748 -363.808162)
			(xy 114.749111 -363.829989) (xy 114.796749 -363.859062) (xy 114.839645 -363.894761) (xy 114.876887 -363.936325)
			(xy 114.907681 -363.982869) (xy 114.931369 -364.0334) (xy 114.947447 -364.086842) (xy 114.955573 -364.142056)
			(xy 114.956082 -364.16996) (xy 114.955573 -364.197864) (xy 114.947447 -364.253078) (xy 114.931369 -364.30652)
			(xy 114.907681 -364.357051) (xy 114.876887 -364.403595) (xy 114.839645 -364.445159) (xy 114.796749 -364.480858)
			(xy 114.749111 -364.509931) (xy 114.697748 -364.531758) (xy 114.643755 -364.545874) (xy 114.588281 -364.551977)
			(xy 114.53251 -364.549939) (xy 114.477631 -364.539802) (xy 114.424811 -364.521783) (xy 114.375179 -364.496265)
			(xy 114.329791 -364.463793) (xy 114.289614 -364.425058) (xy 114.255506 -364.380886) (xy 114.228192 -364.332218)
			(xy 114.208256 -364.280092) (xy 114.196121 -364.225619) (xy 114.192048 -364.16996) (xy 112.177713 -364.16996)
			(xy 112.182655 -364.203542) (xy 112.183164 -364.231428) (xy 112.182655 -364.259314) (xy 112.174535 -364.31449)
			(xy 112.158467 -364.367897) (xy 112.134795 -364.418394) (xy 112.104022 -364.464907) (xy 112.066805 -364.506444)
			(xy 112.023937 -364.542119) (xy 111.976331 -364.571173) (xy 111.925002 -364.592985) (xy 111.871045 -364.607091)
			(xy 111.815608 -364.613191) (xy 111.759874 -364.611154) (xy 111.705031 -364.601024) (xy 111.652247 -364.583017)
			(xy 111.602647 -364.557516) (xy 111.557289 -364.525065) (xy 111.51714 -364.486356) (xy 111.483054 -364.442213)
			(xy 111.455758 -364.393578) (xy 111.435835 -364.341487) (xy 111.423709 -364.28705) (xy 111.419638 -364.231428)
			(xy 110.548703 -364.231428) (xy 110.566649 -364.269711) (xy 110.582717 -364.323118) (xy 110.590837 -364.378294)
			(xy 110.591346 -364.40618) (xy 110.590837 -364.434066) (xy 110.582717 -364.489242) (xy 110.566649 -364.542649)
			(xy 110.542977 -364.593146) (xy 110.512204 -364.639659) (xy 110.474987 -364.681196) (xy 110.432119 -364.716871)
			(xy 110.384513 -364.745925) (xy 110.333184 -364.767737) (xy 110.279227 -364.781843) (xy 110.22379 -364.787943)
			(xy 110.168056 -364.785906) (xy 110.113213 -364.775776) (xy 110.060429 -364.757769) (xy 110.010829 -364.732268)
			(xy 109.965471 -364.699817) (xy 109.925322 -364.661108) (xy 109.891236 -364.616965) (xy 109.86394 -364.56833)
			(xy 109.844017 -364.516239) (xy 109.831891 -364.461802) (xy 109.82782 -364.40618) (xy 108.326603 -364.40618)
			(xy 108.314431 -364.446637) (xy 108.290759 -364.497134) (xy 108.259986 -364.543647) (xy 108.222769 -364.585184)
			(xy 108.179901 -364.620859) (xy 108.132295 -364.649913) (xy 108.080966 -364.671725) (xy 108.027009 -364.685831)
			(xy 107.971572 -364.691931) (xy 107.915838 -364.689894) (xy 107.860995 -364.679764) (xy 107.808211 -364.661757)
			(xy 107.758611 -364.636256) (xy 107.713253 -364.603805) (xy 107.673104 -364.565096) (xy 107.639018 -364.520953)
			(xy 107.611722 -364.472318) (xy 107.591799 -364.420227) (xy 107.579673 -364.36579) (xy 107.575602 -364.310168)
			(xy 106.869398 -364.310168) (xy 106.875587 -364.330738) (xy 106.883707 -364.385914) (xy 106.884216 -364.4138)
			(xy 106.883707 -364.441686) (xy 106.875587 -364.496862) (xy 106.859519 -364.550269) (xy 106.835847 -364.600766)
			(xy 106.805074 -364.647279) (xy 106.767857 -364.688816) (xy 106.724989 -364.724491) (xy 106.677383 -364.753545)
			(xy 106.626054 -364.775357) (xy 106.572097 -364.789463) (xy 106.51666 -364.795563) (xy 106.460926 -364.793526)
			(xy 106.406083 -364.783396) (xy 106.353299 -364.765389) (xy 106.303699 -364.739888) (xy 106.258341 -364.707437)
			(xy 106.218192 -364.668728) (xy 106.184106 -364.624585) (xy 106.15681 -364.57595) (xy 106.136887 -364.523859)
			(xy 106.124761 -364.469422) (xy 106.12069 -364.4138) (xy 102.593235 -364.4138) (xy 103.319602 -365.14024)
			(xy 106.985814 -365.14024) (xy 106.989885 -365.084618) (xy 107.002011 -365.030181) (xy 107.021934 -364.97809)
			(xy 107.04923 -364.929455) (xy 107.083316 -364.885312) (xy 107.123465 -364.846603) (xy 107.168823 -364.814152)
			(xy 107.218423 -364.788651) (xy 107.271207 -364.770644) (xy 107.32605 -364.760514) (xy 107.381784 -364.758477)
			(xy 107.437221 -364.764577) (xy 107.491178 -364.778683) (xy 107.542507 -364.800495) (xy 107.590113 -364.829549)
			(xy 107.632981 -364.865224) (xy 107.670198 -364.906761) (xy 107.692583 -364.940596) (xy 110.691928 -364.940596)
			(xy 110.695999 -364.884974) (xy 110.708125 -364.830537) (xy 110.728048 -364.778446) (xy 110.755344 -364.729811)
			(xy 110.78943 -364.685668) (xy 110.829579 -364.646959) (xy 110.874937 -364.614508) (xy 110.924537 -364.589007)
			(xy 110.977321 -364.571) (xy 111.032164 -364.56087) (xy 111.087898 -364.558833) (xy 111.143335 -364.564933)
			(xy 111.197292 -364.579039) (xy 111.248621 -364.600851) (xy 111.296227 -364.629905) (xy 111.339095 -364.66558)
			(xy 111.376312 -364.707117) (xy 111.407085 -364.75363) (xy 111.408762 -364.757208) (xy 112.321592 -364.757208)
			(xy 112.325663 -364.701586) (xy 112.337789 -364.647149) (xy 112.357712 -364.595058) (xy 112.385008 -364.546423)
			(xy 112.419094 -364.50228) (xy 112.459243 -364.463571) (xy 112.504601 -364.43112) (xy 112.554201 -364.405619)
			(xy 112.606985 -364.387612) (xy 112.661828 -364.377482) (xy 112.717562 -364.375445) (xy 112.772999 -364.381545)
			(xy 112.826956 -364.395651) (xy 112.878285 -364.417463) (xy 112.925891 -364.446517) (xy 112.968759 -364.482192)
			(xy 113.005976 -364.523729) (xy 113.036749 -364.570242) (xy 113.060421 -364.620739) (xy 113.076489 -364.674146)
			(xy 113.080714 -364.702852) (xy 119.224042 -364.702852) (xy 119.228113 -364.64723) (xy 119.240239 -364.592793)
			(xy 119.260162 -364.540702) (xy 119.287458 -364.492067) (xy 119.321544 -364.447924) (xy 119.361693 -364.409215)
			(xy 119.407051 -364.376764) (xy 119.456651 -364.351263) (xy 119.509435 -364.333256) (xy 119.564278 -364.323126)
			(xy 119.620012 -364.321089) (xy 119.675449 -364.327189) (xy 119.729406 -364.341295) (xy 119.780735 -364.363107)
			(xy 119.828341 -364.392161) (xy 119.871209 -364.427836) (xy 119.908426 -364.469373) (xy 119.939199 -364.515886)
			(xy 119.962871 -364.566383) (xy 119.978939 -364.61979) (xy 119.987059 -364.674966) (xy 119.987568 -364.702852)
			(xy 119.987059 -364.730738) (xy 119.978939 -364.785914) (xy 119.962871 -364.839321) (xy 119.939199 -364.889818)
			(xy 119.908426 -364.936331) (xy 119.871209 -364.977868) (xy 119.828341 -365.013543) (xy 119.780735 -365.042597)
			(xy 119.729406 -365.064409) (xy 119.675449 -365.078515) (xy 119.620012 -365.084615) (xy 119.564278 -365.082578)
			(xy 119.509435 -365.072448) (xy 119.456651 -365.054441) (xy 119.407051 -365.02894) (xy 119.361693 -364.996489)
			(xy 119.321544 -364.95778) (xy 119.287458 -364.913637) (xy 119.260162 -364.865002) (xy 119.240239 -364.812911)
			(xy 119.228113 -364.758474) (xy 119.224042 -364.702852) (xy 113.080714 -364.702852) (xy 113.084609 -364.729322)
			(xy 113.085118 -364.757208) (xy 113.084609 -364.785094) (xy 113.076489 -364.84027) (xy 113.060421 -364.893677)
			(xy 113.036749 -364.944174) (xy 113.005976 -364.990687) (xy 112.968759 -365.032224) (xy 112.925891 -365.067899)
			(xy 112.878285 -365.096953) (xy 112.826956 -365.118765) (xy 112.772999 -365.132871) (xy 112.717562 -365.138971)
			(xy 112.661828 -365.136934) (xy 112.606985 -365.126804) (xy 112.554201 -365.108797) (xy 112.504601 -365.083296)
			(xy 112.459243 -365.050845) (xy 112.419094 -365.012136) (xy 112.385008 -364.967993) (xy 112.357712 -364.919358)
			(xy 112.337789 -364.867267) (xy 112.325663 -364.81283) (xy 112.321592 -364.757208) (xy 111.408762 -364.757208)
			(xy 111.430757 -364.804127) (xy 111.446825 -364.857534) (xy 111.454945 -364.91271) (xy 111.455454 -364.940596)
			(xy 111.454945 -364.968482) (xy 111.446825 -365.023658) (xy 111.430757 -365.077065) (xy 111.407085 -365.127562)
			(xy 111.376312 -365.174075) (xy 111.339095 -365.215612) (xy 111.296227 -365.251287) (xy 111.248621 -365.280341)
			(xy 111.197292 -365.302153) (xy 111.143335 -365.316259) (xy 111.087898 -365.322359) (xy 111.032164 -365.320322)
			(xy 110.977321 -365.310192) (xy 110.924537 -365.292185) (xy 110.874937 -365.266684) (xy 110.829579 -365.234233)
			(xy 110.78943 -365.195524) (xy 110.755344 -365.151381) (xy 110.728048 -365.102746) (xy 110.708125 -365.050655)
			(xy 110.695999 -364.996218) (xy 110.691928 -364.940596) (xy 107.692583 -364.940596) (xy 107.700971 -364.953274)
			(xy 107.724643 -365.003771) (xy 107.740711 -365.057178) (xy 107.748831 -365.112354) (xy 107.74934 -365.14024)
			(xy 107.748831 -365.168126) (xy 107.740711 -365.223302) (xy 107.724643 -365.276709) (xy 107.700971 -365.327206)
			(xy 107.670198 -365.373719) (xy 107.632981 -365.415256) (xy 107.590113 -365.450931) (xy 107.542507 -365.479985)
			(xy 107.491178 -365.501797) (xy 107.446925 -365.513366) (xy 109.842298 -365.513366) (xy 109.846369 -365.457744)
			(xy 109.858495 -365.403307) (xy 109.878418 -365.351216) (xy 109.905714 -365.302581) (xy 109.9398 -365.258438)
			(xy 109.979949 -365.219729) (xy 110.025307 -365.187278) (xy 110.074907 -365.161777) (xy 110.127691 -365.14377)
			(xy 110.182534 -365.13364) (xy 110.238268 -365.131603) (xy 110.293705 -365.137703) (xy 110.347662 -365.151809)
			(xy 110.398991 -365.173621) (xy 110.446597 -365.202675) (xy 110.489465 -365.23835) (xy 110.526682 -365.279887)
			(xy 110.557455 -365.3264) (xy 110.581127 -365.376897) (xy 110.597195 -365.430304) (xy 110.605315 -365.48548)
			(xy 110.605824 -365.513366) (xy 110.605315 -365.541252) (xy 110.597195 -365.596428) (xy 110.581127 -365.649835)
			(xy 110.557455 -365.700332) (xy 110.526682 -365.746845) (xy 110.525819 -365.747808) (xy 132.860799 -365.747808)
			(xy 132.864835 -365.664361) (xy 132.876907 -365.581693) (xy 132.8969 -365.500576) (xy 132.924629 -365.421767)
			(xy 132.959835 -365.346002) (xy 133.002189 -365.273989) (xy 133.051295 -365.2064) (xy 133.106696 -365.143866)
			(xy 133.167873 -365.086971) (xy 133.234256 -365.036245) (xy 133.305224 -364.992164) (xy 133.380116 -364.955138)
			(xy 133.458232 -364.925512) (xy 133.538842 -364.903564) (xy 133.621194 -364.889499) (xy 133.70452 -364.883447)
			(xy 133.78804 -364.885466) (xy 133.870976 -364.895536) (xy 133.952552 -364.913564) (xy 134.032008 -364.939381)
			(xy 134.108601 -364.972746) (xy 134.181617 -365.013347) (xy 134.250373 -365.060806) (xy 134.314227 -365.114679)
			(xy 134.372584 -365.174464) (xy 134.424899 -365.239601) (xy 134.470682 -365.309484) (xy 134.509507 -365.383459)
			(xy 134.541012 -365.460836) (xy 134.564901 -365.540893) (xy 134.580952 -365.622881) (xy 134.589015 -365.706036)
			(xy 134.58952 -365.747808) (xy 134.589015 -365.78958) (xy 134.580952 -365.872735) (xy 134.564901 -365.954723)
			(xy 134.541012 -366.03478) (xy 134.528065 -366.066578) (xy 138.60324 -366.066578) (xy 138.607206 -365.982047)
			(xy 138.619071 -365.89826) (xy 138.638729 -365.815951) (xy 138.666009 -365.735845) (xy 138.70067 -365.658646)
			(xy 138.742408 -365.585031) (xy 138.790855 -365.515648) (xy 138.845587 -365.451107) (xy 138.906123 -365.391975)
			(xy 138.971929 -365.338771) (xy 139.042429 -365.291963) (xy 139.117001 -365.251962) (xy 139.194992 -365.21912)
			(xy 139.275716 -365.193726) (xy 139.358463 -365.176003) (xy 139.442505 -365.166105) (xy 139.527106 -365.164122)
			(xy 139.61152 -365.170069) (xy 139.695007 -365.183894) (xy 139.776832 -365.205477) (xy 139.856276 -365.234627)
			(xy 139.932642 -365.271088) (xy 140.005258 -365.31454) (xy 140.073486 -365.364601) (xy 140.136726 -365.420831)
			(xy 140.194423 -365.482736) (xy 140.24607 -365.549772) (xy 140.291212 -365.621349) (xy 140.329454 -365.696839)
			(xy 140.360458 -365.775578) (xy 140.383953 -365.856875) (xy 140.399732 -365.940014) (xy 140.407656 -366.024266)
			(xy 140.408152 -366.066578) (xy 140.407663 -366.108322) (xy 141.169633 -366.108322) (xy 141.169633 -366.024834)
			(xy 141.177569 -365.941724) (xy 141.193369 -365.859746) (xy 141.21689 -365.77964) (xy 141.247919 -365.702132)
			(xy 141.286176 -365.627926) (xy 141.331312 -365.557691) (xy 141.382921 -365.492065) (xy 141.440534 -365.431643)
			(xy 141.50363 -365.37697) (xy 141.571637 -365.328542) (xy 141.64394 -365.286798) (xy 141.719883 -365.252116)
			(xy 141.798779 -365.22481) (xy 141.879913 -365.205127) (xy 141.962551 -365.193246) (xy 142.045944 -365.189273)
			(xy 142.129337 -365.193246) (xy 142.211975 -365.205127) (xy 142.293109 -365.22481) (xy 142.372005 -365.252116)
			(xy 142.447948 -365.286798) (xy 142.520251 -365.328542) (xy 142.588258 -365.37697) (xy 142.651354 -365.431643)
			(xy 142.708967 -365.492065) (xy 142.760576 -365.557691) (xy 142.805712 -365.627926) (xy 142.843969 -365.702132)
			(xy 142.874998 -365.77964) (xy 142.898519 -365.859746) (xy 142.914319 -365.941724) (xy 142.922255 -366.024834)
			(xy 142.922752 -366.066578) (xy 143.68324 -366.066578) (xy 143.687206 -365.982047) (xy 143.699071 -365.89826)
			(xy 143.718729 -365.815951) (xy 143.746009 -365.735845) (xy 143.78067 -365.658646) (xy 143.822408 -365.585031)
			(xy 143.870855 -365.515648) (xy 143.925587 -365.451107) (xy 143.986123 -365.391975) (xy 144.051929 -365.338771)
			(xy 144.122429 -365.291963) (xy 144.197001 -365.251962) (xy 144.274992 -365.21912) (xy 144.355716 -365.193726)
			(xy 144.438463 -365.176003) (xy 144.522505 -365.166105) (xy 144.607106 -365.164122) (xy 144.69152 -365.170069)
			(xy 144.775007 -365.183894) (xy 144.856832 -365.205477) (xy 144.936276 -365.234627) (xy 145.012642 -365.271088)
			(xy 145.085258 -365.31454) (xy 145.153486 -365.364601) (xy 145.216726 -365.420831) (xy 145.274423 -365.482736)
			(xy 145.32607 -365.549772) (xy 145.371212 -365.621349) (xy 145.409454 -365.696839) (xy 145.440458 -365.775578)
			(xy 145.463953 -365.856875) (xy 145.479732 -365.940014) (xy 145.487656 -366.024266) (xy 145.488152 -366.066578)
			(xy 145.487656 -366.10889) (xy 145.479732 -366.193142) (xy 145.463953 -366.276281) (xy 145.440458 -366.357578)
			(xy 145.409454 -366.436317) (xy 145.371212 -366.511807) (xy 145.32607 -366.583384) (xy 145.274423 -366.65042)
			(xy 145.216726 -366.712325) (xy 145.153486 -366.768555) (xy 145.085258 -366.818616) (xy 145.012642 -366.862068)
			(xy 144.936276 -366.898529) (xy 144.856832 -366.927679) (xy 144.775007 -366.949262) (xy 144.69152 -366.963087)
			(xy 144.607106 -366.969034) (xy 144.522505 -366.967051) (xy 144.438463 -366.957153) (xy 144.355716 -366.93943)
			(xy 144.274992 -366.914036) (xy 144.197001 -366.881194) (xy 144.122429 -366.841193) (xy 144.051929 -366.794385)
			(xy 143.986123 -366.741181) (xy 143.925587 -366.682049) (xy 143.870855 -366.617508) (xy 143.822408 -366.548125)
			(xy 143.78067 -366.47451) (xy 143.746009 -366.397311) (xy 143.718729 -366.317205) (xy 143.699071 -366.234896)
			(xy 143.687206 -366.151109) (xy 143.68324 -366.066578) (xy 142.922752 -366.066578) (xy 142.922255 -366.108322)
			(xy 142.914319 -366.191432) (xy 142.898519 -366.27341) (xy 142.874998 -366.353516) (xy 142.843969 -366.431024)
			(xy 142.805712 -366.505231) (xy 142.760576 -366.575465) (xy 142.708967 -366.641091) (xy 142.651354 -366.701513)
			(xy 142.588258 -366.756186) (xy 142.520251 -366.804614) (xy 142.447948 -366.846358) (xy 142.372005 -366.88104)
			(xy 142.293109 -366.908346) (xy 142.211975 -366.928029) (xy 142.129337 -366.93991) (xy 142.045944 -366.943883)
			(xy 141.962551 -366.93991) (xy 141.879913 -366.928029) (xy 141.798779 -366.908346) (xy 141.719883 -366.88104)
			(xy 141.64394 -366.846358) (xy 141.571637 -366.804614) (xy 141.50363 -366.756186) (xy 141.440534 -366.701513)
			(xy 141.382921 -366.641091) (xy 141.331312 -366.575465) (xy 141.286176 -366.505231) (xy 141.247919 -366.431024)
			(xy 141.21689 -366.353516) (xy 141.193369 -366.27341) (xy 141.177569 -366.191432) (xy 141.169633 -366.108322)
			(xy 140.407663 -366.108322) (xy 140.407656 -366.10889) (xy 140.399732 -366.193142) (xy 140.383953 -366.276281)
			(xy 140.360458 -366.357578) (xy 140.329454 -366.436317) (xy 140.291212 -366.511807) (xy 140.24607 -366.583384)
			(xy 140.194423 -366.65042) (xy 140.136726 -366.712325) (xy 140.073486 -366.768555) (xy 140.005258 -366.818616)
			(xy 139.932642 -366.862068) (xy 139.856276 -366.898529) (xy 139.776832 -366.927679) (xy 139.695007 -366.949262)
			(xy 139.61152 -366.963087) (xy 139.527106 -366.969034) (xy 139.442505 -366.967051) (xy 139.358463 -366.957153)
			(xy 139.275716 -366.93943) (xy 139.194992 -366.914036) (xy 139.117001 -366.881194) (xy 139.042429 -366.841193)
			(xy 138.971929 -366.794385) (xy 138.906123 -366.741181) (xy 138.845587 -366.682049) (xy 138.790855 -366.617508)
			(xy 138.742408 -366.548125) (xy 138.70067 -366.47451) (xy 138.666009 -366.397311) (xy 138.638729 -366.317205)
			(xy 138.619071 -366.234896) (xy 138.607206 -366.151109) (xy 138.60324 -366.066578) (xy 134.528065 -366.066578)
			(xy 134.509507 -366.112157) (xy 134.470682 -366.186132) (xy 134.424899 -366.256015) (xy 134.372584 -366.321152)
			(xy 134.314227 -366.380937) (xy 134.250373 -366.43481) (xy 134.181617 -366.482269) (xy 134.108601 -366.52287)
			(xy 134.032008 -366.556235) (xy 133.952552 -366.582052) (xy 133.870976 -366.60008) (xy 133.78804 -366.61015)
			(xy 133.70452 -366.612169) (xy 133.621194 -366.606117) (xy 133.538842 -366.592052) (xy 133.458232 -366.570104)
			(xy 133.380116 -366.540478) (xy 133.305224 -366.503452) (xy 133.234256 -366.459371) (xy 133.167873 -366.408645)
			(xy 133.106696 -366.35175) (xy 133.051295 -366.289216) (xy 133.002189 -366.221627) (xy 132.959835 -366.149614)
			(xy 132.924629 -366.073849) (xy 132.8969 -365.99504) (xy 132.876907 -365.913923) (xy 132.864835 -365.831255)
			(xy 132.860799 -365.747808) (xy 110.525819 -365.747808) (xy 110.489465 -365.788382) (xy 110.446597 -365.824057)
			(xy 110.398991 -365.853111) (xy 110.347662 -365.874923) (xy 110.293705 -365.889029) (xy 110.238268 -365.895129)
			(xy 110.182534 -365.893092) (xy 110.127691 -365.882962) (xy 110.074907 -365.864955) (xy 110.025307 -365.839454)
			(xy 109.979949 -365.807003) (xy 109.9398 -365.768294) (xy 109.905714 -365.724151) (xy 109.878418 -365.675516)
			(xy 109.858495 -365.623425) (xy 109.846369 -365.568988) (xy 109.842298 -365.513366) (xy 107.446925 -365.513366)
			(xy 107.437221 -365.515903) (xy 107.381784 -365.522003) (xy 107.32605 -365.519966) (xy 107.271207 -365.509836)
			(xy 107.218423 -365.491829) (xy 107.168823 -365.466328) (xy 107.123465 -365.433877) (xy 107.083316 -365.395168)
			(xy 107.04923 -365.351025) (xy 107.021934 -365.30239) (xy 107.002011 -365.250299) (xy 106.989885 -365.195862)
			(xy 106.985814 -365.14024) (xy 103.319602 -365.14024) (xy 103.542084 -365.362744) (xy 103.562209 -365.383594)
			(xy 103.596309 -365.430444) (xy 103.622658 -365.482053) (xy 103.640607 -365.537149) (xy 103.649713 -365.594375)
			(xy 103.650288 -365.623348) (xy 103.650288 -366.271853) (xy 104.673087 -366.271853) (xy 104.673087 -366.217347)
			(xy 104.680845 -366.163397) (xy 104.696202 -366.1111) (xy 104.718846 -366.061521) (xy 104.748316 -366.015669)
			(xy 104.784011 -365.974479) (xy 104.825206 -365.938788) (xy 104.871061 -365.909324) (xy 104.920643 -365.886686)
			(xy 104.972942 -365.871335) (xy 105.026893 -365.863584) (xy 105.054146 -365.863124) (xy 105.080526 -365.863544)
			(xy 105.132786 -365.870804) (xy 105.183547 -365.885191) (xy 105.231843 -365.906433) (xy 105.276753 -365.934124)
			(xy 105.317421 -365.967737) (xy 105.353072 -366.006631) (xy 105.383026 -366.050064) (xy 105.395268 -366.073436)
			(xy 105.40197 -366.085795) (xy 105.420945 -366.106523) (xy 105.444859 -366.121285) (xy 105.471895 -366.128957)
			(xy 105.499997 -366.128957) (xy 105.527033 -366.121285) (xy 105.550947 -366.106523) (xy 105.569922 -366.085795)
			(xy 105.576624 -366.073436) (xy 105.588879 -366.050073) (xy 105.618842 -366.006652) (xy 105.654497 -365.967769)
			(xy 105.695164 -365.934164) (xy 105.740071 -365.906477) (xy 105.788361 -365.885234) (xy 105.839116 -365.870842)
			(xy 105.891368 -365.863572) (xy 105.917746 -365.863124) (xy 105.944997 -365.863549) (xy 105.998945 -365.871311)
			(xy 106.051238 -365.886672) (xy 106.100814 -365.909318) (xy 106.146662 -365.938788) (xy 106.187851 -365.974482)
			(xy 106.22354 -366.015675) (xy 106.253005 -366.061527) (xy 106.275644 -366.111105) (xy 106.290998 -366.1634)
			(xy 106.298754 -366.217349) (xy 106.298754 -366.271851) (xy 106.290998 -366.3258) (xy 106.275644 -366.378095)
			(xy 106.253005 -366.427673) (xy 106.22354 -366.473525) (xy 106.187851 -366.514718) (xy 106.146662 -366.550412)
			(xy 106.100814 -366.579882) (xy 106.051238 -366.602528) (xy 105.998945 -366.617889) (xy 105.944997 -366.625651)
			(xy 105.917746 -366.62614) (xy 105.891367 -366.625691) (xy 105.839111 -366.618432) (xy 105.788352 -366.604046)
			(xy 105.740058 -366.582807) (xy 105.695148 -366.55512) (xy 105.65448 -366.521513) (xy 105.618826 -366.482625)
			(xy 105.588868 -366.439197) (xy 105.576624 -366.415828) (xy 105.569922 -366.403469) (xy 105.550947 -366.382741)
			(xy 105.527033 -366.367979) (xy 105.499997 -366.360307) (xy 105.471895 -366.360307) (xy 105.444859 -366.367979)
			(xy 105.420945 -366.382741) (xy 105.40197 -366.403469) (xy 105.395268 -366.415828) (xy 105.383003 -366.439186)
			(xy 105.353043 -366.482608) (xy 105.317391 -366.521493) (xy 105.276725 -366.555099) (xy 105.231819 -366.582787)
			(xy 105.18353 -366.60403) (xy 105.132776 -366.618423) (xy 105.080524 -366.625692) (xy 105.054146 -366.62614)
			(xy 105.026893 -366.625616) (xy 104.972942 -366.617865) (xy 104.920643 -366.602514) (xy 104.871061 -366.579876)
			(xy 104.825206 -366.550412) (xy 104.784011 -366.514721) (xy 104.748316 -366.473531) (xy 104.718846 -366.427679)
			(xy 104.696202 -366.3781) (xy 104.680845 -366.325803) (xy 104.673087 -366.271853) (xy 103.650288 -366.271853)
			(xy 103.650288 -366.653651) (xy 107.352072 -366.653651) (xy 107.352072 -366.599149) (xy 107.359828 -366.545202)
			(xy 107.375183 -366.492908) (xy 107.397823 -366.443331) (xy 107.427288 -366.39748) (xy 107.462978 -366.35629)
			(xy 107.504167 -366.320598) (xy 107.550017 -366.291131) (xy 107.599593 -366.268488) (xy 107.651886 -366.253131)
			(xy 107.705833 -366.245373) (xy 107.733084 -366.244886) (xy 107.759465 -366.245296) (xy 107.811723 -366.252559)
			(xy 107.862484 -366.26695) (xy 107.910779 -366.288195) (xy 107.955688 -366.315887) (xy 107.996356 -366.3495)
			(xy 108.032008 -366.388394) (xy 108.061963 -366.431826) (xy 108.074206 -366.455198) (xy 108.080908 -366.467557)
			(xy 108.099883 -366.488285) (xy 108.123797 -366.503047) (xy 108.150833 -366.510719) (xy 108.178935 -366.510719)
			(xy 108.205971 -366.503047) (xy 108.229885 -366.488285) (xy 108.24886 -366.467557) (xy 108.255562 -366.455198)
			(xy 108.267815 -366.431834) (xy 108.297776 -366.38841) (xy 108.333429 -366.349524) (xy 108.374097 -366.315917)
			(xy 108.419004 -366.28823) (xy 108.467296 -366.266988) (xy 108.518052 -366.252598) (xy 108.570306 -366.245332)
			(xy 108.596684 -366.244886) (xy 108.623937 -366.24536) (xy 108.677889 -366.253115) (xy 108.730188 -366.26847)
			(xy 108.779769 -366.291111) (xy 108.825624 -366.320578) (xy 108.866818 -366.356271) (xy 108.902512 -366.397463)
			(xy 108.931981 -366.443317) (xy 108.954625 -366.492897) (xy 108.969981 -366.545195) (xy 108.977739 -366.599147)
			(xy 108.977739 -366.653653) (xy 108.969981 -366.707605) (xy 108.954625 -366.759903) (xy 108.931981 -366.809483)
			(xy 108.902512 -366.855337) (xy 108.866818 -366.896529) (xy 108.825624 -366.932222) (xy 108.779769 -366.961689)
			(xy 108.730188 -366.98433) (xy 108.677889 -366.999685) (xy 108.623937 -367.00744) (xy 108.596684 -367.007902)
			(xy 108.570305 -367.007443) (xy 108.518048 -367.000188) (xy 108.467289 -366.985805) (xy 108.418994 -366.964569)
			(xy 108.374084 -366.936883) (xy 108.333415 -366.903276) (xy 108.297762 -366.864388) (xy 108.267805 -366.82096)
			(xy 108.255562 -366.79759) (xy 108.24886 -366.785231) (xy 108.229885 -366.764503) (xy 108.205971 -366.749741)
			(xy 108.178935 -366.742069) (xy 108.150833 -366.742069) (xy 108.123797 -366.749741) (xy 108.099883 -366.764503)
			(xy 108.080908 -366.785231) (xy 108.074206 -366.79759) (xy 108.061972 -366.820965) (xy 108.032009 -366.86439)
			(xy 107.996354 -366.903276) (xy 107.955683 -366.936882) (xy 107.910773 -366.964569) (xy 107.862479 -366.985808)
			(xy 107.81172 -367.000196) (xy 107.759463 -367.007458) (xy 107.733084 -367.007902) (xy 107.705833 -367.007427)
			(xy 107.651886 -366.999669) (xy 107.599593 -366.984312) (xy 107.550017 -366.961669) (xy 107.504167 -366.932202)
			(xy 107.462978 -366.89651) (xy 107.427288 -366.85532) (xy 107.397823 -366.809469) (xy 107.375183 -366.759892)
			(xy 107.359828 -366.707598) (xy 107.352072 -366.653651) (xy 103.650288 -366.653651) (xy 103.650288 -367.832132)
			(xy 121.144028 -367.832132) (xy 121.148099 -367.77651) (xy 121.160225 -367.722073) (xy 121.180148 -367.669982)
			(xy 121.207444 -367.621347) (xy 121.24153 -367.577204) (xy 121.281679 -367.538495) (xy 121.327037 -367.506044)
			(xy 121.376637 -367.480543) (xy 121.429421 -367.462536) (xy 121.484264 -367.452406) (xy 121.539998 -367.450369)
			(xy 121.595435 -367.456469) (xy 121.649392 -367.470575) (xy 121.700721 -367.492387) (xy 121.748327 -367.521441)
			(xy 121.791195 -367.557116) (xy 121.828412 -367.598653) (xy 121.859185 -367.645166) (xy 121.882857 -367.695663)
			(xy 121.898925 -367.74907) (xy 121.907045 -367.804246) (xy 121.907554 -367.832132) (xy 121.907045 -367.860018)
			(xy 121.898925 -367.915194) (xy 121.882857 -367.968601) (xy 121.859185 -368.019098) (xy 121.828412 -368.065611)
			(xy 121.825273 -368.069114) (xy 122.207274 -368.069114) (xy 122.207774 -368.040196) (xy 122.216503 -367.983023)
			(xy 122.233763 -367.927822) (xy 122.259158 -367.87586) (xy 122.292106 -367.828327) (xy 122.331852 -367.786312)
			(xy 122.35434 -367.768124) (xy 122.366136 -367.758214) (xy 122.383662 -367.732896) (xy 122.392843 -367.703505)
			(xy 122.392846 -367.672712) (xy 122.383669 -367.64332) (xy 122.366148 -367.617999) (xy 122.35434 -367.608104)
			(xy 122.331867 -367.589901) (xy 122.292129 -367.547885) (xy 122.259188 -367.500353) (xy 122.233797 -367.448394)
			(xy 122.216539 -367.393198) (xy 122.207809 -367.336029) (xy 122.207274 -367.307114) (xy 122.20776 -367.279863)
			(xy 122.215516 -367.225915) (xy 122.230871 -367.17362) (xy 122.253513 -367.124043) (xy 122.282979 -367.078193)
			(xy 122.31867 -367.037002) (xy 122.359861 -367.001311) (xy 122.405711 -366.971845) (xy 122.455288 -366.949203)
			(xy 122.507583 -366.933848) (xy 122.561531 -366.926092) (xy 122.616033 -366.926092) (xy 122.669981 -366.933848)
			(xy 122.722276 -366.949203) (xy 122.771853 -366.971845) (xy 122.817703 -367.001311) (xy 122.858894 -367.037002)
			(xy 122.894585 -367.078193) (xy 122.924051 -367.124043) (xy 122.946693 -367.17362) (xy 122.962048 -367.225915)
			(xy 122.969804 -367.279863) (xy 122.97029 -367.307114) (xy 122.969714 -367.336029) (xy 122.960997 -367.393198)
			(xy 122.943751 -367.448395) (xy 122.91837 -367.500357) (xy 122.885437 -367.547893) (xy 122.845705 -367.589912)
			(xy 122.823224 -367.608104) (xy 122.811404 -367.617986) (xy 122.793885 -367.643313) (xy 122.784709 -367.672711)
			(xy 122.784712 -367.703507) (xy 122.793892 -367.732903) (xy 122.811416 -367.758227) (xy 122.823224 -367.768124)
			(xy 122.845724 -367.786295) (xy 122.885457 -367.82832) (xy 122.918393 -367.875859) (xy 122.943779 -367.927824)
			(xy 122.961032 -367.983025) (xy 122.969757 -368.040197) (xy 122.97029 -368.069114) (xy 124.355098 -368.069114)
			(xy 124.355627 -368.040198) (xy 124.364354 -367.983027) (xy 124.38161 -367.927828) (xy 124.407 -367.875867)
			(xy 124.439941 -367.828332) (xy 124.47968 -367.786315) (xy 124.502164 -367.768124) (xy 124.513957 -367.758212)
			(xy 124.531479 -367.732894) (xy 124.540659 -367.703504) (xy 124.540661 -367.672713) (xy 124.531487 -367.643322)
			(xy 124.513969 -367.618) (xy 124.502164 -367.608104) (xy 124.479675 -367.58992) (xy 124.439942 -367.547898)
			(xy 124.407004 -367.500361) (xy 124.381617 -367.448398) (xy 124.364362 -367.3932) (xy 124.355633 -367.33603)
			(xy 124.355098 -367.307114) (xy 124.355584 -367.279863) (xy 124.36334 -367.225915) (xy 124.378695 -367.17362)
			(xy 124.401337 -367.124043) (xy 124.430803 -367.078193) (xy 124.466494 -367.037002) (xy 124.507685 -367.001311)
			(xy 124.553535 -366.971845) (xy 124.603112 -366.949203) (xy 124.655407 -366.933848) (xy 124.709355 -366.926092)
			(xy 124.763857 -366.926092) (xy 124.817805 -366.933848) (xy 124.8701 -366.949203) (xy 124.919677 -366.971845)
			(xy 124.965527 -367.001311) (xy 125.006718 -367.037002) (xy 125.042409 -367.078193) (xy 125.071875 -367.124043)
			(xy 125.094517 -367.17362) (xy 125.109872 -367.225915) (xy 125.117628 -367.279863) (xy 125.118114 -367.307114)
			(xy 125.117566 -367.33603) (xy 125.108848 -367.393202) (xy 125.091598 -367.448401) (xy 125.066212 -367.500364)
			(xy 125.033272 -367.547898) (xy 124.993533 -367.589914) (xy 124.971048 -367.608104) (xy 124.959226 -367.617984)
			(xy 124.941702 -367.643311) (xy 124.932525 -367.67271) (xy 124.932527 -367.703508) (xy 124.94171 -367.732905)
			(xy 124.959237 -367.758228) (xy 124.971048 -367.768124) (xy 124.993553 -367.786289) (xy 125.033285 -367.828316)
			(xy 125.06622 -367.875857) (xy 125.091604 -367.927823) (xy 125.108856 -367.983024) (xy 125.117581 -368.040197)
			(xy 125.118114 -368.069114) (xy 126.488698 -368.069114) (xy 126.489227 -368.040198) (xy 126.497954 -367.983027)
			(xy 126.51521 -367.927828) (xy 126.5406 -367.875867) (xy 126.573541 -367.828332) (xy 126.61328 -367.786315)
			(xy 126.635764 -367.768124) (xy 126.647557 -367.758212) (xy 126.665079 -367.732894) (xy 126.674259 -367.703504)
			(xy 126.674261 -367.672713) (xy 126.665087 -367.643322) (xy 126.647569 -367.618) (xy 126.635764 -367.608104)
			(xy 126.613275 -367.58992) (xy 126.573542 -367.547898) (xy 126.540604 -367.500361) (xy 126.515217 -367.448398)
			(xy 126.497962 -367.3932) (xy 126.489233 -367.33603) (xy 126.488698 -367.307114) (xy 126.489184 -367.279863)
			(xy 126.49694 -367.225915) (xy 126.512295 -367.17362) (xy 126.534937 -367.124043) (xy 126.564403 -367.078193)
			(xy 126.600094 -367.037002) (xy 126.641285 -367.001311) (xy 126.687135 -366.971845) (xy 126.736712 -366.949203)
			(xy 126.789007 -366.933848) (xy 126.842955 -366.926092) (xy 126.897457 -366.926092) (xy 126.951405 -366.933848)
			(xy 127.0037 -366.949203) (xy 127.053277 -366.971845) (xy 127.099127 -367.001311) (xy 127.140318 -367.037002)
			(xy 127.176009 -367.078193) (xy 127.205475 -367.124043) (xy 127.228117 -367.17362) (xy 127.243472 -367.225915)
			(xy 127.251228 -367.279863) (xy 127.251714 -367.307114) (xy 127.251166 -367.33603) (xy 127.242448 -367.393202)
			(xy 127.225198 -367.448401) (xy 127.199812 -367.500364) (xy 127.166872 -367.547898) (xy 127.127133 -367.589914)
			(xy 127.104648 -367.608104) (xy 127.092826 -367.617984) (xy 127.075302 -367.643311) (xy 127.066125 -367.67271)
			(xy 127.066127 -367.703508) (xy 127.07531 -367.732905) (xy 127.092837 -367.758228) (xy 127.104648 -367.768124)
			(xy 127.127153 -367.786289) (xy 127.166885 -367.828316) (xy 127.19982 -367.875857) (xy 127.225204 -367.927823)
			(xy 127.242456 -367.983024) (xy 127.251181 -368.040197) (xy 127.25119 -368.040666) (xy 128.641348 -368.040666)
			(xy 128.641896 -368.01175) (xy 128.650616 -367.954579) (xy 128.667867 -367.89938) (xy 128.693253 -367.847418)
			(xy 128.726193 -367.799884) (xy 128.76593 -367.757867) (xy 128.788414 -367.739676) (xy 128.800251 -367.729814)
			(xy 128.817763 -367.70448) (xy 128.826932 -367.675078) (xy 128.826926 -367.64428) (xy 128.817744 -367.614882)
			(xy 128.800222 -367.589555) (xy 128.788414 -367.579656) (xy 128.765912 -367.561486) (xy 128.726178 -367.519463)
			(xy 128.69324 -367.471923) (xy 128.667855 -367.419958) (xy 128.650603 -367.364756) (xy 128.64188 -367.307583)
			(xy 128.641348 -367.278666) (xy 128.641834 -367.251415) (xy 128.64959 -367.197467) (xy 128.664945 -367.145172)
			(xy 128.687587 -367.095595) (xy 128.717053 -367.049745) (xy 128.752744 -367.008554) (xy 128.793935 -366.972863)
			(xy 128.839785 -366.943397) (xy 128.889362 -366.920755) (xy 128.941657 -366.9054) (xy 128.995605 -366.897644)
			(xy 129.050107 -366.897644) (xy 129.104055 -366.9054) (xy 129.15635 -366.920755) (xy 129.205927 -366.943397)
			(xy 129.251777 -366.972863) (xy 129.292968 -367.008554) (xy 129.328659 -367.049745) (xy 129.358125 -367.095595)
			(xy 129.380767 -367.145172) (xy 129.396122 -367.197467) (xy 129.403878 -367.251415) (xy 129.404364 -367.278666)
			(xy 129.403835 -367.307583) (xy 129.39511 -367.364754) (xy 129.377855 -367.419953) (xy 129.352466 -367.471915)
			(xy 129.319523 -367.519449) (xy 129.279783 -367.561466) (xy 129.257298 -367.579656) (xy 129.245528 -367.589592)
			(xy 129.228013 -367.614905) (xy 129.218835 -367.644288) (xy 129.218829 -367.675071) (xy 129.227994 -367.704457)
			(xy 129.2455 -367.729778) (xy 129.257298 -367.739676) (xy 129.27977 -367.757881) (xy 129.319506 -367.799898)
			(xy 129.352446 -367.84743) (xy 129.377836 -367.899388) (xy 129.395095 -367.954583) (xy 129.403827 -368.011751)
			(xy 129.404364 -368.040666) (xy 129.403878 -368.067917) (xy 129.396122 -368.121865) (xy 129.380767 -368.17416)
			(xy 129.358125 -368.223737) (xy 129.328659 -368.269587) (xy 129.310731 -368.290278) (xy 132.836408 -368.290278)
			(xy 132.836408 -368.205582) (xy 132.844459 -368.121268) (xy 132.860488 -368.038102) (xy 132.884349 -367.956835)
			(xy 132.915828 -367.878205) (xy 132.954639 -367.802924) (xy 133.000429 -367.731672) (xy 133.052785 -367.665096)
			(xy 133.111233 -367.603798) (xy 133.175243 -367.548333) (xy 133.244235 -367.499204) (xy 133.317585 -367.456855)
			(xy 133.394628 -367.421671) (xy 133.474667 -367.393969) (xy 133.556976 -367.374001) (xy 133.640811 -367.361948)
			(xy 133.725412 -367.357918) (xy 133.810013 -367.361948) (xy 133.893848 -367.374001) (xy 133.976157 -367.393969)
			(xy 134.056196 -367.421671) (xy 134.133239 -367.456855) (xy 134.206589 -367.499204) (xy 134.275581 -367.548333)
			(xy 134.339591 -367.603798) (xy 134.398039 -367.665096) (xy 134.450395 -367.731672) (xy 134.496185 -367.802924)
			(xy 134.534996 -367.878205) (xy 134.566475 -367.956835) (xy 134.590336 -368.038102) (xy 134.606365 -368.121268)
			(xy 134.608758 -368.14633) (xy 140.60246 -368.14633) (xy 140.606531 -368.090708) (xy 140.618657 -368.036271)
			(xy 140.63858 -367.98418) (xy 140.665876 -367.935545) (xy 140.699962 -367.891402) (xy 140.740111 -367.852693)
			(xy 140.785469 -367.820242) (xy 140.835069 -367.794741) (xy 140.887853 -367.776734) (xy 140.942696 -367.766604)
			(xy 140.99843 -367.764567) (xy 141.053867 -367.770667) (xy 141.107824 -367.784773) (xy 141.159153 -367.806585)
			(xy 141.206759 -367.835639) (xy 141.249627 -367.871314) (xy 141.286844 -367.912851) (xy 141.317617 -367.959364)
			(xy 141.341289 -368.009861) (xy 141.357357 -368.063268) (xy 141.365477 -368.118444) (xy 141.365986 -368.14633)
			(xy 141.365477 -368.174216) (xy 141.357357 -368.229392) (xy 141.341289 -368.282799) (xy 141.317617 -368.333296)
			(xy 141.286844 -368.379809) (xy 141.249627 -368.421346) (xy 141.206759 -368.457021) (xy 141.159153 -368.486075)
			(xy 141.107824 -368.507887) (xy 141.053867 -368.521993) (xy 140.99843 -368.528093) (xy 140.942696 -368.526056)
			(xy 140.887853 -368.515926) (xy 140.835069 -368.497919) (xy 140.785469 -368.472418) (xy 140.740111 -368.439967)
			(xy 140.699962 -368.401258) (xy 140.665876 -368.357115) (xy 140.63858 -368.30848) (xy 140.618657 -368.256389)
			(xy 140.606531 -368.201952) (xy 140.60246 -368.14633) (xy 134.608758 -368.14633) (xy 134.614416 -368.205582)
			(xy 134.61492 -368.24793) (xy 134.614416 -368.290278) (xy 134.606365 -368.374592) (xy 134.590336 -368.457758)
			(xy 134.566475 -368.539025) (xy 134.534996 -368.617655) (xy 134.496185 -368.692936) (xy 134.450395 -368.764188)
			(xy 134.398039 -368.830764) (xy 134.339591 -368.892062) (xy 134.275581 -368.947527) (xy 134.206589 -368.996656)
			(xy 134.133239 -369.039005) (xy 134.056196 -369.074189) (xy 133.976157 -369.101891) (xy 133.893848 -369.121859)
			(xy 133.810013 -369.133912) (xy 133.725412 -369.137943) (xy 133.640811 -369.133912) (xy 133.556976 -369.121859)
			(xy 133.474667 -369.101891) (xy 133.394628 -369.074189) (xy 133.317585 -369.039005) (xy 133.244235 -368.996656)
			(xy 133.175243 -368.947527) (xy 133.111233 -368.892062) (xy 133.052785 -368.830764) (xy 133.000429 -368.764188)
			(xy 132.954639 -368.692936) (xy 132.915828 -368.617655) (xy 132.884349 -368.539025) (xy 132.860488 -368.457758)
			(xy 132.844459 -368.374592) (xy 132.836408 -368.290278) (xy 129.310731 -368.290278) (xy 129.292968 -368.310778)
			(xy 129.251777 -368.346469) (xy 129.205927 -368.375935) (xy 129.15635 -368.398577) (xy 129.104055 -368.413932)
			(xy 129.050107 -368.421688) (xy 128.995605 -368.421688) (xy 128.941657 -368.413932) (xy 128.889362 -368.398577)
			(xy 128.839785 -368.375935) (xy 128.793935 -368.346469) (xy 128.752744 -368.310778) (xy 128.717053 -368.269587)
			(xy 128.687587 -368.223737) (xy 128.664945 -368.17416) (xy 128.64959 -368.121865) (xy 128.641834 -368.067917)
			(xy 128.641348 -368.040666) (xy 127.25119 -368.040666) (xy 127.251714 -368.069114) (xy 127.251228 -368.096365)
			(xy 127.243472 -368.150313) (xy 127.228117 -368.202608) (xy 127.205475 -368.252185) (xy 127.176009 -368.298035)
			(xy 127.140318 -368.339226) (xy 127.099127 -368.374917) (xy 127.053277 -368.404383) (xy 127.0037 -368.427025)
			(xy 126.951405 -368.44238) (xy 126.897457 -368.450136) (xy 126.842955 -368.450136) (xy 126.789007 -368.44238)
			(xy 126.736712 -368.427025) (xy 126.687135 -368.404383) (xy 126.641285 -368.374917) (xy 126.600094 -368.339226)
			(xy 126.564403 -368.298035) (xy 126.534937 -368.252185) (xy 126.512295 -368.202608) (xy 126.49694 -368.150313)
			(xy 126.489184 -368.096365) (xy 126.488698 -368.069114) (xy 125.118114 -368.069114) (xy 125.117628 -368.096365)
			(xy 125.109872 -368.150313) (xy 125.094517 -368.202608) (xy 125.071875 -368.252185) (xy 125.042409 -368.298035)
			(xy 125.006718 -368.339226) (xy 124.965527 -368.374917) (xy 124.919677 -368.404383) (xy 124.8701 -368.427025)
			(xy 124.817805 -368.44238) (xy 124.763857 -368.450136) (xy 124.709355 -368.450136) (xy 124.655407 -368.44238)
			(xy 124.603112 -368.427025) (xy 124.553535 -368.404383) (xy 124.507685 -368.374917) (xy 124.466494 -368.339226)
			(xy 124.430803 -368.298035) (xy 124.401337 -368.252185) (xy 124.378695 -368.202608) (xy 124.36334 -368.150313)
			(xy 124.355584 -368.096365) (xy 124.355098 -368.069114) (xy 122.97029 -368.069114) (xy 122.969804 -368.096365)
			(xy 122.962048 -368.150313) (xy 122.946693 -368.202608) (xy 122.924051 -368.252185) (xy 122.894585 -368.298035)
			(xy 122.858894 -368.339226) (xy 122.817703 -368.374917) (xy 122.771853 -368.404383) (xy 122.722276 -368.427025)
			(xy 122.669981 -368.44238) (xy 122.616033 -368.450136) (xy 122.561531 -368.450136) (xy 122.507583 -368.44238)
			(xy 122.455288 -368.427025) (xy 122.405711 -368.404383) (xy 122.359861 -368.374917) (xy 122.31867 -368.339226)
			(xy 122.282979 -368.298035) (xy 122.253513 -368.252185) (xy 122.230871 -368.202608) (xy 122.215516 -368.150313)
			(xy 122.20776 -368.096365) (xy 122.207274 -368.069114) (xy 121.825273 -368.069114) (xy 121.791195 -368.107148)
			(xy 121.748327 -368.142823) (xy 121.700721 -368.171877) (xy 121.649392 -368.193689) (xy 121.595435 -368.207795)
			(xy 121.539998 -368.213895) (xy 121.484264 -368.211858) (xy 121.429421 -368.201728) (xy 121.376637 -368.183721)
			(xy 121.327037 -368.15822) (xy 121.281679 -368.125769) (xy 121.24153 -368.08706) (xy 121.207444 -368.042917)
			(xy 121.180148 -367.994282) (xy 121.160225 -367.942191) (xy 121.148099 -367.887754) (xy 121.144028 -367.832132)
			(xy 103.650288 -367.832132) (xy 103.650288 -368.696748) (xy 117.255542 -368.696748) (xy 117.259613 -368.641126)
			(xy 117.271739 -368.586689) (xy 117.291662 -368.534598) (xy 117.318958 -368.485963) (xy 117.353044 -368.44182)
			(xy 117.393193 -368.403111) (xy 117.438551 -368.37066) (xy 117.488151 -368.345159) (xy 117.540935 -368.327152)
			(xy 117.595778 -368.317022) (xy 117.651512 -368.314985) (xy 117.706949 -368.321085) (xy 117.760906 -368.335191)
			(xy 117.812235 -368.357003) (xy 117.859841 -368.386057) (xy 117.902709 -368.421732) (xy 117.939926 -368.463269)
			(xy 117.970699 -368.509782) (xy 117.994371 -368.560279) (xy 118.010439 -368.613686) (xy 118.018559 -368.668862)
			(xy 118.019068 -368.696748) (xy 118.018559 -368.724634) (xy 118.010439 -368.77981) (xy 117.994371 -368.833217)
			(xy 117.970699 -368.883714) (xy 117.939926 -368.930227) (xy 117.902709 -368.971764) (xy 117.859841 -369.007439)
			(xy 117.812235 -369.036493) (xy 117.760906 -369.058305) (xy 117.706949 -369.072411) (xy 117.651512 -369.078511)
			(xy 117.595778 -369.076474) (xy 117.540935 -369.066344) (xy 117.488151 -369.048337) (xy 117.438551 -369.022836)
			(xy 117.393193 -368.990385) (xy 117.353044 -368.951676) (xy 117.318958 -368.907533) (xy 117.291662 -368.858898)
			(xy 117.271739 -368.806807) (xy 117.259613 -368.75237) (xy 117.255542 -368.696748) (xy 103.650288 -368.696748)
			(xy 103.650288 -373.822468) (xy 140.18641 -373.822468) (xy 145.214594 -367.670588) (xy 145.21942 -367.664746)
			(xy 147.839938 -361.33532) (xy 147.839938 -339.639402) (xy 147.824952 -339.624416) (xy 140.054584 -331.854048)
			(xy 133.6802 -331.854048) (xy 133.51891 -331.692758) (xy 133.50494 -331.689202) (xy 133.498176 -331.687358)
			(xy 133.485945 -331.680515) (xy 133.48081 -331.67574) (xy 131.635246 -329.830176) (xy 127.139192 -329.830176)
			(xy 127.129123 -329.829751) (xy 127.110523 -329.822032) (xy 127.103124 -329.81519) (xy 123.497086 -326.209152)
			(xy 95.379286 -326.209152) (xy 95.3643 -326.224138) (xy 92.148152 -329.440286) (xy 92.140752 -329.447127)
			(xy 92.122153 -329.454846) (xy 92.112084 -329.455272) (xy 86.514686 -329.455272) (xy 86.4997 -329.470258)
			(xy 84.945728 -331.02423) (xy 84.945728 -332.384146) (xy 84.945297 -332.394213) (xy 84.937574 -332.412808)
			(xy 84.930742 -332.420214) (xy 84.289138 -333.061818) (xy 84.28174 -333.068663) (xy 84.263141 -333.076388)
			(xy 84.25307 -333.076804) (xy 76.531724 -333.076804) (xy 76.516738 -333.09179) (xy 76.372974 -333.235554)
			(xy 76.372974 -334.541368) (xy 93.012768 -334.541368) (xy 93.013254 -334.514117) (xy 93.02101 -334.460169)
			(xy 93.036365 -334.407874) (xy 93.059007 -334.358297) (xy 93.088473 -334.312447) (xy 93.124164 -334.271256)
			(xy 93.165355 -334.235565) (xy 93.211205 -334.206099) (xy 93.260782 -334.183457) (xy 93.313077 -334.168102)
			(xy 93.367025 -334.160346) (xy 93.421527 -334.160346) (xy 93.475475 -334.168102) (xy 93.52777 -334.183457)
			(xy 93.577347 -334.206099) (xy 93.623197 -334.235565) (xy 93.664388 -334.271256) (xy 93.700079 -334.312447)
			(xy 93.729545 -334.358297) (xy 93.752187 -334.407874) (xy 93.767542 -334.460169) (xy 93.775298 -334.514117)
			(xy 93.775784 -334.541368) (xy 93.775371 -334.567043) (xy 93.768491 -334.61793) (xy 93.75485 -334.667435)
			(xy 93.734695 -334.714664) (xy 93.70839 -334.758764) (xy 93.692726 -334.779112) (xy 93.683994 -334.790855)
			(xy 93.672944 -334.817938) (xy 93.670019 -334.847042) (xy 93.675461 -334.875781) (xy 93.688821 -334.901802)
			(xy 93.698568 -334.912716) (xy 93.718314 -334.934136) (xy 93.751715 -334.981866) (xy 93.777482 -335.034113)
			(xy 93.795016 -335.089668) (xy 93.803912 -335.147241) (xy 93.804486 -335.176368) (xy 101.201982 -335.176368)
			(xy 101.202409 -335.148996) (xy 101.210233 -335.094815) (xy 101.22573 -335.04231) (xy 101.248581 -334.992564)
			(xy 101.278316 -334.9466) (xy 101.295962 -334.92567) (xy 101.305233 -334.914367) (xy 101.317411 -334.887801)
			(xy 101.321579 -334.858876) (xy 101.317397 -334.829952) (xy 101.305206 -334.803392) (xy 101.295962 -334.792066)
			(xy 101.278334 -334.771125) (xy 101.248622 -334.725154) (xy 101.225784 -334.675409) (xy 101.21029 -334.62291)
			(xy 101.202458 -334.568736) (xy 101.201982 -334.541368) (xy 101.202468 -334.514117) (xy 101.210224 -334.460169)
			(xy 101.225579 -334.407874) (xy 101.248221 -334.358297) (xy 101.277687 -334.312447) (xy 101.313378 -334.271256)
			(xy 101.354569 -334.235565) (xy 101.400419 -334.206099) (xy 101.449996 -334.183457) (xy 101.502291 -334.168102)
			(xy 101.556239 -334.160346) (xy 101.610741 -334.160346) (xy 101.664689 -334.168102) (xy 101.716984 -334.183457)
			(xy 101.766561 -334.206099) (xy 101.812411 -334.235565) (xy 101.853602 -334.271256) (xy 101.889293 -334.312447)
			(xy 101.918759 -334.358297) (xy 101.941401 -334.407874) (xy 101.956756 -334.460169) (xy 101.964512 -334.514117)
			(xy 101.964998 -334.541368) (xy 101.964514 -334.568738) (xy 101.9567 -334.622916) (xy 101.941216 -334.675419)
			(xy 101.918378 -334.725166) (xy 101.888657 -334.771134) (xy 101.871018 -334.792066) (xy 101.861811 -334.803416)
			(xy 101.849628 -334.829965) (xy 101.845448 -334.858876) (xy 101.849614 -334.887788) (xy 101.861785 -334.914343)
			(xy 101.871018 -334.92567) (xy 101.888659 -334.9466) (xy 101.91837 -334.992574) (xy 101.941205 -335.042322)
			(xy 101.956696 -335.094823) (xy 101.964524 -335.148999) (xy 101.964998 -335.176368) (xy 109.362494 -335.176368)
			(xy 109.362943 -335.148997) (xy 109.370765 -335.094817) (xy 109.386258 -335.042314) (xy 109.409104 -334.992568)
			(xy 109.438831 -334.946601) (xy 109.456474 -334.92567) (xy 109.465744 -334.914367) (xy 109.477921 -334.887801)
			(xy 109.482088 -334.858876) (xy 109.477907 -334.829953) (xy 109.465717 -334.803393) (xy 109.456474 -334.792066)
			(xy 109.438848 -334.771123) (xy 109.409135 -334.725153) (xy 109.386297 -334.675408) (xy 109.370803 -334.62291)
			(xy 109.362971 -334.568736) (xy 109.362494 -334.541368) (xy 109.36298 -334.514117) (xy 109.370736 -334.460169)
			(xy 109.386091 -334.407874) (xy 109.408733 -334.358297) (xy 109.438199 -334.312447) (xy 109.47389 -334.271256)
			(xy 109.515081 -334.235565) (xy 109.560931 -334.206099) (xy 109.610508 -334.183457) (xy 109.662803 -334.168102)
			(xy 109.716751 -334.160346) (xy 109.771253 -334.160346) (xy 109.825201 -334.168102) (xy 109.877496 -334.183457)
			(xy 109.927073 -334.206099) (xy 109.972923 -334.235565) (xy 110.014114 -334.271256) (xy 110.049805 -334.312447)
			(xy 110.079271 -334.358297) (xy 110.101913 -334.407874) (xy 110.117268 -334.460169) (xy 110.125024 -334.514117)
			(xy 110.12551 -334.541368) (xy 110.125023 -334.568737) (xy 110.11721 -334.622916) (xy 110.101725 -334.675418)
			(xy 110.078888 -334.725165) (xy 110.049169 -334.771133) (xy 110.03153 -334.792066) (xy 110.022322 -334.803415)
			(xy 110.010137 -334.829965) (xy 110.005957 -334.858876) (xy 110.010123 -334.887789) (xy 110.022296 -334.914344)
			(xy 110.03153 -334.92567) (xy 110.049173 -334.946599) (xy 110.078883 -334.992573) (xy 110.101718 -335.042321)
			(xy 110.117208 -335.094823) (xy 110.125036 -335.148999) (xy 110.12551 -335.176368) (xy 117.523006 -335.176368)
			(xy 117.523452 -335.148997) (xy 117.531274 -335.094817) (xy 117.546768 -335.042314) (xy 117.569614 -334.992567)
			(xy 117.599343 -334.946601) (xy 117.616986 -334.92567) (xy 117.626255 -334.914366) (xy 117.63843 -334.8878)
			(xy 117.642597 -334.858876) (xy 117.638416 -334.829953) (xy 117.626228 -334.803393) (xy 117.616986 -334.792066)
			(xy 117.599362 -334.771122) (xy 117.569649 -334.725152) (xy 117.54681 -334.675408) (xy 117.531315 -334.62291)
			(xy 117.523483 -334.568736) (xy 117.523006 -334.541368) (xy 117.523492 -334.514117) (xy 117.531248 -334.460169)
			(xy 117.546603 -334.407874) (xy 117.569245 -334.358297) (xy 117.598711 -334.312447) (xy 117.634402 -334.271256)
			(xy 117.675593 -334.235565) (xy 117.721443 -334.206099) (xy 117.77102 -334.183457) (xy 117.823315 -334.168102)
			(xy 117.877263 -334.160346) (xy 117.931765 -334.160346) (xy 117.985713 -334.168102) (xy 118.038008 -334.183457)
			(xy 118.087585 -334.206099) (xy 118.133435 -334.235565) (xy 118.174626 -334.271256) (xy 118.210317 -334.312447)
			(xy 118.239783 -334.358297) (xy 118.262425 -334.407874) (xy 118.27778 -334.460169) (xy 118.285536 -334.514117)
			(xy 118.286022 -334.541368) (xy 118.285556 -334.568738) (xy 118.277741 -334.622918) (xy 118.262253 -334.675422)
			(xy 118.239411 -334.725169) (xy 118.209684 -334.771135) (xy 118.192042 -334.792066) (xy 118.182841 -334.803418)
			(xy 118.170666 -334.829968) (xy 118.16649 -334.858876) (xy 118.170653 -334.887785) (xy 118.182814 -334.914341)
			(xy 118.192042 -334.92567) (xy 118.209687 -334.946597) (xy 118.239397 -334.992572) (xy 118.262231 -335.042321)
			(xy 118.277721 -335.094822) (xy 118.285549 -335.148999) (xy 118.286022 -335.176368) (xy 118.285536 -335.203619)
			(xy 118.27778 -335.257567) (xy 118.262425 -335.309862) (xy 118.239783 -335.359439) (xy 118.210317 -335.405289)
			(xy 118.174626 -335.44648) (xy 118.133435 -335.482171) (xy 118.087585 -335.511637) (xy 118.038008 -335.534279)
			(xy 117.985713 -335.549634) (xy 117.931765 -335.55739) (xy 117.877263 -335.55739) (xy 117.823315 -335.549634)
			(xy 117.77102 -335.534279) (xy 117.721443 -335.511637) (xy 117.675593 -335.482171) (xy 117.634402 -335.44648)
			(xy 117.598711 -335.405289) (xy 117.569245 -335.359439) (xy 117.546603 -335.309862) (xy 117.531248 -335.257567)
			(xy 117.523492 -335.203619) (xy 117.523006 -335.176368) (xy 110.12551 -335.176368) (xy 110.125024 -335.203619)
			(xy 110.117268 -335.257567) (xy 110.101913 -335.309862) (xy 110.079271 -335.359439) (xy 110.049805 -335.405289)
			(xy 110.014114 -335.44648) (xy 109.972923 -335.482171) (xy 109.927073 -335.511637) (xy 109.877496 -335.534279)
			(xy 109.825201 -335.549634) (xy 109.771253 -335.55739) (xy 109.716751 -335.55739) (xy 109.662803 -335.549634)
			(xy 109.610508 -335.534279) (xy 109.560931 -335.511637) (xy 109.515081 -335.482171) (xy 109.47389 -335.44648)
			(xy 109.438199 -335.405289) (xy 109.408733 -335.359439) (xy 109.386091 -335.309862) (xy 109.370736 -335.257567)
			(xy 109.36298 -335.203619) (xy 109.362494 -335.176368) (xy 101.964998 -335.176368) (xy 101.964512 -335.203619)
			(xy 101.956756 -335.257567) (xy 101.941401 -335.309862) (xy 101.918759 -335.359439) (xy 101.889293 -335.405289)
			(xy 101.853602 -335.44648) (xy 101.812411 -335.482171) (xy 101.766561 -335.511637) (xy 101.716984 -335.534279)
			(xy 101.664689 -335.549634) (xy 101.610741 -335.55739) (xy 101.556239 -335.55739) (xy 101.502291 -335.549634)
			(xy 101.449996 -335.534279) (xy 101.400419 -335.511637) (xy 101.354569 -335.482171) (xy 101.313378 -335.44648)
			(xy 101.277687 -335.405289) (xy 101.248221 -335.359439) (xy 101.225579 -335.309862) (xy 101.210224 -335.257567)
			(xy 101.202468 -335.203619) (xy 101.201982 -335.176368) (xy 93.804486 -335.176368) (xy 93.804 -335.203619)
			(xy 93.796244 -335.257567) (xy 93.780889 -335.309862) (xy 93.758247 -335.359439) (xy 93.728781 -335.405289)
			(xy 93.69309 -335.44648) (xy 93.651899 -335.482171) (xy 93.606049 -335.511637) (xy 93.556472 -335.534279)
			(xy 93.504177 -335.549634) (xy 93.450229 -335.55739) (xy 93.395727 -335.55739) (xy 93.341779 -335.549634)
			(xy 93.289484 -335.534279) (xy 93.239907 -335.511637) (xy 93.194057 -335.482171) (xy 93.152866 -335.44648)
			(xy 93.117175 -335.405289) (xy 93.087709 -335.359439) (xy 93.065067 -335.309862) (xy 93.049712 -335.257567)
			(xy 93.041956 -335.203619) (xy 93.04147 -335.176368) (xy 93.041913 -335.150694) (xy 93.048788 -335.099809)
			(xy 93.062422 -335.050305) (xy 93.08257 -335.003075) (xy 93.108868 -334.958973) (xy 93.124528 -334.938624)
			(xy 93.133329 -334.926927) (xy 93.144376 -334.899827) (xy 93.147289 -334.870708) (xy 93.14183 -334.841957)
			(xy 93.128445 -334.815933) (xy 93.118686 -334.80502) (xy 93.098966 -334.783577) (xy 93.065559 -334.735854)
			(xy 93.039787 -334.683613) (xy 93.022246 -334.628063) (xy 93.013345 -334.570494) (xy 93.012768 -334.541368)
			(xy 76.372974 -334.541368) (xy 76.372974 -335.579) (xy 97.290117 -335.579) (xy 97.294285 -335.523384)
			(xy 97.306694 -335.469011) (xy 97.327068 -335.417094) (xy 97.354952 -335.368793) (xy 97.389723 -335.325188)
			(xy 97.430604 -335.287251) (xy 97.476682 -335.25583) (xy 97.526928 -335.231627) (xy 97.580221 -335.215183)
			(xy 97.635368 -335.206864) (xy 97.663254 -335.20634) (xy 97.690586 -335.206812) (xy 97.744666 -335.214781)
			(xy 97.797 -335.230569) (xy 97.846465 -335.253837) (xy 97.891997 -335.284084) (xy 97.932619 -335.320663)
			(xy 97.967459 -335.362786) (xy 97.982024 -335.385918) (xy 97.989942 -335.398145) (xy 98.011416 -335.417814)
			(xy 98.03757 -335.430618) (xy 98.066276 -335.435512) (xy 98.095196 -335.4321) (xy 98.10877 -335.426812)
			(xy 98.131987 -335.41734) (xy 98.180316 -335.403982) (xy 98.230003 -335.397247) (xy 98.255074 -335.39684)
			(xy 98.280144 -335.397251) (xy 98.329827 -335.404006) (xy 98.378161 -335.417343) (xy 98.401378 -335.426812)
			(xy 98.414951 -335.43207) (xy 98.443854 -335.435432) (xy 98.472533 -335.430519) (xy 98.498669 -335.417728)
			(xy 98.520144 -335.398094) (xy 98.528124 -335.385918) (xy 98.542693 -335.362787) (xy 98.577536 -335.320666)
			(xy 98.618159 -335.284087) (xy 98.66369 -335.253836) (xy 98.713152 -335.23056) (xy 98.765483 -335.21476)
			(xy 98.819562 -335.206774) (xy 98.874226 -335.206774) (xy 98.928305 -335.21476) (xy 98.980636 -335.23056)
			(xy 99.030098 -335.253836) (xy 99.075629 -335.284087) (xy 99.116252 -335.320666) (xy 99.151095 -335.362787)
			(xy 99.165664 -335.385918) (xy 99.173544 -335.398173) (xy 99.195028 -335.417842) (xy 99.221193 -335.430641)
			(xy 99.249908 -335.435529) (xy 99.278834 -335.432106) (xy 99.29241 -335.426812) (xy 99.315622 -335.417328)
			(xy 99.363954 -335.403974) (xy 99.413643 -335.397244) (xy 99.438714 -335.39684) (xy 99.465556 -335.397321)
			(xy 99.518683 -335.405026) (xy 99.570155 -335.420275) (xy 99.618906 -335.442752) (xy 99.663928 -335.471992)
			(xy 99.704287 -335.50739) (xy 99.73915 -335.548213) (xy 99.767794 -335.593616) (xy 99.789627 -335.642659)
			(xy 99.797362 -335.668366) (xy 99.802083 -335.682841) (xy 99.818592 -335.708398) (xy 99.841895 -335.72796)
			(xy 99.869926 -335.739792) (xy 99.900198 -335.742845) (xy 99.930026 -335.736849) (xy 99.943666 -335.730088)
			(xy 99.97181 -335.715451) (xy 100.031762 -335.694725) (xy 100.094321 -335.684228) (xy 100.126038 -335.683606)
			(xy 100.144057 -335.683825) (xy 100.179932 -335.687261) (xy 100.197666 -335.690464) (xy 100.212879 -335.692764)
			(xy 100.243427 -335.689245) (xy 100.271544 -335.676793) (xy 100.294679 -335.656537) (xy 100.310737 -335.630312)
			(xy 100.315014 -335.615534) (xy 100.3224 -335.588487) (xy 100.344032 -335.536761) (xy 100.372998 -335.488756)
			(xy 100.408676 -335.445505) (xy 100.450296 -335.407938) (xy 100.496965 -335.376865) (xy 100.547677 -335.352952)
			(xy 100.601342 -335.336716) (xy 100.656805 -335.328505) (xy 100.684838 -335.328006) (xy 100.712091 -335.328443)
			(xy 100.766041 -335.336205) (xy 100.818338 -335.351565) (xy 100.867916 -335.374212) (xy 100.913767 -335.403683)
			(xy 100.954957 -335.43938) (xy 100.990648 -335.480575) (xy 101.020113 -335.52643) (xy 101.042753 -335.576011)
			(xy 101.043631 -335.579) (xy 105.450617 -335.579) (xy 105.454785 -335.523383) (xy 105.467195 -335.469009)
			(xy 105.48757 -335.417091) (xy 105.515455 -335.36879) (xy 105.550227 -335.325183) (xy 105.591109 -335.287246)
			(xy 105.637189 -335.255826) (xy 105.687437 -335.231624) (xy 105.740731 -335.21518) (xy 105.79588 -335.206863)
			(xy 105.823766 -335.20634) (xy 105.851098 -335.206803) (xy 105.905179 -335.214774) (xy 105.957513 -335.230563)
			(xy 106.006978 -335.253832) (xy 106.05251 -335.284081) (xy 106.093132 -335.320661) (xy 106.127971 -335.362785)
			(xy 106.142536 -335.385918) (xy 106.150443 -335.398154) (xy 106.17192 -335.417823) (xy 106.198077 -335.430625)
			(xy 106.226786 -335.435517) (xy 106.255707 -335.432101) (xy 106.269282 -335.426812) (xy 106.292497 -335.417336)
			(xy 106.340827 -335.40398) (xy 106.390515 -335.397246) (xy 106.415586 -335.39684) (xy 106.440655 -335.397279)
			(xy 106.490337 -335.404022) (xy 106.538672 -335.417349) (xy 106.56189 -335.426812) (xy 106.575495 -335.431977)
			(xy 106.604381 -335.435359) (xy 106.63305 -335.430467) (xy 106.65918 -335.417697) (xy 106.680654 -335.398084)
			(xy 106.688636 -335.385918) (xy 106.703205 -335.362787) (xy 106.738048 -335.320666) (xy 106.778671 -335.284087)
			(xy 106.824202 -335.253836) (xy 106.873664 -335.23056) (xy 106.925995 -335.21476) (xy 106.980074 -335.206774)
			(xy 107.034738 -335.206774) (xy 107.088817 -335.21476) (xy 107.141148 -335.23056) (xy 107.19061 -335.253836)
			(xy 107.236141 -335.284087) (xy 107.276764 -335.320666) (xy 107.311607 -335.362787) (xy 107.326176 -335.385918)
			(xy 107.33414 -335.398113) (xy 107.355601 -335.417782) (xy 107.381743 -335.430589) (xy 107.410438 -335.435492)
			(xy 107.43935 -335.432092) (xy 107.452922 -335.426812) (xy 107.476132 -335.417324) (xy 107.524465 -335.403972)
			(xy 107.574154 -335.397244) (xy 107.599226 -335.39684) (xy 107.626068 -335.39731) (xy 107.679196 -335.405017)
			(xy 107.730668 -335.420268) (xy 107.779419 -335.442746) (xy 107.824441 -335.471988) (xy 107.8648 -335.507387)
			(xy 107.899663 -335.548211) (xy 107.928307 -335.593614) (xy 107.950139 -335.642658) (xy 107.957874 -335.668366)
			(xy 107.962579 -335.682847) (xy 107.979091 -335.708406) (xy 108.002398 -335.727968) (xy 108.030432 -335.7398)
			(xy 108.060707 -335.742851) (xy 108.090538 -335.736851) (xy 108.104178 -335.730088) (xy 108.13232 -335.715447)
			(xy 108.192273 -335.694722) (xy 108.254833 -335.684227) (xy 108.28655 -335.683606) (xy 108.304569 -335.683824)
			(xy 108.340444 -335.68726) (xy 108.358178 -335.690464) (xy 108.37339 -335.692776) (xy 108.403939 -335.689254)
			(xy 108.432056 -335.676799) (xy 108.455192 -335.65654) (xy 108.471249 -335.630313) (xy 108.475526 -335.615534)
			(xy 108.482901 -335.588483) (xy 108.504534 -335.536757) (xy 108.533502 -335.488751) (xy 108.56918 -335.4455)
			(xy 108.610802 -335.407934) (xy 108.657472 -335.37686) (xy 108.708186 -335.352949) (xy 108.761852 -335.336714)
			(xy 108.817316 -335.328504) (xy 108.84535 -335.328006) (xy 108.872602 -335.328502) (xy 108.926553 -335.336252)
			(xy 108.978851 -335.351603) (xy 109.028432 -335.37424) (xy 109.074286 -335.403705) (xy 109.115479 -335.439395)
			(xy 109.151174 -335.480585) (xy 109.180642 -335.526437) (xy 109.203285 -335.576015) (xy 109.204161 -335.579)
			(xy 113.611117 -335.579) (xy 113.615285 -335.523382) (xy 113.627696 -335.469007) (xy 113.648071 -335.417088)
			(xy 113.675957 -335.368786) (xy 113.710731 -335.325179) (xy 113.751615 -335.287242) (xy 113.797696 -335.255822)
			(xy 113.847945 -335.23162) (xy 113.901241 -335.215178) (xy 113.956391 -335.206863) (xy 113.984278 -335.20634)
			(xy 114.011611 -335.206794) (xy 114.065691 -335.214766) (xy 114.118026 -335.230557) (xy 114.167491 -335.253828)
			(xy 114.213023 -335.284078) (xy 114.253644 -335.320659) (xy 114.288483 -335.362784) (xy 114.303048 -335.385918)
			(xy 114.310943 -335.398162) (xy 114.332423 -335.417831) (xy 114.358584 -335.430632) (xy 114.387295 -335.435522)
			(xy 114.416219 -335.432103) (xy 114.429794 -335.426812) (xy 114.453008 -335.417333) (xy 114.501339 -335.403978)
			(xy 114.551027 -335.397245) (xy 114.576098 -335.39684) (xy 114.601167 -335.397276) (xy 114.65085 -335.40402)
			(xy 114.699184 -335.417348) (xy 114.722402 -335.426812) (xy 114.736003 -335.43199) (xy 114.764891 -335.435369)
			(xy 114.793561 -335.430474) (xy 114.819692 -335.417701) (xy 114.841166 -335.398085) (xy 114.849148 -335.385918)
			(xy 114.863717 -335.362787) (xy 114.89856 -335.320666) (xy 114.939183 -335.284087) (xy 114.984714 -335.253836)
			(xy 115.034176 -335.23056) (xy 115.086507 -335.21476) (xy 115.140586 -335.206774) (xy 115.19525 -335.206774)
			(xy 115.249329 -335.21476) (xy 115.30166 -335.23056) (xy 115.351122 -335.253836) (xy 115.396653 -335.284087)
			(xy 115.437276 -335.320666) (xy 115.472119 -335.362787) (xy 115.486688 -335.385918) (xy 115.49464 -335.398121)
			(xy 115.516105 -335.41779) (xy 115.54225 -335.430596) (xy 115.570948 -335.435497) (xy 115.599861 -335.432094)
			(xy 115.613434 -335.426812) (xy 115.636643 -335.41732) (xy 115.684976 -335.40397) (xy 115.734666 -335.397243)
			(xy 115.759738 -335.39684) (xy 115.78658 -335.3973) (xy 115.839709 -335.405008) (xy 115.891181 -335.420261)
			(xy 115.939933 -335.442741) (xy 115.984954 -335.471983) (xy 116.025313 -335.507383) (xy 116.060175 -335.548208)
			(xy 116.088819 -335.593613) (xy 116.110651 -335.642658) (xy 116.118386 -335.668366) (xy 116.123076 -335.682853)
			(xy 116.13959 -335.708413) (xy 116.1629 -335.727976) (xy 116.190938 -335.739807) (xy 116.221216 -335.742856)
			(xy 116.251049 -335.736853) (xy 116.26469 -335.730088) (xy 116.29283 -335.715442) (xy 116.352784 -335.69472)
			(xy 116.415345 -335.684226) (xy 116.447062 -335.683606) (xy 116.465081 -335.683822) (xy 116.500956 -335.687259)
			(xy 116.51869 -335.690464) (xy 116.5339 -335.692788) (xy 116.564451 -335.689263) (xy 116.592569 -335.676805)
			(xy 116.615704 -335.656543) (xy 116.631761 -335.630314) (xy 116.636038 -335.615534) (xy 116.643402 -335.58848)
			(xy 116.665036 -335.536753) (xy 116.694005 -335.488747) (xy 116.729685 -335.445495) (xy 116.771308 -335.407929)
			(xy 116.81798 -335.376856) (xy 116.868695 -335.352946) (xy 116.922362 -335.336711) (xy 116.977827 -335.328503)
			(xy 117.005862 -335.328006) (xy 117.033115 -335.328491) (xy 117.087065 -335.336243) (xy 117.139364 -335.351595)
			(xy 117.188945 -335.374234) (xy 117.234799 -335.403699) (xy 117.275992 -335.439391) (xy 117.311686 -335.480582)
			(xy 117.341155 -335.526434) (xy 117.363797 -335.576014) (xy 117.364674 -335.579) (xy 121.771617 -335.579)
			(xy 121.775785 -335.523381) (xy 121.788196 -335.469004) (xy 121.808573 -335.417085) (xy 121.83646 -335.368782)
			(xy 121.871235 -335.325175) (xy 121.91212 -335.287238) (xy 121.958203 -335.255818) (xy 122.008454 -335.231617)
			(xy 122.061751 -335.215176) (xy 122.116903 -335.206862) (xy 122.14479 -335.20634) (xy 122.172123 -335.206784)
			(xy 122.226204 -335.214758) (xy 122.278539 -335.230551) (xy 122.328004 -335.253823) (xy 122.373536 -335.284075)
			(xy 122.414157 -335.320657) (xy 122.448995 -335.362784) (xy 122.46356 -335.385918) (xy 122.471444 -335.39817)
			(xy 122.492927 -335.417839) (xy 122.519091 -335.430639) (xy 122.547805 -335.435527) (xy 122.57673 -335.432105)
			(xy 122.590306 -335.426812) (xy 122.613518 -335.417329) (xy 122.66185 -335.403975) (xy 122.711539 -335.397245)
			(xy 122.73661 -335.39684) (xy 122.761679 -335.397272) (xy 122.811362 -335.404018) (xy 122.859696 -335.417347)
			(xy 122.882914 -335.426812) (xy 122.89651 -335.432003) (xy 122.925401 -335.435379) (xy 122.954073 -335.430481)
			(xy 122.980204 -335.417706) (xy 123.001678 -335.398087) (xy 123.00966 -335.385918) (xy 123.024229 -335.362787)
			(xy 123.059072 -335.320666) (xy 123.099695 -335.284087) (xy 123.145226 -335.253836) (xy 123.194688 -335.23056)
			(xy 123.247019 -335.21476) (xy 123.301098 -335.206774) (xy 123.355762 -335.206774) (xy 123.409841 -335.21476)
			(xy 123.462172 -335.23056) (xy 123.511634 -335.253836) (xy 123.557165 -335.284087) (xy 123.597788 -335.320666)
			(xy 123.632631 -335.362787) (xy 123.6472 -335.385918) (xy 123.655141 -335.398129) (xy 123.676608 -335.417798)
			(xy 123.702757 -335.430603) (xy 123.731457 -335.435502) (xy 123.760373 -335.432096) (xy 123.773946 -335.426812)
			(xy 123.797154 -335.417317) (xy 123.845488 -335.403968) (xy 123.895178 -335.397242) (xy 123.92025 -335.39684)
			(xy 123.948136 -335.397416) (xy 124.003286 -335.405721) (xy 124.056582 -335.422155) (xy 124.106833 -335.446348)
			(xy 124.152917 -335.477762) (xy 124.193803 -335.515694) (xy 124.228579 -335.559296) (xy 124.256467 -335.607595)
			(xy 124.276844 -335.659511) (xy 124.289256 -335.713884) (xy 124.293424 -335.7695) (xy 124.289256 -335.825116)
			(xy 124.276844 -335.879489) (xy 124.256467 -335.931405) (xy 124.228579 -335.979704) (xy 124.193803 -336.023306)
			(xy 124.152917 -336.061238) (xy 124.106833 -336.092652) (xy 124.056582 -336.116845) (xy 124.003286 -336.133279)
			(xy 123.948136 -336.141584) (xy 123.92025 -336.142076) (xy 123.892918 -336.141593) (xy 123.838839 -336.133625)
			(xy 123.786506 -336.117839) (xy 123.737042 -336.094572) (xy 123.691509 -336.064327) (xy 123.650887 -336.02775)
			(xy 123.616046 -335.985629) (xy 123.60148 -335.962498) (xy 123.593554 -335.950276) (xy 123.572084 -335.930605)
			(xy 123.545931 -335.9178) (xy 123.517226 -335.912904) (xy 123.488308 -335.916316) (xy 123.474734 -335.921604)
			(xy 123.451517 -335.931076) (xy 123.403188 -335.944433) (xy 123.353501 -335.951169) (xy 123.32843 -335.951576)
			(xy 123.30336 -335.951163) (xy 123.253677 -335.944409) (xy 123.205343 -335.931072) (xy 123.182126 -335.921604)
			(xy 123.168553 -335.916343) (xy 123.13965 -335.912979) (xy 123.110969 -335.917892) (xy 123.084834 -335.930685)
			(xy 123.063359 -335.950321) (xy 123.05538 -335.962498) (xy 123.040811 -335.985629) (xy 123.005968 -336.02775)
			(xy 122.965345 -336.064329) (xy 122.919814 -336.09458) (xy 122.870352 -336.117856) (xy 122.818021 -336.133656)
			(xy 122.763942 -336.141642) (xy 122.709278 -336.141642) (xy 122.655199 -336.133656) (xy 122.602868 -336.117856)
			(xy 122.553406 -336.09458) (xy 122.507875 -336.064329) (xy 122.467252 -336.02775) (xy 122.432409 -335.985629)
			(xy 122.41784 -335.962498) (xy 122.409952 -335.950248) (xy 122.388471 -335.930577) (xy 122.362308 -335.917776)
			(xy 122.333594 -335.912888) (xy 122.304669 -335.91631) (xy 122.291094 -335.921604) (xy 122.267882 -335.931088)
			(xy 122.21955 -335.944441) (xy 122.169861 -335.951171) (xy 122.14479 -335.951576) (xy 122.116903 -335.951138)
			(xy 122.061751 -335.942824) (xy 122.008454 -335.926383) (xy 121.958203 -335.902182) (xy 121.91212 -335.870762)
			(xy 121.871235 -335.832825) (xy 121.83646 -335.789218) (xy 121.808573 -335.740915) (xy 121.788196 -335.688996)
			(xy 121.775785 -335.634619) (xy 121.771617 -335.579) (xy 117.364674 -335.579) (xy 117.379152 -335.628311)
			(xy 117.386908 -335.682261) (xy 117.38737 -335.709514) (xy 117.386856 -335.737087) (xy 117.378914 -335.791658)
			(xy 117.3632 -335.844517) (xy 117.340039 -335.894564) (xy 117.309915 -335.940755) (xy 117.273454 -335.982127)
			(xy 117.25275 -336.000344) (xy 117.241835 -336.010226) (xy 117.225755 -336.034879) (xy 117.217369 -336.063092)
			(xy 117.217371 -336.092526) (xy 117.225763 -336.120737) (xy 117.241847 -336.145388) (xy 117.25275 -336.155284)
			(xy 117.273472 -336.173483) (xy 117.30994 -336.214855) (xy 117.34007 -336.261046) (xy 117.363235 -336.311095)
			(xy 117.378951 -336.363959) (xy 117.386892 -336.418534) (xy 117.38689 -336.473684) (xy 117.378947 -336.528259)
			(xy 117.363229 -336.581121) (xy 117.340061 -336.631169) (xy 117.331207 -336.644742) (xy 118.31396 -336.644742)
			(xy 118.318031 -336.58912) (xy 118.330157 -336.534683) (xy 118.35008 -336.482592) (xy 118.377376 -336.433957)
			(xy 118.411462 -336.389814) (xy 118.451611 -336.351105) (xy 118.496969 -336.318654) (xy 118.546569 -336.293153)
			(xy 118.599353 -336.275146) (xy 118.654196 -336.265016) (xy 118.70993 -336.262979) (xy 118.765367 -336.269079)
			(xy 118.819324 -336.283185) (xy 118.870653 -336.304997) (xy 118.918259 -336.334051) (xy 118.961127 -336.369726)
			(xy 118.998344 -336.411263) (xy 119.029117 -336.457776) (xy 119.052789 -336.508273) (xy 119.068857 -336.56168)
			(xy 119.076977 -336.616856) (xy 119.077486 -336.644742) (xy 119.076977 -336.672628) (xy 119.068857 -336.727804)
			(xy 119.052789 -336.781211) (xy 119.029117 -336.831708) (xy 118.998344 -336.878221) (xy 118.961127 -336.919758)
			(xy 118.918259 -336.955433) (xy 118.870653 -336.984487) (xy 118.819324 -337.006299) (xy 118.765367 -337.020405)
			(xy 118.70993 -337.026505) (xy 118.654196 -337.024468) (xy 118.599353 -337.014338) (xy 118.546569 -336.996331)
			(xy 118.496969 -336.97083) (xy 118.451611 -336.938379) (xy 118.411462 -336.89967) (xy 118.377376 -336.855527)
			(xy 118.35008 -336.806892) (xy 118.330157 -336.754801) (xy 118.318031 -336.700364) (xy 118.31396 -336.644742)
			(xy 117.331207 -336.644742) (xy 117.309929 -336.67736) (xy 117.273459 -336.71873) (xy 117.25275 -336.736944)
			(xy 117.241835 -336.746826) (xy 117.225755 -336.771479) (xy 117.217369 -336.799692) (xy 117.217371 -336.829126)
			(xy 117.225763 -336.857337) (xy 117.241847 -336.881988) (xy 117.25275 -336.891884) (xy 117.273467 -336.910089)
			(xy 117.309934 -336.95146) (xy 117.340065 -336.997652) (xy 117.363229 -337.047701) (xy 117.378945 -337.100564)
			(xy 117.386884 -337.155139) (xy 117.38737 -337.182714) (xy 117.386958 -337.209969) (xy 117.379845 -337.259422)
			(xy 117.522496 -337.259422) (xy 117.526567 -337.2038) (xy 117.538693 -337.149363) (xy 117.558616 -337.097272)
			(xy 117.585912 -337.048637) (xy 117.619998 -337.004494) (xy 117.660147 -336.965785) (xy 117.705505 -336.933334)
			(xy 117.755105 -336.907833) (xy 117.807889 -336.889826) (xy 117.862732 -336.879696) (xy 117.918466 -336.877659)
			(xy 117.973903 -336.883759) (xy 118.02786 -336.897865) (xy 118.079189 -336.919677) (xy 118.126795 -336.948731)
			(xy 118.169663 -336.984406) (xy 118.20688 -337.025943) (xy 118.237653 -337.072456) (xy 118.261325 -337.122953)
			(xy 118.277393 -337.17636) (xy 118.285513 -337.231536) (xy 118.286022 -337.259422) (xy 118.285513 -337.287308)
			(xy 118.277393 -337.342484) (xy 118.261325 -337.395891) (xy 118.237653 -337.446388) (xy 118.20688 -337.492901)
			(xy 118.169663 -337.534438) (xy 118.126795 -337.570113) (xy 118.079189 -337.599167) (xy 118.02786 -337.620979)
			(xy 117.973903 -337.635085) (xy 117.918466 -337.641185) (xy 117.862732 -337.639148) (xy 117.807889 -337.629018)
			(xy 117.755105 -337.611011) (xy 117.705505 -337.58551) (xy 117.660147 -337.553059) (xy 117.619998 -337.51435)
			(xy 117.585912 -337.470207) (xy 117.558616 -337.421572) (xy 117.538693 -337.369481) (xy 117.526567 -337.315044)
			(xy 117.522496 -337.259422) (xy 117.379845 -337.259422) (xy 117.379198 -337.263924) (xy 117.363838 -337.316225)
			(xy 117.341192 -337.365808) (xy 117.311718 -337.411663) (xy 117.276019 -337.452856) (xy 117.234821 -337.48855)
			(xy 117.188962 -337.518016) (xy 117.139376 -337.540657) (xy 117.087073 -337.556009) (xy 117.033117 -337.563762)
			(xy 117.005862 -337.564222) (xy 116.978006 -337.563717) (xy 116.922891 -337.555588) (xy 116.869541 -337.539539)
			(xy 116.819089 -337.515909) (xy 116.772605 -337.4852) (xy 116.731076 -337.448063) (xy 116.695383 -337.405287)
			(xy 116.666284 -337.357779) (xy 116.644395 -337.306547) (xy 116.6368 -337.279742) (xy 116.632472 -337.265645)
			(xy 116.617096 -337.240501) (xy 116.595191 -337.220783) (xy 116.568575 -337.208127) (xy 116.539455 -337.203582)
			(xy 116.524786 -337.205066) (xy 116.511769 -337.206735) (xy 116.485585 -337.208515) (xy 116.472462 -337.208622)
			(xy 116.458313 -337.208532) (xy 116.43009 -337.206495) (xy 116.416074 -337.204558) (xy 116.402721 -337.203043)
			(xy 116.376039 -337.206134) (xy 116.351092 -337.216091) (xy 116.329615 -337.232222) (xy 116.313101 -337.253406)
			(xy 116.302698 -337.27817) (xy 116.300504 -337.291426) (xy 116.296414 -337.318579) (xy 116.281442 -337.37141)
			(xy 116.259052 -337.42155) (xy 116.229705 -337.467961) (xy 116.194009 -337.509686) (xy 116.152699 -337.545863)
			(xy 116.106629 -337.575744) (xy 116.056752 -337.598712) (xy 116.004098 -337.614293) (xy 115.949754 -337.622165)
			(xy 115.922298 -337.622642) (xy 115.895048 -337.622124) (xy 115.841103 -337.614368) (xy 115.788811 -337.599015)
			(xy 115.739236 -337.576376) (xy 115.693388 -337.546912) (xy 115.652198 -337.511224) (xy 115.616507 -337.470038)
			(xy 115.58704 -337.424192) (xy 115.564397 -337.374619) (xy 115.549039 -337.322328) (xy 115.541278 -337.268384)
			(xy 115.54079 -337.241134) (xy 115.541283 -337.21356) (xy 115.54923 -337.158989) (xy 115.56495 -337.10613)
			(xy 115.588115 -337.056084) (xy 115.618243 -337.009893) (xy 115.654705 -336.968521) (xy 115.67541 -336.950304)
			(xy 115.686272 -336.94037) (xy 115.702343 -336.915729) (xy 115.71073 -336.887531) (xy 115.710736 -336.858113)
			(xy 115.702362 -336.829911) (xy 115.686301 -336.805263) (xy 115.67541 -336.795364) (xy 115.65468 -336.777173)
			(xy 115.618211 -336.7358) (xy 115.588081 -336.689606) (xy 115.564918 -336.639554) (xy 115.549206 -336.586688)
			(xy 115.541272 -336.53211) (xy 115.54079 -336.504534) (xy 115.541227 -336.478032) (xy 115.548576 -336.425541)
			(xy 115.563125 -336.374573) (xy 115.584592 -336.326111) (xy 115.612563 -336.281089) (xy 115.629182 -336.26044)
			(xy 115.638623 -336.248295) (xy 115.650406 -336.219894) (xy 115.653226 -336.189276) (xy 115.646829 -336.159201)
			(xy 115.631793 -336.13238) (xy 115.609472 -336.111232) (xy 115.595908 -336.103976) (xy 115.572209 -336.091892)
			(xy 115.528229 -336.061964) (xy 115.48895 -336.026088) (xy 115.45517 -335.984993) (xy 115.440968 -335.962498)
			(xy 115.433053 -335.950267) (xy 115.41158 -335.930597) (xy 115.385424 -335.917793) (xy 115.356717 -335.912899)
			(xy 115.327796 -335.916314) (xy 115.314222 -335.921604) (xy 115.291007 -335.931079) (xy 115.242677 -335.944436)
			(xy 115.192989 -335.95117) (xy 115.167918 -335.951576) (xy 115.142849 -335.951134) (xy 115.093167 -335.944392)
			(xy 115.044832 -335.931067) (xy 115.021614 -335.921604) (xy 115.008009 -335.916436) (xy 114.979123 -335.913053)
			(xy 114.950453 -335.917945) (xy 114.924323 -335.930716) (xy 114.902849 -335.950331) (xy 114.894868 -335.962498)
			(xy 114.880299 -335.985629) (xy 114.845456 -336.02775) (xy 114.804833 -336.064329) (xy 114.759302 -336.09458)
			(xy 114.70984 -336.117856) (xy 114.657509 -336.133656) (xy 114.60343 -336.141642) (xy 114.548766 -336.141642)
			(xy 114.494687 -336.133656) (xy 114.442356 -336.117856) (xy 114.392894 -336.09458) (xy 114.347363 -336.064329)
			(xy 114.30674 -336.02775) (xy 114.271897 -335.985629) (xy 114.257328 -335.962498) (xy 114.249451 -335.95024)
			(xy 114.227967 -335.930569) (xy 114.201801 -335.917769) (xy 114.173085 -335.912883) (xy 114.144158 -335.916308)
			(xy 114.130582 -335.921604) (xy 114.107371 -335.931092) (xy 114.059039 -335.944443) (xy 114.00935 -335.951172)
			(xy 113.984278 -335.951576) (xy 113.956391 -335.951137) (xy 113.901241 -335.942822) (xy 113.847945 -335.92638)
			(xy 113.797696 -335.902178) (xy 113.751615 -335.870758) (xy 113.710731 -335.832821) (xy 113.675957 -335.789214)
			(xy 113.648071 -335.740912) (xy 113.627696 -335.688993) (xy 113.615285 -335.634618) (xy 113.611117 -335.579)
			(xy 109.204161 -335.579) (xy 109.21864 -335.628312) (xy 109.226396 -335.682262) (xy 109.226858 -335.709514)
			(xy 109.226348 -335.737087) (xy 109.218406 -335.791659) (xy 109.202691 -335.844518) (xy 109.17953 -335.894565)
			(xy 109.149404 -335.940755) (xy 109.112943 -335.982128) (xy 109.092238 -336.000344) (xy 109.081324 -336.010227)
			(xy 109.065246 -336.03488) (xy 109.056861 -336.063093) (xy 109.056864 -336.092525) (xy 109.065254 -336.120737)
			(xy 109.081336 -336.145387) (xy 109.092238 -336.155284) (xy 109.11296 -336.173483) (xy 109.149429 -336.214854)
			(xy 109.179561 -336.261046) (xy 109.202726 -336.311095) (xy 109.218443 -336.363958) (xy 109.226384 -336.418534)
			(xy 109.226383 -336.473684) (xy 109.218439 -336.52826) (xy 109.20272 -336.581122) (xy 109.179552 -336.63117)
			(xy 109.170698 -336.644742) (xy 110.153448 -336.644742) (xy 110.157519 -336.58912) (xy 110.169645 -336.534683)
			(xy 110.189568 -336.482592) (xy 110.216864 -336.433957) (xy 110.25095 -336.389814) (xy 110.291099 -336.351105)
			(xy 110.336457 -336.318654) (xy 110.386057 -336.293153) (xy 110.438841 -336.275146) (xy 110.493684 -336.265016)
			(xy 110.549418 -336.262979) (xy 110.604855 -336.269079) (xy 110.658812 -336.283185) (xy 110.710141 -336.304997)
			(xy 110.757747 -336.334051) (xy 110.800615 -336.369726) (xy 110.837832 -336.411263) (xy 110.868605 -336.457776)
			(xy 110.892277 -336.508273) (xy 110.908345 -336.56168) (xy 110.916465 -336.616856) (xy 110.916974 -336.644742)
			(xy 110.916465 -336.672628) (xy 110.908345 -336.727804) (xy 110.892277 -336.781211) (xy 110.868605 -336.831708)
			(xy 110.837832 -336.878221) (xy 110.800615 -336.919758) (xy 110.757747 -336.955433) (xy 110.710141 -336.984487)
			(xy 110.658812 -337.006299) (xy 110.604855 -337.020405) (xy 110.549418 -337.026505) (xy 110.493684 -337.024468)
			(xy 110.438841 -337.014338) (xy 110.386057 -336.996331) (xy 110.336457 -336.97083) (xy 110.291099 -336.938379)
			(xy 110.25095 -336.89967) (xy 110.216864 -336.855527) (xy 110.189568 -336.806892) (xy 110.169645 -336.754801)
			(xy 110.157519 -336.700364) (xy 110.153448 -336.644742) (xy 109.170698 -336.644742) (xy 109.149418 -336.677361)
			(xy 109.112947 -336.71873) (xy 109.092238 -336.736944) (xy 109.081324 -336.746827) (xy 109.065246 -336.77148)
			(xy 109.056861 -336.799693) (xy 109.056864 -336.829125) (xy 109.065254 -336.857337) (xy 109.081336 -336.881987)
			(xy 109.092238 -336.891884) (xy 109.112952 -336.910092) (xy 109.149421 -336.951462) (xy 109.179551 -336.997653)
			(xy 109.202716 -337.047702) (xy 109.218433 -337.100564) (xy 109.226372 -337.155139) (xy 109.226858 -337.182714)
			(xy 109.226458 -337.20997) (xy 109.218698 -337.263925) (xy 109.216141 -337.27263) (xy 109.505494 -337.27263)
			(xy 109.509565 -337.217008) (xy 109.521691 -337.162571) (xy 109.541614 -337.11048) (xy 109.56891 -337.061845)
			(xy 109.602996 -337.017702) (xy 109.643145 -336.978993) (xy 109.688503 -336.946542) (xy 109.738103 -336.921041)
			(xy 109.790887 -336.903034) (xy 109.84573 -336.892904) (xy 109.901464 -336.890867) (xy 109.956901 -336.896967)
			(xy 110.010858 -336.911073) (xy 110.062187 -336.932885) (xy 110.109793 -336.961939) (xy 110.152661 -336.997614)
			(xy 110.189878 -337.039151) (xy 110.220651 -337.085664) (xy 110.244323 -337.136161) (xy 110.260391 -337.189568)
			(xy 110.268511 -337.244744) (xy 110.26902 -337.27263) (xy 110.268511 -337.300516) (xy 110.260391 -337.355692)
			(xy 110.244323 -337.409099) (xy 110.220651 -337.459596) (xy 110.189878 -337.506109) (xy 110.152661 -337.547646)
			(xy 110.109793 -337.583321) (xy 110.062187 -337.612375) (xy 110.010858 -337.634187) (xy 109.956901 -337.648293)
			(xy 109.901464 -337.654393) (xy 109.84573 -337.652356) (xy 109.790887 -337.642226) (xy 109.738103 -337.624219)
			(xy 109.688503 -337.598718) (xy 109.643145 -337.566267) (xy 109.602996 -337.527558) (xy 109.56891 -337.483415)
			(xy 109.541614 -337.43478) (xy 109.521691 -337.382689) (xy 109.509565 -337.328252) (xy 109.505494 -337.27263)
			(xy 109.216141 -337.27263) (xy 109.203337 -337.316227) (xy 109.18069 -337.365811) (xy 109.151216 -337.411667)
			(xy 109.115515 -337.45286) (xy 109.074315 -337.488554) (xy 109.028455 -337.51802) (xy 108.978867 -337.54066)
			(xy 108.926563 -337.556011) (xy 108.872606 -337.563763) (xy 108.84535 -337.564222) (xy 108.817494 -337.563728)
			(xy 108.762378 -337.555598) (xy 108.709028 -337.539546) (xy 108.658576 -337.515915) (xy 108.612092 -337.485204)
			(xy 108.570563 -337.448066) (xy 108.534871 -337.405289) (xy 108.505771 -337.35778) (xy 108.483883 -337.306548)
			(xy 108.476288 -337.279742) (xy 108.471972 -337.26564) (xy 108.456594 -337.240496) (xy 108.434686 -337.220778)
			(xy 108.408067 -337.208123) (xy 108.378944 -337.20358) (xy 108.364274 -337.205066) (xy 108.351258 -337.206736)
			(xy 108.325073 -337.208515) (xy 108.31195 -337.208622) (xy 108.297801 -337.208523) (xy 108.269578 -337.206492)
			(xy 108.255562 -337.204558) (xy 108.24221 -337.203031) (xy 108.215527 -337.206124) (xy 108.19058 -337.216084)
			(xy 108.169103 -337.232218) (xy 108.152589 -337.253404) (xy 108.142186 -337.278169) (xy 108.139992 -337.291426)
			(xy 108.135913 -337.318581) (xy 108.120941 -337.371413) (xy 108.09855 -337.421553) (xy 108.069202 -337.467965)
			(xy 108.033504 -337.509691) (xy 107.992193 -337.545867) (xy 107.946122 -337.575748) (xy 107.896244 -337.598716)
			(xy 107.843588 -337.614295) (xy 107.789242 -337.622166) (xy 107.761786 -337.622642) (xy 107.734536 -337.622135)
			(xy 107.680591 -337.614378) (xy 107.628298 -337.599023) (xy 107.578723 -337.576382) (xy 107.532875 -337.546918)
			(xy 107.491686 -337.511229) (xy 107.455994 -337.470041) (xy 107.426527 -337.424194) (xy 107.403884 -337.37462)
			(xy 107.388526 -337.322329) (xy 107.380766 -337.268384) (xy 107.380278 -337.241134) (xy 107.380775 -337.213561)
			(xy 107.388722 -337.15899) (xy 107.404441 -337.106131) (xy 107.427606 -337.056085) (xy 107.457732 -337.009894)
			(xy 107.494194 -336.968521) (xy 107.514898 -336.950304) (xy 107.525761 -336.940371) (xy 107.541834 -336.91573)
			(xy 107.550222 -336.887532) (xy 107.550228 -336.858112) (xy 107.541853 -336.82991) (xy 107.52579 -336.805262)
			(xy 107.514898 -336.795364) (xy 107.494166 -336.777176) (xy 107.457697 -336.735802) (xy 107.427568 -336.689607)
			(xy 107.404406 -336.639555) (xy 107.388694 -336.586688) (xy 107.38076 -336.53211) (xy 107.380278 -336.504534)
			(xy 107.380717 -336.478032) (xy 107.388067 -336.425541) (xy 107.402615 -336.374573) (xy 107.424081 -336.326111)
			(xy 107.452052 -336.281089) (xy 107.46867 -336.26044) (xy 107.478115 -336.248298) (xy 107.489899 -336.219896)
			(xy 107.49272 -336.189276) (xy 107.486322 -336.1592) (xy 107.471284 -336.132379) (xy 107.448961 -336.111232)
			(xy 107.435396 -336.103976) (xy 107.411695 -336.091896) (xy 107.367716 -336.061966) (xy 107.328437 -336.026089)
			(xy 107.294658 -335.984993) (xy 107.280456 -335.962498) (xy 107.272553 -335.950259) (xy 107.251076 -335.930588)
			(xy 107.224917 -335.917786) (xy 107.196207 -335.912894) (xy 107.167285 -335.916313) (xy 107.15371 -335.921604)
			(xy 107.130496 -335.931083) (xy 107.082165 -335.944438) (xy 107.032477 -335.95117) (xy 107.007406 -335.951576)
			(xy 106.982337 -335.951138) (xy 106.932655 -335.944394) (xy 106.88432 -335.931067) (xy 106.861102 -335.921604)
			(xy 106.847502 -335.916424) (xy 106.818613 -335.913043) (xy 106.789942 -335.917938) (xy 106.763811 -335.930712)
			(xy 106.742337 -335.95033) (xy 106.734356 -335.962498) (xy 106.719787 -335.985629) (xy 106.684944 -336.02775)
			(xy 106.644321 -336.064329) (xy 106.59879 -336.09458) (xy 106.549328 -336.117856) (xy 106.496997 -336.133656)
			(xy 106.442918 -336.141642) (xy 106.388254 -336.141642) (xy 106.334175 -336.133656) (xy 106.281844 -336.117856)
			(xy 106.232382 -336.09458) (xy 106.186851 -336.064329) (xy 106.146228 -336.02775) (xy 106.111385 -335.985629)
			(xy 106.096816 -335.962498) (xy 106.088856 -335.9503) (xy 106.067395 -335.930629) (xy 106.041251 -335.917821)
			(xy 106.012555 -335.912919) (xy 105.983642 -335.916322) (xy 105.97007 -335.921604) (xy 105.946861 -335.931095)
			(xy 105.898528 -335.944446) (xy 105.848838 -335.951173) (xy 105.823766 -335.951576) (xy 105.79588 -335.951137)
			(xy 105.740731 -335.94282) (xy 105.687437 -335.926376) (xy 105.637189 -335.902174) (xy 105.591109 -335.870754)
			(xy 105.550227 -335.832817) (xy 105.515455 -335.78921) (xy 105.48757 -335.740909) (xy 105.467195 -335.688991)
			(xy 105.454785 -335.634617) (xy 105.450617 -335.579) (xy 101.043631 -335.579) (xy 101.058107 -335.62831)
			(xy 101.065861 -335.682261) (xy 101.066346 -335.709514) (xy 101.06584 -335.737087) (xy 101.057898 -335.791659)
			(xy 101.042183 -335.844519) (xy 101.01902 -335.894566) (xy 100.988894 -335.940756) (xy 100.952431 -335.982128)
			(xy 100.931726 -336.000344) (xy 100.920813 -336.010227) (xy 100.904737 -336.034881) (xy 100.896353 -336.063093)
			(xy 100.896356 -336.092525) (xy 100.904745 -336.120736) (xy 100.920825 -336.145386) (xy 100.931726 -336.155284)
			(xy 100.952444 -336.173485) (xy 100.988906 -336.214859) (xy 101.01903 -336.261052) (xy 101.04219 -336.311101)
			(xy 101.057903 -336.363962) (xy 101.065842 -336.418535) (xy 101.06584 -336.473683) (xy 101.057899 -336.528256)
			(xy 101.042184 -336.581116) (xy 101.019021 -336.631164) (xy 101.010165 -336.644742) (xy 101.992936 -336.644742)
			(xy 101.997007 -336.58912) (xy 102.009133 -336.534683) (xy 102.029056 -336.482592) (xy 102.056352 -336.433957)
			(xy 102.090438 -336.389814) (xy 102.130587 -336.351105) (xy 102.175945 -336.318654) (xy 102.225545 -336.293153)
			(xy 102.278329 -336.275146) (xy 102.333172 -336.265016) (xy 102.388906 -336.262979) (xy 102.444343 -336.269079)
			(xy 102.4983 -336.283185) (xy 102.549629 -336.304997) (xy 102.597235 -336.334051) (xy 102.640103 -336.369726)
			(xy 102.67732 -336.411263) (xy 102.708093 -336.457776) (xy 102.731765 -336.508273) (xy 102.747833 -336.56168)
			(xy 102.755953 -336.616856) (xy 102.756462 -336.644742) (xy 102.755953 -336.672628) (xy 102.747833 -336.727804)
			(xy 102.731765 -336.781211) (xy 102.708093 -336.831708) (xy 102.67732 -336.878221) (xy 102.640103 -336.919758)
			(xy 102.597235 -336.955433) (xy 102.549629 -336.984487) (xy 102.4983 -337.006299) (xy 102.444343 -337.020405)
			(xy 102.388906 -337.026505) (xy 102.333172 -337.024468) (xy 102.278329 -337.014338) (xy 102.225545 -336.996331)
			(xy 102.175945 -336.97083) (xy 102.130587 -336.938379) (xy 102.090438 -336.89967) (xy 102.056352 -336.855527)
			(xy 102.029056 -336.806892) (xy 102.009133 -336.754801) (xy 101.997007 -336.700364) (xy 101.992936 -336.644742)
			(xy 101.010165 -336.644742) (xy 100.988895 -336.677355) (xy 100.952431 -336.718728) (xy 100.931726 -336.736944)
			(xy 100.920813 -336.746827) (xy 100.904737 -336.771481) (xy 100.896353 -336.799693) (xy 100.896356 -336.829125)
			(xy 100.904745 -336.857336) (xy 100.920825 -336.881986) (xy 100.931726 -336.891884) (xy 100.952438 -336.910094)
			(xy 100.988907 -336.951464) (xy 101.019038 -336.997654) (xy 101.042204 -337.047702) (xy 101.05792 -337.100565)
			(xy 101.06586 -337.155139) (xy 101.066346 -337.182714) (xy 101.065835 -337.209964) (xy 101.063837 -337.223862)
			(xy 101.236524 -337.223862) (xy 101.240595 -337.16824) (xy 101.252721 -337.113803) (xy 101.272644 -337.061712)
			(xy 101.29994 -337.013077) (xy 101.334026 -336.968934) (xy 101.374175 -336.930225) (xy 101.419533 -336.897774)
			(xy 101.469133 -336.872273) (xy 101.521917 -336.854266) (xy 101.57676 -336.844136) (xy 101.632494 -336.842099)
			(xy 101.687931 -336.848199) (xy 101.741888 -336.862305) (xy 101.793217 -336.884117) (xy 101.840823 -336.913171)
			(xy 101.883691 -336.948846) (xy 101.920908 -336.990383) (xy 101.951681 -337.036896) (xy 101.975353 -337.087393)
			(xy 101.991421 -337.1408) (xy 101.999541 -337.195976) (xy 102.00005 -337.223862) (xy 101.999541 -337.251748)
			(xy 101.991421 -337.306924) (xy 101.975353 -337.360331) (xy 101.951681 -337.410828) (xy 101.920908 -337.457341)
			(xy 101.883691 -337.498878) (xy 101.840823 -337.534553) (xy 101.793217 -337.563607) (xy 101.741888 -337.585419)
			(xy 101.687931 -337.599525) (xy 101.632494 -337.605625) (xy 101.57676 -337.603588) (xy 101.521917 -337.593458)
			(xy 101.469133 -337.575451) (xy 101.419533 -337.54995) (xy 101.374175 -337.517499) (xy 101.334026 -337.47879)
			(xy 101.29994 -337.434647) (xy 101.272644 -337.386012) (xy 101.252721 -337.333921) (xy 101.240595 -337.279484)
			(xy 101.236524 -337.223862) (xy 101.063837 -337.223862) (xy 101.058078 -337.263909) (xy 101.042723 -337.316201)
			(xy 101.020083 -337.365775) (xy 100.990619 -337.411624) (xy 100.95493 -337.452813) (xy 100.913743 -337.488504)
			(xy 100.867897 -337.517971) (xy 100.818323 -337.540615) (xy 100.766032 -337.555973) (xy 100.712088 -337.563734)
			(xy 100.684838 -337.564222) (xy 100.656985 -337.563648) (xy 100.601872 -337.555531) (xy 100.548524 -337.539491)
			(xy 100.498072 -337.515871) (xy 100.451588 -337.48517) (xy 100.410058 -337.448041) (xy 100.374364 -337.405272)
			(xy 100.345263 -337.357771) (xy 100.323372 -337.306545) (xy 100.315776 -337.279742) (xy 100.311472 -337.265636)
			(xy 100.296091 -337.24049) (xy 100.274181 -337.220772) (xy 100.247558 -337.208119) (xy 100.218433 -337.203579)
			(xy 100.203762 -337.205066) (xy 100.190746 -337.206737) (xy 100.164561 -337.208516) (xy 100.151438 -337.208622)
			(xy 100.137289 -337.208524) (xy 100.109066 -337.206493) (xy 100.09505 -337.204558) (xy 100.081699 -337.203018)
			(xy 100.055015 -337.206115) (xy 100.030067 -337.216077) (xy 100.00859 -337.232213) (xy 99.992076 -337.253401)
			(xy 99.981673 -337.278168) (xy 99.97948 -337.291426) (xy 99.975413 -337.318584) (xy 99.96044 -337.371416)
			(xy 99.938048 -337.421557) (xy 99.908699 -337.46797) (xy 99.873 -337.509695) (xy 99.831687 -337.545872)
			(xy 99.785615 -337.575752) (xy 99.735735 -337.598719) (xy 99.683078 -337.614298) (xy 99.628731 -337.622166)
			(xy 99.601274 -337.622642) (xy 99.574024 -337.622146) (xy 99.520078 -337.614387) (xy 99.467786 -337.599031)
			(xy 99.418211 -337.576389) (xy 99.372362 -337.546923) (xy 99.331173 -337.511233) (xy 99.295482 -337.470045)
			(xy 99.266015 -337.424197) (xy 99.243372 -337.374622) (xy 99.228014 -337.32233) (xy 99.220254 -337.268384)
			(xy 99.219766 -337.241134) (xy 99.220232 -337.213559) (xy 99.228181 -337.158985) (xy 99.243905 -337.106124)
			(xy 99.267075 -337.056078) (xy 99.297208 -337.009889) (xy 99.333678 -336.968519) (xy 99.354386 -336.950304)
			(xy 99.36525 -336.940371) (xy 99.381326 -336.915731) (xy 99.389714 -336.887532) (xy 99.389721 -336.858112)
			(xy 99.381344 -336.829909) (xy 99.365279 -336.805262) (xy 99.354386 -336.795364) (xy 99.333651 -336.777178)
			(xy 99.297184 -336.735804) (xy 99.267055 -336.689609) (xy 99.243893 -336.639556) (xy 99.228182 -336.586689)
			(xy 99.220248 -336.53211) (xy 99.219766 -336.504534) (xy 99.220208 -336.478033) (xy 99.227557 -336.425541)
			(xy 99.242105 -336.374574) (xy 99.26357 -336.326112) (xy 99.29154 -336.281089) (xy 99.308158 -336.26044)
			(xy 99.317607 -336.2483) (xy 99.329393 -336.219898) (xy 99.332214 -336.189277) (xy 99.325816 -336.159199)
			(xy 99.310776 -336.132377) (xy 99.28845 -336.111231) (xy 99.274884 -336.103976) (xy 99.251197 -336.091869)
			(xy 99.207215 -336.061949) (xy 99.167932 -336.026079) (xy 99.134148 -335.98499) (xy 99.119944 -335.962498)
			(xy 99.112052 -335.950251) (xy 99.090572 -335.93058) (xy 99.06441 -335.917779) (xy 99.035698 -335.912889)
			(xy 99.006773 -335.916311) (xy 98.993198 -335.921604) (xy 98.969986 -335.931087) (xy 98.921654 -335.94444)
			(xy 98.871965 -335.951171) (xy 98.846894 -335.951576) (xy 98.821825 -335.951142) (xy 98.772142 -335.944396)
			(xy 98.723808 -335.931068) (xy 98.70059 -335.921604) (xy 98.686994 -335.916411) (xy 98.658103 -335.913032)
			(xy 98.62943 -335.91793) (xy 98.603298 -335.930707) (xy 98.581825 -335.950328) (xy 98.573844 -335.962498)
			(xy 98.559275 -335.985629) (xy 98.524432 -336.02775) (xy 98.483809 -336.064329) (xy 98.438278 -336.09458)
			(xy 98.388816 -336.117856) (xy 98.336485 -336.133656) (xy 98.282406 -336.141642) (xy 98.227742 -336.141642)
			(xy 98.173663 -336.133656) (xy 98.121332 -336.117856) (xy 98.07187 -336.09458) (xy 98.026339 -336.064329)
			(xy 97.985716 -336.02775) (xy 97.950873 -335.985629) (xy 97.936304 -335.962498) (xy 97.928355 -335.950292)
			(xy 97.906891 -335.930621) (xy 97.880744 -335.917814) (xy 97.852045 -335.912914) (xy 97.823131 -335.91632)
			(xy 97.809558 -335.921604) (xy 97.78635 -335.931099) (xy 97.738016 -335.944448) (xy 97.688326 -335.951174)
			(xy 97.663254 -335.951576) (xy 97.635368 -335.951136) (xy 97.580221 -335.942817) (xy 97.526928 -335.926373)
			(xy 97.476682 -335.90217) (xy 97.430604 -335.870749) (xy 97.389723 -335.832812) (xy 97.354952 -335.789207)
			(xy 97.327068 -335.740906) (xy 97.306694 -335.688989) (xy 97.294285 -335.634616) (xy 97.290117 -335.579)
			(xy 76.372974 -335.579) (xy 76.372974 -336.644742) (xy 93.832424 -336.644742) (xy 93.836495 -336.58912)
			(xy 93.848621 -336.534683) (xy 93.868544 -336.482592) (xy 93.89584 -336.433957) (xy 93.929926 -336.389814)
			(xy 93.970075 -336.351105) (xy 94.015433 -336.318654) (xy 94.065033 -336.293153) (xy 94.117817 -336.275146)
			(xy 94.17266 -336.265016) (xy 94.228394 -336.262979) (xy 94.283831 -336.269079) (xy 94.337788 -336.283185)
			(xy 94.389117 -336.304997) (xy 94.436723 -336.334051) (xy 94.479591 -336.369726) (xy 94.516808 -336.411263)
			(xy 94.547581 -336.457776) (xy 94.571253 -336.508273) (xy 94.587321 -336.56168) (xy 94.595441 -336.616856)
			(xy 94.59595 -336.644742) (xy 94.595441 -336.672628) (xy 94.587321 -336.727804) (xy 94.571253 -336.781211)
			(xy 94.547581 -336.831708) (xy 94.516808 -336.878221) (xy 94.479591 -336.919758) (xy 94.436723 -336.955433)
			(xy 94.389117 -336.984487) (xy 94.337788 -337.006299) (xy 94.283831 -337.020405) (xy 94.228394 -337.026505)
			(xy 94.17266 -337.024468) (xy 94.117817 -337.014338) (xy 94.065033 -336.996331) (xy 94.015433 -336.97083)
			(xy 93.970075 -336.938379) (xy 93.929926 -336.89967) (xy 93.89584 -336.855527) (xy 93.868544 -336.806892)
			(xy 93.848621 -336.754801) (xy 93.836495 -336.700364) (xy 93.832424 -336.644742) (xy 76.372974 -336.644742)
			(xy 76.372974 -337.352894) (xy 93.189296 -337.352894) (xy 93.193367 -337.297272) (xy 93.205493 -337.242835)
			(xy 93.225416 -337.190744) (xy 93.252712 -337.142109) (xy 93.286798 -337.097966) (xy 93.326947 -337.059257)
			(xy 93.372305 -337.026806) (xy 93.421905 -337.001305) (xy 93.474689 -336.983298) (xy 93.529532 -336.973168)
			(xy 93.585266 -336.971131) (xy 93.640703 -336.977231) (xy 93.69466 -336.991337) (xy 93.745989 -337.013149)
			(xy 93.793595 -337.042203) (xy 93.836463 -337.077878) (xy 93.87368 -337.119415) (xy 93.904453 -337.165928)
			(xy 93.928125 -337.216425) (xy 93.944193 -337.269832) (xy 93.952313 -337.325008) (xy 93.952822 -337.352894)
			(xy 93.952313 -337.38078) (xy 93.944193 -337.435956) (xy 93.928125 -337.489363) (xy 93.904453 -337.53986)
			(xy 93.87368 -337.586373) (xy 93.836463 -337.62791) (xy 93.793595 -337.663585) (xy 93.745989 -337.692639)
			(xy 93.69466 -337.714451) (xy 93.640703 -337.728557) (xy 93.585266 -337.734657) (xy 93.529532 -337.73262)
			(xy 93.474689 -337.72249) (xy 93.421905 -337.704483) (xy 93.372305 -337.678982) (xy 93.326947 -337.646531)
			(xy 93.286798 -337.607822) (xy 93.252712 -337.563679) (xy 93.225416 -337.515044) (xy 93.205493 -337.462953)
			(xy 93.193367 -337.408516) (xy 93.189296 -337.352894) (xy 76.372974 -337.352894) (xy 76.372974 -338.671662)
			(xy 84.701634 -338.671662) (xy 84.70209 -338.644953) (xy 84.709554 -338.592057) (xy 84.724317 -338.540718)
			(xy 84.746092 -338.491938) (xy 84.774452 -338.446669) (xy 84.808845 -338.405794) (xy 84.848599 -338.370111)
			(xy 84.892938 -338.340318) (xy 84.916772 -338.328254) (xy 84.929938 -338.321345) (xy 84.951847 -338.301262)
			(xy 84.967048 -338.275722) (xy 84.974254 -338.246888) (xy 84.972856 -338.2172) (xy 84.962971 -338.189171)
			(xy 84.954618 -338.17687) (xy 84.937282 -338.152202) (xy 84.909765 -338.098558) (xy 84.891027 -338.041254)
			(xy 84.881534 -337.981717) (xy 84.880958 -337.951572) (xy 84.881444 -337.924321) (xy 84.8892 -337.870373)
			(xy 84.904555 -337.818078) (xy 84.927197 -337.768501) (xy 84.956663 -337.722651) (xy 84.992354 -337.68146)
			(xy 85.033545 -337.645769) (xy 85.079395 -337.616303) (xy 85.128972 -337.593661) (xy 85.181267 -337.578306)
			(xy 85.235215 -337.57055) (xy 85.289717 -337.57055) (xy 85.343665 -337.578306) (xy 85.39596 -337.593661)
			(xy 85.445537 -337.616303) (xy 85.491387 -337.645769) (xy 85.532578 -337.68146) (xy 85.568269 -337.722651)
			(xy 85.597735 -337.768501) (xy 85.620377 -337.818078) (xy 85.635732 -337.870373) (xy 85.643488 -337.924321)
			(xy 85.643974 -337.951572) (xy 85.643543 -337.978282) (xy 85.636074 -338.031178) (xy 85.621306 -338.082518)
			(xy 85.599528 -338.131298) (xy 85.571165 -338.176567) (xy 85.536769 -338.217441) (xy 85.513487 -338.238338)
			(xy 94.63913 -338.238338) (xy 94.639701 -338.20865) (xy 94.648894 -338.149991) (xy 94.667066 -338.093465)
			(xy 94.693776 -338.040437) (xy 94.72838 -337.992188) (xy 94.770042 -337.949884) (xy 94.793562 -337.93176)
			(xy 94.804147 -337.923306) (xy 94.820861 -337.902002) (xy 94.831386 -337.877054) (xy 94.834982 -337.850216)
			(xy 94.831395 -337.823376) (xy 94.820877 -337.798425) (xy 94.80417 -337.777116) (xy 94.793562 -337.768692)
			(xy 94.77004 -337.750571) (xy 94.728382 -337.708263) (xy 94.69378 -337.660013) (xy 94.667069 -337.606985)
			(xy 94.648895 -337.55046) (xy 94.639696 -337.491801) (xy 94.63913 -337.462114) (xy 94.639616 -337.434863)
			(xy 94.647372 -337.380915) (xy 94.662727 -337.32862) (xy 94.685369 -337.279043) (xy 94.714835 -337.233193)
			(xy 94.750526 -337.192002) (xy 94.791717 -337.156311) (xy 94.837567 -337.126845) (xy 94.887144 -337.104203)
			(xy 94.939439 -337.088848) (xy 94.993387 -337.081092) (xy 95.047889 -337.081092) (xy 95.101837 -337.088848)
			(xy 95.154132 -337.104203) (xy 95.203709 -337.126845) (xy 95.249559 -337.156311) (xy 95.29075 -337.192002)
			(xy 95.326441 -337.233193) (xy 95.355907 -337.279043) (xy 95.378549 -337.32862) (xy 95.393904 -337.380915)
			(xy 95.40166 -337.434863) (xy 95.402146 -337.462114) (xy 95.401623 -337.491804) (xy 95.39242 -337.550465)
			(xy 95.37424 -337.606993) (xy 95.347521 -337.66002) (xy 95.335442 -337.676857) (xy 95.655521 -337.676857)
			(xy 95.655521 -337.622343) (xy 95.66328 -337.568384) (xy 95.678639 -337.516078) (xy 95.701286 -337.466491)
			(xy 95.730761 -337.420632) (xy 95.766462 -337.379435) (xy 95.807662 -337.343738) (xy 95.853524 -337.314268)
			(xy 95.903114 -337.291626) (xy 95.955421 -337.276272) (xy 96.009381 -337.268518) (xy 96.036638 -337.268058)
			(xy 96.061874 -337.268444) (xy 96.111908 -337.275066) (xy 96.160628 -337.288243) (xy 96.20718 -337.307742)
			(xy 96.22917 -337.320128) (xy 96.24216 -337.327118) (xy 96.270787 -337.334163) (xy 96.300234 -337.332729)
			(xy 96.328041 -337.322936) (xy 96.351888 -337.305602) (xy 96.369784 -337.282173) (xy 96.375474 -337.268566)
			(xy 96.386157 -337.241784) (xy 96.414448 -337.191543) (xy 96.44998 -337.146135) (xy 96.491944 -337.106593)
			(xy 96.539383 -337.07382) (xy 96.591215 -337.048563) (xy 96.64626 -337.031398) (xy 96.703261 -337.022716)
			(xy 96.73209 -337.022186) (xy 96.759342 -337.022665) (xy 96.813292 -337.03042) (xy 96.86559 -337.045775)
			(xy 96.915169 -337.068415) (xy 96.961022 -337.097882) (xy 97.002215 -337.133574) (xy 97.037909 -337.174765)
			(xy 97.067377 -337.220617) (xy 97.09002 -337.270195) (xy 97.105377 -337.322492) (xy 97.113134 -337.376442)
			(xy 97.113598 -337.403694) (xy 97.113073 -337.433599) (xy 97.103754 -337.492678) (xy 97.095056 -337.521296)
			(xy 97.091124 -337.53523) (xy 97.090201 -337.564145) (xy 97.097449 -337.592153) (xy 97.112281 -337.616992)
			(xy 97.1335 -337.636657) (xy 97.159394 -337.64956) (xy 97.173542 -337.652614) (xy 97.199616 -337.657777)
			(xy 97.25012 -337.674349) (xy 97.297832 -337.697774) (xy 97.34183 -337.727597) (xy 97.38126 -337.763241)
			(xy 97.415359 -337.804014) (xy 97.443465 -337.849128) (xy 97.465035 -337.897707) (xy 97.47965 -337.948811)
			(xy 97.487027 -338.00145) (xy 97.487486 -338.028026) (xy 97.487 -338.055277) (xy 97.479244 -338.109225)
			(xy 97.463889 -338.16152) (xy 97.441247 -338.211097) (xy 97.42374 -338.238338) (xy 102.799642 -338.238338)
			(xy 102.800208 -338.20865) (xy 102.809402 -338.149991) (xy 102.827574 -338.093464) (xy 102.854285 -338.040436)
			(xy 102.88889 -337.992187) (xy 102.930553 -337.949883) (xy 102.954074 -337.93176) (xy 102.964658 -337.923305)
			(xy 102.98137 -337.902001) (xy 102.991894 -337.877053) (xy 102.995489 -337.850216) (xy 102.991902 -337.823377)
			(xy 102.981386 -337.798426) (xy 102.964681 -337.777116) (xy 102.954074 -337.768692) (xy 102.930554 -337.750568)
			(xy 102.888895 -337.708261) (xy 102.854293 -337.660011) (xy 102.827582 -337.606984) (xy 102.809407 -337.550459)
			(xy 102.800208 -337.491801) (xy 102.799642 -337.462114) (xy 102.800128 -337.434863) (xy 102.807884 -337.380915)
			(xy 102.823239 -337.32862) (xy 102.845881 -337.279043) (xy 102.875347 -337.233193) (xy 102.911038 -337.192002)
			(xy 102.952229 -337.156311) (xy 102.998079 -337.126845) (xy 103.047656 -337.104203) (xy 103.099951 -337.088848)
			(xy 103.153899 -337.081092) (xy 103.208401 -337.081092) (xy 103.262349 -337.088848) (xy 103.314644 -337.104203)
			(xy 103.364221 -337.126845) (xy 103.410071 -337.156311) (xy 103.451262 -337.192002) (xy 103.486953 -337.233193)
			(xy 103.516419 -337.279043) (xy 103.539061 -337.32862) (xy 103.554416 -337.380915) (xy 103.562172 -337.434863)
			(xy 103.562658 -337.462114) (xy 103.56213 -337.491803) (xy 103.552928 -337.550464) (xy 103.534748 -337.606992)
			(xy 103.50803 -337.660019) (xy 103.495955 -337.676851) (xy 103.816144 -337.676851) (xy 103.816144 -337.622349)
			(xy 103.8239 -337.5684) (xy 103.839254 -337.516105) (xy 103.861893 -337.466527) (xy 103.891357 -337.420675)
			(xy 103.927047 -337.379482) (xy 103.968235 -337.343787) (xy 104.014083 -337.314317) (xy 104.063658 -337.291671)
			(xy 104.115952 -337.27631) (xy 104.169899 -337.268547) (xy 104.19715 -337.268058) (xy 104.222386 -337.268439)
			(xy 104.27242 -337.275063) (xy 104.32114 -337.288241) (xy 104.367692 -337.307741) (xy 104.389682 -337.320128)
			(xy 104.402665 -337.327132) (xy 104.431295 -337.334175) (xy 104.460744 -337.332738) (xy 104.488552 -337.322943)
			(xy 104.5124 -337.305606) (xy 104.530296 -337.282174) (xy 104.535986 -337.268566) (xy 104.546659 -337.24178)
			(xy 104.574951 -337.191539) (xy 104.610485 -337.14613) (xy 104.65245 -337.106588) (xy 104.699891 -337.073816)
			(xy 104.751724 -337.04856) (xy 104.80677 -337.031396) (xy 104.863772 -337.022715) (xy 104.892602 -337.022186)
			(xy 104.919853 -337.022676) (xy 104.9738 -337.030433) (xy 105.026095 -337.045788) (xy 105.075671 -337.068429)
			(xy 105.121522 -337.097894) (xy 105.162712 -337.133586) (xy 105.198403 -337.174775) (xy 105.22787 -337.220625)
			(xy 105.250511 -337.270202) (xy 105.265867 -337.322496) (xy 105.273624 -337.376443) (xy 105.27411 -337.403694)
			(xy 105.273584 -337.433599) (xy 105.264265 -337.492678) (xy 105.255568 -337.521296) (xy 105.251626 -337.535228)
			(xy 105.250703 -337.564145) (xy 105.257952 -337.592155) (xy 105.272786 -337.616995) (xy 105.294008 -337.63666)
			(xy 105.319904 -337.649562) (xy 105.334054 -337.652614) (xy 105.36013 -337.657768) (xy 105.410633 -337.674342)
			(xy 105.458346 -337.697768) (xy 105.502343 -337.727592) (xy 105.541773 -337.763237) (xy 105.575872 -337.804012)
			(xy 105.603978 -337.849126) (xy 105.625547 -337.897706) (xy 105.640162 -337.948811) (xy 105.647539 -338.001449)
			(xy 105.647998 -338.028026) (xy 105.647512 -338.055277) (xy 105.639756 -338.109225) (xy 105.624401 -338.16152)
			(xy 105.601759 -338.211097) (xy 105.584252 -338.238338) (xy 110.960154 -338.238338) (xy 110.960715 -338.20865)
			(xy 110.969909 -338.14999) (xy 110.988082 -338.093463) (xy 111.014794 -338.040435) (xy 111.0494 -337.992187)
			(xy 111.091064 -337.949883) (xy 111.114586 -337.93176) (xy 111.125169 -337.923305) (xy 111.141879 -337.902)
			(xy 111.152402 -337.877052) (xy 111.155996 -337.850216) (xy 111.15241 -337.823378) (xy 111.141895 -337.798427)
			(xy 111.125192 -337.777117) (xy 111.114586 -337.768692) (xy 111.091069 -337.750565) (xy 111.049409 -337.708259)
			(xy 111.014806 -337.66001) (xy 110.988095 -337.606983) (xy 110.96992 -337.550459) (xy 110.96072 -337.491801)
			(xy 110.960154 -337.462114) (xy 110.96064 -337.434863) (xy 110.968396 -337.380915) (xy 110.983751 -337.32862)
			(xy 111.006393 -337.279043) (xy 111.035859 -337.233193) (xy 111.07155 -337.192002) (xy 111.112741 -337.156311)
			(xy 111.158591 -337.126845) (xy 111.208168 -337.104203) (xy 111.260463 -337.088848) (xy 111.314411 -337.081092)
			(xy 111.368913 -337.081092) (xy 111.422861 -337.088848) (xy 111.475156 -337.104203) (xy 111.524733 -337.126845)
			(xy 111.570583 -337.156311) (xy 111.611774 -337.192002) (xy 111.647465 -337.233193) (xy 111.676931 -337.279043)
			(xy 111.699573 -337.32862) (xy 111.714928 -337.380915) (xy 111.722684 -337.434863) (xy 111.72317 -337.462114)
			(xy 111.722637 -337.491803) (xy 111.713435 -337.550464) (xy 111.695256 -337.606991) (xy 111.668539 -337.660018)
			(xy 111.656463 -337.676852) (xy 111.976644 -337.676852) (xy 111.976644 -337.622348) (xy 111.9844 -337.568399)
			(xy 111.999755 -337.516102) (xy 112.022395 -337.466523) (xy 112.05186 -337.420671) (xy 112.087551 -337.379478)
			(xy 112.12874 -337.343783) (xy 112.17459 -337.314313) (xy 112.224167 -337.291668) (xy 112.276462 -337.276308)
			(xy 112.33041 -337.268546) (xy 112.357662 -337.268058) (xy 112.382898 -337.268433) (xy 112.432933 -337.275059)
			(xy 112.481653 -337.288238) (xy 112.528204 -337.307741) (xy 112.550194 -337.320128) (xy 112.56317 -337.327146)
			(xy 112.591803 -337.334187) (xy 112.621253 -337.332748) (xy 112.649064 -337.322949) (xy 112.672912 -337.30561)
			(xy 112.690808 -337.282176) (xy 112.696498 -337.268566) (xy 112.707161 -337.241776) (xy 112.735454 -337.191534)
			(xy 112.770989 -337.146125) (xy 112.812956 -337.106583) (xy 112.860398 -337.073812) (xy 112.912233 -337.048556)
			(xy 112.96728 -337.031393) (xy 113.024284 -337.022714) (xy 113.053114 -337.022186) (xy 113.080365 -337.022665)
			(xy 113.134313 -337.030423) (xy 113.186608 -337.04578) (xy 113.236184 -337.068422) (xy 113.282034 -337.097889)
			(xy 113.323224 -337.133581) (xy 113.358916 -337.174772) (xy 113.388382 -337.220623) (xy 113.411023 -337.2702)
			(xy 113.426379 -337.322495) (xy 113.434136 -337.376443) (xy 113.434622 -337.403694) (xy 113.434096 -337.433599)
			(xy 113.424777 -337.492678) (xy 113.41608 -337.521296) (xy 113.412129 -337.535225) (xy 113.411206 -337.564145)
			(xy 113.418455 -337.592157) (xy 113.433291 -337.616998) (xy 113.454516 -337.636663) (xy 113.480415 -337.649563)
			(xy 113.494566 -337.652614) (xy 113.520644 -337.657759) (xy 113.571147 -337.674334) (xy 113.61886 -337.697762)
			(xy 113.662857 -337.727588) (xy 113.702286 -337.763233) (xy 113.736384 -337.804009) (xy 113.76449 -337.849124)
			(xy 113.78606 -337.897705) (xy 113.800674 -337.94881) (xy 113.808051 -338.001449) (xy 113.80851 -338.028026)
			(xy 113.808024 -338.055277) (xy 113.800268 -338.109225) (xy 113.784913 -338.16152) (xy 113.762271 -338.211097)
			(xy 113.744764 -338.238338) (xy 119.120666 -338.238338) (xy 119.121223 -338.20865) (xy 119.130417 -338.149989)
			(xy 119.148591 -338.093463) (xy 119.175304 -338.040434) (xy 119.209911 -337.992186) (xy 119.251576 -337.949883)
			(xy 119.275098 -337.93176) (xy 119.28568 -337.923304) (xy 119.302388 -337.901999) (xy 119.312909 -337.877051)
			(xy 119.316503 -337.850216) (xy 119.312918 -337.823379) (xy 119.302404 -337.798428) (xy 119.285703 -337.777118)
			(xy 119.275098 -337.768692) (xy 119.251583 -337.750562) (xy 119.209923 -337.708256) (xy 119.175319 -337.660008)
			(xy 119.148607 -337.606982) (xy 119.130432 -337.550458) (xy 119.121232 -337.491801) (xy 119.120666 -337.462114)
			(xy 119.121152 -337.434863) (xy 119.128908 -337.380915) (xy 119.144263 -337.32862) (xy 119.166905 -337.279043)
			(xy 119.196371 -337.233193) (xy 119.232062 -337.192002) (xy 119.273253 -337.156311) (xy 119.319103 -337.126845)
			(xy 119.36868 -337.104203) (xy 119.420975 -337.088848) (xy 119.474923 -337.081092) (xy 119.529425 -337.081092)
			(xy 119.583373 -337.088848) (xy 119.635668 -337.104203) (xy 119.685245 -337.126845) (xy 119.731095 -337.156311)
			(xy 119.772286 -337.192002) (xy 119.807977 -337.233193) (xy 119.837443 -337.279043) (xy 119.860085 -337.32862)
			(xy 119.87544 -337.380915) (xy 119.883196 -337.434863) (xy 119.883682 -337.462114) (xy 119.883144 -337.491803)
			(xy 119.873943 -337.550463) (xy 119.855765 -337.60699) (xy 119.829048 -337.660017) (xy 119.816972 -337.676852)
			(xy 120.137144 -337.676852) (xy 120.137144 -337.622348) (xy 120.1449 -337.568397) (xy 120.160255 -337.5161)
			(xy 120.182897 -337.46652) (xy 120.212363 -337.420667) (xy 120.248055 -337.379474) (xy 120.289246 -337.343779)
			(xy 120.335097 -337.314309) (xy 120.384676 -337.291665) (xy 120.436972 -337.276306) (xy 120.490922 -337.268546)
			(xy 120.518174 -337.268058) (xy 120.54341 -337.268428) (xy 120.593445 -337.275055) (xy 120.642165 -337.288236)
			(xy 120.688716 -337.30774) (xy 120.710706 -337.320128) (xy 120.723675 -337.32716) (xy 120.75231 -337.334199)
			(xy 120.781763 -337.332757) (xy 120.809575 -337.322956) (xy 120.833424 -337.305614) (xy 120.85132 -337.282177)
			(xy 120.85701 -337.268566) (xy 120.867663 -337.241771) (xy 120.895957 -337.191529) (xy 120.931494 -337.14612)
			(xy 120.973462 -337.106579) (xy 121.020905 -337.073807) (xy 121.072742 -337.048553) (xy 121.127791 -337.031391)
			(xy 121.184795 -337.022713) (xy 121.213626 -337.022186) (xy 121.240878 -337.022654) (xy 121.294826 -337.030413)
			(xy 121.34712 -337.045772) (xy 121.396697 -337.068415) (xy 121.442547 -337.097884) (xy 121.483737 -337.133577)
			(xy 121.519428 -337.174769) (xy 121.548894 -337.22062) (xy 121.571535 -337.270198) (xy 121.586891 -337.322494)
			(xy 121.594648 -337.376442) (xy 121.595134 -337.403694) (xy 121.594607 -337.433599) (xy 121.586865 -337.482688)
			(xy 123.707398 -337.482688) (xy 123.707925 -337.455116) (xy 123.715865 -337.400546) (xy 123.731578 -337.347687)
			(xy 123.754737 -337.297641) (xy 123.784858 -337.251449) (xy 123.821316 -337.210076) (xy 123.842018 -337.191858)
			(xy 123.852925 -337.18197) (xy 123.868994 -337.157316) (xy 123.877374 -337.129106) (xy 123.877372 -337.099678)
			(xy 123.868987 -337.071469) (xy 123.852915 -337.046818) (xy 123.842018 -337.036918) (xy 123.821316 -337.018697)
			(xy 123.784844 -336.977331) (xy 123.75471 -336.931143) (xy 123.731543 -336.881097) (xy 123.715825 -336.828236)
			(xy 123.707884 -336.773662) (xy 123.707398 -336.746088) (xy 123.707867 -336.718836) (xy 123.715625 -336.664888)
			(xy 123.730982 -336.612592) (xy 123.753625 -336.563014) (xy 123.783093 -336.517164) (xy 123.818786 -336.475974)
			(xy 123.859978 -336.440282) (xy 123.90583 -336.410816) (xy 123.955409 -336.388176) (xy 124.007705 -336.372821)
			(xy 124.061654 -336.365065) (xy 124.088906 -336.36458) (xy 124.101067 -336.364674) (xy 124.125343 -336.366197)
			(xy 124.13742 -336.367628) (xy 124.151183 -336.36885) (xy 124.178509 -336.364881) (xy 124.203774 -336.353739)
			(xy 124.225132 -336.336237) (xy 124.241022 -336.313655) (xy 124.250284 -336.287641) (xy 124.25172 -336.273902)
			(xy 124.254288 -336.245371) (xy 124.26677 -336.189468) (xy 124.287472 -336.136059) (xy 124.315929 -336.086348)
			(xy 124.351502 -336.041452) (xy 124.393389 -336.002382) (xy 124.440649 -335.970016) (xy 124.492218 -335.945083)
			(xy 124.546936 -335.928143) (xy 124.603572 -335.919578) (xy 124.632212 -335.919064) (xy 124.650231 -335.919288)
			(xy 124.686106 -335.92272) (xy 124.70384 -335.925922) (xy 124.719042 -335.928328) (xy 124.749605 -335.924788)
			(xy 124.77773 -335.912312) (xy 124.800866 -335.89203) (xy 124.816917 -335.865781) (xy 124.821188 -335.850992)
			(xy 124.828636 -335.823962) (xy 124.850258 -335.772237) (xy 124.879215 -335.724232) (xy 124.914884 -335.68098)
			(xy 124.956497 -335.643411) (xy 125.003158 -335.612335) (xy 125.053864 -335.588419) (xy 125.107523 -335.57218)
			(xy 125.162981 -335.563965) (xy 125.191012 -335.563464) (xy 125.218262 -335.563967) (xy 125.272208 -335.571724)
			(xy 125.324501 -335.587079) (xy 125.374076 -335.60972) (xy 125.419925 -335.639185) (xy 125.461114 -335.674874)
			(xy 125.496806 -335.716062) (xy 125.526273 -335.76191) (xy 125.548915 -335.811484) (xy 125.564273 -335.863776)
			(xy 125.572032 -335.917722) (xy 125.57252 -335.944972) (xy 125.572028 -335.972546) (xy 125.56408 -336.027117)
			(xy 125.54836 -336.079976) (xy 125.525194 -336.130022) (xy 125.495067 -336.176212) (xy 125.458605 -336.217585)
			(xy 125.4379 -336.235802) (xy 125.427031 -336.245729) (xy 125.410958 -336.270371) (xy 125.402572 -336.298572)
			(xy 125.402566 -336.327992) (xy 125.410943 -336.356195) (xy 125.427007 -336.380843) (xy 125.4379 -336.390742)
			(xy 125.458577 -336.408988) (xy 125.495041 -336.450356) (xy 125.525168 -336.496542) (xy 125.548331 -336.546585)
			(xy 125.564048 -336.599441) (xy 125.57199 -336.65401) (xy 125.571993 -336.709154) (xy 125.564056 -336.763723)
			(xy 125.548344 -336.816581) (xy 125.525186 -336.866626) (xy 125.495063 -336.912816) (xy 125.458603 -336.954186)
			(xy 125.4379 -336.972402) (xy 125.427031 -336.982329) (xy 125.410958 -337.006971) (xy 125.402572 -337.035172)
			(xy 125.402566 -337.064592) (xy 125.410943 -337.092795) (xy 125.427007 -337.117443) (xy 125.4379 -337.127342)
			(xy 125.458586 -337.14558) (xy 125.495059 -337.186943) (xy 125.525194 -337.233127) (xy 125.548364 -337.28317)
			(xy 125.564086 -337.336028) (xy 125.572031 -337.390599) (xy 125.57252 -337.418172) (xy 125.572019 -337.445424)
			(xy 125.564266 -337.499373) (xy 125.548914 -337.551669) (xy 125.526276 -337.601248) (xy 125.496812 -337.647101)
			(xy 125.461122 -337.688294) (xy 125.419933 -337.723988) (xy 125.374083 -337.753456) (xy 125.324506 -337.7761)
			(xy 125.272212 -337.791457) (xy 125.218264 -337.799216) (xy 125.191012 -337.79968) (xy 125.163156 -337.799161)
			(xy 125.10804 -337.791038) (xy 125.054689 -337.774993) (xy 125.004235 -337.751367) (xy 124.95775 -337.720659)
			(xy 124.916221 -337.683523) (xy 124.880528 -337.640747) (xy 124.85143 -337.593238) (xy 124.829543 -337.542006)
			(xy 124.82195 -337.5152) (xy 124.817696 -337.501077) (xy 124.802301 -337.475931) (xy 124.780378 -337.456216)
			(xy 124.753745 -337.443567) (xy 124.724611 -337.439033) (xy 124.709936 -337.440524) (xy 124.69692 -337.442198)
			(xy 124.670735 -337.443975) (xy 124.657612 -337.44408) (xy 124.639981 -337.443844) (xy 124.604873 -337.440538)
			(xy 124.587508 -337.437476) (xy 124.573734 -337.435253) (xy 124.545948 -337.437699) (xy 124.519864 -337.447584)
			(xy 124.497434 -337.464166) (xy 124.480337 -337.486207) (xy 124.469852 -337.512055) (xy 124.467874 -337.525868)
			(xy 124.464232 -337.553444) (xy 124.450001 -337.607215) (xy 124.428107 -337.658348) (xy 124.399017 -337.705757)
			(xy 124.363347 -337.748436) (xy 124.321855 -337.78548) (xy 124.27542 -337.816102) (xy 124.225029 -337.839652)
			(xy 124.171752 -337.85563) (xy 124.116717 -337.863699) (xy 124.088906 -337.864196) (xy 124.061653 -337.863739)
			(xy 124.007701 -337.855983) (xy 123.955402 -337.840627) (xy 123.905821 -337.817984) (xy 123.859968 -337.788516)
			(xy 123.818775 -337.752821) (xy 123.783081 -337.711628) (xy 123.753613 -337.665773) (xy 123.730971 -337.616192)
			(xy 123.715616 -337.563893) (xy 123.707861 -337.509941) (xy 123.707398 -337.482688) (xy 121.586865 -337.482688)
			(xy 121.585289 -337.492678) (xy 121.576592 -337.521296) (xy 121.572631 -337.535223) (xy 121.571708 -337.564145)
			(xy 121.578958 -337.592158) (xy 121.593796 -337.617001) (xy 121.615023 -337.636665) (xy 121.640926 -337.649564)
			(xy 121.655078 -337.652614) (xy 121.681143 -337.657824) (xy 121.731646 -337.674388) (xy 121.779359 -337.697805)
			(xy 121.823358 -337.727622) (xy 121.86279 -337.76326) (xy 121.89689 -337.804029) (xy 121.924998 -337.849138)
			(xy 121.94657 -337.897714) (xy 121.961186 -337.948815) (xy 121.968563 -338.001451) (xy 121.969022 -338.028026)
			(xy 121.968536 -338.055277) (xy 121.96078 -338.109225) (xy 121.945425 -338.16152) (xy 121.922783 -338.211097)
			(xy 121.893317 -338.256947) (xy 121.857626 -338.298138) (xy 121.816435 -338.333829) (xy 121.770585 -338.363295)
			(xy 121.721008 -338.385937) (xy 121.668713 -338.401292) (xy 121.614765 -338.409048) (xy 121.560263 -338.409048)
			(xy 121.506315 -338.401292) (xy 121.45402 -338.385937) (xy 121.404443 -338.363295) (xy 121.358593 -338.333829)
			(xy 121.317402 -338.298138) (xy 121.281711 -338.256947) (xy 121.252245 -338.211097) (xy 121.229603 -338.16152)
			(xy 121.214248 -338.109225) (xy 121.206492 -338.055277) (xy 121.206006 -338.028026) (xy 121.206536 -337.998121)
			(xy 121.215852 -337.939042) (xy 121.224548 -337.910424) (xy 121.228568 -337.896513) (xy 121.229471 -337.867586)
			(xy 121.222206 -337.83957) (xy 121.207357 -337.814728) (xy 121.186123 -337.795062) (xy 121.160217 -337.782159)
			(xy 121.146062 -337.779106) (xy 121.113226 -337.77251) (xy 121.050372 -337.749396) (xy 121.021094 -337.733132)
			(xy 121.008116 -337.72612) (xy 120.979485 -337.719086) (xy 120.950038 -337.720528) (xy 120.92223 -337.730325)
			(xy 120.898382 -337.74766) (xy 120.880483 -337.771087) (xy 120.87479 -337.784694) (xy 120.864116 -337.81148)
			(xy 120.835826 -337.861723) (xy 120.800294 -337.907134) (xy 120.758329 -337.946677) (xy 120.710889 -337.97945)
			(xy 120.659054 -338.004706) (xy 120.604007 -338.021869) (xy 120.547004 -338.030547) (xy 120.518174 -338.031074)
			(xy 120.490922 -338.030654) (xy 120.436972 -338.022894) (xy 120.384676 -338.007535) (xy 120.335097 -337.984891)
			(xy 120.289246 -337.955421) (xy 120.248055 -337.919726) (xy 120.212363 -337.878533) (xy 120.182897 -337.83268)
			(xy 120.160255 -337.7831) (xy 120.1449 -337.730803) (xy 120.137144 -337.676852) (xy 119.816972 -337.676852)
			(xy 119.794439 -337.708265) (xy 119.752772 -337.750569) (xy 119.72925 -337.768692) (xy 119.718621 -337.77709)
			(xy 119.701921 -337.798411) (xy 119.691409 -337.823371) (xy 119.687823 -337.850216) (xy 119.691417 -337.877059)
			(xy 119.701936 -337.902015) (xy 119.718643 -337.923331) (xy 119.72925 -337.93176) (xy 119.7528 -337.949847)
			(xy 119.794456 -337.992163) (xy 119.829054 -338.04042) (xy 119.85576 -338.093455) (xy 119.873928 -338.149986)
			(xy 119.88312 -338.208649) (xy 119.883682 -338.238338) (xy 119.883196 -338.265589) (xy 119.87544 -338.319537)
			(xy 119.860085 -338.371832) (xy 119.837443 -338.421409) (xy 119.807977 -338.467259) (xy 119.772286 -338.50845)
			(xy 119.731095 -338.544141) (xy 119.685245 -338.573607) (xy 119.642953 -338.592922) (xy 125.683518 -338.592922)
			(xy 125.684014 -338.564882) (xy 125.692213 -338.509403) (xy 125.708438 -338.455721) (xy 125.732339 -338.404989)
			(xy 125.763403 -338.358298) (xy 125.781816 -338.337144) (xy 125.791486 -338.325722) (xy 125.804259 -338.298671)
			(xy 125.808638 -338.269079) (xy 125.804246 -338.239489) (xy 125.791463 -338.212443) (xy 125.781816 -338.201)
			(xy 125.763361 -338.179878) (xy 125.732274 -338.133192) (xy 125.708366 -338.082454) (xy 125.692154 -338.028759)
			(xy 125.683988 -337.973267) (xy 125.683518 -337.945222) (xy 125.684004 -337.917971) (xy 125.69176 -337.864023)
			(xy 125.707115 -337.811728) (xy 125.729757 -337.762151) (xy 125.759223 -337.716301) (xy 125.794914 -337.67511)
			(xy 125.836105 -337.639419) (xy 125.881955 -337.609953) (xy 125.931532 -337.587311) (xy 125.983827 -337.571956)
			(xy 126.037775 -337.5642) (xy 126.092277 -337.5642) (xy 126.146225 -337.571956) (xy 126.19852 -337.587311)
			(xy 126.248097 -337.609953) (xy 126.293947 -337.639419) (xy 126.335138 -337.67511) (xy 126.370829 -337.716301)
			(xy 126.400295 -337.762151) (xy 126.422937 -337.811728) (xy 126.438292 -337.864023) (xy 126.446048 -337.917971)
			(xy 126.446534 -337.945222) (xy 126.446051 -337.973263) (xy 126.437847 -338.028741) (xy 126.421619 -338.082423)
			(xy 126.397715 -338.133155) (xy 126.366649 -338.179846) (xy 126.348236 -338.201) (xy 126.338617 -338.212462)
			(xy 126.325831 -338.239497) (xy 126.321439 -338.269079) (xy 126.325819 -338.298663) (xy 126.338594 -338.325703)
			(xy 126.348236 -338.337144) (xy 126.366656 -338.358295) (xy 126.39775 -338.404972) (xy 126.421665 -338.455703)
			(xy 126.437885 -338.509392) (xy 126.44606 -338.564879) (xy 126.446534 -338.592922) (xy 126.446048 -338.620173)
			(xy 126.438292 -338.674121) (xy 126.422937 -338.726416) (xy 126.400295 -338.775993) (xy 126.370829 -338.821843)
			(xy 126.335138 -338.863034) (xy 126.293947 -338.898725) (xy 126.248097 -338.928191) (xy 126.19852 -338.950833)
			(xy 126.146225 -338.966188) (xy 126.092277 -338.973944) (xy 126.037775 -338.973944) (xy 125.983827 -338.966188)
			(xy 125.931532 -338.950833) (xy 125.881955 -338.928191) (xy 125.836105 -338.898725) (xy 125.794914 -338.863034)
			(xy 125.759223 -338.821843) (xy 125.729757 -338.775993) (xy 125.707115 -338.726416) (xy 125.69176 -338.674121)
			(xy 125.684004 -338.620173) (xy 125.683518 -338.592922) (xy 119.642953 -338.592922) (xy 119.635668 -338.596249)
			(xy 119.583373 -338.611604) (xy 119.529425 -338.61936) (xy 119.474923 -338.61936) (xy 119.420975 -338.611604)
			(xy 119.36868 -338.596249) (xy 119.319103 -338.573607) (xy 119.273253 -338.544141) (xy 119.232062 -338.50845)
			(xy 119.196371 -338.467259) (xy 119.166905 -338.421409) (xy 119.144263 -338.371832) (xy 119.128908 -338.319537)
			(xy 119.121152 -338.265589) (xy 119.120666 -338.238338) (xy 113.744764 -338.238338) (xy 113.732805 -338.256947)
			(xy 113.697114 -338.298138) (xy 113.655923 -338.333829) (xy 113.610073 -338.363295) (xy 113.560496 -338.385937)
			(xy 113.508201 -338.401292) (xy 113.454253 -338.409048) (xy 113.399751 -338.409048) (xy 113.345803 -338.401292)
			(xy 113.293508 -338.385937) (xy 113.243931 -338.363295) (xy 113.198081 -338.333829) (xy 113.15689 -338.298138)
			(xy 113.121199 -338.256947) (xy 113.091733 -338.211097) (xy 113.069091 -338.16152) (xy 113.053736 -338.109225)
			(xy 113.04598 -338.055277) (xy 113.045494 -338.028026) (xy 113.046024 -337.998121) (xy 113.05534 -337.939042)
			(xy 113.064036 -337.910424) (xy 113.068065 -337.896515) (xy 113.068969 -337.867586) (xy 113.061702 -337.839569)
			(xy 113.046852 -337.814725) (xy 113.025615 -337.79506) (xy 112.999706 -337.782158) (xy 112.98555 -337.779106)
			(xy 112.952713 -337.772512) (xy 112.889859 -337.749397) (xy 112.860582 -337.733132) (xy 112.847611 -337.726106)
			(xy 112.818977 -337.719074) (xy 112.789528 -337.720518) (xy 112.761719 -337.730318) (xy 112.73787 -337.747656)
			(xy 112.719971 -337.771086) (xy 112.714278 -337.784694) (xy 112.70353 -337.811448) (xy 112.67525 -337.861689)
			(xy 112.639727 -337.907098) (xy 112.597773 -337.946642) (xy 112.550343 -337.979418) (xy 112.498519 -338.00468)
			(xy 112.443483 -338.021851) (xy 112.386488 -338.030541) (xy 112.357662 -338.031074) (xy 112.33041 -338.030654)
			(xy 112.276462 -338.022892) (xy 112.224167 -338.007532) (xy 112.17459 -337.984887) (xy 112.12874 -337.955417)
			(xy 112.087551 -337.919722) (xy 112.05186 -337.878529) (xy 112.022395 -337.832677) (xy 111.999755 -337.783098)
			(xy 111.9844 -337.730801) (xy 111.976644 -337.676852) (xy 111.656463 -337.676852) (xy 111.633929 -337.708266)
			(xy 111.592261 -337.750569) (xy 111.568738 -337.768692) (xy 111.558101 -337.777085) (xy 111.541386 -337.798403)
			(xy 111.530865 -337.823365) (xy 111.527276 -337.850216) (xy 111.530873 -337.877065) (xy 111.541402 -337.902024)
			(xy 111.558123 -337.923336) (xy 111.568738 -337.93176) (xy 111.592285 -337.94985) (xy 111.633942 -337.992165)
			(xy 111.668541 -338.040422) (xy 111.695247 -338.093455) (xy 111.713416 -338.149986) (xy 111.722608 -338.208649)
			(xy 111.72317 -338.238338) (xy 111.722684 -338.265589) (xy 111.714928 -338.319537) (xy 111.699573 -338.371832)
			(xy 111.676931 -338.421409) (xy 111.647465 -338.467259) (xy 111.611774 -338.50845) (xy 111.570583 -338.544141)
			(xy 111.524733 -338.573607) (xy 111.475156 -338.596249) (xy 111.422861 -338.611604) (xy 111.368913 -338.61936)
			(xy 111.314411 -338.61936) (xy 111.260463 -338.611604) (xy 111.208168 -338.596249) (xy 111.158591 -338.573607)
			(xy 111.112741 -338.544141) (xy 111.07155 -338.50845) (xy 111.035859 -338.467259) (xy 111.006393 -338.421409)
			(xy 110.983751 -338.371832) (xy 110.968396 -338.319537) (xy 110.96064 -338.265589) (xy 110.960154 -338.238338)
			(xy 105.584252 -338.238338) (xy 105.572293 -338.256947) (xy 105.536602 -338.298138) (xy 105.495411 -338.333829)
			(xy 105.449561 -338.363295) (xy 105.399984 -338.385937) (xy 105.347689 -338.401292) (xy 105.293741 -338.409048)
			(xy 105.239239 -338.409048) (xy 105.185291 -338.401292) (xy 105.132996 -338.385937) (xy 105.083419 -338.363295)
			(xy 105.037569 -338.333829) (xy 104.996378 -338.298138) (xy 104.960687 -338.256947) (xy 104.931221 -338.211097)
			(xy 104.908579 -338.16152) (xy 104.893224 -338.109225) (xy 104.885468 -338.055277) (xy 104.884982 -338.028026)
			(xy 104.885513 -337.998121) (xy 104.894828 -337.939042) (xy 104.903524 -337.910424) (xy 104.907562 -337.896517)
			(xy 104.908467 -337.867586) (xy 104.901199 -337.839567) (xy 104.886347 -337.814723) (xy 104.865107 -337.795057)
			(xy 104.839195 -337.782157) (xy 104.825038 -337.779106) (xy 104.7922 -337.772515) (xy 104.729347 -337.749398)
			(xy 104.70007 -337.733132) (xy 104.687106 -337.726092) (xy 104.65847 -337.719062) (xy 104.629018 -337.720509)
			(xy 104.601208 -337.730311) (xy 104.577358 -337.747652) (xy 104.559459 -337.771085) (xy 104.553766 -337.784694)
			(xy 104.543028 -337.811453) (xy 104.514746 -337.861693) (xy 104.479223 -337.907103) (xy 104.437267 -337.946647)
			(xy 104.389836 -337.979422) (xy 104.33801 -338.004683) (xy 104.282973 -338.021854) (xy 104.225977 -338.030542)
			(xy 104.19715 -338.031074) (xy 104.169899 -338.030653) (xy 104.115952 -338.02289) (xy 104.063658 -338.007529)
			(xy 104.014083 -337.984883) (xy 103.968235 -337.955413) (xy 103.927047 -337.919718) (xy 103.891357 -337.878525)
			(xy 103.861893 -337.832673) (xy 103.839254 -337.783095) (xy 103.8239 -337.7308) (xy 103.816144 -337.676851)
			(xy 103.495955 -337.676851) (xy 103.473419 -337.708267) (xy 103.43175 -337.75057) (xy 103.408226 -337.768692)
			(xy 103.39759 -337.777086) (xy 103.380877 -337.798404) (xy 103.370357 -337.823366) (xy 103.366769 -337.850216)
			(xy 103.370365 -337.877064) (xy 103.380893 -337.902023) (xy 103.397612 -337.923336) (xy 103.408226 -337.93176)
			(xy 103.43177 -337.949853) (xy 103.473428 -337.992167) (xy 103.508028 -338.040423) (xy 103.534735 -338.093456)
			(xy 103.552903 -338.149986) (xy 103.562096 -338.208649) (xy 103.562658 -338.238338) (xy 103.562172 -338.265589)
			(xy 103.554416 -338.319537) (xy 103.539061 -338.371832) (xy 103.516419 -338.421409) (xy 103.486953 -338.467259)
			(xy 103.451262 -338.50845) (xy 103.410071 -338.544141) (xy 103.364221 -338.573607) (xy 103.314644 -338.596249)
			(xy 103.262349 -338.611604) (xy 103.208401 -338.61936) (xy 103.153899 -338.61936) (xy 103.099951 -338.611604)
			(xy 103.047656 -338.596249) (xy 102.998079 -338.573607) (xy 102.952229 -338.544141) (xy 102.911038 -338.50845)
			(xy 102.875347 -338.467259) (xy 102.845881 -338.421409) (xy 102.823239 -338.371832) (xy 102.807884 -338.319537)
			(xy 102.800128 -338.265589) (xy 102.799642 -338.238338) (xy 97.42374 -338.238338) (xy 97.411781 -338.256947)
			(xy 97.37609 -338.298138) (xy 97.334899 -338.333829) (xy 97.289049 -338.363295) (xy 97.239472 -338.385937)
			(xy 97.187177 -338.401292) (xy 97.133229 -338.409048) (xy 97.078727 -338.409048) (xy 97.024779 -338.401292)
			(xy 96.972484 -338.385937) (xy 96.922907 -338.363295) (xy 96.877057 -338.333829) (xy 96.835866 -338.298138)
			(xy 96.800175 -338.256947) (xy 96.770709 -338.211097) (xy 96.748067 -338.16152) (xy 96.732712 -338.109225)
			(xy 96.724956 -338.055277) (xy 96.72447 -338.028026) (xy 96.725001 -337.998121) (xy 96.734316 -337.939042)
			(xy 96.743012 -337.910424) (xy 96.74706 -337.896519) (xy 96.747965 -337.867586) (xy 96.740696 -337.839565)
			(xy 96.725842 -337.81472) (xy 96.704599 -337.795054) (xy 96.678684 -337.782155) (xy 96.664526 -337.779106)
			(xy 96.631688 -337.772518) (xy 96.568835 -337.749399) (xy 96.539558 -337.733132) (xy 96.526602 -337.726078)
			(xy 96.497962 -337.71905) (xy 96.468508 -337.720499) (xy 96.440696 -337.730304) (xy 96.416846 -337.747648)
			(xy 96.398947 -337.771083) (xy 96.393254 -337.784694) (xy 96.382526 -337.811457) (xy 96.354243 -337.861698)
			(xy 96.318718 -337.907108) (xy 96.276761 -337.946651) (xy 96.229328 -337.979427) (xy 96.177501 -338.004687)
			(xy 96.122462 -338.021856) (xy 96.065465 -338.030542) (xy 96.036638 -338.031074) (xy 96.009381 -338.030682)
			(xy 95.955421 -338.022928) (xy 95.903114 -338.007574) (xy 95.853525 -337.984932) (xy 95.807662 -337.955462)
			(xy 95.766462 -337.919765) (xy 95.730761 -337.878568) (xy 95.701286 -337.832709) (xy 95.678639 -337.783122)
			(xy 95.66328 -337.730816) (xy 95.655521 -337.676857) (xy 95.335442 -337.676857) (xy 95.312908 -337.708268)
			(xy 95.271238 -337.75057) (xy 95.247714 -337.768692) (xy 95.237079 -337.777087) (xy 95.220368 -337.798405)
			(xy 95.209849 -337.823367) (xy 95.206262 -337.850216) (xy 95.209858 -337.877063) (xy 95.220384 -337.902021)
			(xy 95.237101 -337.923335) (xy 95.247714 -337.93176) (xy 95.271256 -337.949857) (xy 95.312914 -337.992169)
			(xy 95.347515 -338.040424) (xy 95.374222 -338.093457) (xy 95.392391 -338.149987) (xy 95.401584 -338.208649)
			(xy 95.402146 -338.238338) (xy 95.40166 -338.265589) (xy 95.393904 -338.319537) (xy 95.378549 -338.371832)
			(xy 95.355907 -338.421409) (xy 95.326441 -338.467259) (xy 95.29075 -338.50845) (xy 95.249559 -338.544141)
			(xy 95.203709 -338.573607) (xy 95.154132 -338.596249) (xy 95.101837 -338.611604) (xy 95.047889 -338.61936)
			(xy 94.993387 -338.61936) (xy 94.939439 -338.611604) (xy 94.887144 -338.596249) (xy 94.837567 -338.573607)
			(xy 94.791717 -338.544141) (xy 94.750526 -338.50845) (xy 94.714835 -338.467259) (xy 94.685369 -338.421409)
			(xy 94.662727 -338.371832) (xy 94.647372 -338.319537) (xy 94.639616 -338.265589) (xy 94.63913 -338.238338)
			(xy 85.513487 -338.238338) (xy 85.497013 -338.253124) (xy 85.452672 -338.282917) (xy 85.428836 -338.29498)
			(xy 85.415646 -338.301849) (xy 85.393733 -338.32194) (xy 85.378532 -338.347489) (xy 85.371329 -338.376332)
			(xy 85.372735 -338.406028) (xy 85.382631 -338.434062) (xy 85.39099 -338.446364) (xy 85.408342 -338.471021)
			(xy 85.435855 -338.524669) (xy 85.454589 -338.581976) (xy 85.464077 -338.641516) (xy 85.46465 -338.671662)
			(xy 85.464164 -338.698913) (xy 85.456408 -338.752861) (xy 85.441053 -338.805156) (xy 85.418411 -338.854733)
			(xy 85.388945 -338.900583) (xy 85.353254 -338.941774) (xy 85.312063 -338.977465) (xy 85.293803 -338.9892)
			(xy 89.129495 -338.9892) (xy 89.133664 -338.933573) (xy 89.146078 -338.879188) (xy 89.16646 -338.827262)
			(xy 89.194353 -338.778953) (xy 89.229135 -338.735342) (xy 89.27003 -338.697402) (xy 89.316122 -338.665981)
			(xy 89.366383 -338.641782) (xy 89.419689 -338.625344) (xy 89.47485 -338.617036) (xy 89.502742 -338.616544)
			(xy 89.530074 -338.617024) (xy 89.584153 -338.624991) (xy 89.636488 -338.640777) (xy 89.685952 -338.664044)
			(xy 89.731485 -338.69429) (xy 89.772107 -338.730868) (xy 89.806946 -338.77299) (xy 89.821512 -338.796122)
			(xy 89.829441 -338.808342) (xy 89.850912 -338.82801) (xy 89.877063 -338.840814) (xy 89.905767 -338.845711)
			(xy 89.934684 -338.842302) (xy 89.948258 -338.837016) (xy 89.971464 -338.827517) (xy 90.019799 -338.814169)
			(xy 90.06949 -338.807445) (xy 90.094562 -338.807044) (xy 90.119632 -338.807458) (xy 90.169315 -338.814212)
			(xy 90.217649 -338.827548) (xy 90.240866 -338.837016) (xy 90.254444 -338.84226) (xy 90.283344 -338.845625)
			(xy 90.312022 -338.840714) (xy 90.338156 -338.827926) (xy 90.359631 -338.808296) (xy 90.367612 -338.796122)
			(xy 90.382181 -338.772991) (xy 90.417024 -338.73087) (xy 90.457647 -338.694291) (xy 90.503178 -338.66404)
			(xy 90.55264 -338.640764) (xy 90.604971 -338.624964) (xy 90.65905 -338.616978) (xy 90.713714 -338.616978)
			(xy 90.767793 -338.624964) (xy 90.820124 -338.640764) (xy 90.869586 -338.66404) (xy 90.915117 -338.694291)
			(xy 90.95574 -338.73087) (xy 90.990583 -338.772991) (xy 91.005152 -338.796122) (xy 91.013043 -338.808369)
			(xy 91.034524 -338.828038) (xy 91.060686 -338.840838) (xy 91.089398 -338.845727) (xy 91.118322 -338.842308)
			(xy 91.131898 -338.837016) (xy 91.155111 -338.827536) (xy 91.203442 -338.814181) (xy 91.253131 -338.807449)
			(xy 91.278202 -338.807044) (xy 91.30584 -338.807554) (xy 91.360507 -338.815747) (xy 91.413365 -338.831923)
			(xy 91.463254 -338.855727) (xy 91.509081 -338.886638) (xy 91.549841 -338.923978) (xy 91.584639 -338.966928)
			(xy 91.612713 -339.014545) (xy 91.633448 -339.065787) (xy 91.640406 -339.09254) (xy 91.644031 -339.105642)
			(xy 91.657168 -339.129428) (xy 91.676113 -339.148908) (xy 91.699525 -339.162702) (xy 91.725746 -339.169834)
			(xy 91.752919 -339.169798) (xy 91.779121 -339.162598) (xy 91.791028 -339.15604) (xy 91.813174 -339.143407)
			(xy 91.860126 -339.123531) (xy 91.909309 -339.110095) (xy 91.959845 -339.103339) (xy 91.985338 -339.102954)
			(xy 91.993466 -339.102954) (xy 92.008325 -339.102719) (xy 92.036942 -339.094758) (xy 92.062067 -339.078913)
			(xy 92.081582 -339.056521) (xy 92.093844 -339.029466) (xy 92.096336 -339.014816) (xy 92.100451 -338.987679)
			(xy 92.115458 -338.934885) (xy 92.137872 -338.884785) (xy 92.167232 -338.838412) (xy 92.202933 -338.796724)
			(xy 92.244237 -338.76058) (xy 92.290293 -338.730725) (xy 92.34015 -338.707776) (xy 92.392781 -338.692205)
			(xy 92.447099 -338.684334) (xy 92.474542 -338.683854) (xy 92.501793 -338.684339) (xy 92.555738 -338.6921)
			(xy 92.608031 -338.707458) (xy 92.657606 -338.730102) (xy 92.703454 -338.759569) (xy 92.744643 -338.79526)
			(xy 92.780334 -338.836449) (xy 92.8098 -338.882298) (xy 92.832443 -338.931873) (xy 92.847801 -338.984166)
			(xy 92.848525 -338.9892) (xy 129.932095 -338.9892) (xy 129.936264 -338.933577) (xy 129.948676 -338.879196)
			(xy 129.969055 -338.827272) (xy 129.996944 -338.778966) (xy 130.031722 -338.735356) (xy 130.072612 -338.697416)
			(xy 130.118699 -338.665995) (xy 130.168955 -338.641793) (xy 130.222256 -338.625352) (xy 130.277412 -338.617039)
			(xy 130.305302 -338.616544) (xy 130.332635 -338.616977) (xy 130.386717 -338.624953) (xy 130.439052 -338.640747)
			(xy 130.488517 -338.664021) (xy 130.534049 -338.694275) (xy 130.57467 -338.730859) (xy 130.609508 -338.772987)
			(xy 130.624072 -338.796122) (xy 130.631944 -338.808383) (xy 130.65343 -338.828052) (xy 130.679597 -338.84085)
			(xy 130.708314 -338.845736) (xy 130.737242 -338.842311) (xy 130.750818 -338.837016) (xy 130.774029 -338.827529)
			(xy 130.822361 -338.814177) (xy 130.87205 -338.807448) (xy 130.897122 -338.807044) (xy 130.922191 -338.807471)
			(xy 130.971874 -338.814219) (xy 131.020209 -338.82755) (xy 131.043426 -338.837016) (xy 131.057019 -338.842218)
			(xy 131.085911 -338.845591) (xy 131.114584 -338.840691) (xy 131.140716 -338.827912) (xy 131.16219 -338.808292)
			(xy 131.170172 -338.796122) (xy 131.184741 -338.772991) (xy 131.219584 -338.73087) (xy 131.260207 -338.694291)
			(xy 131.305738 -338.66404) (xy 131.3552 -338.640764) (xy 131.407531 -338.624964) (xy 131.46161 -338.616978)
			(xy 131.516274 -338.616978) (xy 131.570353 -338.624964) (xy 131.622684 -338.640764) (xy 131.672146 -338.66404)
			(xy 131.717677 -338.694291) (xy 131.7583 -338.73087) (xy 131.793143 -338.772991) (xy 131.807712 -338.796122)
			(xy 131.815641 -338.808342) (xy 131.837112 -338.82801) (xy 131.863263 -338.840814) (xy 131.891967 -338.845711)
			(xy 131.920884 -338.842302) (xy 131.934458 -338.837016) (xy 131.957664 -338.827517) (xy 132.005999 -338.814169)
			(xy 132.05569 -338.807445) (xy 132.080762 -338.807044) (xy 132.105703 -338.807423) (xy 132.15514 -338.81407)
			(xy 132.203249 -338.827251) (xy 132.249171 -338.84673) (xy 132.292085 -338.872159) (xy 132.311902 -338.887308)
			(xy 132.3234 -338.89589) (xy 132.34993 -338.906786) (xy 132.378445 -338.909859) (xy 132.406688 -338.904866)
			(xy 132.432421 -338.892202) (xy 132.453607 -338.87287) (xy 132.461508 -338.860892) (xy 132.476508 -338.837421)
			(xy 132.512171 -338.794638) (xy 132.553678 -338.757497) (xy 132.600146 -338.726789) (xy 132.650587 -338.703166)
			(xy 132.703928 -338.687133) (xy 132.759033 -338.679028) (xy 132.786882 -338.67852) (xy 132.815037 -338.678965)
			(xy 132.870737 -338.687226) (xy 132.924618 -338.703587) (xy 132.975508 -338.727691) (xy 133.0223 -338.759016)
			(xy 133.06398 -338.796879) (xy 133.099639 -338.840459) (xy 133.128504 -338.888807) (xy 133.149947 -338.940874)
			(xy 133.157214 -338.96808) (xy 133.161562 -338.983021) (xy 133.177813 -339.009536) (xy 133.201287 -339.029935)
			(xy 133.229809 -339.042329) (xy 133.260739 -339.04557) (xy 133.276086 -339.04301) (xy 133.294869 -339.03944)
			(xy 133.332914 -339.035624) (xy 133.352032 -339.03539) (xy 133.379282 -339.035882) (xy 133.433226 -339.043642)
			(xy 133.485516 -339.059) (xy 133.535089 -339.081643) (xy 133.580935 -339.11111) (xy 133.622122 -339.146801)
			(xy 133.657809 -339.18799) (xy 133.687273 -339.233839) (xy 133.709911 -339.283414) (xy 133.725265 -339.335706)
			(xy 133.73302 -339.38965) (xy 133.73302 -339.44415) (xy 133.725265 -339.498094) (xy 133.709911 -339.550386)
			(xy 133.687273 -339.599961) (xy 133.657809 -339.64581) (xy 133.622122 -339.686999) (xy 133.580935 -339.72269)
			(xy 133.535089 -339.752157) (xy 133.485516 -339.7748) (xy 133.433226 -339.790158) (xy 133.379282 -339.797918)
			(xy 133.352032 -339.798406) (xy 133.323878 -339.797929) (xy 133.26818 -339.78967) (xy 133.214302 -339.773313)
			(xy 133.163413 -339.749212) (xy 133.116621 -339.717892) (xy 133.074942 -339.680033) (xy 133.039281 -339.636457)
			(xy 133.010414 -339.588113) (xy 132.988968 -339.53605) (xy 132.9817 -339.508846) (xy 132.977428 -339.493877)
			(xy 132.961165 -339.467351) (xy 132.937673 -339.446949) (xy 132.909129 -339.434563) (xy 132.878181 -339.431342)
			(xy 132.862828 -339.433916) (xy 132.844045 -339.437484) (xy 132.806 -339.441301) (xy 132.786882 -339.441536)
			(xy 132.760716 -339.441097) (xy 132.708871 -339.433986) (xy 132.658488 -339.419844) (xy 132.610515 -339.398938)
			(xy 132.565855 -339.371661) (xy 132.545328 -339.35543) (xy 132.533921 -339.346707) (xy 132.507553 -339.33537)
			(xy 132.47907 -339.331838) (xy 132.450732 -339.336391) (xy 132.424788 -339.348667) (xy 132.403298 -339.367692)
			(xy 132.395214 -339.37956) (xy 132.389483 -339.388432) (xy 132.377156 -339.405587) (xy 132.370576 -339.41385)
			(xy 132.361312 -339.426139) (xy 132.349909 -339.454705) (xy 132.347517 -339.485371) (xy 132.354353 -339.515361)
			(xy 132.369797 -339.541961) (xy 132.392453 -339.562764) (xy 132.406136 -339.569806) (xy 132.429267 -339.581168)
			(xy 132.472506 -339.609205) (xy 132.51157 -339.642817) (xy 132.545746 -339.681389) (xy 132.574408 -339.724217)
			(xy 132.597033 -339.770519) (xy 132.605526 -339.79485) (xy 132.610638 -339.808596) (xy 132.627402 -339.832642)
			(xy 132.650295 -339.850949) (xy 132.67744 -339.862015) (xy 132.706607 -339.864932) (xy 132.721096 -339.862668)
			(xy 132.739021 -339.859459) (xy 132.775277 -339.85602) (xy 132.793486 -339.85581) (xy 132.820739 -339.856268)
			(xy 132.874691 -339.864024) (xy 132.92699 -339.879379) (xy 132.976572 -339.902021) (xy 133.022426 -339.931489)
			(xy 133.063619 -339.967184) (xy 133.099313 -340.008377) (xy 133.128781 -340.054232) (xy 133.151422 -340.103813)
			(xy 133.166777 -340.156113) (xy 133.174532 -340.210065) (xy 133.174994 -340.237318) (xy 133.17474 -340.247732)
			(xy 133.174877 -340.262098) (xy 133.18214 -340.28988) (xy 133.196844 -340.314545) (xy 133.21783 -340.334145)
			(xy 133.24344 -340.347133) (xy 133.271652 -340.352484) (xy 133.285992 -340.351618) (xy 133.322568 -340.34984)
			(xy 133.349826 -340.350205) (xy 133.403787 -340.357959) (xy 133.456095 -340.373314) (xy 133.505686 -340.395958)
			(xy 133.551549 -340.425429) (xy 133.59275 -340.461127) (xy 133.628452 -340.502326) (xy 133.657927 -340.548186)
			(xy 133.680575 -340.597775) (xy 133.695934 -340.650082) (xy 133.703693 -340.704042) (xy 133.703693 -340.758558)
			(xy 133.695934 -340.812518) (xy 133.680575 -340.864825) (xy 133.657927 -340.914414) (xy 133.628452 -340.960274)
			(xy 133.59275 -341.001473) (xy 133.551549 -341.037171) (xy 133.505686 -341.066642) (xy 133.456095 -341.089286)
			(xy 133.403787 -341.104641) (xy 133.349826 -341.112395) (xy 133.322568 -341.112856) (xy 133.311557 -341.112774)
			(xy 133.289572 -341.111506) (xy 133.278626 -341.110316) (xy 133.263768 -341.109077) (xy 133.234433 -341.114331)
			(xy 133.207865 -341.127834) (xy 133.18633 -341.148435) (xy 133.171663 -341.174379) (xy 133.167882 -341.188802)
			(xy 133.161046 -341.216549) (xy 133.140188 -341.269751) (xy 133.111632 -341.31925) (xy 133.076016 -341.363938)
			(xy 133.034138 -341.402819) (xy 132.986931 -341.435023) (xy 132.935451 -341.45983) (xy 132.880849 -341.476686)
			(xy 132.824344 -341.485215) (xy 132.795772 -341.485728) (xy 132.766784 -341.485202) (xy 132.709477 -341.476427)
			(xy 132.654157 -341.459083) (xy 132.602097 -341.433569) (xy 132.554497 -341.400472) (xy 132.512452 -341.360556)
			(xy 132.476929 -341.314737) (xy 132.448748 -341.264073) (xy 132.428556 -341.209727) (xy 132.416818 -341.152952)
			(xy 132.414772 -341.124032) (xy 132.413612 -341.109956) (xy 132.40452 -341.083227) (xy 132.388444 -341.060018)
			(xy 132.366618 -341.042109) (xy 132.340716 -341.030875) (xy 132.312727 -341.027177) (xy 132.298694 -341.028782)
			(xy 132.28493 -341.030679) (xy 132.257216 -341.032711) (xy 132.243322 -341.032846) (xy 132.216073 -341.032301)
			(xy 132.162129 -341.024549) (xy 132.109838 -341.009198) (xy 132.060264 -340.986563) (xy 132.014415 -340.957102)
			(xy 131.973226 -340.921417) (xy 131.937534 -340.880233) (xy 131.908066 -340.834389) (xy 131.885423 -340.784818)
			(xy 131.870064 -340.732529) (xy 131.862303 -340.678587) (xy 131.861814 -340.651338) (xy 131.862301 -340.623764)
			(xy 131.870248 -340.569192) (xy 131.885969 -340.516332) (xy 131.909135 -340.466286) (xy 131.939264 -340.420096)
			(xy 131.975728 -340.378724) (xy 131.996434 -340.360508) (xy 132.00729 -340.350569) (xy 132.023358 -340.325929)
			(xy 132.031742 -340.297733) (xy 132.03175 -340.268316) (xy 132.023378 -340.240116) (xy 132.007322 -340.215468)
			(xy 131.996434 -340.205568) (xy 131.975711 -340.18737) (xy 131.93924 -340.145999) (xy 131.909109 -340.099807)
			(xy 131.885945 -340.049756) (xy 131.870231 -339.996891) (xy 131.862296 -339.942314) (xy 131.861814 -339.914738)
			(xy 131.862248 -339.888236) (xy 131.869597 -339.835744) (xy 131.884146 -339.784776) (xy 131.905614 -339.736314)
			(xy 131.933586 -339.691292) (xy 131.950206 -339.670644) (xy 131.959669 -339.658512) (xy 131.971464 -339.630107)
			(xy 131.974288 -339.599481) (xy 131.967888 -339.569398) (xy 131.95284 -339.542574) (xy 131.930504 -339.521431)
			(xy 131.916932 -339.51418) (xy 131.893237 -339.502088) (xy 131.849257 -339.472162) (xy 131.809977 -339.436289)
			(xy 131.776195 -339.395196) (xy 131.761992 -339.372702) (xy 131.754054 -339.360488) (xy 131.732587 -339.340817)
			(xy 131.706437 -339.328011) (xy 131.677736 -339.323113) (xy 131.648819 -339.326522) (xy 131.635246 -339.331808)
			(xy 131.61204 -339.341307) (xy 131.563705 -339.354654) (xy 131.514014 -339.361379) (xy 131.488942 -339.36178)
			(xy 131.463872 -339.361362) (xy 131.414189 -339.35461) (xy 131.365855 -339.341275) (xy 131.342638 -339.331808)
			(xy 131.329062 -339.326558) (xy 131.30016 -339.323191) (xy 131.27148 -339.328102) (xy 131.245345 -339.340892)
			(xy 131.223871 -339.360526) (xy 131.215892 -339.372702) (xy 131.201323 -339.395833) (xy 131.16648 -339.437954)
			(xy 131.125857 -339.474533) (xy 131.080326 -339.504784) (xy 131.030864 -339.52806) (xy 130.978533 -339.54386)
			(xy 130.924454 -339.551846) (xy 130.86979 -339.551846) (xy 130.815711 -339.54386) (xy 130.76338 -339.52806)
			(xy 130.713918 -339.504784) (xy 130.668387 -339.474533) (xy 130.627764 -339.437954) (xy 130.592921 -339.395833)
			(xy 130.578352 -339.372702) (xy 130.570452 -339.360461) (xy 130.548974 -339.34079) (xy 130.522815 -339.327987)
			(xy 130.494104 -339.323096) (xy 130.465181 -339.326516) (xy 130.451606 -339.331808) (xy 130.428393 -339.341288)
			(xy 130.380061 -339.354643) (xy 130.330373 -339.361375) (xy 130.305302 -339.36178) (xy 130.277412 -339.361361)
			(xy 130.222256 -339.353048) (xy 130.168955 -339.336607) (xy 130.118699 -339.312405) (xy 130.072612 -339.280984)
			(xy 130.031722 -339.243044) (xy 129.996944 -339.199434) (xy 129.969055 -339.151128) (xy 129.948676 -339.099204)
			(xy 129.936264 -339.044823) (xy 129.932095 -338.9892) (xy 92.848525 -338.9892) (xy 92.855562 -339.038111)
			(xy 92.85605 -339.065362) (xy 92.855523 -339.093963) (xy 92.846994 -339.150525) (xy 92.83012 -339.205182)
			(xy 92.80528 -339.256709) (xy 92.77303 -339.303952) (xy 92.734092 -339.345855) (xy 92.712032 -339.364066)
			(xy 92.701416 -339.373139) (xy 92.685125 -339.395806) (xy 92.675581 -339.422039) (xy 92.6735 -339.449875)
			(xy 92.679035 -339.477235) (xy 92.691773 -339.502074) (xy 92.710763 -339.522534) (xy 92.722446 -339.530182)
			(xy 92.746065 -339.545126) (xy 92.789079 -339.580814) (xy 92.826427 -339.622394) (xy 92.857311 -339.668977)
			(xy 92.881071 -339.719566) (xy 92.897198 -339.773079) (xy 92.905347 -339.828373) (xy 92.905834 -339.856318)
			(xy 92.905414 -339.882211) (xy 92.898413 -339.933522) (xy 92.884529 -339.983413) (xy 92.864018 -340.030964)
			(xy 92.849543 -340.054946) (xy 126.474472 -340.054946) (xy 126.478543 -339.999324) (xy 126.490669 -339.944887)
			(xy 126.510592 -339.892796) (xy 126.537888 -339.844161) (xy 126.571974 -339.800018) (xy 126.612123 -339.761309)
			(xy 126.657481 -339.728858) (xy 126.707081 -339.703357) (xy 126.759865 -339.68535) (xy 126.814708 -339.67522)
			(xy 126.870442 -339.673183) (xy 126.925879 -339.679283) (xy 126.979836 -339.693389) (xy 127.031165 -339.715201)
			(xy 127.078771 -339.744255) (xy 127.121639 -339.77993) (xy 127.158856 -339.821467) (xy 127.189629 -339.86798)
			(xy 127.213301 -339.918477) (xy 127.229369 -339.971884) (xy 127.237489 -340.02706) (xy 127.237998 -340.054946)
			(xy 127.237489 -340.082832) (xy 127.229369 -340.138008) (xy 127.213301 -340.191415) (xy 127.189629 -340.241912)
			(xy 127.158856 -340.288425) (xy 127.121639 -340.329962) (xy 127.078771 -340.365637) (xy 127.031165 -340.394691)
			(xy 126.979836 -340.416503) (xy 126.925879 -340.430609) (xy 126.870442 -340.436709) (xy 126.814708 -340.434672)
			(xy 126.759865 -340.424542) (xy 126.707081 -340.406535) (xy 126.657481 -340.381034) (xy 126.612123 -340.348583)
			(xy 126.571974 -340.309874) (xy 126.537888 -340.265731) (xy 126.510592 -340.217096) (xy 126.490669 -340.165005)
			(xy 126.478543 -340.110568) (xy 126.474472 -340.054946) (xy 92.849543 -340.054946) (xy 92.837257 -340.075301)
			(xy 92.80474 -340.115605) (xy 92.7862 -340.133686) (xy 92.776099 -340.143826) (xy 92.761486 -340.16842)
			(xy 92.754279 -340.196106) (xy 92.755045 -340.224704) (xy 92.763725 -340.251964) (xy 92.779634 -340.27574)
			(xy 92.790264 -340.285324) (xy 92.811084 -340.303523) (xy 92.847757 -340.344909) (xy 92.878062 -340.391161)
			(xy 92.901364 -340.441308) (xy 92.917173 -340.494297) (xy 92.925157 -340.549014) (xy 92.925646 -340.576662)
			(xy 92.925087 -340.603911) (xy 92.917336 -340.657854) (xy 92.910526 -340.681056) (xy 125.683008 -340.681056)
			(xy 125.687079 -340.625434) (xy 125.699205 -340.570997) (xy 125.719128 -340.518906) (xy 125.746424 -340.470271)
			(xy 125.78051 -340.426128) (xy 125.820659 -340.387419) (xy 125.866017 -340.354968) (xy 125.915617 -340.329467)
			(xy 125.968401 -340.31146) (xy 126.023244 -340.30133) (xy 126.078978 -340.299293) (xy 126.134415 -340.305393)
			(xy 126.188372 -340.319499) (xy 126.239701 -340.341311) (xy 126.287307 -340.370365) (xy 126.330175 -340.40604)
			(xy 126.367392 -340.447577) (xy 126.398165 -340.49409) (xy 126.421837 -340.544587) (xy 126.437905 -340.597994)
			(xy 126.446025 -340.65317) (xy 126.446534 -340.681056) (xy 126.446025 -340.708942) (xy 126.437905 -340.764118)
			(xy 126.421837 -340.817525) (xy 126.398165 -340.868022) (xy 126.367392 -340.914535) (xy 126.330175 -340.956072)
			(xy 126.287307 -340.991747) (xy 126.239701 -341.020801) (xy 126.188372 -341.042613) (xy 126.134415 -341.056719)
			(xy 126.078978 -341.062819) (xy 126.023244 -341.060782) (xy 125.968401 -341.050652) (xy 125.915617 -341.032645)
			(xy 125.866017 -341.007144) (xy 125.820659 -340.974693) (xy 125.78051 -340.935984) (xy 125.746424 -340.891841)
			(xy 125.719128 -340.843206) (xy 125.699205 -340.791115) (xy 125.687079 -340.736678) (xy 125.683008 -340.681056)
			(xy 92.910526 -340.681056) (xy 92.901988 -340.710145) (xy 92.879354 -340.759719) (xy 92.849895 -340.805568)
			(xy 92.814211 -340.846757) (xy 92.773029 -340.88245) (xy 92.727186 -340.911917) (xy 92.677616 -340.934561)
			(xy 92.625328 -340.94992) (xy 92.571386 -340.957681) (xy 92.544138 -340.95817) (xy 92.515061 -340.957651)
			(xy 92.45758 -340.948831) (xy 92.402103 -340.931388) (xy 92.349916 -340.905728) (xy 92.302229 -340.872445)
			(xy 92.260145 -340.83231) (xy 92.22464 -340.786252) (xy 92.196536 -340.73534) (xy 92.185998 -340.708234)
			(xy 92.180456 -340.694696) (xy 92.162994 -340.671244) (xy 92.1396 -340.653705) (xy 92.112194 -340.643518)
			(xy 92.083024 -340.641518) (xy 92.06865 -340.644226) (xy 92.048091 -340.648521) (xy 92.006339 -340.653098)
			(xy 91.985338 -340.65337) (xy 91.971122 -340.65321) (xy 91.942772 -340.65105) (xy 91.928696 -340.649052)
			(xy 91.913365 -340.647367) (xy 91.882917 -340.652173) (xy 91.855285 -340.665837) (xy 91.832982 -340.687116)
			(xy 91.818036 -340.714076) (xy 91.814396 -340.729062) (xy 91.807912 -340.757296) (xy 91.787671 -340.811571)
			(xy 91.759458 -340.862163) (xy 91.723922 -340.907908) (xy 91.68188 -340.947757) (xy 91.634297 -340.980792)
			(xy 91.582268 -341.006255) (xy 91.526987 -341.023561) (xy 91.469725 -341.032311) (xy 91.440762 -341.032846)
			(xy 91.413512 -341.032358) (xy 91.359566 -341.024597) (xy 91.307274 -341.009239) (xy 91.257699 -340.986596)
			(xy 91.21185 -340.957129) (xy 91.170662 -340.921438) (xy 91.134971 -340.88025) (xy 91.105504 -340.834401)
			(xy 91.082861 -340.784826) (xy 91.067503 -340.732534) (xy 91.059742 -340.678588) (xy 91.059254 -340.651338)
			(xy 91.059727 -340.623764) (xy 91.067675 -340.56919) (xy 91.083398 -340.51633) (xy 91.106566 -340.466283)
			(xy 91.136698 -340.420094) (xy 91.173166 -340.378723) (xy 91.193874 -340.360508) (xy 91.204735 -340.350572)
			(xy 91.220813 -340.325933) (xy 91.229203 -340.297735) (xy 91.22921 -340.268314) (xy 91.220833 -340.240112)
			(xy 91.204768 -340.215465) (xy 91.193874 -340.205568) (xy 91.173139 -340.187383) (xy 91.136672 -340.146008)
			(xy 91.106543 -340.099812) (xy 91.083382 -340.049759) (xy 91.06767 -339.996893) (xy 91.059736 -339.942314)
			(xy 91.059254 -339.914738) (xy 91.059701 -339.888237) (xy 91.06705 -339.835746) (xy 91.081596 -339.784778)
			(xy 91.10306 -339.736316) (xy 91.131029 -339.691293) (xy 91.147646 -339.670644) (xy 91.157095 -339.658503)
			(xy 91.168883 -339.630101) (xy 91.171706 -339.59948) (xy 91.165308 -339.569401) (xy 91.150267 -339.542579)
			(xy 91.127939 -339.521434) (xy 91.114372 -339.51418) (xy 91.090684 -339.502075) (xy 91.046702 -339.472154)
			(xy 91.00742 -339.436284) (xy 90.973636 -339.395194) (xy 90.959432 -339.372702) (xy 90.951551 -339.360448)
			(xy 90.930068 -339.340776) (xy 90.903903 -339.327975) (xy 90.875188 -339.323088) (xy 90.846262 -339.326513)
			(xy 90.832686 -339.331808) (xy 90.809475 -339.341295) (xy 90.761143 -339.354647) (xy 90.711454 -339.361376)
			(xy 90.686382 -339.36178) (xy 90.661313 -339.361349) (xy 90.61163 -339.354603) (xy 90.563296 -339.341273)
			(xy 90.540078 -339.331808) (xy 90.526487 -339.3266) (xy 90.497593 -339.323225) (xy 90.468919 -339.328125)
			(xy 90.442786 -339.340906) (xy 90.421312 -339.36053) (xy 90.413332 -339.372702) (xy 90.398763 -339.395833)
			(xy 90.36392 -339.437954) (xy 90.323297 -339.474533) (xy 90.277766 -339.504784) (xy 90.228304 -339.52806)
			(xy 90.175973 -339.54386) (xy 90.121894 -339.551846) (xy 90.06723 -339.551846) (xy 90.013151 -339.54386)
			(xy 89.96082 -339.52806) (xy 89.911358 -339.504784) (xy 89.865827 -339.474533) (xy 89.825204 -339.437954)
			(xy 89.790361 -339.395833) (xy 89.775792 -339.372702) (xy 89.767854 -339.360488) (xy 89.746387 -339.340817)
			(xy 89.720237 -339.328011) (xy 89.691536 -339.323113) (xy 89.662619 -339.326522) (xy 89.649046 -339.331808)
			(xy 89.62584 -339.341307) (xy 89.577505 -339.354654) (xy 89.527814 -339.361379) (xy 89.502742 -339.36178)
			(xy 89.47485 -339.361364) (xy 89.419689 -339.353056) (xy 89.366383 -339.336618) (xy 89.316122 -339.312419)
			(xy 89.27003 -339.280998) (xy 89.229135 -339.243058) (xy 89.194353 -339.199447) (xy 89.16646 -339.151138)
			(xy 89.146078 -339.099212) (xy 89.133664 -339.044827) (xy 89.129495 -338.9892) (xy 85.293803 -338.9892)
			(xy 85.266213 -339.006931) (xy 85.216636 -339.029573) (xy 85.164341 -339.044928) (xy 85.110393 -339.052684)
			(xy 85.055891 -339.052684) (xy 85.001943 -339.044928) (xy 84.949648 -339.029573) (xy 84.900071 -339.006931)
			(xy 84.854221 -338.977465) (xy 84.81303 -338.941774) (xy 84.777339 -338.900583) (xy 84.747873 -338.854733)
			(xy 84.725231 -338.805156) (xy 84.709876 -338.752861) (xy 84.70212 -338.698913) (xy 84.701634 -338.671662)
			(xy 76.372974 -338.671662) (xy 76.372974 -340.054946) (xy 85.671912 -340.054946) (xy 85.675983 -339.999324)
			(xy 85.688109 -339.944887) (xy 85.708032 -339.892796) (xy 85.735328 -339.844161) (xy 85.769414 -339.800018)
			(xy 85.809563 -339.761309) (xy 85.854921 -339.728858) (xy 85.904521 -339.703357) (xy 85.957305 -339.68535)
			(xy 86.012148 -339.67522) (xy 86.067882 -339.673183) (xy 86.123319 -339.679283) (xy 86.177276 -339.693389)
			(xy 86.228605 -339.715201) (xy 86.276211 -339.744255) (xy 86.319079 -339.77993) (xy 86.356296 -339.821467)
			(xy 86.387069 -339.86798) (xy 86.410741 -339.918477) (xy 86.426809 -339.971884) (xy 86.434929 -340.02706)
			(xy 86.435438 -340.054946) (xy 86.434929 -340.082832) (xy 86.426809 -340.138008) (xy 86.410741 -340.191415)
			(xy 86.387069 -340.241912) (xy 86.356296 -340.288425) (xy 86.319079 -340.329962) (xy 86.276211 -340.365637)
			(xy 86.228605 -340.394691) (xy 86.177276 -340.416503) (xy 86.123319 -340.430609) (xy 86.067882 -340.436709)
			(xy 86.012148 -340.434672) (xy 85.957305 -340.424542) (xy 85.904521 -340.406535) (xy 85.854921 -340.381034)
			(xy 85.809563 -340.348583) (xy 85.769414 -340.309874) (xy 85.735328 -340.265731) (xy 85.708032 -340.217096)
			(xy 85.688109 -340.165005) (xy 85.675983 -340.110568) (xy 85.671912 -340.054946) (xy 76.372974 -340.054946)
			(xy 76.372974 -341.059262) (xy 85.007448 -341.059262) (xy 85.011519 -341.00364) (xy 85.023645 -340.949203)
			(xy 85.043568 -340.897112) (xy 85.070864 -340.848477) (xy 85.10495 -340.804334) (xy 85.145099 -340.765625)
			(xy 85.190457 -340.733174) (xy 85.240057 -340.707673) (xy 85.292841 -340.689666) (xy 85.347684 -340.679536)
			(xy 85.403418 -340.677499) (xy 85.458855 -340.683599) (xy 85.512812 -340.697705) (xy 85.564141 -340.719517)
			(xy 85.611747 -340.748571) (xy 85.654615 -340.784246) (xy 85.691832 -340.825783) (xy 85.722605 -340.872296)
			(xy 85.746277 -340.922793) (xy 85.762345 -340.9762) (xy 85.770465 -341.031376) (xy 85.770974 -341.059262)
			(xy 85.770465 -341.087148) (xy 85.762345 -341.142324) (xy 85.746277 -341.195731) (xy 85.722605 -341.246228)
			(xy 85.691832 -341.292741) (xy 85.654615 -341.334278) (xy 85.611747 -341.369953) (xy 85.564141 -341.399007)
			(xy 85.512812 -341.420819) (xy 85.458855 -341.434925) (xy 85.403418 -341.441025) (xy 85.347684 -341.438988)
			(xy 85.292841 -341.428858) (xy 85.240057 -341.410851) (xy 85.190457 -341.38535) (xy 85.145099 -341.352899)
			(xy 85.10495 -341.31419) (xy 85.070864 -341.270047) (xy 85.043568 -341.221412) (xy 85.023645 -341.169321)
			(xy 85.011519 -341.114884) (xy 85.007448 -341.059262) (xy 76.372974 -341.059262) (xy 76.372974 -341.648542)
			(xy 86.478618 -341.648542) (xy 86.479196 -341.618855) (xy 86.488389 -341.560196) (xy 86.506559 -341.503671)
			(xy 86.533268 -341.450643) (xy 86.56787 -341.402394) (xy 86.609531 -341.360088) (xy 86.63305 -341.341964)
			(xy 86.643624 -341.333501) (xy 86.660324 -341.312195) (xy 86.670839 -341.28725) (xy 86.674432 -341.260418)
			(xy 86.670849 -341.233585) (xy 86.660342 -341.208636) (xy 86.64365 -341.187324) (xy 86.63305 -341.178896)
			(xy 86.609527 -341.160776) (xy 86.56787 -341.118467) (xy 86.533268 -341.070217) (xy 86.506558 -341.017189)
			(xy 86.488384 -340.960663) (xy 86.479184 -340.902005) (xy 86.478618 -340.872318) (xy 86.479104 -340.845067)
			(xy 86.48686 -340.791119) (xy 86.502215 -340.738824) (xy 86.524857 -340.689247) (xy 86.554323 -340.643397)
			(xy 86.590014 -340.602206) (xy 86.631205 -340.566515) (xy 86.677055 -340.537049) (xy 86.726632 -340.514407)
			(xy 86.778927 -340.499052) (xy 86.832875 -340.491296) (xy 86.887377 -340.491296) (xy 86.941325 -340.499052)
			(xy 86.99362 -340.514407) (xy 87.043197 -340.537049) (xy 87.089047 -340.566515) (xy 87.130238 -340.602206)
			(xy 87.165929 -340.643397) (xy 87.195395 -340.689247) (xy 87.218037 -340.738824) (xy 87.233392 -340.791119)
			(xy 87.241148 -340.845067) (xy 87.241634 -340.872318) (xy 87.241119 -340.902008) (xy 87.231915 -340.96067)
			(xy 87.213734 -341.017198) (xy 87.187013 -341.070226) (xy 87.174939 -341.087056) (xy 87.495025 -341.087056)
			(xy 87.495025 -341.032544) (xy 87.502783 -340.978586) (xy 87.518142 -340.926282) (xy 87.540788 -340.876696)
			(xy 87.570261 -340.830838) (xy 87.60596 -340.789642) (xy 87.647159 -340.753945) (xy 87.693019 -340.724476)
			(xy 87.742607 -340.701833) (xy 87.794912 -340.686478) (xy 87.84887 -340.678723) (xy 87.876126 -340.678262)
			(xy 87.901361 -340.678653) (xy 87.951396 -340.685273) (xy 88.000116 -340.698449) (xy 88.046667 -340.717947)
			(xy 88.068658 -340.730332) (xy 88.081597 -340.737424) (xy 88.110245 -340.744453) (xy 88.139706 -340.743)
			(xy 88.167523 -340.733188) (xy 88.191376 -340.715834) (xy 88.209273 -340.692386) (xy 88.214962 -340.67877)
			(xy 88.225657 -340.651993) (xy 88.253946 -340.601753) (xy 88.289477 -340.556344) (xy 88.331439 -340.516802)
			(xy 88.378876 -340.484029) (xy 88.430707 -340.458771) (xy 88.48575 -340.441604) (xy 88.542749 -340.43292)
			(xy 88.571578 -340.43239) (xy 88.59883 -340.432876) (xy 88.65278 -340.44063) (xy 88.705078 -340.455983)
			(xy 88.754657 -340.478623) (xy 88.800511 -340.508088) (xy 88.841703 -340.54378) (xy 88.877397 -340.58497)
			(xy 88.906866 -340.630821) (xy 88.929509 -340.6804) (xy 88.944865 -340.732696) (xy 88.952623 -340.786646)
			(xy 88.953086 -340.813898) (xy 88.952562 -340.843803) (xy 88.943242 -340.902883) (xy 88.934544 -340.9315)
			(xy 88.930537 -340.945417) (xy 88.929613 -340.974348) (xy 88.936868 -341.00237) (xy 88.951716 -341.027217)
			(xy 88.972956 -341.046881) (xy 88.998872 -341.059774) (xy 89.01303 -341.062818) (xy 89.039103 -341.067986)
			(xy 89.089607 -341.084557) (xy 89.13732 -341.107981) (xy 89.181318 -341.137803) (xy 89.220748 -341.173446)
			(xy 89.254847 -341.214219) (xy 89.282954 -341.259332) (xy 89.304524 -341.307912) (xy 89.319139 -341.359015)
			(xy 89.326516 -341.411654) (xy 89.326974 -341.43823) (xy 89.326488 -341.465481) (xy 89.318732 -341.519429)
			(xy 89.303377 -341.571724) (xy 89.280735 -341.621301) (xy 89.263228 -341.648542) (xy 127.281178 -341.648542)
			(xy 127.281772 -341.618856) (xy 127.290964 -341.560199) (xy 127.309132 -341.503674) (xy 127.335838 -341.450647)
			(xy 127.370437 -341.402397) (xy 127.412093 -341.360089) (xy 127.43561 -341.341964) (xy 127.446187 -341.333503)
			(xy 127.462893 -341.312198) (xy 127.473413 -341.287252) (xy 127.477007 -341.260418) (xy 127.473423 -341.233583)
			(xy 127.462912 -341.208633) (xy 127.446213 -341.187322) (xy 127.43561 -341.178896) (xy 127.4121 -341.16076)
			(xy 127.370439 -341.118456) (xy 127.335834 -341.07021) (xy 127.309121 -341.017184) (xy 127.290945 -340.960661)
			(xy 127.281744 -340.902005) (xy 127.281178 -340.872318) (xy 127.281664 -340.845067) (xy 127.28942 -340.791119)
			(xy 127.304775 -340.738824) (xy 127.327417 -340.689247) (xy 127.356883 -340.643397) (xy 127.392574 -340.602206)
			(xy 127.433765 -340.566515) (xy 127.479615 -340.537049) (xy 127.529192 -340.514407) (xy 127.581487 -340.499052)
			(xy 127.635435 -340.491296) (xy 127.689937 -340.491296) (xy 127.743885 -340.499052) (xy 127.79618 -340.514407)
			(xy 127.845757 -340.537049) (xy 127.891607 -340.566515) (xy 127.932798 -340.602206) (xy 127.968489 -340.643397)
			(xy 127.997955 -340.689247) (xy 128.020597 -340.738824) (xy 128.035952 -340.791119) (xy 128.043708 -340.845067)
			(xy 128.044194 -340.872318) (xy 128.043654 -340.902007) (xy 128.034453 -340.960667) (xy 128.016274 -341.017193)
			(xy 127.989558 -341.07022) (xy 127.977484 -341.087053) (xy 128.297648 -341.087053) (xy 128.297648 -341.032547)
			(xy 128.305405 -340.978597) (xy 128.32076 -340.926299) (xy 128.343402 -340.876719) (xy 128.372869 -340.830865)
			(xy 128.408562 -340.789672) (xy 128.449754 -340.753978) (xy 128.495606 -340.724509) (xy 128.545186 -340.701865)
			(xy 128.597483 -340.686508) (xy 128.651433 -340.678749) (xy 128.678686 -340.678262) (xy 128.703921 -340.67867)
			(xy 128.753954 -340.685286) (xy 128.802675 -340.698456) (xy 128.849227 -340.717949) (xy 128.871218 -340.730332)
			(xy 128.88418 -340.737377) (xy 128.912819 -340.744413) (xy 128.942273 -340.742969) (xy 128.970086 -340.733165)
			(xy 128.993936 -340.715821) (xy 129.011832 -340.692382) (xy 129.017522 -340.67877) (xy 129.02825 -340.652008)
			(xy 129.056536 -340.601769) (xy 129.092062 -340.556361) (xy 129.134019 -340.516818) (xy 129.181451 -340.484043)
			(xy 129.233277 -340.458783) (xy 129.288315 -340.441612) (xy 129.345311 -340.432923) (xy 129.374138 -340.43239)
			(xy 129.40139 -340.432842) (xy 129.455339 -340.440604) (xy 129.507634 -340.455964) (xy 129.557211 -340.478609)
			(xy 129.603061 -340.508079) (xy 129.644251 -340.543774) (xy 129.679942 -340.584967) (xy 129.709408 -340.63082)
			(xy 129.732049 -340.6804) (xy 129.747404 -340.732696) (xy 129.75516 -340.786646) (xy 129.755646 -340.813898)
			(xy 129.75512 -340.843803) (xy 129.745801 -340.902882) (xy 129.737104 -340.9315) (xy 129.733129 -340.945424)
			(xy 129.732206 -340.974348) (xy 129.739458 -341.002364) (xy 129.754299 -341.027207) (xy 129.77553 -341.046872)
			(xy 129.801436 -341.05977) (xy 129.81559 -341.062818) (xy 129.841657 -341.068015) (xy 129.892161 -341.084581)
			(xy 129.939874 -341.108) (xy 129.983873 -341.137818) (xy 130.023305 -341.173458) (xy 130.057405 -341.214228)
			(xy 130.085512 -341.259339) (xy 130.107083 -341.307916) (xy 130.121698 -341.359018) (xy 130.129076 -341.411654)
			(xy 130.129534 -341.43823) (xy 130.129048 -341.465481) (xy 130.121292 -341.519429) (xy 130.105937 -341.571724)
			(xy 130.083295 -341.621301) (xy 130.053829 -341.667151) (xy 130.018138 -341.708342) (xy 129.976947 -341.744033)
			(xy 129.931097 -341.773499) (xy 129.88152 -341.796141) (xy 129.829225 -341.811496) (xy 129.775277 -341.819252)
			(xy 129.720775 -341.819252) (xy 129.666827 -341.811496) (xy 129.614532 -341.796141) (xy 129.564955 -341.773499)
			(xy 129.519105 -341.744033) (xy 129.477914 -341.708342) (xy 129.442223 -341.667151) (xy 129.412757 -341.621301)
			(xy 129.390115 -341.571724) (xy 129.37476 -341.519429) (xy 129.367004 -341.465481) (xy 129.366518 -341.43823)
			(xy 129.367048 -341.408325) (xy 129.376364 -341.349246) (xy 129.38506 -341.320628) (xy 129.389144 -341.306731)
			(xy 129.390052 -341.27779) (xy 129.382781 -341.249762) (xy 129.367918 -341.224911) (xy 129.346665 -341.205246)
			(xy 129.320738 -341.192354) (xy 129.306574 -341.18931) (xy 129.273733 -341.182734) (xy 129.210882 -341.159606)
			(xy 129.181606 -341.143336) (xy 129.168622 -341.136337) (xy 129.139993 -341.1293) (xy 129.110547 -341.130739)
			(xy 129.082741 -341.140534) (xy 129.058894 -341.157867) (xy 129.040995 -341.181292) (xy 129.035302 -341.194898)
			(xy 129.02462 -341.22168) (xy 128.996331 -341.271923) (xy 128.9608 -341.317334) (xy 128.918836 -341.356877)
			(xy 128.871397 -341.38965) (xy 128.819563 -341.414906) (xy 128.764518 -341.43207) (xy 128.707516 -341.44075)
			(xy 128.678686 -341.441278) (xy 128.651433 -341.440851) (xy 128.597483 -341.433092) (xy 128.545186 -341.417735)
			(xy 128.495606 -341.395091) (xy 128.449754 -341.365622) (xy 128.408562 -341.329928) (xy 128.372869 -341.288735)
			(xy 128.343402 -341.242881) (xy 128.32076 -341.193301) (xy 128.305405 -341.141003) (xy 128.297648 -341.087053)
			(xy 127.977484 -341.087053) (xy 127.95495 -341.118469) (xy 127.913284 -341.160773) (xy 127.889762 -341.178896)
			(xy 127.879128 -341.187289) (xy 127.862426 -341.208611) (xy 127.851913 -341.233572) (xy 127.848327 -341.260418)
			(xy 127.851922 -341.287263) (xy 127.862444 -341.31222) (xy 127.879153 -341.333536) (xy 127.889762 -341.341964)
			(xy 127.913247 -341.360131) (xy 127.954911 -341.402427) (xy 127.989519 -341.450668) (xy 128.016237 -341.503687)
			(xy 128.034418 -341.560205) (xy 128.043625 -341.618857) (xy 128.044194 -341.648542) (xy 128.043708 -341.675793)
			(xy 128.035952 -341.729741) (xy 128.020597 -341.782036) (xy 127.997955 -341.831613) (xy 127.968489 -341.877463)
			(xy 127.932798 -341.918654) (xy 127.891607 -341.954345) (xy 127.845757 -341.983811) (xy 127.79618 -342.006453)
			(xy 127.743885 -342.021808) (xy 127.689937 -342.029564) (xy 127.635435 -342.029564) (xy 127.581487 -342.021808)
			(xy 127.529192 -342.006453) (xy 127.479615 -341.983811) (xy 127.433765 -341.954345) (xy 127.392574 -341.918654)
			(xy 127.356883 -341.877463) (xy 127.327417 -341.831613) (xy 127.304775 -341.782036) (xy 127.28942 -341.729741)
			(xy 127.281664 -341.675793) (xy 127.281178 -341.648542) (xy 89.263228 -341.648542) (xy 89.251269 -341.667151)
			(xy 89.215578 -341.708342) (xy 89.174387 -341.744033) (xy 89.128537 -341.773499) (xy 89.07896 -341.796141)
			(xy 89.026665 -341.811496) (xy 88.972717 -341.819252) (xy 88.918215 -341.819252) (xy 88.864267 -341.811496)
			(xy 88.811972 -341.796141) (xy 88.762395 -341.773499) (xy 88.716545 -341.744033) (xy 88.675354 -341.708342)
			(xy 88.639663 -341.667151) (xy 88.610197 -341.621301) (xy 88.587555 -341.571724) (xy 88.5722 -341.519429)
			(xy 88.564444 -341.465481) (xy 88.563958 -341.43823) (xy 88.564491 -341.408325) (xy 88.573805 -341.349246)
			(xy 88.5825 -341.320628) (xy 88.586553 -341.306724) (xy 88.587459 -341.277789) (xy 88.580191 -341.249768)
			(xy 88.565335 -341.224921) (xy 88.544091 -341.205255) (xy 88.518173 -341.192358) (xy 88.504014 -341.18931)
			(xy 88.471175 -341.182725) (xy 88.408323 -341.159603) (xy 88.379046 -341.143336) (xy 88.366097 -341.136266)
			(xy 88.337454 -341.12924) (xy 88.307998 -341.130691) (xy 88.280185 -341.140499) (xy 88.256334 -341.157846)
			(xy 88.238434 -341.181286) (xy 88.232742 -341.194898) (xy 88.222026 -341.221666) (xy 88.193742 -341.271908)
			(xy 88.158215 -341.317317) (xy 88.116256 -341.356861) (xy 88.068821 -341.389635) (xy 88.016993 -341.414895)
			(xy 87.961952 -341.432062) (xy 87.904954 -341.440747) (xy 87.876126 -341.441278) (xy 87.84887 -341.440877)
			(xy 87.794912 -341.433122) (xy 87.742607 -341.417767) (xy 87.693019 -341.395124) (xy 87.647159 -341.365655)
			(xy 87.60596 -341.329958) (xy 87.570261 -341.288762) (xy 87.540788 -341.242904) (xy 87.518142 -341.193318)
			(xy 87.502783 -341.141014) (xy 87.495025 -341.087056) (xy 87.174939 -341.087056) (xy 87.152399 -341.118473)
			(xy 87.110727 -341.160775) (xy 87.087202 -341.178896) (xy 87.076564 -341.187287) (xy 87.059855 -341.208607)
			(xy 87.049338 -341.233569) (xy 87.045751 -341.260418) (xy 87.049347 -341.287266) (xy 87.059874 -341.312224)
			(xy 87.07659 -341.333538) (xy 87.087202 -341.341964) (xy 87.110696 -341.36012) (xy 87.152357 -341.40242)
			(xy 87.186963 -341.450663) (xy 87.213679 -341.503684) (xy 87.231859 -341.560203) (xy 87.241065 -341.618856)
			(xy 87.241634 -341.648542) (xy 87.241148 -341.675793) (xy 87.233392 -341.729741) (xy 87.218037 -341.782036)
			(xy 87.195395 -341.831613) (xy 87.165929 -341.877463) (xy 87.130238 -341.918654) (xy 87.089047 -341.954345)
			(xy 87.043197 -341.983811) (xy 86.99362 -342.006453) (xy 86.941325 -342.021808) (xy 86.887377 -342.029564)
			(xy 86.832875 -342.029564) (xy 86.778927 -342.021808) (xy 86.726632 -342.006453) (xy 86.677055 -341.983811)
			(xy 86.631205 -341.954345) (xy 86.590014 -341.918654) (xy 86.554323 -341.877463) (xy 86.524857 -341.831613)
			(xy 86.502215 -341.782036) (xy 86.48686 -341.729741) (xy 86.479104 -341.675793) (xy 86.478618 -341.648542)
			(xy 76.372974 -341.648542) (xy 76.372974 -344.386662) (xy 76.764134 -344.386662) (xy 76.76463 -344.358787)
			(xy 76.772738 -344.30363) (xy 76.78879 -344.250241) (xy 76.812445 -344.199758) (xy 76.843197 -344.153257)
			(xy 76.861416 -344.132154) (xy 76.870999 -344.120785) (xy 76.883633 -344.093879) (xy 76.887962 -344.064472)
			(xy 76.883617 -344.035068) (xy 76.870968 -344.008169) (xy 76.861416 -343.996772) (xy 76.843231 -343.975642)
			(xy 76.812482 -343.929145) (xy 76.788826 -343.878668) (xy 76.772767 -343.825287) (xy 76.764646 -343.770136)
			(xy 76.764134 -343.742264) (xy 76.76462 -343.715013) (xy 76.772376 -343.661065) (xy 76.787731 -343.60877)
			(xy 76.810373 -343.559193) (xy 76.839839 -343.513343) (xy 76.87553 -343.472152) (xy 76.916721 -343.436461)
			(xy 76.962571 -343.406995) (xy 77.012148 -343.384353) (xy 77.064443 -343.368998) (xy 77.118391 -343.361242)
			(xy 77.172893 -343.361242) (xy 77.226841 -343.368998) (xy 77.279136 -343.384353) (xy 77.328713 -343.406995)
			(xy 77.374563 -343.436461) (xy 77.415754 -343.472152) (xy 77.451445 -343.513343) (xy 77.480911 -343.559193)
			(xy 77.503553 -343.60877) (xy 77.518908 -343.661065) (xy 77.526664 -343.715013) (xy 77.52715 -343.742264)
			(xy 77.526649 -343.770139) (xy 77.518539 -343.825295) (xy 77.502486 -343.878683) (xy 77.478834 -343.929165)
			(xy 77.448085 -343.975667) (xy 77.429868 -343.996772) (xy 77.420413 -344.008221) (xy 77.407861 -344.035111)
			(xy 77.403551 -344.064472) (xy 77.404598 -344.071632) (xy 96.449892 -344.071632) (xy 96.449892 -343.986936)
			(xy 96.457943 -343.902622) (xy 96.473972 -343.819456) (xy 96.497833 -343.738189) (xy 96.529312 -343.659559)
			(xy 96.568123 -343.584278) (xy 96.613913 -343.513026) (xy 96.666269 -343.44645) (xy 96.724717 -343.385152)
			(xy 96.788727 -343.329687) (xy 96.857719 -343.280558) (xy 96.931069 -343.238209) (xy 97.008112 -343.203025)
			(xy 97.088151 -343.175323) (xy 97.17046 -343.155355) (xy 97.254295 -343.143302) (xy 97.338896 -343.139272)
			(xy 97.423497 -343.143302) (xy 97.507332 -343.155355) (xy 97.589641 -343.175323) (xy 97.66968 -343.203025)
			(xy 97.746723 -343.238209) (xy 97.820073 -343.280558) (xy 97.889065 -343.329687) (xy 97.953075 -343.385152)
			(xy 98.011523 -343.44645) (xy 98.063879 -343.513026) (xy 98.109669 -343.584278) (xy 98.14848 -343.659559)
			(xy 98.179959 -343.738189) (xy 98.20382 -343.819456) (xy 98.219849 -343.902622) (xy 98.2279 -343.986936)
			(xy 98.228404 -344.029284) (xy 98.974405 -344.029284) (xy 98.978441 -343.945837) (xy 98.990513 -343.863169)
			(xy 99.010506 -343.782052) (xy 99.038235 -343.703243) (xy 99.073441 -343.627478) (xy 99.115795 -343.555465)
			(xy 99.164901 -343.487876) (xy 99.220302 -343.425342) (xy 99.281479 -343.368447) (xy 99.347862 -343.317721)
			(xy 99.41883 -343.27364) (xy 99.493722 -343.236614) (xy 99.571838 -343.206988) (xy 99.652448 -343.18504)
			(xy 99.7348 -343.170975) (xy 99.818126 -343.164923) (xy 99.901646 -343.166942) (xy 99.984582 -343.177012)
			(xy 100.066158 -343.19504) (xy 100.145614 -343.220857) (xy 100.222207 -343.254222) (xy 100.295223 -343.294823)
			(xy 100.363979 -343.342282) (xy 100.427833 -343.396155) (xy 100.48619 -343.45594) (xy 100.538505 -343.521077)
			(xy 100.584288 -343.59096) (xy 100.623113 -343.664935) (xy 100.654618 -343.742312) (xy 100.678507 -343.822369)
			(xy 100.694558 -343.904357) (xy 100.702621 -343.987512) (xy 100.703126 -344.029284) (xy 100.702621 -344.071056)
			(xy 100.702565 -344.071632) (xy 104.010456 -344.071632) (xy 104.010456 -343.986936) (xy 104.018507 -343.902622)
			(xy 104.034536 -343.819456) (xy 104.058397 -343.738189) (xy 104.089876 -343.659559) (xy 104.128687 -343.584278)
			(xy 104.174477 -343.513026) (xy 104.226833 -343.44645) (xy 104.285281 -343.385152) (xy 104.349291 -343.329687)
			(xy 104.418283 -343.280558) (xy 104.491633 -343.238209) (xy 104.568676 -343.203025) (xy 104.648715 -343.175323)
			(xy 104.731024 -343.155355) (xy 104.814859 -343.143302) (xy 104.89946 -343.139272) (xy 104.984061 -343.143302)
			(xy 105.067896 -343.155355) (xy 105.150205 -343.175323) (xy 105.230244 -343.203025) (xy 105.307287 -343.238209)
			(xy 105.380637 -343.280558) (xy 105.449629 -343.329687) (xy 105.513639 -343.385152) (xy 105.572087 -343.44645)
			(xy 105.624443 -343.513026) (xy 105.670233 -343.584278) (xy 105.709044 -343.659559) (xy 105.740523 -343.738189)
			(xy 105.764384 -343.819456) (xy 105.780413 -343.902622) (xy 105.788464 -343.986936) (xy 105.788968 -344.029284)
			(xy 106.534969 -344.029284) (xy 106.539005 -343.945837) (xy 106.551077 -343.863169) (xy 106.57107 -343.782052)
			(xy 106.598799 -343.703243) (xy 106.634005 -343.627478) (xy 106.676359 -343.555465) (xy 106.725465 -343.487876)
			(xy 106.780866 -343.425342) (xy 106.842043 -343.368447) (xy 106.908426 -343.317721) (xy 106.979394 -343.27364)
			(xy 107.054286 -343.236614) (xy 107.132402 -343.206988) (xy 107.213012 -343.18504) (xy 107.295364 -343.170975)
			(xy 107.37869 -343.164923) (xy 107.46221 -343.166942) (xy 107.545146 -343.177012) (xy 107.626722 -343.19504)
			(xy 107.706178 -343.220857) (xy 107.782771 -343.254222) (xy 107.855787 -343.294823) (xy 107.924543 -343.342282)
			(xy 107.988397 -343.396155) (xy 108.046754 -343.45594) (xy 108.099069 -343.521077) (xy 108.144852 -343.59096)
			(xy 108.183677 -343.664935) (xy 108.215182 -343.742312) (xy 108.239071 -343.822369) (xy 108.255122 -343.904357)
			(xy 108.263185 -343.987512) (xy 108.26369 -344.029284) (xy 108.263185 -344.071056) (xy 108.263129 -344.071632)
			(xy 111.7158 -344.071632) (xy 111.7158 -343.986936) (xy 111.723851 -343.902622) (xy 111.73988 -343.819456)
			(xy 111.763741 -343.738189) (xy 111.79522 -343.659559) (xy 111.834031 -343.584278) (xy 111.879821 -343.513026)
			(xy 111.932177 -343.44645) (xy 111.990625 -343.385152) (xy 112.054635 -343.329687) (xy 112.123627 -343.280558)
			(xy 112.196977 -343.238209) (xy 112.27402 -343.203025) (xy 112.354059 -343.175323) (xy 112.436368 -343.155355)
			(xy 112.520203 -343.143302) (xy 112.604804 -343.139272) (xy 112.689405 -343.143302) (xy 112.77324 -343.155355)
			(xy 112.855549 -343.175323) (xy 112.935588 -343.203025) (xy 113.012631 -343.238209) (xy 113.085981 -343.280558)
			(xy 113.154973 -343.329687) (xy 113.218983 -343.385152) (xy 113.277431 -343.44645) (xy 113.329787 -343.513026)
			(xy 113.375577 -343.584278) (xy 113.414388 -343.659559) (xy 113.445867 -343.738189) (xy 113.469728 -343.819456)
			(xy 113.485757 -343.902622) (xy 113.493808 -343.986936) (xy 113.494312 -344.029284) (xy 114.240313 -344.029284)
			(xy 114.244349 -343.945837) (xy 114.256421 -343.863169) (xy 114.276414 -343.782052) (xy 114.304143 -343.703243)
			(xy 114.339349 -343.627478) (xy 114.381703 -343.555465) (xy 114.430809 -343.487876) (xy 114.48621 -343.425342)
			(xy 114.547387 -343.368447) (xy 114.61377 -343.317721) (xy 114.684738 -343.27364) (xy 114.75963 -343.236614)
			(xy 114.837746 -343.206988) (xy 114.918356 -343.18504) (xy 115.000708 -343.170975) (xy 115.084034 -343.164923)
			(xy 115.167554 -343.166942) (xy 115.25049 -343.177012) (xy 115.332066 -343.19504) (xy 115.411522 -343.220857)
			(xy 115.488115 -343.254222) (xy 115.561131 -343.294823) (xy 115.629887 -343.342282) (xy 115.693741 -343.396155)
			(xy 115.752098 -343.45594) (xy 115.804413 -343.521077) (xy 115.850196 -343.59096) (xy 115.889021 -343.664935)
			(xy 115.920526 -343.742312) (xy 115.944415 -343.822369) (xy 115.960466 -343.904357) (xy 115.964765 -343.948696)
			(xy 119.176796 -343.948696) (xy 119.176796 -343.864) (xy 119.184847 -343.779686) (xy 119.200876 -343.69652)
			(xy 119.224737 -343.615253) (xy 119.256216 -343.536623) (xy 119.295027 -343.461342) (xy 119.340817 -343.39009)
			(xy 119.393173 -343.323514) (xy 119.451621 -343.262216) (xy 119.515631 -343.206751) (xy 119.584623 -343.157622)
			(xy 119.657973 -343.115273) (xy 119.735016 -343.080089) (xy 119.815055 -343.052387) (xy 119.897364 -343.032419)
			(xy 119.981199 -343.020366) (xy 120.0658 -343.016336) (xy 120.150401 -343.020366) (xy 120.234236 -343.032419)
			(xy 120.316545 -343.052387) (xy 120.396584 -343.080089) (xy 120.473627 -343.115273) (xy 120.546977 -343.157622)
			(xy 120.615969 -343.206751) (xy 120.679979 -343.262216) (xy 120.738427 -343.323514) (xy 120.790783 -343.39009)
			(xy 120.836573 -343.461342) (xy 120.875384 -343.536623) (xy 120.906863 -343.615253) (xy 120.930724 -343.69652)
			(xy 120.946753 -343.779686) (xy 120.954804 -343.864) (xy 120.955308 -343.906348) (xy 121.701309 -343.906348)
			(xy 121.705345 -343.822901) (xy 121.717417 -343.740233) (xy 121.73741 -343.659116) (xy 121.765139 -343.580307)
			(xy 121.800345 -343.504542) (xy 121.842699 -343.432529) (xy 121.891805 -343.36494) (xy 121.947206 -343.302406)
			(xy 122.008383 -343.245511) (xy 122.074766 -343.194785) (xy 122.145734 -343.150704) (xy 122.220626 -343.113678)
			(xy 122.298742 -343.084052) (xy 122.379352 -343.062104) (xy 122.461704 -343.048039) (xy 122.54503 -343.041987)
			(xy 122.62855 -343.044006) (xy 122.711486 -343.054076) (xy 122.793062 -343.072104) (xy 122.872518 -343.097921)
			(xy 122.949111 -343.131286) (xy 123.022127 -343.171887) (xy 123.090883 -343.219346) (xy 123.154737 -343.273219)
			(xy 123.213094 -343.333004) (xy 123.265409 -343.398141) (xy 123.311192 -343.468024) (xy 123.350017 -343.541999)
			(xy 123.381522 -343.619376) (xy 123.405411 -343.699433) (xy 123.421462 -343.781421) (xy 123.429525 -343.864576)
			(xy 123.43003 -343.906348) (xy 123.429525 -343.94812) (xy 123.421462 -344.031275) (xy 123.405411 -344.113263)
			(xy 123.381522 -344.19332) (xy 123.350017 -344.270697) (xy 123.311192 -344.344672) (xy 123.28984 -344.377264)
			(xy 133.84403 -344.377264) (xy 133.844468 -344.349893) (xy 133.852291 -344.295712) (xy 133.867787 -344.243208)
			(xy 133.890635 -344.193462) (xy 133.920366 -344.147497) (xy 133.93801 -344.126566) (xy 133.947281 -344.115264)
			(xy 133.959453 -344.088697) (xy 133.963618 -344.059773) (xy 133.959437 -344.030851) (xy 133.947251 -344.00429)
			(xy 133.93801 -343.992962) (xy 133.920388 -343.972016) (xy 133.890673 -343.926047) (xy 133.867834 -343.876303)
			(xy 133.852339 -343.823806) (xy 133.844506 -343.769632) (xy 133.84403 -343.742264) (xy 133.844516 -343.715013)
			(xy 133.852272 -343.661065) (xy 133.867627 -343.60877) (xy 133.890269 -343.559193) (xy 133.919735 -343.513343)
			(xy 133.955426 -343.472152) (xy 133.996617 -343.436461) (xy 134.042467 -343.406995) (xy 134.092044 -343.384353)
			(xy 134.144339 -343.368998) (xy 134.198287 -343.361242) (xy 134.252789 -343.361242) (xy 134.306737 -343.368998)
			(xy 134.359032 -343.384353) (xy 134.408609 -343.406995) (xy 134.454459 -343.436461) (xy 134.485224 -343.463118)
			(xy 143.511522 -343.463118) (xy 143.515593 -343.407496) (xy 143.527719 -343.353059) (xy 143.547642 -343.300968)
			(xy 143.574938 -343.252333) (xy 143.609024 -343.20819) (xy 143.649173 -343.169481) (xy 143.694531 -343.13703)
			(xy 143.744131 -343.111529) (xy 143.796915 -343.093522) (xy 143.851758 -343.083392) (xy 143.907492 -343.081355)
			(xy 143.962929 -343.087455) (xy 144.016886 -343.101561) (xy 144.068215 -343.123373) (xy 144.115821 -343.152427)
			(xy 144.158689 -343.188102) (xy 144.195906 -343.229639) (xy 144.226679 -343.276152) (xy 144.250351 -343.326649)
			(xy 144.266419 -343.380056) (xy 144.274539 -343.435232) (xy 144.275048 -343.463118) (xy 144.274539 -343.491004)
			(xy 144.26855 -343.531698) (xy 144.792952 -343.531698) (xy 144.797023 -343.476076) (xy 144.809149 -343.421639)
			(xy 144.829072 -343.369548) (xy 144.856368 -343.320913) (xy 144.890454 -343.27677) (xy 144.930603 -343.238061)
			(xy 144.975961 -343.20561) (xy 145.025561 -343.180109) (xy 145.078345 -343.162102) (xy 145.133188 -343.151972)
			(xy 145.188922 -343.149935) (xy 145.244359 -343.156035) (xy 145.298316 -343.170141) (xy 145.349645 -343.191953)
			(xy 145.397251 -343.221007) (xy 145.440119 -343.256682) (xy 145.477336 -343.298219) (xy 145.508109 -343.344732)
			(xy 145.531781 -343.395229) (xy 145.547849 -343.448636) (xy 145.555969 -343.503812) (xy 145.556478 -343.531698)
			(xy 145.555969 -343.559584) (xy 145.547849 -343.61476) (xy 145.531781 -343.668167) (xy 145.508109 -343.718664)
			(xy 145.477336 -343.765177) (xy 145.440119 -343.806714) (xy 145.397251 -343.842389) (xy 145.349645 -343.871443)
			(xy 145.298316 -343.893255) (xy 145.244359 -343.907361) (xy 145.188922 -343.913461) (xy 145.133188 -343.911424)
			(xy 145.078345 -343.901294) (xy 145.025561 -343.883287) (xy 144.975961 -343.857786) (xy 144.930603 -343.825335)
			(xy 144.890454 -343.786626) (xy 144.856368 -343.742483) (xy 144.829072 -343.693848) (xy 144.809149 -343.641757)
			(xy 144.797023 -343.58732) (xy 144.792952 -343.531698) (xy 144.26855 -343.531698) (xy 144.266419 -343.54618)
			(xy 144.250351 -343.599587) (xy 144.226679 -343.650084) (xy 144.195906 -343.696597) (xy 144.158689 -343.738134)
			(xy 144.115821 -343.773809) (xy 144.068215 -343.802863) (xy 144.016886 -343.824675) (xy 143.962929 -343.838781)
			(xy 143.907492 -343.844881) (xy 143.851758 -343.842844) (xy 143.796915 -343.832714) (xy 143.744131 -343.814707)
			(xy 143.694531 -343.789206) (xy 143.649173 -343.756755) (xy 143.609024 -343.718046) (xy 143.574938 -343.673903)
			(xy 143.547642 -343.625268) (xy 143.527719 -343.573177) (xy 143.515593 -343.51874) (xy 143.511522 -343.463118)
			(xy 134.485224 -343.463118) (xy 134.49565 -343.472152) (xy 134.531341 -343.513343) (xy 134.560807 -343.559193)
			(xy 134.583449 -343.60877) (xy 134.598804 -343.661065) (xy 134.60656 -343.715013) (xy 134.607046 -343.742264)
			(xy 134.606572 -343.769634) (xy 134.598758 -343.823813) (xy 134.583272 -343.876317) (xy 134.560431 -343.926064)
			(xy 134.530707 -343.972031) (xy 134.513066 -343.992962) (xy 134.503867 -344.004316) (xy 134.491689 -344.030865)
			(xy 134.487511 -344.059773) (xy 134.491674 -344.088683) (xy 134.503837 -344.115238) (xy 134.513066 -344.126566)
			(xy 134.530697 -344.147504) (xy 134.560411 -344.193475) (xy 134.583249 -344.243221) (xy 134.598742 -344.29572)
			(xy 134.606572 -344.349895) (xy 134.607046 -344.377264) (xy 134.60656 -344.404515) (xy 134.598804 -344.458463)
			(xy 134.583449 -344.510758) (xy 134.560807 -344.560335) (xy 134.531341 -344.606185) (xy 134.49565 -344.647376)
			(xy 134.454459 -344.683067) (xy 134.408609 -344.712533) (xy 134.359032 -344.735175) (xy 134.306737 -344.75053)
			(xy 134.252789 -344.758286) (xy 134.198287 -344.758286) (xy 134.144339 -344.75053) (xy 134.092044 -344.735175)
			(xy 134.042467 -344.712533) (xy 133.996617 -344.683067) (xy 133.955426 -344.647376) (xy 133.919735 -344.606185)
			(xy 133.890269 -344.560335) (xy 133.867627 -344.510758) (xy 133.852272 -344.458463) (xy 133.844516 -344.404515)
			(xy 133.84403 -344.377264) (xy 123.28984 -344.377264) (xy 123.265409 -344.414555) (xy 123.213094 -344.479692)
			(xy 123.154737 -344.539477) (xy 123.090883 -344.59335) (xy 123.022127 -344.640809) (xy 122.949111 -344.68141)
			(xy 122.872518 -344.714775) (xy 122.793062 -344.740592) (xy 122.711486 -344.75862) (xy 122.62855 -344.76869)
			(xy 122.54503 -344.770709) (xy 122.461704 -344.764657) (xy 122.379352 -344.750592) (xy 122.298742 -344.728644)
			(xy 122.220626 -344.699018) (xy 122.145734 -344.661992) (xy 122.074766 -344.617911) (xy 122.008383 -344.567185)
			(xy 121.947206 -344.51029) (xy 121.891805 -344.447756) (xy 121.842699 -344.380167) (xy 121.800345 -344.308154)
			(xy 121.765139 -344.232389) (xy 121.73741 -344.15358) (xy 121.717417 -344.072463) (xy 121.705345 -343.989795)
			(xy 121.701309 -343.906348) (xy 120.955308 -343.906348) (xy 120.954804 -343.948696) (xy 120.946753 -344.03301)
			(xy 120.930724 -344.116176) (xy 120.906863 -344.197443) (xy 120.875384 -344.276073) (xy 120.836573 -344.351354)
			(xy 120.790783 -344.422606) (xy 120.738427 -344.489182) (xy 120.679979 -344.55048) (xy 120.615969 -344.605945)
			(xy 120.546977 -344.655074) (xy 120.473627 -344.697423) (xy 120.396584 -344.732607) (xy 120.316545 -344.760309)
			(xy 120.23579 -344.7799) (xy 138.092587 -344.7799) (xy 138.096756 -344.724274) (xy 138.109169 -344.669891)
			(xy 138.129549 -344.617966) (xy 138.15744 -344.569658) (xy 138.19222 -344.526046) (xy 138.233112 -344.488106)
			(xy 138.279202 -344.456684) (xy 138.32946 -344.432482) (xy 138.382764 -344.416042) (xy 138.437923 -344.40773)
			(xy 138.465814 -344.407236) (xy 138.493148 -344.407663) (xy 138.547229 -344.41564) (xy 138.599565 -344.431436)
			(xy 138.649029 -344.454711) (xy 138.694561 -344.484966) (xy 138.735182 -344.52155) (xy 138.77002 -344.563679)
			(xy 138.784584 -344.586814) (xy 138.792541 -344.599014) (xy 138.814004 -344.618683) (xy 138.840148 -344.63149)
			(xy 138.868845 -344.636392) (xy 138.897758 -344.63299) (xy 138.91133 -344.627708) (xy 138.934539 -344.618217)
			(xy 138.982873 -344.604867) (xy 139.032562 -344.598139) (xy 139.057634 -344.597736) (xy 139.082703 -344.59816)
			(xy 139.132386 -344.604909) (xy 139.180721 -344.618242) (xy 139.203938 -344.627708) (xy 139.217525 -344.632926)
			(xy 139.246421 -344.636297) (xy 139.275096 -344.631393) (xy 139.301229 -344.618611) (xy 139.322703 -344.598986)
			(xy 139.330684 -344.586814) (xy 139.345253 -344.563683) (xy 139.380096 -344.521562) (xy 139.420719 -344.484983)
			(xy 139.46625 -344.454732) (xy 139.515712 -344.431456) (xy 139.568043 -344.415656) (xy 139.622122 -344.40767)
			(xy 139.676786 -344.40767) (xy 139.730865 -344.415656) (xy 139.783196 -344.431456) (xy 139.832658 -344.454732)
			(xy 139.878189 -344.484983) (xy 139.918812 -344.521562) (xy 139.953655 -344.563683) (xy 139.968224 -344.586814)
			(xy 139.976143 -344.599041) (xy 139.997616 -344.61871) (xy 140.023771 -344.631514) (xy 140.052476 -344.636408)
			(xy 140.081396 -344.632996) (xy 140.09497 -344.627708) (xy 140.118187 -344.618236) (xy 140.166516 -344.604878)
			(xy 140.216203 -344.598143) (xy 140.241274 -344.597736) (xy 140.268118 -344.598183) (xy 140.32125 -344.605885)
			(xy 140.372727 -344.621134) (xy 140.421482 -344.643612) (xy 140.466505 -344.672856) (xy 140.506866 -344.70826)
			(xy 140.541726 -344.74909) (xy 140.570366 -344.7945) (xy 140.592192 -344.843551) (xy 140.599922 -344.869262)
			(xy 140.604566 -344.883766) (xy 140.621088 -344.909332) (xy 140.644408 -344.928897) (xy 140.672456 -344.940726)
			(xy 140.702743 -344.943768) (xy 140.732583 -344.937755) (xy 140.746226 -344.930984) (xy 140.774377 -344.916361)
			(xy 140.834326 -344.89563) (xy 140.896882 -344.885128) (xy 140.928598 -344.884502) (xy 140.946617 -344.884727)
			(xy 140.982492 -344.888158) (xy 141.000226 -344.89136) (xy 141.015432 -344.893723) (xy 141.045988 -344.890188)
			(xy 141.074107 -344.877721) (xy 141.097243 -344.85745) (xy 141.113299 -344.831213) (xy 141.117574 -344.81643)
			(xy 141.124994 -344.789393) (xy 141.146623 -344.737669) (xy 141.175586 -344.689666) (xy 141.21126 -344.646416)
			(xy 141.252876 -344.608849) (xy 141.29954 -344.577774) (xy 141.350247 -344.55386) (xy 141.403907 -344.53762)
			(xy 141.459366 -344.529404) (xy 141.487398 -344.528902) (xy 141.514651 -344.529357) (xy 141.568603 -344.537114)
			(xy 141.620902 -344.55247) (xy 141.670482 -344.575113) (xy 141.716336 -344.604582) (xy 141.757529 -344.640277)
			(xy 141.793223 -344.68147) (xy 141.82269 -344.727325) (xy 141.845332 -344.776906) (xy 141.860688 -344.829205)
			(xy 141.868443 -344.883157) (xy 141.868906 -344.91041) (xy 141.868376 -344.937982) (xy 141.860437 -344.992552)
			(xy 141.844724 -345.045411) (xy 141.821566 -345.095457) (xy 141.791445 -345.141648) (xy 141.754988 -345.183022)
			(xy 141.734286 -345.20124) (xy 141.72338 -345.211129) (xy 141.707311 -345.235783) (xy 141.69893 -345.263992)
			(xy 141.698932 -345.293421) (xy 141.707317 -345.321629) (xy 141.723389 -345.34628) (xy 141.734286 -345.35618)
			(xy 141.755002 -345.374385) (xy 141.791467 -345.415757) (xy 141.821594 -345.461948) (xy 141.844757 -345.511997)
			(xy 141.860472 -345.564859) (xy 141.868412 -345.619432) (xy 141.868411 -345.674581) (xy 141.860469 -345.729154)
			(xy 141.844752 -345.782016) (xy 141.843402 -345.784932) (xy 144.561812 -345.784932) (xy 144.565883 -345.72931)
			(xy 144.578009 -345.674873) (xy 144.597932 -345.622782) (xy 144.625228 -345.574147) (xy 144.659314 -345.530004)
			(xy 144.699463 -345.491295) (xy 144.744821 -345.458844) (xy 144.794421 -345.433343) (xy 144.847205 -345.415336)
			(xy 144.902048 -345.405206) (xy 144.957782 -345.403169) (xy 145.013219 -345.409269) (xy 145.067176 -345.423375)
			(xy 145.118505 -345.445187) (xy 145.166111 -345.474241) (xy 145.208979 -345.509916) (xy 145.246196 -345.551453)
			(xy 145.276969 -345.597966) (xy 145.300641 -345.648463) (xy 145.316709 -345.70187) (xy 145.324829 -345.757046)
			(xy 145.325338 -345.784932) (xy 145.324829 -345.812818) (xy 145.316709 -345.867994) (xy 145.300641 -345.921401)
			(xy 145.276969 -345.971898) (xy 145.246196 -346.018411) (xy 145.208979 -346.059948) (xy 145.166111 -346.095623)
			(xy 145.118505 -346.124677) (xy 145.067176 -346.146489) (xy 145.013219 -346.160595) (xy 144.957782 -346.166695)
			(xy 144.902048 -346.164658) (xy 144.847205 -346.154528) (xy 144.794421 -346.136521) (xy 144.744821 -346.11102)
			(xy 144.699463 -346.078569) (xy 144.659314 -346.03986) (xy 144.625228 -345.995717) (xy 144.597932 -345.947082)
			(xy 144.578009 -345.894991) (xy 144.565883 -345.840554) (xy 144.561812 -345.784932) (xy 141.843402 -345.784932)
			(xy 141.821588 -345.832063) (xy 141.791459 -345.878254) (xy 141.754993 -345.919625) (xy 141.734286 -345.93784)
			(xy 141.72338 -345.947729) (xy 141.707311 -345.972383) (xy 141.69893 -346.000592) (xy 141.698932 -346.030021)
			(xy 141.707317 -346.058229) (xy 141.723389 -346.08288) (xy 141.734286 -346.09278) (xy 141.754988 -346.111001)
			(xy 141.791459 -346.152368) (xy 141.821593 -346.198555) (xy 141.844761 -346.248601) (xy 141.860479 -346.301462)
			(xy 141.86842 -346.356036) (xy 141.868906 -346.38361) (xy 141.868432 -346.410862) (xy 141.860674 -346.46481)
			(xy 141.845317 -346.517105) (xy 141.822675 -346.566682) (xy 141.793207 -346.612533) (xy 141.757514 -346.653723)
			(xy 141.716323 -346.689414) (xy 141.670472 -346.71888) (xy 141.620894 -346.741521) (xy 141.568598 -346.756876)
			(xy 141.51465 -346.764632) (xy 141.487398 -346.765118) (xy 141.459543 -346.764584) (xy 141.404429 -346.75646)
			(xy 141.35108 -346.740415) (xy 141.300628 -346.716789) (xy 141.254143 -346.686084) (xy 141.212614 -346.64895)
			(xy 141.17692 -346.606177) (xy 141.14782 -346.558672) (xy 141.125931 -346.507442) (xy 141.118336 -346.480638)
			(xy 141.114074 -346.466517) (xy 141.098685 -346.441368) (xy 141.076764 -346.42165) (xy 141.050131 -346.409)
			(xy 141.020997 -346.404469) (xy 141.006322 -346.405962) (xy 140.993305 -346.407627) (xy 140.967121 -346.40941)
			(xy 140.953998 -346.409518) (xy 140.939849 -346.409424) (xy 140.911626 -346.40739) (xy 140.89761 -346.405454)
			(xy 140.884268 -346.403791) (xy 140.857565 -346.406899) (xy 140.832604 -346.416882) (xy 140.811121 -346.433043)
			(xy 140.794611 -346.454258) (xy 140.784222 -346.479052) (xy 140.78204 -346.492322) (xy 140.777912 -346.519469)
			(xy 140.762943 -346.572297) (xy 140.740556 -346.622434) (xy 140.711213 -346.668844) (xy 140.67552 -346.710569)
			(xy 140.634215 -346.746746) (xy 140.588151 -346.776628) (xy 140.538278 -346.799598) (xy 140.485628 -346.815183)
			(xy 140.431288 -346.823058) (xy 140.403834 -346.823538) (xy 140.376583 -346.823013) (xy 140.322636 -346.815262)
			(xy 140.270341 -346.799911) (xy 140.220763 -346.777275) (xy 140.174911 -346.747813) (xy 140.133719 -346.712126)
			(xy 140.098025 -346.67094) (xy 140.068556 -346.625093) (xy 140.045911 -346.575519) (xy 140.030552 -346.523226)
			(xy 140.022791 -346.469281) (xy 140.022326 -346.44203) (xy 140.022803 -346.414456) (xy 140.030752 -346.359883)
			(xy 140.046474 -346.307023) (xy 140.069642 -346.256977) (xy 140.099773 -346.210787) (xy 140.136239 -346.169416)
			(xy 140.156946 -346.1512) (xy 140.167817 -346.141273) (xy 140.183899 -346.116633) (xy 140.192291 -346.088431)
			(xy 140.192296 -346.059007) (xy 140.183915 -346.030802) (xy 140.167843 -346.006156) (xy 140.156946 -345.99626)
			(xy 140.13627 -345.978011) (xy 140.099795 -345.936651) (xy 140.069657 -345.89047) (xy 140.046485 -345.840429)
			(xy 140.030762 -345.787573) (xy 140.022815 -345.733003) (xy 140.022326 -345.70543) (xy 140.022752 -345.678928)
			(xy 140.030103 -345.626435) (xy 140.044654 -345.575467) (xy 140.066123 -345.527005) (xy 140.094098 -345.481984)
			(xy 140.110718 -345.461336) (xy 140.120186 -345.449208) (xy 140.131978 -345.420802) (xy 140.1348 -345.390175)
			(xy 140.128399 -345.360092) (xy 140.113351 -345.333268) (xy 140.091015 -345.312124) (xy 140.077444 -345.304872)
			(xy 140.05375 -345.292778) (xy 140.009769 -345.262853) (xy 139.970489 -345.22698) (xy 139.936707 -345.185888)
			(xy 139.922504 -345.163394) (xy 139.914556 -345.151187) (xy 139.893091 -345.131517) (xy 139.866945 -345.11871)
			(xy 139.838245 -345.11381) (xy 139.809331 -345.117216) (xy 139.795758 -345.1225) (xy 139.77255 -345.131995)
			(xy 139.724216 -345.145344) (xy 139.674526 -345.15207) (xy 139.649454 -345.152472) (xy 139.624385 -345.152051)
			(xy 139.574701 -345.1453) (xy 139.526367 -345.131967) (xy 139.50315 -345.1225) (xy 139.489568 -345.117266)
			(xy 139.46067 -345.113897) (xy 139.431992 -345.118804) (xy 139.405858 -345.13159) (xy 139.384384 -345.15122)
			(xy 139.376404 -345.163394) (xy 139.361835 -345.186525) (xy 139.326992 -345.228646) (xy 139.286369 -345.265225)
			(xy 139.240838 -345.295476) (xy 139.191376 -345.318752) (xy 139.139045 -345.334552) (xy 139.084966 -345.342538)
			(xy 139.030302 -345.342538) (xy 138.976223 -345.334552) (xy 138.923892 -345.318752) (xy 138.87443 -345.295476)
			(xy 138.828899 -345.265225) (xy 138.788276 -345.228646) (xy 138.753433 -345.186525) (xy 138.738864 -345.163394)
			(xy 138.730954 -345.15116) (xy 138.709479 -345.13149) (xy 138.683322 -345.118687) (xy 138.654614 -345.113794)
			(xy 138.625692 -345.11721) (xy 138.612118 -345.1225) (xy 138.588903 -345.131976) (xy 138.540573 -345.145332)
			(xy 138.490885 -345.152066) (xy 138.465814 -345.152472) (xy 138.437923 -345.15207) (xy 138.382764 -345.143758)
			(xy 138.32946 -345.127318) (xy 138.279202 -345.103116) (xy 138.233112 -345.071694) (xy 138.19222 -345.033754)
			(xy 138.15744 -344.990143) (xy 138.129549 -344.941834) (xy 138.109169 -344.889909) (xy 138.096756 -344.835526)
			(xy 138.092587 -344.7799) (xy 120.23579 -344.7799) (xy 120.234236 -344.780277) (xy 120.150401 -344.79233)
			(xy 120.0658 -344.796361) (xy 119.981199 -344.79233) (xy 119.897364 -344.780277) (xy 119.815055 -344.760309)
			(xy 119.735016 -344.732607) (xy 119.657973 -344.697423) (xy 119.584623 -344.655074) (xy 119.515631 -344.605945)
			(xy 119.451621 -344.55048) (xy 119.393173 -344.489182) (xy 119.340817 -344.422606) (xy 119.295027 -344.351354)
			(xy 119.256216 -344.276073) (xy 119.224737 -344.197443) (xy 119.200876 -344.116176) (xy 119.184847 -344.03301)
			(xy 119.176796 -343.948696) (xy 115.964765 -343.948696) (xy 115.968529 -343.987512) (xy 115.969034 -344.029284)
			(xy 115.968529 -344.071056) (xy 115.960466 -344.154211) (xy 115.944415 -344.236199) (xy 115.920526 -344.316256)
			(xy 115.889021 -344.393633) (xy 115.850196 -344.467608) (xy 115.804413 -344.537491) (xy 115.752098 -344.602628)
			(xy 115.693741 -344.662413) (xy 115.629887 -344.716286) (xy 115.561131 -344.763745) (xy 115.488115 -344.804346)
			(xy 115.411522 -344.837711) (xy 115.332066 -344.863528) (xy 115.25049 -344.881556) (xy 115.167554 -344.891626)
			(xy 115.084034 -344.893645) (xy 115.000708 -344.887593) (xy 114.918356 -344.873528) (xy 114.837746 -344.85158)
			(xy 114.75963 -344.821954) (xy 114.684738 -344.784928) (xy 114.61377 -344.740847) (xy 114.547387 -344.690121)
			(xy 114.48621 -344.633226) (xy 114.430809 -344.570692) (xy 114.381703 -344.503103) (xy 114.339349 -344.43109)
			(xy 114.304143 -344.355325) (xy 114.276414 -344.276516) (xy 114.256421 -344.195399) (xy 114.244349 -344.112731)
			(xy 114.240313 -344.029284) (xy 113.494312 -344.029284) (xy 113.493808 -344.071632) (xy 113.485757 -344.155946)
			(xy 113.469728 -344.239112) (xy 113.445867 -344.320379) (xy 113.414388 -344.399009) (xy 113.375577 -344.47429)
			(xy 113.329787 -344.545542) (xy 113.277431 -344.612118) (xy 113.218983 -344.673416) (xy 113.154973 -344.728881)
			(xy 113.085981 -344.77801) (xy 113.012631 -344.820359) (xy 112.935588 -344.855543) (xy 112.855549 -344.883245)
			(xy 112.77324 -344.903213) (xy 112.689405 -344.915266) (xy 112.604804 -344.919297) (xy 112.520203 -344.915266)
			(xy 112.436368 -344.903213) (xy 112.354059 -344.883245) (xy 112.27402 -344.855543) (xy 112.196977 -344.820359)
			(xy 112.123627 -344.77801) (xy 112.054635 -344.728881) (xy 111.990625 -344.673416) (xy 111.932177 -344.612118)
			(xy 111.879821 -344.545542) (xy 111.834031 -344.47429) (xy 111.79522 -344.399009) (xy 111.763741 -344.320379)
			(xy 111.73988 -344.239112) (xy 111.723851 -344.155946) (xy 111.7158 -344.071632) (xy 108.263129 -344.071632)
			(xy 108.255122 -344.154211) (xy 108.239071 -344.236199) (xy 108.215182 -344.316256) (xy 108.183677 -344.393633)
			(xy 108.144852 -344.467608) (xy 108.099069 -344.537491) (xy 108.046754 -344.602628) (xy 107.988397 -344.662413)
			(xy 107.924543 -344.716286) (xy 107.855787 -344.763745) (xy 107.782771 -344.804346) (xy 107.706178 -344.837711)
			(xy 107.626722 -344.863528) (xy 107.545146 -344.881556) (xy 107.46221 -344.891626) (xy 107.37869 -344.893645)
			(xy 107.295364 -344.887593) (xy 107.213012 -344.873528) (xy 107.132402 -344.85158) (xy 107.054286 -344.821954)
			(xy 106.979394 -344.784928) (xy 106.908426 -344.740847) (xy 106.842043 -344.690121) (xy 106.780866 -344.633226)
			(xy 106.725465 -344.570692) (xy 106.676359 -344.503103) (xy 106.634005 -344.43109) (xy 106.598799 -344.355325)
			(xy 106.57107 -344.276516) (xy 106.551077 -344.195399) (xy 106.539005 -344.112731) (xy 106.534969 -344.029284)
			(xy 105.788968 -344.029284) (xy 105.788464 -344.071632) (xy 105.780413 -344.155946) (xy 105.764384 -344.239112)
			(xy 105.740523 -344.320379) (xy 105.709044 -344.399009) (xy 105.670233 -344.47429) (xy 105.624443 -344.545542)
			(xy 105.572087 -344.612118) (xy 105.513639 -344.673416) (xy 105.449629 -344.728881) (xy 105.380637 -344.77801)
			(xy 105.307287 -344.820359) (xy 105.230244 -344.855543) (xy 105.150205 -344.883245) (xy 105.067896 -344.903213)
			(xy 104.984061 -344.915266) (xy 104.89946 -344.919297) (xy 104.814859 -344.915266) (xy 104.731024 -344.903213)
			(xy 104.648715 -344.883245) (xy 104.568676 -344.855543) (xy 104.491633 -344.820359) (xy 104.418283 -344.77801)
			(xy 104.349291 -344.728881) (xy 104.285281 -344.673416) (xy 104.226833 -344.612118) (xy 104.174477 -344.545542)
			(xy 104.128687 -344.47429) (xy 104.089876 -344.399009) (xy 104.058397 -344.320379) (xy 104.034536 -344.239112)
			(xy 104.018507 -344.155946) (xy 104.010456 -344.071632) (xy 100.702565 -344.071632) (xy 100.694558 -344.154211)
			(xy 100.678507 -344.236199) (xy 100.654618 -344.316256) (xy 100.623113 -344.393633) (xy 100.584288 -344.467608)
			(xy 100.538505 -344.537491) (xy 100.48619 -344.602628) (xy 100.427833 -344.662413) (xy 100.363979 -344.716286)
			(xy 100.295223 -344.763745) (xy 100.222207 -344.804346) (xy 100.145614 -344.837711) (xy 100.066158 -344.863528)
			(xy 99.984582 -344.881556) (xy 99.901646 -344.891626) (xy 99.818126 -344.893645) (xy 99.7348 -344.887593)
			(xy 99.652448 -344.873528) (xy 99.571838 -344.85158) (xy 99.493722 -344.821954) (xy 99.41883 -344.784928)
			(xy 99.347862 -344.740847) (xy 99.281479 -344.690121) (xy 99.220302 -344.633226) (xy 99.164901 -344.570692)
			(xy 99.115795 -344.503103) (xy 99.073441 -344.43109) (xy 99.038235 -344.355325) (xy 99.010506 -344.276516)
			(xy 98.990513 -344.195399) (xy 98.978441 -344.112731) (xy 98.974405 -344.029284) (xy 98.228404 -344.029284)
			(xy 98.2279 -344.071632) (xy 98.219849 -344.155946) (xy 98.20382 -344.239112) (xy 98.179959 -344.320379)
			(xy 98.14848 -344.399009) (xy 98.109669 -344.47429) (xy 98.063879 -344.545542) (xy 98.011523 -344.612118)
			(xy 97.953075 -344.673416) (xy 97.889065 -344.728881) (xy 97.820073 -344.77801) (xy 97.746723 -344.820359)
			(xy 97.66968 -344.855543) (xy 97.589641 -344.883245) (xy 97.507332 -344.903213) (xy 97.423497 -344.915266)
			(xy 97.338896 -344.919297) (xy 97.254295 -344.915266) (xy 97.17046 -344.903213) (xy 97.088151 -344.883245)
			(xy 97.008112 -344.855543) (xy 96.931069 -344.820359) (xy 96.857719 -344.77801) (xy 96.788727 -344.728881)
			(xy 96.724717 -344.673416) (xy 96.666269 -344.612118) (xy 96.613913 -344.545542) (xy 96.568123 -344.47429)
			(xy 96.529312 -344.399009) (xy 96.497833 -344.320379) (xy 96.473972 -344.239112) (xy 96.457943 -344.155946)
			(xy 96.449892 -344.071632) (xy 77.404598 -344.071632) (xy 77.407845 -344.093836) (xy 77.420383 -344.120733)
			(xy 77.429868 -344.132154) (xy 77.448078 -344.153263) (xy 77.478821 -344.199767) (xy 77.50247 -344.250249)
			(xy 77.518524 -344.303635) (xy 77.52664 -344.358788) (xy 77.52715 -344.386662) (xy 77.526664 -344.413913)
			(xy 77.518908 -344.467861) (xy 77.503553 -344.520156) (xy 77.480911 -344.569733) (xy 77.451445 -344.615583)
			(xy 77.415754 -344.656774) (xy 77.374563 -344.692465) (xy 77.328713 -344.721931) (xy 77.279136 -344.744573)
			(xy 77.226841 -344.759928) (xy 77.172893 -344.767684) (xy 77.118391 -344.767684) (xy 77.064443 -344.759928)
			(xy 77.012148 -344.744573) (xy 76.962571 -344.721931) (xy 76.916721 -344.692465) (xy 76.87553 -344.656774)
			(xy 76.839839 -344.615583) (xy 76.810373 -344.569733) (xy 76.787731 -344.520156) (xy 76.772376 -344.467861)
			(xy 76.76462 -344.413913) (xy 76.764134 -344.386662) (xy 76.372974 -344.386662) (xy 76.372974 -344.7799)
			(xy 80.968987 -344.7799) (xy 80.973156 -344.724273) (xy 80.98557 -344.669888) (xy 81.005951 -344.617961)
			(xy 81.033844 -344.569652) (xy 81.068626 -344.526041) (xy 81.109519 -344.4881) (xy 81.155611 -344.456678)
			(xy 81.205871 -344.432478) (xy 81.259178 -344.416039) (xy 81.314338 -344.407729) (xy 81.34223 -344.407236)
			(xy 81.369561 -344.407729) (xy 81.42364 -344.415694) (xy 81.475974 -344.431479) (xy 81.525438 -344.454743)
			(xy 81.570971 -344.484988) (xy 81.611594 -344.521563) (xy 81.646434 -344.563683) (xy 81.661 -344.586814)
			(xy 81.668942 -344.599025) (xy 81.690409 -344.618694) (xy 81.716557 -344.631499) (xy 81.745257 -344.636399)
			(xy 81.774173 -344.632992) (xy 81.787746 -344.627708) (xy 81.810954 -344.618212) (xy 81.859288 -344.604863)
			(xy 81.908978 -344.598138) (xy 81.93405 -344.597736) (xy 81.95912 -344.598155) (xy 82.008803 -344.604906)
			(xy 82.057137 -344.618241) (xy 82.080354 -344.627708) (xy 82.093935 -344.632943) (xy 82.122834 -344.63631)
			(xy 82.151511 -344.631403) (xy 82.177645 -344.618617) (xy 82.199119 -344.598987) (xy 82.2071 -344.586814)
			(xy 82.221669 -344.563683) (xy 82.256512 -344.521562) (xy 82.297135 -344.484983) (xy 82.342666 -344.454732)
			(xy 82.392128 -344.431456) (xy 82.444459 -344.415656) (xy 82.498538 -344.40767) (xy 82.553202 -344.40767)
			(xy 82.607281 -344.415656) (xy 82.659612 -344.431456) (xy 82.709074 -344.454732) (xy 82.754605 -344.484983)
			(xy 82.795228 -344.521562) (xy 82.830071 -344.563683) (xy 82.84464 -344.586814) (xy 82.852544 -344.599052)
			(xy 82.874021 -344.618721) (xy 82.90018 -344.631523) (xy 82.928889 -344.636415) (xy 82.957811 -344.632998)
			(xy 82.971386 -344.627708) (xy 82.994601 -344.618231) (xy 83.042931 -344.604875) (xy 83.092619 -344.598142)
			(xy 83.11769 -344.597736) (xy 83.144534 -344.598169) (xy 83.197667 -344.605873) (xy 83.249144 -344.621124)
			(xy 83.297899 -344.643605) (xy 83.342923 -344.67285) (xy 83.383283 -344.708255) (xy 83.418143 -344.749087)
			(xy 83.446783 -344.794498) (xy 83.468608 -344.843551) (xy 83.476338 -344.869262) (xy 83.480962 -344.883774)
			(xy 83.497487 -344.909342) (xy 83.520811 -344.928908) (xy 83.548863 -344.940736) (xy 83.579155 -344.943775)
			(xy 83.608998 -344.937758) (xy 83.622642 -344.930984) (xy 83.65079 -344.916355) (xy 83.71074 -344.895627)
			(xy 83.773298 -344.885126) (xy 83.805014 -344.884502) (xy 83.828133 -344.884836) (xy 83.874034 -344.890404)
			(xy 83.918922 -344.901491) (xy 83.94065 -344.909394) (xy 83.954434 -344.914181) (xy 83.983516 -344.916438)
			(xy 84.012051 -344.910385) (xy 84.037712 -344.896514) (xy 84.058407 -344.875956) (xy 84.072448 -344.850388)
			(xy 84.076032 -344.836242) (xy 84.082655 -344.808282) (xy 84.103249 -344.754639) (xy 84.131655 -344.704692)
			(xy 84.167231 -344.65957) (xy 84.209172 -344.620294) (xy 84.25653 -344.587753) (xy 84.308232 -344.562682)
			(xy 84.363109 -344.545649) (xy 84.41992 -344.537039) (xy 84.44865 -344.536522) (xy 84.475903 -344.537002)
			(xy 84.529855 -344.544753) (xy 84.582154 -344.560104) (xy 84.631736 -344.582743) (xy 84.677591 -344.612208)
			(xy 84.718785 -344.647901) (xy 84.75448 -344.689093) (xy 84.783947 -344.734946) (xy 84.806589 -344.784527)
			(xy 84.821943 -344.836826) (xy 84.829697 -344.890777) (xy 84.830158 -344.91803) (xy 84.82972 -344.945401)
			(xy 84.821897 -344.999582) (xy 84.806402 -345.052086) (xy 84.783554 -345.101832) (xy 84.753822 -345.147798)
			(xy 84.736178 -345.168728) (xy 84.726914 -345.180034) (xy 84.714743 -345.2066) (xy 84.710577 -345.235523)
			(xy 84.714756 -345.264444) (xy 84.726939 -345.291004) (xy 84.736178 -345.302332) (xy 84.753795 -345.323282)
			(xy 84.783511 -345.369249) (xy 84.806352 -345.418992) (xy 84.821848 -345.471489) (xy 84.829681 -345.525662)
			(xy 84.830158 -345.55303) (xy 84.829659 -345.580604) (xy 84.821715 -345.635176) (xy 84.805998 -345.688035)
			(xy 84.782834 -345.738082) (xy 84.752707 -345.784272) (xy 84.716243 -345.825644) (xy 84.695538 -345.84386)
			(xy 84.693568 -345.845638) (xy 134.634984 -345.845638) (xy 134.639055 -345.790016) (xy 134.651181 -345.735579)
			(xy 134.671104 -345.683488) (xy 134.6984 -345.634853) (xy 134.732486 -345.59071) (xy 134.772635 -345.552001)
			(xy 134.817993 -345.51955) (xy 134.867593 -345.494049) (xy 134.920377 -345.476042) (xy 134.97522 -345.465912)
			(xy 135.030954 -345.463875) (xy 135.086391 -345.469975) (xy 135.140348 -345.484081) (xy 135.191677 -345.505893)
			(xy 135.239283 -345.534947) (xy 135.282151 -345.570622) (xy 135.319368 -345.612159) (xy 135.350141 -345.658672)
			(xy 135.373813 -345.709169) (xy 135.389881 -345.762576) (xy 135.398001 -345.817752) (xy 135.39851 -345.845638)
			(xy 135.398001 -345.873524) (xy 135.389881 -345.9287) (xy 135.373813 -345.982107) (xy 135.350141 -346.032604)
			(xy 135.319368 -346.079117) (xy 135.282151 -346.120654) (xy 135.239283 -346.156329) (xy 135.191677 -346.185383)
			(xy 135.140348 -346.207195) (xy 135.086391 -346.221301) (xy 135.030954 -346.227401) (xy 134.97522 -346.225364)
			(xy 134.920377 -346.215234) (xy 134.867593 -346.197227) (xy 134.817993 -346.171726) (xy 134.772635 -346.139275)
			(xy 134.732486 -346.100566) (xy 134.6984 -346.056423) (xy 134.671104 -346.007788) (xy 134.651181 -345.955697)
			(xy 134.639055 -345.90126) (xy 134.634984 -345.845638) (xy 84.693568 -345.845638) (xy 84.684608 -345.853726)
			(xy 84.668531 -345.878384) (xy 84.660147 -345.906601) (xy 84.660153 -345.936037) (xy 84.668547 -345.964251)
			(xy 84.684633 -345.988903) (xy 84.695538 -345.9988) (xy 84.71626 -346.016999) (xy 84.752728 -346.058371)
			(xy 84.782858 -346.104564) (xy 84.806021 -346.154614) (xy 84.821736 -346.207479) (xy 84.829674 -346.262055)
			(xy 84.830158 -346.28963) (xy 84.829773 -346.316886) (xy 84.822011 -346.370842) (xy 84.806648 -346.423145)
			(xy 84.783998 -346.472728) (xy 84.760138 -346.509848) (xy 133.965948 -346.509848) (xy 133.970019 -346.454226)
			(xy 133.982145 -346.399789) (xy 134.002068 -346.347698) (xy 134.029364 -346.299063) (xy 134.06345 -346.25492)
			(xy 134.103599 -346.216211) (xy 134.148957 -346.18376) (xy 134.198557 -346.158259) (xy 134.251341 -346.140252)
			(xy 134.306184 -346.130122) (xy 134.361918 -346.128085) (xy 134.417355 -346.134185) (xy 134.471312 -346.148291)
			(xy 134.522641 -346.170103) (xy 134.570247 -346.199157) (xy 134.613115 -346.234832) (xy 134.650332 -346.276369)
			(xy 134.681105 -346.322882) (xy 134.704777 -346.373379) (xy 134.720845 -346.426786) (xy 134.728965 -346.481962)
			(xy 134.729474 -346.509848) (xy 134.728965 -346.537734) (xy 134.720845 -346.59291) (xy 134.704777 -346.646317)
			(xy 134.681105 -346.696814) (xy 134.650332 -346.743327) (xy 134.613115 -346.784864) (xy 134.570247 -346.820539)
			(xy 134.522641 -346.849593) (xy 134.471312 -346.871405) (xy 134.417355 -346.885511) (xy 134.361918 -346.891611)
			(xy 134.306184 -346.889574) (xy 134.251341 -346.879444) (xy 134.198557 -346.861437) (xy 134.148957 -346.835936)
			(xy 134.103599 -346.803485) (xy 134.06345 -346.764776) (xy 134.029364 -346.720633) (xy 134.002068 -346.671998)
			(xy 133.982145 -346.619907) (xy 133.970019 -346.56547) (xy 133.965948 -346.509848) (xy 84.760138 -346.509848)
			(xy 84.754523 -346.518584) (xy 84.718821 -346.559777) (xy 84.67762 -346.595471) (xy 84.631758 -346.624937)
			(xy 84.58217 -346.647576) (xy 84.529864 -346.662928) (xy 84.475906 -346.670679) (xy 84.44865 -346.671138)
			(xy 84.420776 -346.670626) (xy 84.365624 -346.662506) (xy 84.31224 -346.646446) (xy 84.261761 -346.622788)
			(xy 84.215263 -346.592036) (xy 84.173735 -346.554845) (xy 84.138062 -346.512006) (xy 84.109002 -346.464432)
			(xy 84.097622 -346.438982) (xy 84.090901 -346.424856) (xy 84.070496 -346.40117) (xy 84.043891 -346.384752)
			(xy 84.013571 -346.377136) (xy 83.982366 -346.379032) (xy 83.967574 -346.384118) (xy 83.945612 -346.392165)
			(xy 83.900228 -346.403485) (xy 83.853801 -346.409176) (xy 83.830414 -346.409518) (xy 83.816265 -346.409423)
			(xy 83.788042 -346.407389) (xy 83.774026 -346.405454) (xy 83.760682 -346.403807) (xy 83.733981 -346.406912)
			(xy 83.709021 -346.41689) (xy 83.687538 -346.433048) (xy 83.671028 -346.454261) (xy 83.660638 -346.479053)
			(xy 83.658456 -346.492322) (xy 83.654312 -346.519466) (xy 83.639344 -346.572293) (xy 83.616959 -346.622429)
			(xy 83.587617 -346.668838) (xy 83.551926 -346.710563) (xy 83.510623 -346.74674) (xy 83.464561 -346.776623)
			(xy 83.41469 -346.799594) (xy 83.362042 -346.81518) (xy 83.307703 -346.823057) (xy 83.28025 -346.823538)
			(xy 83.253 -346.822998) (xy 83.199053 -346.815249) (xy 83.146759 -346.799901) (xy 83.097181 -346.777266)
			(xy 83.051329 -346.747806) (xy 83.010136 -346.71212) (xy 82.974442 -346.670935) (xy 82.944972 -346.62509)
			(xy 82.922327 -346.575517) (xy 82.906968 -346.523225) (xy 82.899207 -346.46928) (xy 82.898742 -346.44203)
			(xy 82.899214 -346.414456) (xy 82.907163 -346.359882) (xy 82.922886 -346.307022) (xy 82.946055 -346.256976)
			(xy 82.976187 -346.210786) (xy 83.012655 -346.169415) (xy 83.033362 -346.1512) (xy 83.044232 -346.141273)
			(xy 83.060311 -346.116632) (xy 83.068702 -346.088431) (xy 83.068707 -346.059008) (xy 83.060328 -346.030803)
			(xy 83.044258 -346.006157) (xy 83.033362 -345.99626) (xy 83.012669 -345.978029) (xy 82.976199 -345.936664)
			(xy 82.946066 -345.890478) (xy 82.922897 -345.840434) (xy 82.907176 -345.787575) (xy 82.899231 -345.733003)
			(xy 82.898742 -345.70543) (xy 82.899165 -345.678928) (xy 82.906516 -345.626435) (xy 82.921067 -345.575466)
			(xy 82.942537 -345.527005) (xy 82.970513 -345.481984) (xy 82.987134 -345.461336) (xy 82.996597 -345.449205)
			(xy 83.008386 -345.420799) (xy 83.011207 -345.390174) (xy 83.004807 -345.360093) (xy 82.989762 -345.33327)
			(xy 82.96743 -345.312125) (xy 82.95386 -345.304872) (xy 82.930169 -345.292774) (xy 82.886187 -345.26285)
			(xy 82.846906 -345.226979) (xy 82.813123 -345.185887) (xy 82.79892 -345.163394) (xy 82.790957 -345.151198)
			(xy 82.769496 -345.131528) (xy 82.743354 -345.11872) (xy 82.714658 -345.113817) (xy 82.685746 -345.117219)
			(xy 82.672174 -345.1225) (xy 82.648964 -345.13199) (xy 82.600631 -345.145341) (xy 82.550942 -345.152069)
			(xy 82.52587 -345.152472) (xy 82.500801 -345.152046) (xy 82.451118 -345.145297) (xy 82.402783 -345.131966)
			(xy 82.379566 -345.1225) (xy 82.365978 -345.117283) (xy 82.337083 -345.11391) (xy 82.308408 -345.118814)
			(xy 82.282275 -345.131596) (xy 82.2608 -345.151222) (xy 82.25282 -345.163394) (xy 82.238251 -345.186525)
			(xy 82.203408 -345.228646) (xy 82.162785 -345.265225) (xy 82.117254 -345.295476) (xy 82.067792 -345.318752)
			(xy 82.015461 -345.334552) (xy 81.961382 -345.342538) (xy 81.906718 -345.342538) (xy 81.852639 -345.334552)
			(xy 81.800308 -345.318752) (xy 81.750846 -345.295476) (xy 81.705315 -345.265225) (xy 81.664692 -345.228646)
			(xy 81.629849 -345.186525) (xy 81.61528 -345.163394) (xy 81.607355 -345.151171) (xy 81.585884 -345.131501)
			(xy 81.559731 -345.118696) (xy 81.531026 -345.113801) (xy 81.502108 -345.117212) (xy 81.488534 -345.1225)
			(xy 81.465317 -345.131971) (xy 81.416988 -345.145329) (xy 81.367301 -345.152065) (xy 81.34223 -345.152472)
			(xy 81.314338 -345.152071) (xy 81.259178 -345.143761) (xy 81.205871 -345.127322) (xy 81.155611 -345.103122)
			(xy 81.109519 -345.0717) (xy 81.068626 -345.033759) (xy 81.033844 -344.990148) (xy 81.005951 -344.941839)
			(xy 80.98557 -344.889912) (xy 80.973156 -344.835527) (xy 80.968987 -344.7799) (xy 76.372974 -344.7799)
			(xy 76.372974 -345.845638) (xy 77.5114 -345.845638) (xy 77.515471 -345.790016) (xy 77.527597 -345.735579)
			(xy 77.54752 -345.683488) (xy 77.574816 -345.634853) (xy 77.608902 -345.59071) (xy 77.649051 -345.552001)
			(xy 77.694409 -345.51955) (xy 77.744009 -345.494049) (xy 77.796793 -345.476042) (xy 77.851636 -345.465912)
			(xy 77.90737 -345.463875) (xy 77.962807 -345.469975) (xy 78.016764 -345.484081) (xy 78.068093 -345.505893)
			(xy 78.115699 -345.534947) (xy 78.158567 -345.570622) (xy 78.195784 -345.612159) (xy 78.226557 -345.658672)
			(xy 78.250229 -345.709169) (xy 78.266297 -345.762576) (xy 78.274417 -345.817752) (xy 78.274926 -345.845638)
			(xy 78.274417 -345.873524) (xy 78.266297 -345.9287) (xy 78.250229 -345.982107) (xy 78.226557 -346.032604)
			(xy 78.195784 -346.079117) (xy 78.158567 -346.120654) (xy 78.115699 -346.156329) (xy 78.068093 -346.185383)
			(xy 78.016764 -346.207195) (xy 77.962807 -346.221301) (xy 77.90737 -346.227401) (xy 77.851636 -346.225364)
			(xy 77.796793 -346.215234) (xy 77.744009 -346.197227) (xy 77.694409 -346.171726) (xy 77.649051 -346.139275)
			(xy 77.608902 -346.100566) (xy 77.574816 -346.056423) (xy 77.54752 -346.007788) (xy 77.527597 -345.955697)
			(xy 77.515471 -345.90126) (xy 77.5114 -345.845638) (xy 76.372974 -345.845638) (xy 76.372974 -346.825062)
			(xy 76.846936 -346.825062) (xy 76.851007 -346.76944) (xy 76.863133 -346.715003) (xy 76.883056 -346.662912)
			(xy 76.910352 -346.614277) (xy 76.944438 -346.570134) (xy 76.984587 -346.531425) (xy 77.029945 -346.498974)
			(xy 77.079545 -346.473473) (xy 77.132329 -346.455466) (xy 77.187172 -346.445336) (xy 77.242906 -346.443299)
			(xy 77.298343 -346.449399) (xy 77.3523 -346.463505) (xy 77.403629 -346.485317) (xy 77.451235 -346.514371)
			(xy 77.494103 -346.550046) (xy 77.53132 -346.591583) (xy 77.562093 -346.638096) (xy 77.585765 -346.688593)
			(xy 77.601833 -346.742) (xy 77.609953 -346.797176) (xy 77.610462 -346.825062) (xy 77.609953 -346.852948)
			(xy 77.601833 -346.908124) (xy 77.585765 -346.961531) (xy 77.562093 -347.012028) (xy 77.53132 -347.058541)
			(xy 77.494103 -347.100078) (xy 77.451235 -347.135753) (xy 77.403629 -347.164807) (xy 77.3523 -347.186619)
			(xy 77.298343 -347.200725) (xy 77.242906 -347.206825) (xy 77.187172 -347.204788) (xy 77.132329 -347.194658)
			(xy 77.079545 -347.176651) (xy 77.029945 -347.15115) (xy 76.984587 -347.118699) (xy 76.944438 -347.07999)
			(xy 76.910352 -347.035847) (xy 76.883056 -346.987212) (xy 76.863133 -346.935121) (xy 76.851007 -346.880684)
			(xy 76.846936 -346.825062) (xy 76.372974 -346.825062) (xy 76.372974 -347.439234) (xy 78.318106 -347.439234)
			(xy 78.318683 -347.409547) (xy 78.327877 -347.350889) (xy 78.346048 -347.294363) (xy 78.372757 -347.241335)
			(xy 78.407359 -347.193086) (xy 78.449019 -347.15078) (xy 78.472538 -347.132656) (xy 78.483121 -347.124203)
			(xy 78.499823 -347.102895) (xy 78.510339 -347.077947) (xy 78.513931 -347.051113) (xy 78.510346 -347.024278)
			(xy 78.499836 -346.999328) (xy 78.48314 -346.978016) (xy 78.472538 -346.969588) (xy 78.44903 -346.951449)
			(xy 78.407367 -346.909147) (xy 78.372762 -346.860901) (xy 78.346048 -346.807876) (xy 78.327872 -346.751353)
			(xy 78.318672 -346.692697) (xy 78.318106 -346.66301) (xy 78.318592 -346.635759) (xy 78.326348 -346.581811)
			(xy 78.341703 -346.529516) (xy 78.364345 -346.479939) (xy 78.393811 -346.434089) (xy 78.429502 -346.392898)
			(xy 78.470693 -346.357207) (xy 78.516543 -346.327741) (xy 78.56612 -346.305099) (xy 78.618415 -346.289744)
			(xy 78.672363 -346.281988) (xy 78.726865 -346.281988) (xy 78.780813 -346.289744) (xy 78.833108 -346.305099)
			(xy 78.882685 -346.327741) (xy 78.928535 -346.357207) (xy 78.969726 -346.392898) (xy 79.005417 -346.434089)
			(xy 79.034883 -346.479939) (xy 79.057525 -346.529516) (xy 79.07288 -346.581811) (xy 79.080636 -346.635759)
			(xy 79.081122 -346.66301) (xy 79.080565 -346.692698) (xy 79.071366 -346.751356) (xy 79.05319 -346.807882)
			(xy 79.026477 -346.860909) (xy 79.014394 -346.877756) (xy 79.334517 -346.877756) (xy 79.334517 -346.823244)
			(xy 79.342275 -346.769286) (xy 79.357633 -346.716982) (xy 79.380279 -346.667396) (xy 79.409751 -346.621537)
			(xy 79.44545 -346.58034) (xy 79.486649 -346.544643) (xy 79.532508 -346.515172) (xy 79.582095 -346.492528)
			(xy 79.6344 -346.477172) (xy 79.688358 -346.469416) (xy 79.715614 -346.468954) (xy 79.740849 -346.469351)
			(xy 79.790883 -346.47597) (xy 79.839603 -346.489143) (xy 79.886155 -346.50864) (xy 79.908146 -346.521024)
			(xy 79.92109 -346.528106) (xy 79.949736 -346.535138) (xy 79.979196 -346.533688) (xy 80.007013 -346.523877)
			(xy 80.030865 -346.506525) (xy 80.048761 -346.483078) (xy 80.05445 -346.469462) (xy 80.065151 -346.442688)
			(xy 80.09344 -346.392448) (xy 80.12897 -346.34704) (xy 80.170931 -346.307498) (xy 80.218368 -346.274725)
			(xy 80.270197 -346.249466) (xy 80.325239 -346.232299) (xy 80.382238 -346.223613) (xy 80.411066 -346.223082)
			(xy 80.438318 -346.223587) (xy 80.492266 -346.231339) (xy 80.544563 -346.24669) (xy 80.594142 -346.269328)
			(xy 80.639995 -346.298792) (xy 80.681188 -346.334481) (xy 80.716882 -346.37567) (xy 80.746351 -346.421519)
			(xy 80.768994 -346.471096) (xy 80.784352 -346.52339) (xy 80.79211 -346.577338) (xy 80.792574 -346.60459)
			(xy 80.792049 -346.634495) (xy 80.782729 -346.693574) (xy 80.774032 -346.722192) (xy 80.769931 -346.736084)
			(xy 80.769028 -346.765028) (xy 80.776304 -346.793057) (xy 80.791169 -346.817907) (xy 80.812425 -346.837573)
			(xy 80.838354 -346.850466) (xy 80.852518 -346.85351) (xy 80.878588 -346.858694) (xy 80.929091 -346.875263)
			(xy 80.976803 -346.898685) (xy 81.020801 -346.928505) (xy 81.060232 -346.964146) (xy 81.094332 -347.004918)
			(xy 81.122439 -347.050029) (xy 81.144009 -347.098607) (xy 81.158625 -347.149709) (xy 81.166003 -347.202346)
			(xy 81.166462 -347.228922) (xy 81.165976 -347.256173) (xy 81.15822 -347.310121) (xy 81.142865 -347.362416)
			(xy 81.120223 -347.411993) (xy 81.102716 -347.439234) (xy 135.44169 -347.439234) (xy 135.442274 -347.409547)
			(xy 135.451467 -347.35089) (xy 135.469637 -347.294364) (xy 135.496345 -347.241337) (xy 135.530946 -347.193087)
			(xy 135.572604 -347.150781) (xy 135.596122 -347.132656) (xy 135.606706 -347.124204) (xy 135.623411 -347.102896)
			(xy 135.633929 -347.077948) (xy 135.637521 -347.051113) (xy 135.633936 -347.024277) (xy 135.623424 -346.999326)
			(xy 135.606725 -346.978015) (xy 135.596122 -346.969588) (xy 135.572611 -346.951453) (xy 135.530949 -346.90915)
			(xy 135.496344 -346.860903) (xy 135.469631 -346.807878) (xy 135.451455 -346.751354) (xy 135.442256 -346.692697)
			(xy 135.44169 -346.66301) (xy 135.442176 -346.635759) (xy 135.449932 -346.581811) (xy 135.465287 -346.529516)
			(xy 135.487929 -346.479939) (xy 135.517395 -346.434089) (xy 135.553086 -346.392898) (xy 135.594277 -346.357207)
			(xy 135.640127 -346.327741) (xy 135.689704 -346.305099) (xy 135.741999 -346.289744) (xy 135.795947 -346.281988)
			(xy 135.850449 -346.281988) (xy 135.904397 -346.289744) (xy 135.956692 -346.305099) (xy 136.006269 -346.327741)
			(xy 136.052119 -346.357207) (xy 136.09331 -346.392898) (xy 136.129001 -346.434089) (xy 136.158467 -346.479939)
			(xy 136.181109 -346.529516) (xy 136.196464 -346.581811) (xy 136.20422 -346.635759) (xy 136.204706 -346.66301)
			(xy 136.204156 -346.692698) (xy 136.194956 -346.751357) (xy 136.176779 -346.807883) (xy 136.150065 -346.860911)
			(xy 136.137984 -346.877754) (xy 136.45814 -346.877754) (xy 136.45814 -346.823246) (xy 136.465897 -346.769293)
			(xy 136.481254 -346.716993) (xy 136.503897 -346.667411) (xy 136.533366 -346.621557) (xy 136.569061 -346.580362)
			(xy 136.610255 -346.544667) (xy 136.65611 -346.515198) (xy 136.705692 -346.492554) (xy 136.757991 -346.477198)
			(xy 136.811944 -346.46944) (xy 136.839198 -346.468954) (xy 136.864433 -346.469358) (xy 136.914467 -346.475975)
			(xy 136.963187 -346.489146) (xy 137.009739 -346.508641) (xy 137.03173 -346.521024) (xy 137.044684 -346.528087)
			(xy 137.073326 -346.535122) (xy 137.102783 -346.533675) (xy 137.130598 -346.523868) (xy 137.154449 -346.506519)
			(xy 137.172345 -346.483076) (xy 137.178034 -346.469462) (xy 137.188748 -346.442694) (xy 137.217036 -346.392454)
			(xy 137.252564 -346.347046) (xy 137.294524 -346.307505) (xy 137.341958 -346.27473) (xy 137.393785 -346.249471)
			(xy 137.448825 -346.232302) (xy 137.505822 -346.223614) (xy 137.53465 -346.223082) (xy 137.561901 -346.223602)
			(xy 137.61585 -346.231352) (xy 137.668146 -346.246701) (xy 137.717725 -346.269337) (xy 137.763578 -346.298799)
			(xy 137.804771 -346.334487) (xy 137.840465 -346.375674) (xy 137.869934 -346.421522) (xy 137.892578 -346.471098)
			(xy 137.907936 -346.523392) (xy 137.915694 -346.577339) (xy 137.916158 -346.60459) (xy 137.915629 -346.634495)
			(xy 137.906312 -346.693574) (xy 137.897616 -346.722192) (xy 137.893528 -346.736087) (xy 137.892626 -346.765028)
			(xy 137.8999 -346.793054) (xy 137.914763 -346.817903) (xy 137.936014 -346.837569) (xy 137.961939 -346.850464)
			(xy 137.976102 -346.85351) (xy 138.002169 -346.858706) (xy 138.052672 -346.875273) (xy 138.100385 -346.898693)
			(xy 138.144384 -346.928511) (xy 138.183815 -346.964151) (xy 138.217914 -347.004921) (xy 138.246022 -347.050032)
			(xy 138.267593 -347.098609) (xy 138.282209 -347.14971) (xy 138.289587 -347.202347) (xy 138.290046 -347.228922)
			(xy 138.28956 -347.256173) (xy 138.281804 -347.310121) (xy 138.266449 -347.362416) (xy 138.243807 -347.411993)
			(xy 138.214341 -347.457843) (xy 138.17865 -347.499034) (xy 138.137459 -347.534725) (xy 138.091609 -347.564191)
			(xy 138.042032 -347.586833) (xy 137.989737 -347.602188) (xy 137.935789 -347.609944) (xy 137.881287 -347.609944)
			(xy 137.827339 -347.602188) (xy 137.775044 -347.586833) (xy 137.725467 -347.564191) (xy 137.679617 -347.534725)
			(xy 137.638426 -347.499034) (xy 137.602735 -347.457843) (xy 137.573269 -347.411993) (xy 137.550627 -347.362416)
			(xy 137.535272 -347.310121) (xy 137.527516 -347.256173) (xy 137.52703 -347.228922) (xy 137.527558 -347.199017)
			(xy 137.536875 -347.139938) (xy 137.545572 -347.11132) (xy 137.549656 -347.097423) (xy 137.550561 -347.068483)
			(xy 137.543289 -347.040456) (xy 137.528427 -347.015606) (xy 137.507175 -346.995941) (xy 137.481249 -346.983047)
			(xy 137.467086 -346.980002) (xy 137.434246 -346.973424) (xy 137.371394 -346.950298) (xy 137.342118 -346.934028)
			(xy 137.329125 -346.927047) (xy 137.3005 -346.920009) (xy 137.271058 -346.921446) (xy 137.243253 -346.931237)
			(xy 137.219407 -346.948565) (xy 137.201508 -346.971986) (xy 137.195814 -346.98559) (xy 137.185117 -347.012366)
			(xy 137.156831 -347.062609) (xy 137.121302 -347.10802) (xy 137.07934 -347.147563) (xy 137.031903 -347.180337)
			(xy 136.980071 -347.205595) (xy 136.925028 -347.22276) (xy 136.868027 -347.231441) (xy 136.839198 -347.23197)
			(xy 136.811944 -347.23156) (xy 136.757991 -347.223802) (xy 136.705692 -347.208446) (xy 136.65611 -347.185802)
			(xy 136.610255 -347.156333) (xy 136.569061 -347.120638) (xy 136.533366 -347.079443) (xy 136.503897 -347.033589)
			(xy 136.481254 -346.984007) (xy 136.465897 -346.931707) (xy 136.45814 -346.877754) (xy 136.137984 -346.877754)
			(xy 136.115458 -346.909159) (xy 136.073795 -346.951464) (xy 136.050274 -346.969588) (xy 136.039646 -346.97799)
			(xy 136.022942 -346.999309) (xy 136.012428 -347.024268) (xy 136.008841 -347.051113) (xy 136.012435 -347.077957)
			(xy 136.022956 -347.102914) (xy 136.039665 -347.124229) (xy 136.050274 -347.132656) (xy 136.073806 -347.150766)
			(xy 136.115466 -347.193074) (xy 136.150069 -347.241326) (xy 136.176779 -347.294357) (xy 136.19495 -347.350885)
			(xy 136.204144 -347.409546) (xy 136.204706 -347.439234) (xy 136.20422 -347.466485) (xy 136.196464 -347.520433)
			(xy 136.181109 -347.572728) (xy 136.158467 -347.622305) (xy 136.129001 -347.668155) (xy 136.09331 -347.709346)
			(xy 136.052119 -347.745037) (xy 136.006269 -347.774503) (xy 135.956692 -347.797145) (xy 135.904397 -347.8125)
			(xy 135.850449 -347.820256) (xy 135.795947 -347.820256) (xy 135.741999 -347.8125) (xy 135.689704 -347.797145)
			(xy 135.640127 -347.774503) (xy 135.594277 -347.745037) (xy 135.553086 -347.709346) (xy 135.517395 -347.668155)
			(xy 135.487929 -347.622305) (xy 135.465287 -347.572728) (xy 135.449932 -347.520433) (xy 135.442176 -347.466485)
			(xy 135.44169 -347.439234) (xy 81.102716 -347.439234) (xy 81.090757 -347.457843) (xy 81.055066 -347.499034)
			(xy 81.013875 -347.534725) (xy 80.968025 -347.564191) (xy 80.918448 -347.586833) (xy 80.866153 -347.602188)
			(xy 80.812205 -347.609944) (xy 80.757703 -347.609944) (xy 80.703755 -347.602188) (xy 80.65146 -347.586833)
			(xy 80.601883 -347.564191) (xy 80.556033 -347.534725) (xy 80.514842 -347.499034) (xy 80.479151 -347.457843)
			(xy 80.449685 -347.411993) (xy 80.427043 -347.362416) (xy 80.411688 -347.310121) (xy 80.403932 -347.256173)
			(xy 80.403446 -347.228922) (xy 80.403977 -347.199017) (xy 80.413293 -347.139938) (xy 80.421988 -347.11132)
			(xy 80.426059 -347.097421) (xy 80.426964 -347.068483) (xy 80.419693 -347.040458) (xy 80.404833 -347.01561)
			(xy 80.383585 -346.995944) (xy 80.357663 -346.983049) (xy 80.343502 -346.980002) (xy 80.310662 -346.97342)
			(xy 80.24781 -346.950297) (xy 80.218534 -346.934028) (xy 80.205591 -346.926948) (xy 80.176946 -346.919925)
			(xy 80.147488 -346.921379) (xy 80.119674 -346.931189) (xy 80.095823 -346.948537) (xy 80.077923 -346.971977)
			(xy 80.07223 -346.98559) (xy 80.06152 -347.012361) (xy 80.033235 -347.062603) (xy 79.997708 -347.108013)
			(xy 79.955748 -347.147557) (xy 79.908313 -347.180331) (xy 79.856483 -347.20559) (xy 79.801441 -347.222757)
			(xy 79.744442 -347.23144) (xy 79.715614 -347.23197) (xy 79.688358 -347.231584) (xy 79.6344 -347.223828)
			(xy 79.582095 -347.208472) (xy 79.532508 -347.185828) (xy 79.486649 -347.156357) (xy 79.44545 -347.12066)
			(xy 79.409751 -347.079463) (xy 79.380279 -347.033604) (xy 79.357633 -346.984018) (xy 79.342275 -346.931714)
			(xy 79.334517 -346.877756) (xy 79.014394 -346.877756) (xy 78.991872 -346.909158) (xy 78.95021 -346.951464)
			(xy 78.92669 -346.969588) (xy 78.916061 -346.977989) (xy 78.899354 -346.999307) (xy 78.888838 -347.024267)
			(xy 78.885251 -347.051113) (xy 78.888845 -347.077958) (xy 78.899368 -347.102916) (xy 78.91608 -347.12423)
			(xy 78.92669 -347.132656) (xy 78.950225 -347.150762) (xy 78.991885 -347.193071) (xy 79.026487 -347.241324)
			(xy 79.053195 -347.294356) (xy 79.071366 -347.350884) (xy 79.08056 -347.409545) (xy 79.081122 -347.439234)
			(xy 79.080636 -347.466485) (xy 79.07288 -347.520433) (xy 79.057525 -347.572728) (xy 79.034883 -347.622305)
			(xy 79.005417 -347.668155) (xy 78.969726 -347.709346) (xy 78.928535 -347.745037) (xy 78.882685 -347.774503)
			(xy 78.833108 -347.797145) (xy 78.780813 -347.8125) (xy 78.726865 -347.820256) (xy 78.672363 -347.820256)
			(xy 78.618415 -347.8125) (xy 78.56612 -347.797145) (xy 78.516543 -347.774503) (xy 78.470693 -347.745037)
			(xy 78.429502 -347.709346) (xy 78.393811 -347.668155) (xy 78.364345 -347.622305) (xy 78.341703 -347.572728)
			(xy 78.326348 -347.520433) (xy 78.318592 -347.466485) (xy 78.318106 -347.439234) (xy 76.372974 -347.439234)
			(xy 76.372974 -350.505014) (xy 76.530962 -350.505014) (xy 76.531383 -350.478634) (xy 76.538647 -350.426376)
			(xy 76.553037 -350.375617) (xy 76.57428 -350.327322) (xy 76.601971 -350.282413) (xy 76.635582 -350.241745)
			(xy 76.674473 -350.206093) (xy 76.717903 -350.176136) (xy 76.741274 -350.163892) (xy 76.75362 -350.157169)
			(xy 76.774345 -350.138196) (xy 76.789105 -350.114286) (xy 76.796777 -350.087256) (xy 76.796779 -350.059157)
			(xy 76.78911 -350.032125) (xy 76.774353 -350.008213) (xy 76.75363 -349.989238) (xy 76.741274 -349.982536)
			(xy 76.717904 -349.970295) (xy 76.67448 -349.940332) (xy 76.635596 -349.904676) (xy 76.60199 -349.864006)
			(xy 76.574303 -349.819098) (xy 76.553063 -349.770805) (xy 76.538673 -349.720048) (xy 76.531408 -349.667793)
			(xy 76.530962 -349.641414) (xy 76.531448 -349.614163) (xy 76.539204 -349.560215) (xy 76.554559 -349.50792)
			(xy 76.577201 -349.458343) (xy 76.606667 -349.412493) (xy 76.642358 -349.371302) (xy 76.683549 -349.335611)
			(xy 76.729399 -349.306145) (xy 76.778976 -349.283503) (xy 76.831271 -349.268148) (xy 76.885219 -349.260392)
			(xy 76.939721 -349.260392) (xy 76.993669 -349.268148) (xy 77.045964 -349.283503) (xy 77.095541 -349.306145)
			(xy 77.141391 -349.335611) (xy 77.182582 -349.371302) (xy 77.218273 -349.412493) (xy 77.247739 -349.458343)
			(xy 77.270381 -349.50792) (xy 77.285736 -349.560215) (xy 77.293492 -349.614163) (xy 77.293978 -349.641414)
			(xy 77.29353 -349.667794) (xy 77.286275 -349.720051) (xy 77.271892 -349.770812) (xy 77.250654 -349.819107)
			(xy 77.222967 -349.864018) (xy 77.189357 -349.904686) (xy 77.150467 -349.940338) (xy 77.107037 -349.970294)
			(xy 77.083666 -349.982536) (xy 77.071292 -349.989214) (xy 77.050555 -350.008192) (xy 77.035789 -350.03211)
			(xy 77.028115 -350.059152) (xy 77.028117 -350.087261) (xy 77.035794 -350.114302) (xy 77.050563 -350.138218)
			(xy 77.071302 -350.157193) (xy 77.083666 -350.163892) (xy 77.107058 -350.176095) (xy 77.15048 -350.206064)
			(xy 77.189363 -350.241727) (xy 77.222966 -350.282402) (xy 77.25065 -350.327316) (xy 77.271887 -350.375614)
			(xy 77.286273 -350.426375) (xy 77.293534 -350.478634) (xy 77.29388 -350.499172) (xy 88.330532 -350.499172)
			(xy 88.33109 -350.470256) (xy 88.339809 -350.413086) (xy 88.357058 -350.357888) (xy 88.382442 -350.305926)
			(xy 88.41538 -350.258391) (xy 88.455115 -350.216373) (xy 88.477598 -350.198182) (xy 88.48943 -350.188315)
			(xy 88.506945 -350.162982) (xy 88.516117 -350.133582) (xy 88.516112 -350.102784) (xy 88.50693 -350.073387)
			(xy 88.489406 -350.04806) (xy 88.477598 -350.038162) (xy 88.455096 -350.019993) (xy 88.415362 -349.977969)
			(xy 88.382425 -349.930429) (xy 88.35704 -349.878463) (xy 88.339788 -349.823262) (xy 88.331064 -349.766089)
			(xy 88.330532 -349.737172) (xy 88.330929 -349.709917) (xy 88.338691 -349.655961) (xy 88.354052 -349.60366)
			(xy 88.376701 -349.554077) (xy 88.406176 -349.508222) (xy 88.441876 -349.467028) (xy 88.483076 -349.431335)
			(xy 88.528936 -349.401868) (xy 88.578523 -349.379229) (xy 88.630828 -349.363876) (xy 88.684785 -349.356124)
			(xy 88.71204 -349.355664) (xy 88.738273 -349.356089) (xy 88.790245 -349.363261) (xy 88.840747 -349.377481)
			(xy 88.888827 -349.398478) (xy 88.91143 -349.411798) (xy 88.921042 -349.417123) (xy 88.942853 -349.419676)
			(xy 88.963746 -349.412914) (xy 88.979926 -349.398067) (xy 88.988453 -349.377831) (xy 88.988646 -349.36684)
			(xy 88.988392 -349.353632) (xy 88.988456 -349.342494) (xy 88.989728 -349.320255) (xy 88.990932 -349.309182)
			(xy 88.992189 -349.294211) (xy 88.986907 -349.264651) (xy 88.973257 -349.237904) (xy 88.952417 -349.216283)
			(xy 88.926191 -349.201657) (xy 88.896845 -349.19529) (xy 88.866916 -349.197734) (xy 88.852756 -349.202756)
			(xy 88.830293 -349.2113) (xy 88.78375 -349.223283) (xy 88.73607 -349.229319) (xy 88.71204 -349.22968)
			(xy 88.684783 -349.229276) (xy 88.630824 -349.221523) (xy 88.578517 -349.206169) (xy 88.528929 -349.183527)
			(xy 88.483067 -349.154058) (xy 88.441866 -349.118362) (xy 88.406166 -349.077165) (xy 88.376692 -349.031307)
			(xy 88.354045 -348.98172) (xy 88.338686 -348.929415) (xy 88.330927 -348.875457) (xy 88.330927 -348.820943)
			(xy 88.338686 -348.766985) (xy 88.354045 -348.71468) (xy 88.376692 -348.665093) (xy 88.406166 -348.619235)
			(xy 88.441866 -348.578038) (xy 88.483067 -348.542342) (xy 88.528929 -348.512873) (xy 88.578517 -348.490231)
			(xy 88.630824 -348.474877) (xy 88.684783 -348.467124) (xy 88.71204 -348.466664) (xy 88.736204 -348.467041)
			(xy 88.784147 -348.473135) (xy 88.830936 -348.485233) (xy 88.853518 -348.493842) (xy 88.868007 -348.499123)
			(xy 88.89874 -348.501541) (xy 88.928796 -348.494686) (xy 88.955441 -348.479182) (xy 88.976252 -348.456438)
			(xy 88.989334 -348.428524) (xy 88.991948 -348.413324) (xy 88.996023 -348.386221) (xy 89.011078 -348.333521)
			(xy 89.033522 -348.283519) (xy 89.062893 -348.237245) (xy 89.098585 -348.195651) (xy 89.139864 -348.159596)
			(xy 89.18588 -348.129821) (xy 89.235683 -348.106939) (xy 89.28825 -348.091423) (xy 89.342496 -348.083591)
			(xy 89.3699 -348.083124) (xy 89.398817 -348.083633) (xy 89.455989 -348.092363) (xy 89.511189 -348.109622)
			(xy 89.563151 -348.135015) (xy 89.610684 -348.167961) (xy 89.6527 -348.207704) (xy 89.67089 -348.23019)
			(xy 89.680787 -348.241995) (xy 89.706111 -348.259514) (xy 89.735504 -348.26869) (xy 89.766296 -348.26869)
			(xy 89.795689 -348.259514) (xy 89.821013 -348.241995) (xy 89.83091 -348.23019) (xy 89.849093 -348.2077)
			(xy 89.891115 -348.167965) (xy 89.938651 -348.135027) (xy 89.990614 -348.10964) (xy 90.045813 -348.092385)
			(xy 90.102984 -348.083658) (xy 90.1319 -348.083124) (xy 90.159154 -348.083546) (xy 90.213106 -348.091303)
			(xy 90.265405 -348.106659) (xy 90.314986 -348.129302) (xy 90.360841 -348.158771) (xy 90.402034 -348.194466)
			(xy 90.437729 -348.235659) (xy 90.467198 -348.281514) (xy 90.489841 -348.331095) (xy 90.505197 -348.383394)
			(xy 90.512954 -348.437346) (xy 90.512954 -348.491854) (xy 90.509949 -348.512757) (xy 90.715215 -348.512757)
			(xy 90.715215 -348.458243) (xy 90.722974 -348.404283) (xy 90.738333 -348.351976) (xy 90.760981 -348.302388)
			(xy 90.790456 -348.256528) (xy 90.826157 -348.21533) (xy 90.867359 -348.179633) (xy 90.913222 -348.150163)
			(xy 90.962812 -348.12752) (xy 91.01512 -348.112166) (xy 91.06908 -348.104412) (xy 91.096338 -348.103952)
			(xy 91.125254 -348.104495) (xy 91.182425 -348.113217) (xy 91.237624 -348.130468) (xy 91.289586 -348.155855)
			(xy 91.337121 -348.188795) (xy 91.379138 -348.228534) (xy 91.397328 -348.251018) (xy 91.407225 -348.262823)
			(xy 91.432549 -348.280342) (xy 91.461942 -348.289518) (xy 91.492734 -348.289518) (xy 91.522127 -348.280342)
			(xy 91.547451 -348.262823) (xy 91.557348 -348.251018) (xy 91.574101 -348.230235) (xy 91.612455 -348.193105)
			(xy 91.655609 -348.161683) (xy 91.702723 -348.136584) (xy 91.752875 -348.118298) (xy 91.805086 -348.107181)
			(xy 91.858338 -348.103451) (xy 91.91159 -348.107181) (xy 91.963801 -348.118298) (xy 92.013953 -348.136584)
			(xy 92.061067 -348.161683) (xy 92.104221 -348.193105) (xy 92.142575 -348.230235) (xy 92.159328 -348.251018)
			(xy 92.169225 -348.262823) (xy 92.194549 -348.280342) (xy 92.223942 -348.289518) (xy 92.254734 -348.289518)
			(xy 92.284127 -348.280342) (xy 92.309451 -348.262823) (xy 92.319348 -348.251018) (xy 92.336101 -348.230235)
			(xy 92.374455 -348.193105) (xy 92.417609 -348.161683) (xy 92.464723 -348.136584) (xy 92.514875 -348.118298)
			(xy 92.567086 -348.107181) (xy 92.620338 -348.103451) (xy 92.67359 -348.107181) (xy 92.725801 -348.118298)
			(xy 92.775953 -348.136584) (xy 92.823067 -348.161683) (xy 92.866221 -348.193105) (xy 92.904575 -348.230235)
			(xy 92.921328 -348.251018) (xy 92.931225 -348.262823) (xy 92.956549 -348.280342) (xy 92.985942 -348.289518)
			(xy 93.016734 -348.289518) (xy 93.046127 -348.280342) (xy 93.071451 -348.262823) (xy 93.081348 -348.251018)
			(xy 93.099573 -348.228563) (xy 93.141585 -348.188825) (xy 93.189113 -348.155882) (xy 93.241067 -348.130489)
			(xy 93.296259 -348.113227) (xy 93.353424 -348.104491) (xy 93.382338 -348.103952) (xy 93.410905 -348.104492)
			(xy 93.467399 -348.113024) (xy 93.521992 -348.129875) (xy 93.573466 -348.15467) (xy 93.620672 -348.186857)
			(xy 93.662557 -348.225716) (xy 93.680788 -348.247716) (xy 93.690372 -348.258945) (xy 93.714608 -348.275783)
			(xy 93.742643 -348.284996) (xy 93.772143 -348.285814) (xy 93.800646 -348.278172) (xy 93.825779 -348.262704)
			(xy 93.835982 -348.252034) (xy 93.854145 -348.232411) (xy 93.895029 -348.197953) (xy 93.940324 -348.16954)
			(xy 93.989143 -348.147728) (xy 94.040528 -348.132946) (xy 94.093473 -348.125482) (xy 94.120208 -348.125034)
			(xy 94.149123 -348.125606) (xy 94.206292 -348.134322) (xy 94.261491 -348.151568) (xy 94.313453 -348.17695)
			(xy 94.360988 -348.209885) (xy 94.403007 -348.249618) (xy 94.421198 -348.2721) (xy 94.431095 -348.283905)
			(xy 94.456419 -348.301424) (xy 94.485812 -348.3106) (xy 94.516604 -348.3106) (xy 94.545997 -348.301424)
			(xy 94.571321 -348.283905) (xy 94.581218 -348.2721) (xy 94.599399 -348.249608) (xy 94.641421 -348.209873)
			(xy 94.688958 -348.176935) (xy 94.740921 -348.151548) (xy 94.79612 -348.134294) (xy 94.853291 -348.125568)
			(xy 94.882208 -348.125034) (xy 94.909462 -348.125436) (xy 94.963415 -348.133195) (xy 95.015714 -348.148552)
			(xy 95.065296 -348.171196) (xy 95.11115 -348.200666) (xy 95.152344 -348.236362) (xy 95.188039 -348.277556)
			(xy 95.217508 -348.323411) (xy 95.240151 -348.372993) (xy 95.255507 -348.425293) (xy 95.263264 -348.479246)
			(xy 95.263264 -348.512752) (xy 95.383338 -348.512752) (xy 95.383338 -348.458248) (xy 95.391094 -348.404299)
			(xy 95.406448 -348.352003) (xy 95.429088 -348.302424) (xy 95.458553 -348.256571) (xy 95.494242 -348.215378)
			(xy 95.535431 -348.179683) (xy 95.58128 -348.150212) (xy 95.630856 -348.127565) (xy 95.68315 -348.112204)
			(xy 95.737098 -348.104441) (xy 95.76435 -348.103952) (xy 95.793267 -348.104486) (xy 95.850438 -348.113209)
			(xy 95.905637 -348.130463) (xy 95.9576 -348.155851) (xy 96.005134 -348.188793) (xy 96.04715 -348.228533)
			(xy 96.06534 -348.251018) (xy 96.075237 -348.262823) (xy 96.100561 -348.280342) (xy 96.129954 -348.289518)
			(xy 96.160746 -348.289518) (xy 96.190139 -348.280342) (xy 96.215463 -348.262823) (xy 96.22536 -348.251018)
			(xy 96.243578 -348.228557) (xy 96.285592 -348.18882) (xy 96.333121 -348.155878) (xy 96.385077 -348.130485)
			(xy 96.44027 -348.113224) (xy 96.497436 -348.10449) (xy 96.52635 -348.103952) (xy 96.553602 -348.104492)
			(xy 96.607553 -348.112242) (xy 96.659851 -348.127592) (xy 96.709433 -348.15023) (xy 96.755287 -348.179693)
			(xy 96.796482 -348.215383) (xy 96.832177 -348.256573) (xy 96.861646 -348.302423) (xy 96.88429 -348.352002)
			(xy 96.899647 -348.404298) (xy 96.907405 -348.458248) (xy 96.907405 -348.512752) (xy 96.899647 -348.566702)
			(xy 96.88429 -348.618998) (xy 96.861646 -348.668577) (xy 96.832177 -348.714427) (xy 96.796482 -348.755617)
			(xy 96.755287 -348.791307) (xy 96.709433 -348.82077) (xy 96.659851 -348.843408) (xy 96.607553 -348.858758)
			(xy 96.553602 -348.866508) (xy 96.52635 -348.866968) (xy 96.497434 -348.866426) (xy 96.440263 -348.857704)
			(xy 96.385064 -348.840451) (xy 96.333102 -348.815064) (xy 96.285568 -348.782124) (xy 96.24355 -348.742386)
			(xy 96.22536 -348.719902) (xy 96.215463 -348.708097) (xy 96.190139 -348.690578) (xy 96.160746 -348.681402)
			(xy 96.129954 -348.681402) (xy 96.100561 -348.690578) (xy 96.075237 -348.708097) (xy 96.06534 -348.719902)
			(xy 96.047127 -348.742367) (xy 96.005112 -348.782103) (xy 95.957581 -348.815044) (xy 95.905624 -348.840436)
			(xy 95.850431 -348.857696) (xy 95.793265 -348.86643) (xy 95.76435 -348.866968) (xy 95.737098 -348.866559)
			(xy 95.68315 -348.858796) (xy 95.630856 -348.843435) (xy 95.58128 -348.820788) (xy 95.535431 -348.791317)
			(xy 95.494242 -348.755622) (xy 95.458553 -348.714429) (xy 95.429088 -348.668576) (xy 95.406448 -348.618997)
			(xy 95.391094 -348.566701) (xy 95.383338 -348.512752) (xy 95.263264 -348.512752) (xy 95.263264 -348.533754)
			(xy 95.255507 -348.587707) (xy 95.240151 -348.640007) (xy 95.217508 -348.689589) (xy 95.188039 -348.735444)
			(xy 95.152344 -348.776638) (xy 95.11115 -348.812334) (xy 95.065296 -348.841804) (xy 95.015714 -348.864448)
			(xy 94.963415 -348.879805) (xy 94.909462 -348.887564) (xy 94.882208 -348.88805) (xy 94.85329 -348.887545)
			(xy 94.796118 -348.878816) (xy 94.740918 -348.861556) (xy 94.688956 -348.836162) (xy 94.641422 -348.803216)
			(xy 94.599407 -348.763471) (xy 94.581218 -348.740984) (xy 94.571321 -348.729179) (xy 94.545997 -348.71166)
			(xy 94.516604 -348.702484) (xy 94.485812 -348.702484) (xy 94.456419 -348.71166) (xy 94.431095 -348.729179)
			(xy 94.421198 -348.740984) (xy 94.403004 -348.763465) (xy 94.360985 -348.803201) (xy 94.313451 -348.836141)
			(xy 94.26149 -348.86153) (xy 94.206293 -348.878786) (xy 94.149124 -348.887515) (xy 94.120208 -348.88805)
			(xy 94.091642 -348.887476) (xy 94.03515 -348.878952) (xy 93.980557 -348.862107) (xy 93.929083 -348.837318)
			(xy 93.881876 -348.805137) (xy 93.83999 -348.766284) (xy 93.821758 -348.744286) (xy 93.812126 -348.733102)
			(xy 93.787903 -348.716262) (xy 93.75988 -348.707045) (xy 93.730391 -348.706217) (xy 93.701895 -348.713849)
			(xy 93.676767 -348.729304) (xy 93.666564 -348.739968) (xy 93.648379 -348.759569) (xy 93.607499 -348.794029)
			(xy 93.562209 -348.822445) (xy 93.513395 -348.84426) (xy 93.462014 -348.859047) (xy 93.409071 -348.866516)
			(xy 93.382338 -348.866968) (xy 93.353422 -348.866435) (xy 93.29625 -348.85771) (xy 93.241051 -348.840456)
			(xy 93.189089 -348.815068) (xy 93.141555 -348.782126) (xy 93.099538 -348.742387) (xy 93.081348 -348.719902)
			(xy 93.071451 -348.708097) (xy 93.046127 -348.690578) (xy 93.016734 -348.681402) (xy 92.985942 -348.681402)
			(xy 92.956549 -348.690578) (xy 92.931225 -348.708097) (xy 92.921328 -348.719902) (xy 92.904575 -348.740685)
			(xy 92.866221 -348.777815) (xy 92.823067 -348.809237) (xy 92.775953 -348.834336) (xy 92.725801 -348.852622)
			(xy 92.67359 -348.863739) (xy 92.620338 -348.867469) (xy 92.567086 -348.863739) (xy 92.514875 -348.852622)
			(xy 92.464723 -348.834336) (xy 92.417609 -348.809237) (xy 92.374455 -348.777815) (xy 92.336101 -348.740685)
			(xy 92.319348 -348.719902) (xy 92.309451 -348.708097) (xy 92.284127 -348.690578) (xy 92.254734 -348.681402)
			(xy 92.223942 -348.681402) (xy 92.194549 -348.690578) (xy 92.169225 -348.708097) (xy 92.159328 -348.719902)
			(xy 92.142575 -348.740685) (xy 92.104221 -348.777815) (xy 92.061067 -348.809237) (xy 92.013953 -348.834336)
			(xy 91.963801 -348.852622) (xy 91.91159 -348.863739) (xy 91.858338 -348.867469) (xy 91.805086 -348.863739)
			(xy 91.752875 -348.852622) (xy 91.702723 -348.834336) (xy 91.655609 -348.809237) (xy 91.612455 -348.777815)
			(xy 91.574101 -348.740685) (xy 91.557348 -348.719902) (xy 91.547451 -348.708097) (xy 91.522127 -348.690578)
			(xy 91.492734 -348.681402) (xy 91.461942 -348.681402) (xy 91.432549 -348.690578) (xy 91.407225 -348.708097)
			(xy 91.397328 -348.719902) (xy 91.379122 -348.742372) (xy 91.337105 -348.782108) (xy 91.289573 -348.815049)
			(xy 91.237615 -348.840439) (xy 91.18242 -348.857699) (xy 91.125253 -348.866431) (xy 91.096338 -348.866968)
			(xy 91.06908 -348.866588) (xy 91.01512 -348.858834) (xy 90.962812 -348.84348) (xy 90.913222 -348.820837)
			(xy 90.867359 -348.791367) (xy 90.826157 -348.75567) (xy 90.790456 -348.714472) (xy 90.760981 -348.668612)
			(xy 90.738333 -348.619024) (xy 90.722974 -348.566717) (xy 90.715215 -348.512757) (xy 90.509949 -348.512757)
			(xy 90.505197 -348.545806) (xy 90.489841 -348.598105) (xy 90.467198 -348.647686) (xy 90.437729 -348.693541)
			(xy 90.402034 -348.734734) (xy 90.360841 -348.770429) (xy 90.314986 -348.799898) (xy 90.265405 -348.822541)
			(xy 90.213106 -348.837897) (xy 90.159154 -348.845654) (xy 90.1319 -348.84614) (xy 90.102982 -348.845644)
			(xy 90.045809 -348.836914) (xy 89.990608 -348.819653) (xy 89.938646 -348.794257) (xy 89.891113 -348.761308)
			(xy 89.849098 -348.721562) (xy 89.83091 -348.699074) (xy 89.821013 -348.687269) (xy 89.795689 -348.66975)
			(xy 89.766296 -348.660574) (xy 89.735504 -348.660574) (xy 89.706111 -348.66975) (xy 89.680787 -348.687269)
			(xy 89.67089 -348.699074) (xy 89.652698 -348.721557) (xy 89.610679 -348.761293) (xy 89.563145 -348.794233)
			(xy 89.511184 -348.819622) (xy 89.455986 -348.836878) (xy 89.398816 -348.845606) (xy 89.3699 -348.84614)
			(xy 89.343668 -348.845697) (xy 89.291696 -348.838529) (xy 89.241195 -348.824316) (xy 89.193114 -348.803323)
			(xy 89.17051 -348.790006) (xy 89.160875 -348.784726) (xy 89.139075 -348.782162) (xy 89.118188 -348.788913)
			(xy 89.102011 -348.80375) (xy 89.093486 -348.823978) (xy 89.093294 -348.834964) (xy 89.093548 -348.848172)
			(xy 89.093485 -348.85931) (xy 89.092212 -348.881549) (xy 89.091008 -348.892622) (xy 89.089693 -348.907591)
			(xy 89.094978 -348.937162) (xy 89.108636 -348.963917) (xy 89.129485 -348.985543) (xy 89.155724 -349.000168)
			(xy 89.185082 -349.00653) (xy 89.215021 -349.004077) (xy 89.229184 -348.999048) (xy 89.251653 -348.990521)
			(xy 89.298193 -348.978532) (xy 89.34587 -348.972489) (xy 89.3699 -348.972124) (xy 89.398817 -348.972633)
			(xy 89.455989 -348.981363) (xy 89.511189 -348.998622) (xy 89.563151 -349.024015) (xy 89.610684 -349.056961)
			(xy 89.6527 -349.096704) (xy 89.67089 -349.11919) (xy 89.680787 -349.130995) (xy 89.706111 -349.148514)
			(xy 89.735504 -349.15769) (xy 89.766296 -349.15769) (xy 89.795689 -349.148514) (xy 89.821013 -349.130995)
			(xy 89.83091 -349.11919) (xy 89.849093 -349.0967) (xy 89.891115 -349.056965) (xy 89.938651 -349.024027)
			(xy 89.990614 -348.99864) (xy 90.045813 -348.981385) (xy 90.102984 -348.972658) (xy 90.1319 -348.972124)
			(xy 90.159154 -348.972555) (xy 90.213108 -348.980313) (xy 90.265408 -348.995671) (xy 90.314991 -349.018316)
			(xy 90.360845 -349.047787) (xy 90.402039 -349.083484) (xy 90.437733 -349.12468) (xy 90.4672 -349.170537)
			(xy 90.48984 -349.220122) (xy 90.505194 -349.272423) (xy 90.512947 -349.326378) (xy 90.513408 -349.353632)
			(xy 90.512876 -349.382549) (xy 90.504154 -349.439721) (xy 90.486902 -349.494921) (xy 90.461513 -349.546884)
			(xy 90.42857 -349.594417) (xy 90.388828 -349.636433) (xy 90.366342 -349.654622) (xy 90.354502 -349.664483)
			(xy 90.33698 -349.689815) (xy 90.327805 -349.719219) (xy 90.327811 -349.750021) (xy 90.336997 -349.779421)
			(xy 90.354529 -349.804746) (xy 90.366342 -349.814642) (xy 90.387156 -349.831358) (xy 90.424287 -349.869715)
			(xy 90.455708 -349.912875) (xy 90.480807 -349.959992) (xy 90.499092 -350.010149) (xy 90.510206 -350.062365)
			(xy 90.513933 -350.11562) (xy 90.512473 -350.13646) (xy 90.71483 -350.13646) (xy 90.71538 -350.107544)
			(xy 90.724101 -350.050374) (xy 90.741352 -349.995175) (xy 90.766737 -349.943213) (xy 90.799676 -349.895678)
			(xy 90.839412 -349.853661) (xy 90.861896 -349.83547) (xy 90.87374 -349.825616) (xy 90.891256 -349.80028)
			(xy 90.900426 -349.770876) (xy 90.900419 -349.740075) (xy 90.891234 -349.710676) (xy 90.873706 -349.685348)
			(xy 90.861896 -349.67545) (xy 90.839436 -349.657232) (xy 90.799699 -349.615218) (xy 90.766758 -349.567688)
			(xy 90.741365 -349.515732) (xy 90.724104 -349.46054) (xy 90.715369 -349.403374) (xy 90.71483 -349.37446)
			(xy 90.715241 -349.347206) (xy 90.723004 -349.293254) (xy 90.738366 -349.240955) (xy 90.761014 -349.191375)
			(xy 90.790488 -349.145523) (xy 90.826188 -349.104332) (xy 90.867386 -349.068642) (xy 90.913244 -349.039177)
			(xy 90.962828 -349.016538) (xy 91.01513 -349.001187) (xy 91.069084 -348.993435) (xy 91.096338 -348.992952)
			(xy 91.125254 -348.993495) (xy 91.182425 -349.002217) (xy 91.237624 -349.019468) (xy 91.289586 -349.044855)
			(xy 91.337121 -349.077795) (xy 91.379138 -349.117534) (xy 91.397328 -349.140018) (xy 91.407225 -349.151823)
			(xy 91.432549 -349.169342) (xy 91.461942 -349.178518) (xy 91.492734 -349.178518) (xy 91.522127 -349.169342)
			(xy 91.547451 -349.151823) (xy 91.557348 -349.140018) (xy 91.574101 -349.119235) (xy 91.612455 -349.082105)
			(xy 91.655609 -349.050683) (xy 91.702723 -349.025584) (xy 91.752875 -349.007298) (xy 91.805086 -348.996181)
			(xy 91.858338 -348.992451) (xy 91.91159 -348.996181) (xy 91.963801 -349.007298) (xy 92.013953 -349.025584)
			(xy 92.061067 -349.050683) (xy 92.104221 -349.082105) (xy 92.142575 -349.119235) (xy 92.159328 -349.140018)
			(xy 92.169225 -349.151823) (xy 92.194549 -349.169342) (xy 92.223942 -349.178518) (xy 92.254734 -349.178518)
			(xy 92.284127 -349.169342) (xy 92.309451 -349.151823) (xy 92.319348 -349.140018) (xy 92.336101 -349.119235)
			(xy 92.374455 -349.082105) (xy 92.417609 -349.050683) (xy 92.464723 -349.025584) (xy 92.514875 -349.007298)
			(xy 92.567086 -348.996181) (xy 92.620338 -348.992451) (xy 92.67359 -348.996181) (xy 92.725801 -349.007298)
			(xy 92.775953 -349.025584) (xy 92.823067 -349.050683) (xy 92.866221 -349.082105) (xy 92.904575 -349.119235)
			(xy 92.921328 -349.140018) (xy 92.931225 -349.151823) (xy 92.956549 -349.169342) (xy 92.985942 -349.178518)
			(xy 93.016734 -349.178518) (xy 93.046127 -349.169342) (xy 93.071451 -349.151823) (xy 93.081348 -349.140018)
			(xy 93.099573 -349.117563) (xy 93.141585 -349.077825) (xy 93.189113 -349.044882) (xy 93.241067 -349.019489)
			(xy 93.296259 -349.002227) (xy 93.353424 -348.993491) (xy 93.382338 -348.992952) (xy 93.410905 -348.993492)
			(xy 93.467399 -349.002024) (xy 93.521992 -349.018875) (xy 93.573466 -349.04367) (xy 93.620672 -349.075857)
			(xy 93.662557 -349.114716) (xy 93.680788 -349.136716) (xy 93.690372 -349.147945) (xy 93.714608 -349.164783)
			(xy 93.742643 -349.173996) (xy 93.772143 -349.174814) (xy 93.800646 -349.167172) (xy 93.825779 -349.151704)
			(xy 93.835982 -349.141034) (xy 93.854145 -349.121411) (xy 93.895029 -349.086953) (xy 93.940324 -349.05854)
			(xy 93.989143 -349.036728) (xy 94.040528 -349.021946) (xy 94.093473 -349.014482) (xy 94.120208 -349.014034)
			(xy 94.149123 -349.014606) (xy 94.206292 -349.023322) (xy 94.261491 -349.040568) (xy 94.313453 -349.06595)
			(xy 94.360988 -349.098885) (xy 94.403007 -349.138618) (xy 94.421198 -349.1611) (xy 94.431095 -349.172905)
			(xy 94.456419 -349.190424) (xy 94.485812 -349.1996) (xy 94.516604 -349.1996) (xy 94.545997 -349.190424)
			(xy 94.571321 -349.172905) (xy 94.581218 -349.1611) (xy 94.599399 -349.138608) (xy 94.641421 -349.098873)
			(xy 94.688958 -349.065935) (xy 94.740921 -349.040548) (xy 94.79612 -349.023294) (xy 94.853291 -349.014568)
			(xy 94.882208 -349.014034) (xy 94.909463 -349.014448) (xy 94.963418 -349.022207) (xy 95.015719 -349.037566)
			(xy 95.065302 -349.060213) (xy 95.111157 -349.089686) (xy 95.152351 -349.125385) (xy 95.188044 -349.166583)
			(xy 95.217511 -349.212442) (xy 95.240151 -349.262028) (xy 95.255503 -349.314331) (xy 95.263256 -349.368287)
			(xy 95.263716 -349.395542) (xy 95.26314 -349.424984) (xy 95.254075 -349.483167) (xy 95.236182 -349.539267)
			(xy 95.209886 -349.591954) (xy 95.17581 -349.639978) (xy 95.134764 -349.682198) (xy 95.11157 -349.700342)
			(xy 95.101069 -349.708669) (xy 95.084553 -349.729767) (xy 95.074096 -349.754435) (xy 95.070417 -349.780975)
			(xy 95.073771 -349.807558) (xy 95.083926 -349.832353) (xy 95.100182 -349.853651) (xy 95.110554 -349.86214)
			(xy 95.133163 -349.880342) (xy 95.173168 -349.922394) (xy 95.20634 -349.970022) (xy 95.231914 -350.022125)
			(xy 95.249298 -350.077501) (xy 95.258093 -350.134872) (xy 95.258123 -350.136475) (xy 95.382291 -350.136475)
			(xy 95.386025 -350.083218) (xy 95.397148 -350.031001) (xy 95.415441 -349.980845) (xy 95.440549 -349.933729)
			(xy 95.471979 -349.890574) (xy 95.50912 -349.852222) (xy 95.529908 -349.83547) (xy 95.541751 -349.825615)
			(xy 95.559264 -349.800279) (xy 95.568434 -349.770875) (xy 95.568426 -349.740076) (xy 95.559243 -349.710677)
			(xy 95.541717 -349.685349) (xy 95.529908 -349.67545) (xy 95.50745 -349.657229) (xy 95.467713 -349.615216)
			(xy 95.434771 -349.567687) (xy 95.409378 -349.515732) (xy 95.392116 -349.460539) (xy 95.383381 -349.403374)
			(xy 95.382842 -349.37446) (xy 95.383218 -349.347204) (xy 95.390982 -349.293247) (xy 95.406345 -349.240945)
			(xy 95.428996 -349.191361) (xy 95.458473 -349.145506) (xy 95.494176 -349.104312) (xy 95.535378 -349.068619)
			(xy 95.58124 -349.039153) (xy 95.630829 -349.016514) (xy 95.683135 -349.001162) (xy 95.737094 -348.993411)
			(xy 95.76435 -348.992952) (xy 95.793267 -348.993486) (xy 95.850438 -349.002209) (xy 95.905637 -349.019463)
			(xy 95.9576 -349.044851) (xy 96.005134 -349.077793) (xy 96.04715 -349.117533) (xy 96.06534 -349.140018)
			(xy 96.075237 -349.151823) (xy 96.100561 -349.169342) (xy 96.129954 -349.178518) (xy 96.160746 -349.178518)
			(xy 96.190139 -349.169342) (xy 96.215463 -349.151823) (xy 96.22536 -349.140018) (xy 96.243578 -349.117557)
			(xy 96.285592 -349.07782) (xy 96.333121 -349.044878) (xy 96.385077 -349.019485) (xy 96.44027 -349.002224)
			(xy 96.497436 -348.99349) (xy 96.52635 -348.992952) (xy 96.5536 -348.993502) (xy 96.607546 -349.001251)
			(xy 96.659839 -349.016598) (xy 96.709417 -349.039232) (xy 96.755268 -349.068691) (xy 96.79646 -349.104376)
			(xy 96.832155 -349.14556) (xy 96.861625 -349.191404) (xy 96.88427 -349.240976) (xy 96.89963 -349.293266)
			(xy 96.907392 -349.34721) (xy 96.907858 -349.37446) (xy 96.907327 -349.403377) (xy 96.898603 -349.460548)
			(xy 96.881348 -349.515747) (xy 96.855959 -349.567709) (xy 96.823017 -349.615243) (xy 96.783277 -349.65726)
			(xy 96.760792 -349.67545) (xy 96.749029 -349.685392) (xy 96.731514 -349.710704) (xy 96.722336 -349.740085)
			(xy 96.722329 -349.770866) (xy 96.731493 -349.800251) (xy 96.748995 -349.825572) (xy 96.760792 -349.83547)
			(xy 96.781538 -349.852269) (xy 96.818672 -349.890615) (xy 96.850097 -349.933763) (xy 96.875201 -349.980871)
			(xy 96.893491 -350.031019) (xy 96.904612 -350.083227) (xy 96.908345 -350.136475) (xy 96.904619 -350.189724)
			(xy 96.893505 -350.241934) (xy 96.875221 -350.292084) (xy 96.850124 -350.339195) (xy 96.818704 -350.382347)
			(xy 96.781574 -350.420698) (xy 96.760792 -350.43745) (xy 96.749029 -350.447392) (xy 96.731514 -350.472704)
			(xy 96.730329 -350.476496) (xy 115.595396 -350.476496) (xy 115.595396 -350.3918) (xy 115.603447 -350.307486)
			(xy 115.619476 -350.22432) (xy 115.643337 -350.143053) (xy 115.674816 -350.064423) (xy 115.713627 -349.989142)
			(xy 115.759417 -349.91789) (xy 115.811773 -349.851314) (xy 115.870221 -349.790016) (xy 115.934231 -349.734551)
			(xy 116.003223 -349.685422) (xy 116.076573 -349.643073) (xy 116.153616 -349.607889) (xy 116.233655 -349.580187)
			(xy 116.315964 -349.560219) (xy 116.399799 -349.548166) (xy 116.4844 -349.544136) (xy 116.569001 -349.548166)
			(xy 116.652836 -349.560219) (xy 116.735145 -349.580187) (xy 116.815184 -349.607889) (xy 116.892227 -349.643073)
			(xy 116.965577 -349.685422) (xy 117.034569 -349.734551) (xy 117.098579 -349.790016) (xy 117.157027 -349.851314)
			(xy 117.209383 -349.91789) (xy 117.255173 -349.989142) (xy 117.293984 -350.064423) (xy 117.325463 -350.143053)
			(xy 117.349324 -350.22432) (xy 117.365353 -350.307486) (xy 117.373404 -350.3918) (xy 117.373908 -350.434148)
			(xy 118.119909 -350.434148) (xy 118.123945 -350.350701) (xy 118.136017 -350.268033) (xy 118.15601 -350.186916)
			(xy 118.183739 -350.108107) (xy 118.218945 -350.032342) (xy 118.261299 -349.960329) (xy 118.310405 -349.89274)
			(xy 118.365806 -349.830206) (xy 118.426983 -349.773311) (xy 118.493366 -349.722585) (xy 118.564334 -349.678504)
			(xy 118.639226 -349.641478) (xy 118.717342 -349.611852) (xy 118.797952 -349.589904) (xy 118.880304 -349.575839)
			(xy 118.96363 -349.569787) (xy 119.04715 -349.571806) (xy 119.130086 -349.581876) (xy 119.211662 -349.599904)
			(xy 119.291118 -349.625721) (xy 119.367711 -349.659086) (xy 119.440727 -349.699687) (xy 119.509483 -349.747146)
			(xy 119.573337 -349.801019) (xy 119.631694 -349.860804) (xy 119.684009 -349.925941) (xy 119.729792 -349.995824)
			(xy 119.768617 -350.069799) (xy 119.800122 -350.147176) (xy 119.824011 -350.227233) (xy 119.840062 -350.309221)
			(xy 119.848125 -350.392376) (xy 119.84863 -350.434148) (xy 119.848125 -350.47592) (xy 119.840062 -350.559075)
			(xy 119.824011 -350.641063) (xy 119.800122 -350.72112) (xy 119.768617 -350.798497) (xy 119.729792 -350.872472)
			(xy 119.684009 -350.942355) (xy 119.631694 -351.007492) (xy 119.573337 -351.067277) (xy 119.509483 -351.12115)
			(xy 119.440727 -351.168609) (xy 119.367711 -351.20921) (xy 119.291118 -351.242575) (xy 119.211662 -351.268392)
			(xy 119.130086 -351.28642) (xy 119.04715 -351.29649) (xy 118.96363 -351.298509) (xy 118.880304 -351.292457)
			(xy 118.797952 -351.278392) (xy 118.717342 -351.256444) (xy 118.639226 -351.226818) (xy 118.564334 -351.189792)
			(xy 118.493366 -351.145711) (xy 118.426983 -351.094985) (xy 118.365806 -351.03809) (xy 118.310405 -350.975556)
			(xy 118.261299 -350.907967) (xy 118.218945 -350.835954) (xy 118.183739 -350.760189) (xy 118.15601 -350.68138)
			(xy 118.136017 -350.600263) (xy 118.123945 -350.517595) (xy 118.119909 -350.434148) (xy 117.373908 -350.434148)
			(xy 117.373404 -350.476496) (xy 117.365353 -350.56081) (xy 117.349324 -350.643976) (xy 117.325463 -350.725243)
			(xy 117.293984 -350.803873) (xy 117.255173 -350.879154) (xy 117.209383 -350.950406) (xy 117.157027 -351.016982)
			(xy 117.098579 -351.07828) (xy 117.034569 -351.133745) (xy 116.965577 -351.182874) (xy 116.892227 -351.225223)
			(xy 116.815184 -351.260407) (xy 116.735145 -351.288109) (xy 116.652836 -351.308077) (xy 116.569001 -351.32013)
			(xy 116.4844 -351.324161) (xy 116.399799 -351.32013) (xy 116.315964 -351.308077) (xy 116.233655 -351.288109)
			(xy 116.153616 -351.260407) (xy 116.076573 -351.225223) (xy 116.003223 -351.182874) (xy 115.934231 -351.133745)
			(xy 115.870221 -351.07828) (xy 115.811773 -351.016982) (xy 115.759417 -350.950406) (xy 115.713627 -350.879154)
			(xy 115.674816 -350.803873) (xy 115.643337 -350.725243) (xy 115.619476 -350.643976) (xy 115.603447 -350.56081)
			(xy 115.595396 -350.476496) (xy 96.730329 -350.476496) (xy 96.722336 -350.502085) (xy 96.722329 -350.532866)
			(xy 96.731493 -350.562251) (xy 96.748995 -350.587572) (xy 96.760792 -350.59747) (xy 96.783259 -350.61568)
			(xy 96.822996 -350.657696) (xy 96.855937 -350.705226) (xy 96.881328 -350.757184) (xy 96.898588 -350.812378)
			(xy 96.907321 -350.869545) (xy 96.907858 -350.89846) (xy 96.907407 -350.925714) (xy 96.899655 -350.979668)
			(xy 96.884301 -351.031969) (xy 96.86166 -351.081553) (xy 96.832191 -351.127408) (xy 96.796496 -351.168603)
			(xy 96.7553 -351.204297) (xy 96.709444 -351.233764) (xy 96.65986 -351.256405) (xy 96.607558 -351.271757)
			(xy 96.553604 -351.279508) (xy 96.52635 -351.279968) (xy 96.497434 -351.279426) (xy 96.440263 -351.270704)
			(xy 96.385064 -351.253451) (xy 96.333102 -351.228064) (xy 96.285568 -351.195124) (xy 96.24355 -351.155386)
			(xy 96.22536 -351.132902) (xy 96.215463 -351.121097) (xy 96.190139 -351.103578) (xy 96.160746 -351.094402)
			(xy 96.129954 -351.094402) (xy 96.100561 -351.103578) (xy 96.075237 -351.121097) (xy 96.06534 -351.132902)
			(xy 96.047127 -351.155367) (xy 96.005112 -351.195103) (xy 95.957581 -351.228044) (xy 95.905624 -351.253436)
			(xy 95.850431 -351.270696) (xy 95.793265 -351.27943) (xy 95.76435 -351.279968) (xy 95.737097 -351.279498)
			(xy 95.683144 -351.271747) (xy 95.630844 -351.256395) (xy 95.581261 -351.233756) (xy 95.535406 -351.204289)
			(xy 95.494211 -351.168596) (xy 95.458517 -351.127402) (xy 95.429049 -351.081548) (xy 95.406408 -351.031966)
			(xy 95.391055 -350.979666) (xy 95.383303 -350.925713) (xy 95.382842 -350.89846) (xy 95.383387 -350.869544)
			(xy 95.392108 -350.812373) (xy 95.40936 -350.757174) (xy 95.434746 -350.705212) (xy 95.467686 -350.657678)
			(xy 95.507424 -350.61566) (xy 95.529908 -350.59747) (xy 95.541751 -350.587615) (xy 95.559264 -350.562279)
			(xy 95.568434 -350.532875) (xy 95.568426 -350.502076) (xy 95.559243 -350.472677) (xy 95.541717 -350.447349)
			(xy 95.529908 -350.43745) (xy 95.509083 -350.420745) (xy 95.471948 -350.382388) (xy 95.440522 -350.339229)
			(xy 95.415421 -350.29211) (xy 95.397134 -350.241951) (xy 95.386018 -350.189733) (xy 95.382291 -350.136475)
			(xy 95.258123 -350.136475) (xy 95.258636 -350.163892) (xy 95.25815 -350.191143) (xy 95.250394 -350.245091)
			(xy 95.235039 -350.297386) (xy 95.212397 -350.346963) (xy 95.182931 -350.392813) (xy 95.14724 -350.434004)
			(xy 95.106049 -350.469695) (xy 95.060199 -350.499161) (xy 95.010622 -350.521803) (xy 94.958327 -350.537158)
			(xy 94.904379 -350.544914) (xy 94.849877 -350.544914) (xy 94.795929 -350.537158) (xy 94.743634 -350.521803)
			(xy 94.694057 -350.499161) (xy 94.648207 -350.469695) (xy 94.607016 -350.434004) (xy 94.571325 -350.392813)
			(xy 94.541859 -350.346963) (xy 94.519217 -350.297386) (xy 94.503862 -350.245091) (xy 94.496106 -350.191143)
			(xy 94.49562 -350.163892) (xy 94.496134 -350.134447) (xy 94.50521 -350.076261) (xy 94.523114 -350.020159)
			(xy 94.549422 -349.967472) (xy 94.583509 -349.91945) (xy 94.624567 -349.877233) (xy 94.647766 -349.859092)
			(xy 94.65823 -349.850724) (xy 94.67474 -349.829634) (xy 94.685196 -349.804975) (xy 94.688878 -349.778445)
			(xy 94.685532 -349.751871) (xy 94.675388 -349.727082) (xy 94.659146 -349.705784) (xy 94.648782 -349.697294)
			(xy 94.63008 -349.682385) (xy 94.596195 -349.648631) (xy 94.581218 -349.629984) (xy 94.571321 -349.618179)
			(xy 94.545997 -349.60066) (xy 94.516604 -349.591484) (xy 94.485812 -349.591484) (xy 94.456419 -349.60066)
			(xy 94.431095 -349.618179) (xy 94.421198 -349.629984) (xy 94.403004 -349.652465) (xy 94.360985 -349.692201)
			(xy 94.313451 -349.725141) (xy 94.26149 -349.75053) (xy 94.206293 -349.767786) (xy 94.149124 -349.776515)
			(xy 94.120208 -349.77705) (xy 94.091642 -349.776476) (xy 94.03515 -349.767952) (xy 93.980557 -349.751107)
			(xy 93.929083 -349.726318) (xy 93.881876 -349.694137) (xy 93.83999 -349.655284) (xy 93.821758 -349.633286)
			(xy 93.812126 -349.622102) (xy 93.787903 -349.605262) (xy 93.75988 -349.596045) (xy 93.730391 -349.595217)
			(xy 93.701895 -349.602849) (xy 93.676767 -349.618304) (xy 93.666564 -349.628968) (xy 93.648379 -349.648569)
			(xy 93.607499 -349.683029) (xy 93.562209 -349.711445) (xy 93.513395 -349.73326) (xy 93.462014 -349.748047)
			(xy 93.409071 -349.755516) (xy 93.382338 -349.755968) (xy 93.353422 -349.755435) (xy 93.29625 -349.74671)
			(xy 93.241051 -349.729456) (xy 93.189089 -349.704068) (xy 93.141555 -349.671126) (xy 93.099538 -349.631387)
			(xy 93.081348 -349.608902) (xy 93.071451 -349.597097) (xy 93.046127 -349.579578) (xy 93.016734 -349.570402)
			(xy 92.985942 -349.570402) (xy 92.956549 -349.579578) (xy 92.931225 -349.597097) (xy 92.921328 -349.608902)
			(xy 92.904575 -349.629685) (xy 92.866221 -349.666815) (xy 92.823067 -349.698237) (xy 92.775953 -349.723336)
			(xy 92.725801 -349.741622) (xy 92.67359 -349.752739) (xy 92.620338 -349.756469) (xy 92.567086 -349.752739)
			(xy 92.514875 -349.741622) (xy 92.464723 -349.723336) (xy 92.417609 -349.698237) (xy 92.374455 -349.666815)
			(xy 92.336101 -349.629685) (xy 92.319348 -349.608902) (xy 92.309451 -349.597097) (xy 92.284127 -349.579578)
			(xy 92.254734 -349.570402) (xy 92.223942 -349.570402) (xy 92.194549 -349.579578) (xy 92.169225 -349.597097)
			(xy 92.159328 -349.608902) (xy 92.142575 -349.629685) (xy 92.104221 -349.666815) (xy 92.061067 -349.698237)
			(xy 92.013953 -349.723336) (xy 91.963801 -349.741622) (xy 91.91159 -349.752739) (xy 91.858338 -349.756469)
			(xy 91.805086 -349.752739) (xy 91.752875 -349.741622) (xy 91.702723 -349.723336) (xy 91.655609 -349.698237)
			(xy 91.612455 -349.666815) (xy 91.574101 -349.629685) (xy 91.557348 -349.608902) (xy 91.547451 -349.597097)
			(xy 91.522127 -349.579578) (xy 91.492734 -349.570402) (xy 91.461942 -349.570402) (xy 91.432549 -349.579578)
			(xy 91.407225 -349.597097) (xy 91.397328 -349.608902) (xy 91.382552 -349.627303) (xy 91.34918 -349.660673)
			(xy 91.33078 -349.67545) (xy 91.319018 -349.685393) (xy 91.301506 -349.710705) (xy 91.292329 -349.740086)
			(xy 91.292321 -349.770865) (xy 91.301484 -349.80025) (xy 91.318984 -349.825571) (xy 91.33078 -349.83547)
			(xy 91.353245 -349.853683) (xy 91.392982 -349.895698) (xy 91.425924 -349.943228) (xy 91.451316 -349.995185)
			(xy 91.468576 -350.050379) (xy 91.477309 -350.107545) (xy 91.477846 -350.13646) (xy 91.47736 -350.163711)
			(xy 91.469604 -350.217659) (xy 91.454249 -350.269954) (xy 91.431607 -350.319531) (xy 91.402141 -350.365381)
			(xy 91.36645 -350.406572) (xy 91.325259 -350.442263) (xy 91.279409 -350.471729) (xy 91.229832 -350.494371)
			(xy 91.177537 -350.509726) (xy 91.123589 -350.517482) (xy 91.069087 -350.517482) (xy 91.015139 -350.509726)
			(xy 90.962844 -350.494371) (xy 90.913267 -350.471729) (xy 90.867417 -350.442263) (xy 90.826226 -350.406572)
			(xy 90.790535 -350.365381) (xy 90.761069 -350.319531) (xy 90.738427 -350.269954) (xy 90.723072 -350.217659)
			(xy 90.715316 -350.163711) (xy 90.71483 -350.13646) (xy 90.512473 -350.13646) (xy 90.510201 -350.168874)
			(xy 90.499081 -350.221089) (xy 90.480791 -350.271244) (xy 90.455688 -350.318359) (xy 90.424262 -350.361515)
			(xy 90.387127 -350.399869) (xy 90.366342 -350.416622) (xy 90.354502 -350.426483) (xy 90.33698 -350.451815)
			(xy 90.327805 -350.481219) (xy 90.327811 -350.512021) (xy 90.336997 -350.541421) (xy 90.354529 -350.566746)
			(xy 90.366342 -350.576642) (xy 90.388854 -350.594799) (xy 90.428586 -350.636827) (xy 90.46152 -350.684369)
			(xy 90.486903 -350.736337) (xy 90.504154 -350.79154) (xy 90.512876 -350.848714) (xy 90.513408 -350.877632)
			(xy 90.512952 -350.904884) (xy 90.505191 -350.958833) (xy 90.489832 -351.011128) (xy 90.467187 -351.060705)
			(xy 90.437717 -351.106556) (xy 90.402023 -351.147746) (xy 90.36083 -351.183437) (xy 90.314977 -351.212902)
			(xy 90.265398 -351.235543) (xy 90.213102 -351.250898) (xy 90.159152 -351.258654) (xy 90.1319 -351.25914)
			(xy 90.102982 -351.258644) (xy 90.045809 -351.249914) (xy 89.990608 -351.232653) (xy 89.938646 -351.207257)
			(xy 89.891113 -351.174308) (xy 89.849098 -351.134562) (xy 89.83091 -351.112074) (xy 89.821013 -351.100269)
			(xy 89.795689 -351.08275) (xy 89.766296 -351.073574) (xy 89.735504 -351.073574) (xy 89.706111 -351.08275)
			(xy 89.680787 -351.100269) (xy 89.67089 -351.112074) (xy 89.652698 -351.134557) (xy 89.610679 -351.174293)
			(xy 89.563145 -351.207233) (xy 89.511184 -351.232622) (xy 89.455986 -351.249878) (xy 89.398816 -351.258606)
			(xy 89.3699 -351.25914) (xy 89.342694 -351.258661) (xy 89.288835 -351.250917) (xy 89.236622 -351.235599)
			(xy 89.187116 -351.21302) (xy 89.141319 -351.183636) (xy 89.100161 -351.148044) (xy 89.064477 -351.106966)
			(xy 89.03499 -351.061235) (xy 89.0123 -351.011779) (xy 88.996866 -350.959601) (xy 88.992456 -350.93275)
			(xy 88.989721 -350.91765) (xy 88.976444 -350.889996) (xy 88.955567 -350.867522) (xy 88.928965 -350.852247)
			(xy 88.89903 -350.845546) (xy 88.868455 -350.84802) (xy 88.854026 -350.853248) (xy 88.831378 -350.861945)
			(xy 88.784423 -350.874154) (xy 88.736298 -350.880304) (xy 88.71204 -350.88068) (xy 88.684787 -350.880207)
			(xy 88.630835 -350.872455) (xy 88.578535 -350.857103) (xy 88.528954 -350.834463) (xy 88.483099 -350.804996)
			(xy 88.441905 -350.769303) (xy 88.406211 -350.728111) (xy 88.376743 -350.682257) (xy 88.354101 -350.632676)
			(xy 88.338747 -350.580377) (xy 88.330993 -350.526425) (xy 88.330532 -350.499172) (xy 77.29388 -350.499172)
			(xy 77.293978 -350.505014) (xy 77.293492 -350.532265) (xy 77.285736 -350.586213) (xy 77.270381 -350.638508)
			(xy 77.247739 -350.688085) (xy 77.218273 -350.733935) (xy 77.182582 -350.775126) (xy 77.141391 -350.810817)
			(xy 77.095541 -350.840283) (xy 77.045964 -350.862925) (xy 76.993669 -350.87828) (xy 76.939721 -350.886036)
			(xy 76.885219 -350.886036) (xy 76.831271 -350.87828) (xy 76.778976 -350.862925) (xy 76.729399 -350.840283)
			(xy 76.683549 -350.810817) (xy 76.642358 -350.775126) (xy 76.606667 -350.733935) (xy 76.577201 -350.688085)
			(xy 76.554559 -350.638508) (xy 76.539204 -350.586213) (xy 76.531448 -350.532265) (xy 76.530962 -350.505014)
			(xy 76.372974 -350.505014) (xy 76.372974 -351.700592) (xy 103.994964 -351.700592) (xy 103.999035 -351.64497)
			(xy 104.011161 -351.590533) (xy 104.031084 -351.538442) (xy 104.05838 -351.489807) (xy 104.092466 -351.445664)
			(xy 104.132615 -351.406955) (xy 104.177973 -351.374504) (xy 104.227573 -351.349003) (xy 104.280357 -351.330996)
			(xy 104.3352 -351.320866) (xy 104.390934 -351.318829) (xy 104.446371 -351.324929) (xy 104.500328 -351.339035)
			(xy 104.551657 -351.360847) (xy 104.599263 -351.389901) (xy 104.642131 -351.425576) (xy 104.679348 -351.467113)
			(xy 104.710121 -351.513626) (xy 104.733793 -351.564123) (xy 104.749861 -351.61753) (xy 104.757981 -351.672706)
			(xy 104.75849 -351.700592) (xy 104.757981 -351.728478) (xy 104.749861 -351.783654) (xy 104.733793 -351.837061)
			(xy 104.721086 -351.864168) (xy 104.858564 -351.864168) (xy 104.862635 -351.808546) (xy 104.874761 -351.754109)
			(xy 104.894684 -351.702018) (xy 104.92198 -351.653383) (xy 104.956066 -351.60924) (xy 104.996215 -351.570531)
			(xy 105.041573 -351.53808) (xy 105.091173 -351.512579) (xy 105.143957 -351.494572) (xy 105.1988 -351.484442)
			(xy 105.254534 -351.482405) (xy 105.309971 -351.488505) (xy 105.357567 -351.500948) (xy 105.871262 -351.500948)
			(xy 105.875333 -351.445326) (xy 105.887459 -351.390889) (xy 105.907382 -351.338798) (xy 105.934678 -351.290163)
			(xy 105.968764 -351.24602) (xy 106.008913 -351.207311) (xy 106.054271 -351.17486) (xy 106.103871 -351.149359)
			(xy 106.156655 -351.131352) (xy 106.211498 -351.121222) (xy 106.267232 -351.119185) (xy 106.322669 -351.125285)
			(xy 106.376626 -351.139391) (xy 106.427955 -351.161203) (xy 106.475561 -351.190257) (xy 106.518429 -351.225932)
			(xy 106.555646 -351.267469) (xy 106.586419 -351.313982) (xy 106.610091 -351.364479) (xy 106.626159 -351.417886)
			(xy 106.634279 -351.473062) (xy 106.634788 -351.500948) (xy 106.887262 -351.500948) (xy 106.891333 -351.445326)
			(xy 106.903459 -351.390889) (xy 106.923382 -351.338798) (xy 106.950678 -351.290163) (xy 106.984764 -351.24602)
			(xy 107.024913 -351.207311) (xy 107.070271 -351.17486) (xy 107.119871 -351.149359) (xy 107.172655 -351.131352)
			(xy 107.227498 -351.121222) (xy 107.283232 -351.119185) (xy 107.338669 -351.125285) (xy 107.392626 -351.139391)
			(xy 107.443955 -351.161203) (xy 107.491561 -351.190257) (xy 107.534429 -351.225932) (xy 107.571646 -351.267469)
			(xy 107.602419 -351.313982) (xy 107.626091 -351.364479) (xy 107.642159 -351.417886) (xy 107.650279 -351.473062)
			(xy 107.650788 -351.500948) (xy 107.903262 -351.500948) (xy 107.907333 -351.445326) (xy 107.919459 -351.390889)
			(xy 107.939382 -351.338798) (xy 107.966678 -351.290163) (xy 108.000764 -351.24602) (xy 108.040913 -351.207311)
			(xy 108.086271 -351.17486) (xy 108.135871 -351.149359) (xy 108.188655 -351.131352) (xy 108.243498 -351.121222)
			(xy 108.299232 -351.119185) (xy 108.354669 -351.125285) (xy 108.408626 -351.139391) (xy 108.459955 -351.161203)
			(xy 108.507561 -351.190257) (xy 108.550429 -351.225932) (xy 108.587646 -351.267469) (xy 108.618419 -351.313982)
			(xy 108.642091 -351.364479) (xy 108.658159 -351.417886) (xy 108.666279 -351.473062) (xy 108.666788 -351.500948)
			(xy 108.919262 -351.500948) (xy 108.923333 -351.445326) (xy 108.935459 -351.390889) (xy 108.955382 -351.338798)
			(xy 108.982678 -351.290163) (xy 109.016764 -351.24602) (xy 109.056913 -351.207311) (xy 109.102271 -351.17486)
			(xy 109.151871 -351.149359) (xy 109.204655 -351.131352) (xy 109.259498 -351.121222) (xy 109.315232 -351.119185)
			(xy 109.370669 -351.125285) (xy 109.424626 -351.139391) (xy 109.475955 -351.161203) (xy 109.523561 -351.190257)
			(xy 109.566429 -351.225932) (xy 109.603646 -351.267469) (xy 109.634419 -351.313982) (xy 109.658091 -351.364479)
			(xy 109.674159 -351.417886) (xy 109.680028 -351.457768) (xy 111.131602 -351.457768) (xy 111.135673 -351.402146)
			(xy 111.147799 -351.347709) (xy 111.167722 -351.295618) (xy 111.195018 -351.246983) (xy 111.229104 -351.20284)
			(xy 111.269253 -351.164131) (xy 111.314611 -351.13168) (xy 111.364211 -351.106179) (xy 111.416995 -351.088172)
			(xy 111.471838 -351.078042) (xy 111.527572 -351.076005) (xy 111.583009 -351.082105) (xy 111.636966 -351.096211)
			(xy 111.688295 -351.118023) (xy 111.735901 -351.147077) (xy 111.778769 -351.182752) (xy 111.815986 -351.224289)
			(xy 111.846759 -351.270802) (xy 111.870431 -351.321299) (xy 111.886499 -351.374706) (xy 111.894619 -351.429882)
			(xy 111.895128 -351.457768) (xy 111.894619 -351.485654) (xy 111.886499 -351.54083) (xy 111.870431 -351.594237)
			(xy 111.846759 -351.644734) (xy 111.815986 -351.691247) (xy 111.778769 -351.732784) (xy 111.735901 -351.768459)
			(xy 111.688295 -351.797513) (xy 111.636966 -351.819325) (xy 111.583009 -351.833431) (xy 111.527572 -351.839531)
			(xy 111.471838 -351.837494) (xy 111.416995 -351.827364) (xy 111.364211 -351.809357) (xy 111.314611 -351.783856)
			(xy 111.269253 -351.751405) (xy 111.229104 -351.712696) (xy 111.195018 -351.668553) (xy 111.167722 -351.619918)
			(xy 111.147799 -351.567827) (xy 111.135673 -351.51339) (xy 111.131602 -351.457768) (xy 109.680028 -351.457768)
			(xy 109.682279 -351.473062) (xy 109.682788 -351.500948) (xy 109.682279 -351.528834) (xy 109.674159 -351.58401)
			(xy 109.658091 -351.637417) (xy 109.634419 -351.687914) (xy 109.603646 -351.734427) (xy 109.566429 -351.775964)
			(xy 109.523561 -351.811639) (xy 109.475955 -351.840693) (xy 109.424626 -351.862505) (xy 109.370669 -351.876611)
			(xy 109.315232 -351.882711) (xy 109.259498 -351.880674) (xy 109.204655 -351.870544) (xy 109.151871 -351.852537)
			(xy 109.102271 -351.827036) (xy 109.056913 -351.794585) (xy 109.016764 -351.755876) (xy 108.982678 -351.711733)
			(xy 108.955382 -351.663098) (xy 108.935459 -351.611007) (xy 108.923333 -351.55657) (xy 108.919262 -351.500948)
			(xy 108.666788 -351.500948) (xy 108.666279 -351.528834) (xy 108.658159 -351.58401) (xy 108.642091 -351.637417)
			(xy 108.618419 -351.687914) (xy 108.587646 -351.734427) (xy 108.550429 -351.775964) (xy 108.507561 -351.811639)
			(xy 108.459955 -351.840693) (xy 108.408626 -351.862505) (xy 108.354669 -351.876611) (xy 108.299232 -351.882711)
			(xy 108.243498 -351.880674) (xy 108.188655 -351.870544) (xy 108.135871 -351.852537) (xy 108.086271 -351.827036)
			(xy 108.040913 -351.794585) (xy 108.000764 -351.755876) (xy 107.966678 -351.711733) (xy 107.939382 -351.663098)
			(xy 107.919459 -351.611007) (xy 107.907333 -351.55657) (xy 107.903262 -351.500948) (xy 107.650788 -351.500948)
			(xy 107.650279 -351.528834) (xy 107.642159 -351.58401) (xy 107.626091 -351.637417) (xy 107.602419 -351.687914)
			(xy 107.571646 -351.734427) (xy 107.534429 -351.775964) (xy 107.491561 -351.811639) (xy 107.443955 -351.840693)
			(xy 107.392626 -351.862505) (xy 107.338669 -351.876611) (xy 107.283232 -351.882711) (xy 107.227498 -351.880674)
			(xy 107.172655 -351.870544) (xy 107.119871 -351.852537) (xy 107.070271 -351.827036) (xy 107.024913 -351.794585)
			(xy 106.984764 -351.755876) (xy 106.950678 -351.711733) (xy 106.923382 -351.663098) (xy 106.903459 -351.611007)
			(xy 106.891333 -351.55657) (xy 106.887262 -351.500948) (xy 106.634788 -351.500948) (xy 106.634279 -351.528834)
			(xy 106.626159 -351.58401) (xy 106.610091 -351.637417) (xy 106.586419 -351.687914) (xy 106.555646 -351.734427)
			(xy 106.518429 -351.775964) (xy 106.475561 -351.811639) (xy 106.427955 -351.840693) (xy 106.376626 -351.862505)
			(xy 106.322669 -351.876611) (xy 106.267232 -351.882711) (xy 106.211498 -351.880674) (xy 106.156655 -351.870544)
			(xy 106.103871 -351.852537) (xy 106.054271 -351.827036) (xy 106.008913 -351.794585) (xy 105.968764 -351.755876)
			(xy 105.934678 -351.711733) (xy 105.907382 -351.663098) (xy 105.887459 -351.611007) (xy 105.875333 -351.55657)
			(xy 105.871262 -351.500948) (xy 105.357567 -351.500948) (xy 105.363928 -351.502611) (xy 105.415257 -351.524423)
			(xy 105.462863 -351.553477) (xy 105.505731 -351.589152) (xy 105.542948 -351.630689) (xy 105.573721 -351.677202)
			(xy 105.597393 -351.727699) (xy 105.613461 -351.781106) (xy 105.621581 -351.836282) (xy 105.62209 -351.864168)
			(xy 105.621581 -351.892054) (xy 105.613461 -351.94723) (xy 105.597393 -352.000637) (xy 105.573721 -352.051134)
			(xy 105.542948 -352.097647) (xy 105.505731 -352.139184) (xy 105.462863 -352.174859) (xy 105.415257 -352.203913)
			(xy 105.363928 -352.225725) (xy 105.309971 -352.239831) (xy 105.254534 -352.245931) (xy 105.1988 -352.243894)
			(xy 105.143957 -352.233764) (xy 105.091173 -352.215757) (xy 105.041573 -352.190256) (xy 104.996215 -352.157805)
			(xy 104.956066 -352.119096) (xy 104.92198 -352.074953) (xy 104.894684 -352.026318) (xy 104.874761 -351.974227)
			(xy 104.862635 -351.91979) (xy 104.858564 -351.864168) (xy 104.721086 -351.864168) (xy 104.710121 -351.887558)
			(xy 104.679348 -351.934071) (xy 104.642131 -351.975608) (xy 104.599263 -352.011283) (xy 104.551657 -352.040337)
			(xy 104.500328 -352.062149) (xy 104.446371 -352.076255) (xy 104.390934 -352.082355) (xy 104.3352 -352.080318)
			(xy 104.280357 -352.070188) (xy 104.227573 -352.052181) (xy 104.177973 -352.02668) (xy 104.132615 -351.994229)
			(xy 104.092466 -351.95552) (xy 104.05838 -351.911377) (xy 104.031084 -351.862742) (xy 104.011161 -351.810651)
			(xy 103.999035 -351.756214) (xy 103.994964 -351.700592) (xy 76.372974 -351.700592) (xy 76.372974 -352.310954)
			(xy 76.40806 -352.396298) (xy 110.560102 -352.396298) (xy 110.564173 -352.340676) (xy 110.576299 -352.286239)
			(xy 110.596222 -352.234148) (xy 110.623518 -352.185513) (xy 110.657604 -352.14137) (xy 110.697753 -352.102661)
			(xy 110.743111 -352.07021) (xy 110.792711 -352.044709) (xy 110.845495 -352.026702) (xy 110.900338 -352.016572)
			(xy 110.956072 -352.014535) (xy 111.011509 -352.020635) (xy 111.065466 -352.034741) (xy 111.116795 -352.056553)
			(xy 111.164401 -352.085607) (xy 111.207269 -352.121282) (xy 111.244486 -352.162819) (xy 111.275259 -352.209332)
			(xy 111.298931 -352.259829) (xy 111.314999 -352.313236) (xy 111.323119 -352.368412) (xy 111.323628 -352.396298)
			(xy 111.323119 -352.424184) (xy 111.314999 -352.47936) (xy 111.298931 -352.532767) (xy 111.275259 -352.583264)
			(xy 111.244486 -352.629777) (xy 111.207269 -352.671314) (xy 111.164401 -352.706989) (xy 111.116795 -352.736043)
			(xy 111.065466 -352.757855) (xy 111.011509 -352.771961) (xy 110.956072 -352.778061) (xy 110.900338 -352.776024)
			(xy 110.845495 -352.765894) (xy 110.792711 -352.747887) (xy 110.743111 -352.722386) (xy 110.697753 -352.689935)
			(xy 110.657604 -352.651226) (xy 110.623518 -352.607083) (xy 110.596222 -352.558448) (xy 110.576299 -352.506357)
			(xy 110.564173 -352.45192) (xy 110.560102 -352.396298) (xy 76.40806 -352.396298) (xy 76.58756 -352.832924)
			(xy 112.35385 -352.832924) (xy 112.357921 -352.777302) (xy 112.370047 -352.722865) (xy 112.38997 -352.670774)
			(xy 112.417266 -352.622139) (xy 112.451352 -352.577996) (xy 112.491501 -352.539287) (xy 112.536859 -352.506836)
			(xy 112.586459 -352.481335) (xy 112.639243 -352.463328) (xy 112.694086 -352.453198) (xy 112.74982 -352.451161)
			(xy 112.805257 -352.457261) (xy 112.859214 -352.471367) (xy 112.910543 -352.493179) (xy 112.958149 -352.522233)
			(xy 113.001017 -352.557908) (xy 113.038234 -352.599445) (xy 113.069007 -352.645958) (xy 113.092679 -352.696455)
			(xy 113.108747 -352.749862) (xy 113.116867 -352.805038) (xy 113.117376 -352.832924) (xy 113.116867 -352.86081)
			(xy 113.108747 -352.915986) (xy 113.092679 -352.969393) (xy 113.069007 -353.01989) (xy 113.038234 -353.066403)
			(xy 113.001017 -353.10794) (xy 112.958149 -353.143615) (xy 112.910543 -353.172669) (xy 112.859214 -353.194481)
			(xy 112.805257 -353.208587) (xy 112.74982 -353.214687) (xy 112.694086 -353.21265) (xy 112.639243 -353.20252)
			(xy 112.586459 -353.184513) (xy 112.536859 -353.159012) (xy 112.491501 -353.126561) (xy 112.451352 -353.087852)
			(xy 112.417266 -353.043709) (xy 112.38997 -352.995074) (xy 112.370047 -352.942983) (xy 112.357921 -352.888546)
			(xy 112.35385 -352.832924) (xy 76.58756 -352.832924) (xy 76.857071 -353.488498) (xy 110.4806 -353.488498)
			(xy 110.484671 -353.432876) (xy 110.496797 -353.378439) (xy 110.51672 -353.326348) (xy 110.544016 -353.277713)
			(xy 110.578102 -353.23357) (xy 110.618251 -353.194861) (xy 110.663609 -353.16241) (xy 110.713209 -353.136909)
			(xy 110.765993 -353.118902) (xy 110.820836 -353.108772) (xy 110.87657 -353.106735) (xy 110.932007 -353.112835)
			(xy 110.985964 -353.126941) (xy 111.037293 -353.148753) (xy 111.084899 -353.177807) (xy 111.127767 -353.213482)
			(xy 111.164984 -353.255019) (xy 111.195757 -353.301532) (xy 111.219429 -353.352029) (xy 111.235497 -353.405436)
			(xy 111.243617 -353.460612) (xy 111.244126 -353.488498) (xy 111.243617 -353.516384) (xy 111.241179 -353.532948)
			(xy 113.415062 -353.532948) (xy 113.419133 -353.477326) (xy 113.431259 -353.422889) (xy 113.451182 -353.370798)
			(xy 113.478478 -353.322163) (xy 113.512564 -353.27802) (xy 113.552713 -353.239311) (xy 113.598071 -353.20686)
			(xy 113.647671 -353.181359) (xy 113.700455 -353.163352) (xy 113.755298 -353.153222) (xy 113.811032 -353.151185)
			(xy 113.866469 -353.157285) (xy 113.920426 -353.171391) (xy 113.971755 -353.193203) (xy 114.019361 -353.222257)
			(xy 114.062229 -353.257932) (xy 114.099446 -353.299469) (xy 114.130219 -353.345982) (xy 114.153891 -353.396479)
			(xy 114.169959 -353.449886) (xy 114.178079 -353.505062) (xy 114.178588 -353.532948) (xy 114.178079 -353.560834)
			(xy 114.169959 -353.61601) (xy 114.153891 -353.669417) (xy 114.130219 -353.719914) (xy 114.099446 -353.766427)
			(xy 114.062229 -353.807964) (xy 114.019361 -353.843639) (xy 113.971755 -353.872693) (xy 113.920426 -353.894505)
			(xy 113.866469 -353.908611) (xy 113.811032 -353.914711) (xy 113.755298 -353.912674) (xy 113.700455 -353.902544)
			(xy 113.647671 -353.884537) (xy 113.598071 -353.859036) (xy 113.552713 -353.826585) (xy 113.512564 -353.787876)
			(xy 113.478478 -353.743733) (xy 113.451182 -353.695098) (xy 113.431259 -353.643007) (xy 113.419133 -353.58857)
			(xy 113.415062 -353.532948) (xy 111.241179 -353.532948) (xy 111.235497 -353.57156) (xy 111.219429 -353.624967)
			(xy 111.195757 -353.675464) (xy 111.164984 -353.721977) (xy 111.127767 -353.763514) (xy 111.084899 -353.799189)
			(xy 111.037293 -353.828243) (xy 110.985964 -353.850055) (xy 110.932007 -353.864161) (xy 110.87657 -353.870261)
			(xy 110.820836 -353.868224) (xy 110.765993 -353.858094) (xy 110.713209 -353.840087) (xy 110.663609 -353.814586)
			(xy 110.618251 -353.782135) (xy 110.578102 -353.743426) (xy 110.544016 -353.699283) (xy 110.51672 -353.650648)
			(xy 110.496797 -353.598557) (xy 110.484671 -353.54412) (xy 110.4806 -353.488498) (xy 76.857071 -353.488498)
			(xy 77.498217 -355.048058) (xy 99.42652 -355.048058) (xy 99.430591 -354.992436) (xy 99.442717 -354.937999)
			(xy 99.46264 -354.885908) (xy 99.489936 -354.837273) (xy 99.524022 -354.79313) (xy 99.564171 -354.754421)
			(xy 99.609529 -354.72197) (xy 99.659129 -354.696469) (xy 99.711913 -354.678462) (xy 99.766756 -354.668332)
			(xy 99.82249 -354.666295) (xy 99.877927 -354.672395) (xy 99.931884 -354.686501) (xy 99.983213 -354.708313)
			(xy 100.030819 -354.737367) (xy 100.073687 -354.773042) (xy 100.110904 -354.814579) (xy 100.141677 -354.861092)
			(xy 100.165349 -354.911589) (xy 100.181417 -354.964996) (xy 100.189537 -355.020172) (xy 100.190046 -355.048058)
			(xy 100.189537 -355.075944) (xy 100.181417 -355.13112) (xy 100.165349 -355.184527) (xy 100.141677 -355.235024)
			(xy 100.110904 -355.281537) (xy 100.073687 -355.323074) (xy 100.030819 -355.358749) (xy 99.983213 -355.387803)
			(xy 99.931884 -355.409615) (xy 99.877927 -355.423721) (xy 99.82249 -355.429821) (xy 99.766756 -355.427784)
			(xy 99.711913 -355.417654) (xy 99.659129 -355.399647) (xy 99.609529 -355.374146) (xy 99.564171 -355.341695)
			(xy 99.524022 -355.302986) (xy 99.489936 -355.258843) (xy 99.46264 -355.210208) (xy 99.442717 -355.158117)
			(xy 99.430591 -355.10368) (xy 99.42652 -355.048058) (xy 77.498217 -355.048058) (xy 79.531717 -359.994454)
			(xy 87.567516 -359.994454) (xy 87.568039 -359.964944) (xy 87.577109 -359.906626) (xy 87.595057 -359.850402)
			(xy 87.621454 -359.797615) (xy 87.655669 -359.749525) (xy 87.696885 -359.707282) (xy 87.72017 -359.689146)
			(xy 87.731669 -359.679895) (xy 87.749252 -359.65621) (xy 87.759335 -359.628487) (xy 87.761075 -359.59904)
			(xy 87.754328 -359.570324) (xy 87.739657 -359.544732) (xy 87.729314 -359.534206) (xy 87.710907 -359.516162)
			(xy 87.678669 -359.475943) (xy 87.652144 -359.431746) (xy 87.631817 -359.384378) (xy 87.618058 -359.334703)
			(xy 87.611119 -359.283627) (xy 87.610696 -359.257854) (xy 87.611135 -359.230601) (xy 87.618898 -359.176652)
			(xy 87.634259 -359.124356) (xy 87.656906 -359.074778) (xy 87.686377 -359.028928) (xy 87.722074 -358.987738)
			(xy 87.763268 -358.952047) (xy 87.809122 -358.922582) (xy 87.858703 -358.899942) (xy 87.911001 -358.884587)
			(xy 87.964951 -358.876831) (xy 87.992204 -358.876346) (xy 88.020942 -358.876882) (xy 88.077768 -358.885504)
			(xy 88.132658 -358.902552) (xy 88.18437 -358.92764) (xy 88.231734 -358.960201) (xy 88.253062 -358.97947)
			(xy 88.264929 -358.989692) (xy 88.293199 -359.003124) (xy 88.324209 -359.007369) (xy 88.35505 -359.002028)
			(xy 88.382827 -358.987604) (xy 88.394286 -358.97693) (xy 88.403382 -358.96806) (xy 88.422574 -358.951408)
			(xy 88.43264 -358.943656) (xy 88.444447 -358.933923) (xy 88.462142 -358.908978) (xy 88.471662 -358.879914)
			(xy 88.472154 -358.849335) (xy 88.463574 -358.81998) (xy 88.44669 -358.794479) (xy 88.43518 -358.784398)
			(xy 88.413773 -358.766185) (xy 88.376036 -358.724534) (xy 88.344817 -358.677798) (xy 88.320791 -358.626987)
			(xy 88.30448 -358.573202) (xy 88.296234 -358.517606) (xy 88.295734 -358.489504) (xy 88.296173 -358.463163)
			(xy 88.303428 -358.410981) (xy 88.317788 -358.360293) (xy 88.338978 -358.31206) (xy 88.366598 -358.267197)
			(xy 88.400123 -358.226557) (xy 88.438915 -358.190911) (xy 88.460326 -358.17556) (xy 88.472459 -358.166357)
			(xy 88.491238 -358.142411) (xy 88.502137 -358.113999) (xy 88.504189 -358.083637) (xy 88.497214 -358.054017)
			(xy 88.481828 -358.027762) (xy 88.470994 -358.017064) (xy 88.451748 -357.998917) (xy 88.417965 -357.958213)
			(xy 88.390127 -357.913234) (xy 88.368767 -357.864841) (xy 88.354294 -357.813962) (xy 88.346986 -357.761573)
			(xy 88.346534 -357.735124) (xy 88.347047 -357.707644) (xy 88.354936 -357.653254) (xy 88.370553 -357.600559)
			(xy 88.393575 -357.550654) (xy 88.423525 -357.504572) (xy 88.459782 -357.463268) (xy 88.501594 -357.427598)
			(xy 88.524588 -357.412544) (xy 88.536216 -357.404727) (xy 88.554933 -357.383886) (xy 88.567286 -357.358745)
			(xy 88.572344 -357.331193) (xy 88.569727 -357.303304) (xy 88.559632 -357.277174) (xy 88.542819 -357.254769)
			(xy 88.531954 -357.24592) (xy 88.509103 -357.227703) (xy 88.468635 -357.185548) (xy 88.435063 -357.137719)
			(xy 88.409171 -357.085333) (xy 88.391564 -357.029614) (xy 88.382653 -356.971862) (xy 88.382094 -356.942644)
			(xy 88.382629 -356.913474) (xy 88.391536 -356.855819) (xy 88.409119 -356.800192) (xy 88.434968 -356.747892)
			(xy 88.468479 -356.700137) (xy 88.508871 -356.658042) (xy 88.5317 -356.639876) (xy 88.54349 -356.630122)
			(xy 88.561192 -356.605185) (xy 88.570719 -356.576125) (xy 88.571214 -356.545548) (xy 88.562635 -356.516195)
			(xy 88.54575 -356.490697) (xy 88.53424 -356.480618) (xy 88.512834 -356.462404) (xy 88.475099 -356.420752)
			(xy 88.443881 -356.374015) (xy 88.419855 -356.323205) (xy 88.403543 -356.269421) (xy 88.395295 -356.213826)
			(xy 88.394794 -356.185724) (xy 88.395234 -356.15908) (xy 88.40264 -356.106308) (xy 88.417325 -356.055083)
			(xy 88.439004 -356.006404) (xy 88.467252 -355.961219) (xy 88.50152 -355.920409) (xy 88.521032 -355.90226)
			(xy 88.530713 -355.892925) (xy 88.545327 -355.870366) (xy 88.553537 -355.844771) (xy 88.554773 -355.81792)
			(xy 88.548948 -355.791679) (xy 88.536467 -355.767873) (xy 88.527636 -355.757734) (xy 88.508665 -355.736462)
			(xy 88.476607 -355.689336) (xy 88.451906 -355.637971) (xy 88.435109 -355.583507) (xy 88.42659 -355.527151)
			(xy 88.426036 -355.498654) (xy 88.426435 -355.4714) (xy 88.434199 -355.417446) (xy 88.449562 -355.365147)
			(xy 88.472212 -355.315567) (xy 88.501687 -355.269715) (xy 88.537388 -355.228524) (xy 88.578587 -355.192833)
			(xy 88.624446 -355.163369) (xy 88.674032 -355.140731) (xy 88.726335 -355.12538) (xy 88.78029 -355.117629)
			(xy 88.807544 -355.117146) (xy 88.834954 -355.117634) (xy 88.889209 -355.125473) (xy 88.941784 -355.140999)
			(xy 88.991595 -355.163892) (xy 89.037615 -355.193679) (xy 89.078897 -355.229748) (xy 89.097104 -355.250242)
			(xy 89.106461 -355.260357) (xy 89.12933 -355.275699) (xy 89.155469 -355.284364) (xy 89.182974 -355.285721)
			(xy 89.20984 -355.279669) (xy 89.234107 -355.266652) (xy 89.254008 -355.247617) (xy 89.261442 -355.236018)
			(xy 89.276312 -355.212088) (xy 89.31195 -355.168457) (xy 89.353619 -355.130542) (xy 89.400412 -355.099171)
			(xy 89.451312 -355.075025) (xy 89.50521 -355.058629) (xy 89.560934 -355.050342) (xy 89.589102 -355.049836)
			(xy 89.61802 -355.050339) (xy 89.675192 -355.05907) (xy 89.730392 -355.07633) (xy 89.782354 -355.101724)
			(xy 89.829887 -355.134671) (xy 89.871903 -355.174415) (xy 89.890092 -355.196902) (xy 89.899989 -355.208707)
			(xy 89.925313 -355.226226) (xy 89.954706 -355.235402) (xy 89.985498 -355.235402) (xy 90.014891 -355.226226)
			(xy 90.040215 -355.208707) (xy 90.050112 -355.196902) (xy 90.066865 -355.176119) (xy 90.105219 -355.138989)
			(xy 90.148373 -355.107567) (xy 90.195487 -355.082468) (xy 90.245639 -355.064182) (xy 90.29785 -355.053065)
			(xy 90.351102 -355.049335) (xy 90.404354 -355.053065) (xy 90.456565 -355.064182) (xy 90.506717 -355.082468)
			(xy 90.553831 -355.107567) (xy 90.596985 -355.138989) (xy 90.635339 -355.176119) (xy 90.652092 -355.196902)
			(xy 90.661989 -355.208707) (xy 90.687313 -355.226226) (xy 90.716706 -355.235402) (xy 90.747498 -355.235402)
			(xy 90.776891 -355.226226) (xy 90.802215 -355.208707) (xy 90.812112 -355.196902) (xy 90.830297 -355.174413)
			(xy 90.872318 -355.134678) (xy 90.919854 -355.10174) (xy 90.971816 -355.076352) (xy 91.027015 -355.059097)
			(xy 91.084186 -355.05037) (xy 91.113102 -355.049836) (xy 91.142411 -355.05037) (xy 91.200337 -355.059342)
			(xy 91.256208 -355.077074) (xy 91.308707 -355.103148) (xy 91.356596 -355.13695) (xy 91.398748 -355.177684)
			(xy 91.416886 -355.200712) (xy 91.426627 -355.212609) (xy 91.451624 -355.230485) (xy 91.48081 -355.240107)
			(xy 91.511537 -355.240603) (xy 91.541018 -355.231927) (xy 91.566578 -355.214866) (xy 91.576652 -355.203252)
			(xy 91.594896 -355.181695) (xy 91.636601 -355.143621) (xy 91.683463 -355.112111) (xy 91.734459 -355.087854)
			(xy 91.788474 -355.07138) (xy 91.844327 -355.063049) (xy 91.872562 -355.062536) (xy 91.901479 -355.063068)
			(xy 91.95865 -355.071792) (xy 92.013849 -355.089047) (xy 92.065811 -355.114436) (xy 92.113345 -355.147377)
			(xy 92.155362 -355.187117) (xy 92.173552 -355.209602) (xy 92.183449 -355.221407) (xy 92.208773 -355.238926)
			(xy 92.238166 -355.248102) (xy 92.268958 -355.248102) (xy 92.298351 -355.238926) (xy 92.323675 -355.221407)
			(xy 92.333572 -355.209602) (xy 92.350325 -355.188819) (xy 92.388679 -355.151689) (xy 92.431833 -355.120267)
			(xy 92.478947 -355.095168) (xy 92.529099 -355.076882) (xy 92.58131 -355.065765) (xy 92.634562 -355.062035)
			(xy 92.687814 -355.065765) (xy 92.740025 -355.076882) (xy 92.790177 -355.095168) (xy 92.837291 -355.120267)
			(xy 92.880445 -355.151689) (xy 92.918799 -355.188819) (xy 92.935552 -355.209602) (xy 92.945449 -355.221407)
			(xy 92.970773 -355.238926) (xy 93.000166 -355.248102) (xy 93.030958 -355.248102) (xy 93.060351 -355.238926)
			(xy 93.085675 -355.221407) (xy 93.095572 -355.209602) (xy 93.112325 -355.188819) (xy 93.150679 -355.151689)
			(xy 93.193833 -355.120267) (xy 93.240947 -355.095168) (xy 93.291099 -355.076882) (xy 93.34331 -355.065765)
			(xy 93.396562 -355.062035) (xy 93.449814 -355.065765) (xy 93.502025 -355.076882) (xy 93.552177 -355.095168)
			(xy 93.599291 -355.120267) (xy 93.642445 -355.151689) (xy 93.680799 -355.188819) (xy 93.697552 -355.209602)
			(xy 93.707449 -355.221407) (xy 93.732773 -355.238926) (xy 93.762166 -355.248102) (xy 93.792958 -355.248102)
			(xy 93.822351 -355.238926) (xy 93.847675 -355.221407) (xy 93.857572 -355.209602) (xy 93.874325 -355.188819)
			(xy 93.912679 -355.151689) (xy 93.955833 -355.120267) (xy 94.002947 -355.095168) (xy 94.053099 -355.076882)
			(xy 94.10531 -355.065765) (xy 94.158562 -355.062035) (xy 94.211814 -355.065765) (xy 94.264025 -355.076882)
			(xy 94.314177 -355.095168) (xy 94.361291 -355.120267) (xy 94.404445 -355.151689) (xy 94.442799 -355.188819)
			(xy 94.459552 -355.209602) (xy 94.469449 -355.221407) (xy 94.494773 -355.238926) (xy 94.524166 -355.248102)
			(xy 94.554958 -355.248102) (xy 94.584351 -355.238926) (xy 94.609675 -355.221407) (xy 94.619572 -355.209602)
			(xy 94.637779 -355.187132) (xy 94.679796 -355.147396) (xy 94.727327 -355.114456) (xy 94.779285 -355.089065)
			(xy 94.83448 -355.071805) (xy 94.891647 -355.063073) (xy 94.920562 -355.062536) (xy 94.946814 -355.062978)
			(xy 94.998823 -355.070162) (xy 95.049354 -355.084412) (xy 95.097454 -355.10546) (xy 95.142211 -355.132907)
			(xy 95.182779 -355.166235) (xy 95.218392 -355.204813) (xy 95.233744 -355.226112) (xy 95.242108 -355.237325)
			(xy 95.263733 -355.255051) (xy 95.289357 -355.266248) (xy 95.317056 -355.270076) (xy 95.344755 -355.266248)
			(xy 95.370379 -355.255051) (xy 95.392004 -355.237325) (xy 95.400368 -355.226112) (xy 95.415735 -355.204826)
			(xy 95.451355 -355.166259) (xy 95.491925 -355.132939) (xy 95.536679 -355.105493) (xy 95.584773 -355.084441)
			(xy 95.635297 -355.070179) (xy 95.6873 -355.062976) (xy 95.71355 -355.062536) (xy 95.742466 -355.063076)
			(xy 95.799637 -355.071799) (xy 95.854836 -355.089052) (xy 95.906798 -355.114439) (xy 95.954333 -355.147379)
			(xy 95.99635 -355.187118) (xy 96.01454 -355.209602) (xy 96.024437 -355.221407) (xy 96.049761 -355.238926)
			(xy 96.079154 -355.248102) (xy 96.109946 -355.248102) (xy 96.139339 -355.238926) (xy 96.164663 -355.221407)
			(xy 96.17456 -355.209602) (xy 96.192774 -355.187138) (xy 96.234789 -355.147402) (xy 96.282319 -355.11446)
			(xy 96.334276 -355.089068) (xy 96.389469 -355.071808) (xy 96.446635 -355.063074) (xy 96.47555 -355.062536)
			(xy 96.502804 -355.063002) (xy 96.556757 -355.070753) (xy 96.609057 -355.086105) (xy 96.65864 -355.108745)
			(xy 96.704496 -355.138212) (xy 96.74569 -355.173906) (xy 96.781384 -355.2151) (xy 96.810852 -355.260955)
			(xy 96.833493 -355.310537) (xy 96.848845 -355.362837) (xy 96.856598 -355.41679) (xy 96.857058 -355.444044)
			(xy 96.856516 -355.47296) (xy 96.847794 -355.530131) (xy 96.830542 -355.58533) (xy 96.805155 -355.637292)
			(xy 96.772215 -355.684827) (xy 96.732476 -355.726844) (xy 96.709992 -355.745034) (xy 96.698145 -355.754885)
			(xy 96.680632 -355.780222) (xy 96.671463 -355.809627) (xy 96.671471 -355.840427) (xy 96.680655 -355.869827)
			(xy 96.698182 -355.895155) (xy 96.709992 -355.905054) (xy 96.730821 -355.921754) (xy 96.767956 -355.960111)
			(xy 96.799382 -356.003272) (xy 96.824483 -356.050391) (xy 96.84277 -356.10055) (xy 96.853885 -356.152769)
			(xy 96.857612 -356.206027) (xy 96.853878 -356.259285) (xy 96.842755 -356.311502) (xy 96.824461 -356.361658)
			(xy 96.799353 -356.408774) (xy 96.767921 -356.45193) (xy 96.73078 -356.490282) (xy 96.709992 -356.507034)
			(xy 96.698145 -356.516885) (xy 96.680632 -356.542222) (xy 96.671463 -356.571627) (xy 96.671471 -356.602427)
			(xy 96.680655 -356.631827) (xy 96.684643 -356.63759) (xy 98.915218 -356.63759) (xy 98.919289 -356.581968)
			(xy 98.931415 -356.527531) (xy 98.951338 -356.47544) (xy 98.978634 -356.426805) (xy 99.01272 -356.382662)
			(xy 99.052869 -356.343953) (xy 99.098227 -356.311502) (xy 99.147827 -356.286001) (xy 99.200611 -356.267994)
			(xy 99.255454 -356.257864) (xy 99.311188 -356.255827) (xy 99.366625 -356.261927) (xy 99.420582 -356.276033)
			(xy 99.471911 -356.297845) (xy 99.519517 -356.326899) (xy 99.562385 -356.362574) (xy 99.599602 -356.404111)
			(xy 99.630375 -356.450624) (xy 99.654047 -356.501121) (xy 99.670115 -356.554528) (xy 99.678235 -356.609704)
			(xy 99.678744 -356.63759) (xy 99.678235 -356.665476) (xy 99.670115 -356.720652) (xy 99.654047 -356.774059)
			(xy 99.630375 -356.824556) (xy 99.599602 -356.871069) (xy 99.562385 -356.912606) (xy 99.519517 -356.948281)
			(xy 99.471911 -356.977335) (xy 99.420582 -356.999147) (xy 99.366625 -357.013253) (xy 99.311188 -357.019353)
			(xy 99.255454 -357.017316) (xy 99.200611 -357.007186) (xy 99.147827 -356.989179) (xy 99.098227 -356.963678)
			(xy 99.052869 -356.931227) (xy 99.01272 -356.892518) (xy 98.978634 -356.848375) (xy 98.951338 -356.79974)
			(xy 98.931415 -356.747649) (xy 98.919289 -356.693212) (xy 98.915218 -356.63759) (xy 96.684643 -356.63759)
			(xy 96.698182 -356.657155) (xy 96.709992 -356.667054) (xy 96.730821 -356.683754) (xy 96.767956 -356.722111)
			(xy 96.799382 -356.765272) (xy 96.824483 -356.812391) (xy 96.84277 -356.86255) (xy 96.853885 -356.914769)
			(xy 96.857612 -356.968027) (xy 96.853878 -357.021285) (xy 96.842755 -357.073502) (xy 96.824461 -357.123658)
			(xy 96.799353 -357.170774) (xy 96.767921 -357.21393) (xy 96.73078 -357.252282) (xy 96.709992 -357.269034)
			(xy 96.698145 -357.278885) (xy 96.680632 -357.304222) (xy 96.671463 -357.333627) (xy 96.671471 -357.364427)
			(xy 96.680655 -357.393827) (xy 96.698182 -357.419155) (xy 96.709992 -357.429054) (xy 96.730821 -357.445754)
			(xy 96.767956 -357.484111) (xy 96.799382 -357.527272) (xy 96.801725 -357.53167) (xy 98.915218 -357.53167)
			(xy 98.919289 -357.476048) (xy 98.931415 -357.421611) (xy 98.951338 -357.36952) (xy 98.978634 -357.320885)
			(xy 99.01272 -357.276742) (xy 99.052869 -357.238033) (xy 99.098227 -357.205582) (xy 99.147827 -357.180081)
			(xy 99.200611 -357.162074) (xy 99.255454 -357.151944) (xy 99.311188 -357.149907) (xy 99.366625 -357.156007)
			(xy 99.420582 -357.170113) (xy 99.471911 -357.191925) (xy 99.519517 -357.220979) (xy 99.562385 -357.256654)
			(xy 99.599602 -357.298191) (xy 99.630375 -357.344704) (xy 99.654047 -357.395201) (xy 99.670115 -357.448608)
			(xy 99.678235 -357.503784) (xy 99.678744 -357.53167) (xy 99.678235 -357.559556) (xy 99.670115 -357.614732)
			(xy 99.654047 -357.668139) (xy 99.630375 -357.718636) (xy 99.599602 -357.765149) (xy 99.562385 -357.806686)
			(xy 99.519517 -357.842361) (xy 99.471911 -357.871415) (xy 99.420582 -357.893227) (xy 99.366625 -357.907333)
			(xy 99.311188 -357.913433) (xy 99.255454 -357.911396) (xy 99.200611 -357.901266) (xy 99.147827 -357.883259)
			(xy 99.098227 -357.857758) (xy 99.052869 -357.825307) (xy 99.01272 -357.786598) (xy 98.978634 -357.742455)
			(xy 98.951338 -357.69382) (xy 98.931415 -357.641729) (xy 98.919289 -357.587292) (xy 98.915218 -357.53167)
			(xy 96.801725 -357.53167) (xy 96.824483 -357.574391) (xy 96.84277 -357.62455) (xy 96.853885 -357.676769)
			(xy 96.857612 -357.730027) (xy 96.853878 -357.783285) (xy 96.842755 -357.835502) (xy 96.824461 -357.885658)
			(xy 96.799353 -357.932774) (xy 96.767921 -357.97593) (xy 96.73078 -358.014282) (xy 96.709992 -358.031034)
			(xy 96.698145 -358.040885) (xy 96.680632 -358.066222) (xy 96.671463 -358.095627) (xy 96.671471 -358.126427)
			(xy 96.680655 -358.155827) (xy 96.698182 -358.181155) (xy 96.709992 -358.191054) (xy 96.730821 -358.207754)
			(xy 96.767956 -358.246111) (xy 96.799382 -358.289272) (xy 96.824483 -358.336391) (xy 96.84277 -358.38655)
			(xy 96.853885 -358.438769) (xy 96.857612 -358.492027) (xy 96.853878 -358.545285) (xy 96.842755 -358.597502)
			(xy 96.824461 -358.647658) (xy 96.799353 -358.694774) (xy 96.767921 -358.73793) (xy 96.73078 -358.776282)
			(xy 96.709992 -358.793034) (xy 96.698145 -358.802885) (xy 96.680632 -358.828222) (xy 96.671463 -358.857627)
			(xy 96.671471 -358.888427) (xy 96.674997 -358.899714) (xy 98.910138 -358.899714) (xy 98.914209 -358.844092)
			(xy 98.926335 -358.789655) (xy 98.946258 -358.737564) (xy 98.973554 -358.688929) (xy 99.00764 -358.644786)
			(xy 99.047789 -358.606077) (xy 99.093147 -358.573626) (xy 99.142747 -358.548125) (xy 99.195531 -358.530118)
			(xy 99.250374 -358.519988) (xy 99.306108 -358.517951) (xy 99.361545 -358.524051) (xy 99.415502 -358.538157)
			(xy 99.466831 -358.559969) (xy 99.514437 -358.589023) (xy 99.557305 -358.624698) (xy 99.594522 -358.666235)
			(xy 99.625295 -358.712748) (xy 99.648967 -358.763245) (xy 99.665035 -358.816652) (xy 99.673155 -358.871828)
			(xy 99.673664 -358.899714) (xy 99.673155 -358.9276) (xy 99.665035 -358.982776) (xy 99.648967 -359.036183)
			(xy 99.625295 -359.08668) (xy 99.594522 -359.133193) (xy 99.557305 -359.17473) (xy 99.514437 -359.210405)
			(xy 99.466831 -359.239459) (xy 99.415502 -359.261271) (xy 99.361545 -359.275377) (xy 99.306108 -359.281477)
			(xy 99.250374 -359.27944) (xy 99.195531 -359.26931) (xy 99.142747 -359.251303) (xy 99.093147 -359.225802)
			(xy 99.047789 -359.193351) (xy 99.00764 -359.154642) (xy 98.973554 -359.110499) (xy 98.946258 -359.061864)
			(xy 98.926335 -359.009773) (xy 98.914209 -358.955336) (xy 98.910138 -358.899714) (xy 96.674997 -358.899714)
			(xy 96.680655 -358.917827) (xy 96.698182 -358.943155) (xy 96.709992 -358.953054) (xy 96.732452 -358.971273)
			(xy 96.772189 -359.013287) (xy 96.805131 -359.060816) (xy 96.830523 -359.112772) (xy 96.847785 -359.167964)
			(xy 96.85652 -359.22513) (xy 96.857058 -359.254044) (xy 96.856686 -359.2813) (xy 96.848922 -359.335257)
			(xy 96.833557 -359.38756) (xy 96.810906 -359.437143) (xy 96.781429 -359.482999) (xy 96.745726 -359.524192)
			(xy 96.704523 -359.559885) (xy 96.658661 -359.589351) (xy 96.609072 -359.61199) (xy 96.556765 -359.627342)
			(xy 96.502806 -359.635093) (xy 96.47555 -359.635552) (xy 96.446634 -359.635016) (xy 96.389462 -359.626293)
			(xy 96.334263 -359.60904) (xy 96.282301 -359.583652) (xy 96.234767 -359.55071) (xy 96.19275 -359.510971)
			(xy 96.17456 -359.488486) (xy 96.164663 -359.476681) (xy 96.139339 -359.459162) (xy 96.109946 -359.449986)
			(xy 96.079154 -359.449986) (xy 96.049761 -359.459162) (xy 96.024437 -359.476681) (xy 96.01454 -359.488486)
			(xy 95.999762 -359.506885) (xy 95.966391 -359.540256) (xy 95.947992 -359.555034) (xy 95.936145 -359.564885)
			(xy 95.918632 -359.590222) (xy 95.909463 -359.619627) (xy 95.909471 -359.650427) (xy 95.918655 -359.679827)
			(xy 95.936182 -359.705155) (xy 95.947992 -359.715054) (xy 95.970452 -359.733273) (xy 96.010189 -359.775287)
			(xy 96.043131 -359.822816) (xy 96.068523 -359.874772) (xy 96.085785 -359.929964) (xy 96.09452 -359.98713)
			(xy 96.095058 -360.016044) (xy 96.094686 -360.0433) (xy 96.086922 -360.097257) (xy 96.071557 -360.14956)
			(xy 96.048906 -360.199143) (xy 96.019429 -360.244999) (xy 95.983726 -360.286192) (xy 95.942523 -360.321885)
			(xy 95.896661 -360.351351) (xy 95.847072 -360.37399) (xy 95.794765 -360.389342) (xy 95.740806 -360.397093)
			(xy 95.71355 -360.397552) (xy 95.687299 -360.397106) (xy 95.635289 -360.389924) (xy 95.584757 -360.375674)
			(xy 95.536658 -360.354627) (xy 95.491901 -360.32718) (xy 95.451332 -360.293853) (xy 95.415719 -360.255275)
			(xy 95.400368 -360.233976) (xy 95.392004 -360.222763) (xy 95.370379 -360.205037) (xy 95.344755 -360.19384)
			(xy 95.317056 -360.190012) (xy 95.289357 -360.19384) (xy 95.263733 -360.205037) (xy 95.242108 -360.222763)
			(xy 95.233744 -360.233976) (xy 95.218366 -360.255254) (xy 95.182748 -360.293821) (xy 95.14218 -360.327143)
			(xy 95.097428 -360.35459) (xy 95.049336 -360.375643) (xy 94.998813 -360.389907) (xy 94.946811 -360.397111)
			(xy 94.920562 -360.397552) (xy 94.892056 -360.397013) (xy 94.835678 -360.388524) (xy 94.781192 -360.37174)
			(xy 94.729809 -360.347035) (xy 94.682675 -360.31496) (xy 94.640838 -360.276228) (xy 94.62262 -360.254296)
			(xy 94.61269 -360.242603) (xy 94.587311 -360.225391) (xy 94.557967 -360.216484) (xy 94.527302 -360.216686)
			(xy 94.498078 -360.225979) (xy 94.472927 -360.243524) (xy 94.463108 -360.255312) (xy 94.444916 -360.277794)
			(xy 94.402896 -360.317529) (xy 94.355361 -360.350468) (xy 94.3034 -360.375856) (xy 94.248203 -360.393113)
			(xy 94.191034 -360.401843) (xy 94.162118 -360.402378) (xy 94.132824 -360.401817) (xy 94.074926 -360.392855)
			(xy 94.019076 -360.375156) (xy 93.966585 -360.349134) (xy 93.918685 -360.315399) (xy 93.876499 -360.274744)
			(xy 93.858334 -360.251756) (xy 93.849905 -360.241474) (xy 93.828885 -360.225217) (xy 93.804384 -360.214928)
			(xy 93.778059 -360.211303) (xy 93.751689 -360.214588) (xy 93.727058 -360.22456) (xy 93.70583 -360.240545)
			(xy 93.697298 -360.25074) (xy 93.679113 -360.27319) (xy 93.637118 -360.312862) (xy 93.589619 -360.345747)
			(xy 93.537703 -360.371091) (xy 93.482559 -360.388314) (xy 93.425448 -360.397022) (xy 93.396562 -360.397552)
			(xy 93.367646 -360.397008) (xy 93.310475 -360.388287) (xy 93.255276 -360.371035) (xy 93.203314 -360.345648)
			(xy 93.155779 -360.312709) (xy 93.113762 -360.27297) (xy 93.095572 -360.250486) (xy 93.085675 -360.238681)
			(xy 93.060351 -360.221162) (xy 93.030958 -360.211986) (xy 93.000166 -360.211986) (xy 92.970773 -360.221162)
			(xy 92.945449 -360.238681) (xy 92.935552 -360.250486) (xy 92.918799 -360.271269) (xy 92.880445 -360.308399)
			(xy 92.837291 -360.339821) (xy 92.790177 -360.36492) (xy 92.740025 -360.383206) (xy 92.687814 -360.394323)
			(xy 92.634562 -360.398053) (xy 92.58131 -360.394323) (xy 92.529099 -360.383206) (xy 92.478947 -360.36492)
			(xy 92.431833 -360.339821) (xy 92.388679 -360.308399) (xy 92.350325 -360.271269) (xy 92.333572 -360.250486)
			(xy 92.323675 -360.238681) (xy 92.298351 -360.221162) (xy 92.268958 -360.211986) (xy 92.238166 -360.211986)
			(xy 92.208773 -360.221162) (xy 92.183449 -360.238681) (xy 92.173552 -360.250486) (xy 92.156799 -360.271269)
			(xy 92.118445 -360.308399) (xy 92.075291 -360.339821) (xy 92.028177 -360.36492) (xy 91.978025 -360.383206)
			(xy 91.925814 -360.394323) (xy 91.872562 -360.398053) (xy 91.81931 -360.394323) (xy 91.767099 -360.383206)
			(xy 91.716947 -360.36492) (xy 91.669833 -360.339821) (xy 91.626679 -360.308399) (xy 91.588325 -360.271269)
			(xy 91.571572 -360.250486) (xy 91.561675 -360.238681) (xy 91.536351 -360.221162) (xy 91.506958 -360.211986)
			(xy 91.476166 -360.211986) (xy 91.446773 -360.221162) (xy 91.421449 -360.238681) (xy 91.411552 -360.250486)
			(xy 91.393328 -360.272942) (xy 91.351316 -360.312679) (xy 91.303788 -360.345622) (xy 91.251833 -360.371015)
			(xy 91.196641 -360.388277) (xy 91.139476 -360.397013) (xy 91.110562 -360.397552) (xy 91.084492 -360.397123)
			(xy 91.03284 -360.39001) (xy 90.982635 -360.375936) (xy 90.934812 -360.355161) (xy 90.890261 -360.328073)
			(xy 90.84981 -360.295175) (xy 90.81421 -360.25708) (xy 90.784126 -360.214495) (xy 90.771726 -360.191558)
			(xy 90.764913 -360.179441) (xy 90.745946 -360.159136) (xy 90.722205 -360.1447) (xy 90.695449 -360.137204)
			(xy 90.667663 -360.137204) (xy 90.640907 -360.1447) (xy 90.617166 -360.159136) (xy 90.598199 -360.179441)
			(xy 90.591386 -360.191558) (xy 90.578996 -360.214503) (xy 90.548924 -360.257102) (xy 90.51333 -360.295209)
			(xy 90.472879 -360.328114) (xy 90.428324 -360.355203) (xy 90.380494 -360.375973) (xy 90.330282 -360.390036)
			(xy 90.278622 -360.397131) (xy 90.25255 -360.397552) (xy 90.22617 -360.397098) (xy 90.173911 -360.389833)
			(xy 90.123153 -360.375435) (xy 90.074863 -360.354179) (xy 90.029964 -360.326471) (xy 89.989312 -360.292839)
			(xy 89.953683 -360.253925) (xy 89.938352 -360.232452) (xy 89.930165 -360.221296) (xy 89.908954 -360.203541)
			(xy 89.883751 -360.192138) (xy 89.856412 -360.187927) (xy 89.828946 -360.191218) (xy 89.803376 -360.201768)
			(xy 89.78158 -360.218802) (xy 89.772998 -360.229658) (xy 89.754877 -360.253141) (xy 89.712594 -360.294738)
			(xy 89.664381 -360.329286) (xy 89.6114 -360.355953) (xy 89.55493 -360.374095) (xy 89.496331 -360.383274)
			(xy 89.466674 -360.383836) (xy 89.440711 -360.38336) (xy 89.389265 -360.376319) (xy 89.339247 -360.36237)
			(xy 89.291582 -360.341771) (xy 89.247148 -360.314902) (xy 89.206765 -360.282259) (xy 89.17118 -360.244444)
			(xy 89.141048 -360.202155) (xy 89.1286 -360.179366) (xy 89.121978 -360.16751) (xy 89.103535 -360.147587)
			(xy 89.080488 -360.133238) (xy 89.054472 -360.12548) (xy 89.02733 -360.124862) (xy 89.000988 -360.131428)
			(xy 88.977312 -360.144712) (xy 88.95798 -360.163774) (xy 88.9508 -360.175302) (xy 88.936041 -360.199594)
			(xy 88.900425 -360.243892) (xy 88.858631 -360.282415) (xy 88.811584 -360.314311) (xy 88.760326 -360.338875)
			(xy 88.705991 -360.355562) (xy 88.649782 -360.364004) (xy 88.621362 -360.364532) (xy 88.592623 -360.364023)
			(xy 88.535795 -360.355395) (xy 88.480904 -360.338341) (xy 88.429193 -360.313247) (xy 88.381831 -360.28068)
			(xy 88.360504 -360.261408) (xy 88.348663 -360.251155) (xy 88.320383 -360.237729) (xy 88.289366 -360.233492)
			(xy 88.258521 -360.23884) (xy 88.23074 -360.253271) (xy 88.21928 -360.263948) (xy 88.197663 -360.284818)
			(xy 88.149082 -360.320173) (xy 88.095557 -360.347473) (xy 88.038414 -360.366042) (xy 87.979067 -360.375421)
			(xy 87.949024 -360.375962) (xy 87.92177 -360.375522) (xy 87.867815 -360.367767) (xy 87.815514 -360.352412)
			(xy 87.765931 -360.329769) (xy 87.720076 -360.300299) (xy 87.678882 -360.264603) (xy 87.643188 -360.223407)
			(xy 87.613721 -360.177549) (xy 87.59108 -360.127965) (xy 87.575728 -360.075663) (xy 87.567976 -360.021708)
			(xy 87.567516 -359.994454) (xy 79.531717 -359.994454) (xy 79.710695 -360.42981) (xy 99.3173 -360.42981)
			(xy 99.321371 -360.374188) (xy 99.333497 -360.319751) (xy 99.35342 -360.26766) (xy 99.380716 -360.219025)
			(xy 99.414802 -360.174882) (xy 99.454951 -360.136173) (xy 99.500309 -360.103722) (xy 99.549909 -360.078221)
			(xy 99.602693 -360.060214) (xy 99.657536 -360.050084) (xy 99.71327 -360.048047) (xy 99.768707 -360.054147)
			(xy 99.822664 -360.068253) (xy 99.873993 -360.090065) (xy 99.921599 -360.119119) (xy 99.964467 -360.154794)
			(xy 100.001684 -360.196331) (xy 100.032457 -360.242844) (xy 100.056129 -360.293341) (xy 100.072197 -360.346748)
			(xy 100.080317 -360.401924) (xy 100.080826 -360.42981) (xy 100.080317 -360.457696) (xy 100.072197 -360.512872)
			(xy 100.056129 -360.566279) (xy 100.032457 -360.616776) (xy 100.001684 -360.663289) (xy 99.964467 -360.704826)
			(xy 99.921599 -360.740501) (xy 99.873993 -360.769555) (xy 99.822664 -360.791367) (xy 99.768707 -360.805473)
			(xy 99.71327 -360.811573) (xy 99.657536 -360.809536) (xy 99.602693 -360.799406) (xy 99.549909 -360.781399)
			(xy 99.500309 -360.755898) (xy 99.454951 -360.723447) (xy 99.414802 -360.684738) (xy 99.380716 -360.640595)
			(xy 99.35342 -360.59196) (xy 99.333497 -360.539869) (xy 99.321371 -360.485432) (xy 99.3173 -360.42981)
			(xy 79.710695 -360.42981) (xy 80.698834 -362.833412) (xy 96.770188 -362.833412) (xy 96.774259 -362.77779)
			(xy 96.786385 -362.723353) (xy 96.806308 -362.671262) (xy 96.833604 -362.622627) (xy 96.86769 -362.578484)
			(xy 96.907839 -362.539775) (xy 96.953197 -362.507324) (xy 97.002797 -362.481823) (xy 97.055581 -362.463816)
			(xy 97.110424 -362.453686) (xy 97.166158 -362.451649) (xy 97.221595 -362.457749) (xy 97.275552 -362.471855)
			(xy 97.326881 -362.493667) (xy 97.374487 -362.522721) (xy 97.417355 -362.558396) (xy 97.454572 -362.599933)
			(xy 97.485345 -362.646446) (xy 97.509017 -362.696943) (xy 97.525085 -362.75035) (xy 97.533205 -362.805526)
			(xy 97.533714 -362.833412) (xy 97.533205 -362.861298) (xy 97.525085 -362.916474) (xy 97.509017 -362.969881)
			(xy 97.485345 -363.020378) (xy 97.454572 -363.066891) (xy 97.425489 -363.09935) (xy 97.87204 -363.09935)
			(xy 97.876111 -363.043728) (xy 97.888237 -362.989291) (xy 97.90816 -362.9372) (xy 97.935456 -362.888565)
			(xy 97.969542 -362.844422) (xy 98.009691 -362.805713) (xy 98.055049 -362.773262) (xy 98.104649 -362.747761)
			(xy 98.157433 -362.729754) (xy 98.212276 -362.719624) (xy 98.26801 -362.717587) (xy 98.323447 -362.723687)
			(xy 98.377404 -362.737793) (xy 98.428733 -362.759605) (xy 98.476339 -362.788659) (xy 98.519207 -362.824334)
			(xy 98.556424 -362.865871) (xy 98.587197 -362.912384) (xy 98.610869 -362.962881) (xy 98.626937 -363.016288)
			(xy 98.635057 -363.071464) (xy 98.635566 -363.09935) (xy 98.635057 -363.127236) (xy 98.626937 -363.182412)
			(xy 98.610869 -363.235819) (xy 98.587197 -363.286316) (xy 98.556424 -363.332829) (xy 98.519207 -363.374366)
			(xy 98.476339 -363.410041) (xy 98.428733 -363.439095) (xy 98.377404 -363.460907) (xy 98.323447 -363.475013)
			(xy 98.26801 -363.481113) (xy 98.212276 -363.479076) (xy 98.157433 -363.468946) (xy 98.104649 -363.450939)
			(xy 98.055049 -363.425438) (xy 98.009691 -363.392987) (xy 97.969542 -363.354278) (xy 97.935456 -363.310135)
			(xy 97.90816 -363.2615) (xy 97.888237 -363.209409) (xy 97.876111 -363.154972) (xy 97.87204 -363.09935)
			(xy 97.425489 -363.09935) (xy 97.417355 -363.108428) (xy 97.374487 -363.144103) (xy 97.326881 -363.173157)
			(xy 97.275552 -363.194969) (xy 97.221595 -363.209075) (xy 97.166158 -363.215175) (xy 97.110424 -363.213138)
			(xy 97.055581 -363.203008) (xy 97.002797 -363.185001) (xy 96.953197 -363.1595) (xy 96.907839 -363.127049)
			(xy 96.86769 -363.08834) (xy 96.833604 -363.044197) (xy 96.806308 -362.995562) (xy 96.786385 -362.943471)
			(xy 96.774259 -362.889034) (xy 96.770188 -362.833412) (xy 80.698834 -362.833412) (xy 81.036637 -363.655102)
			(xy 98.85248 -363.655102) (xy 98.856551 -363.59948) (xy 98.868677 -363.545043) (xy 98.8886 -363.492952)
			(xy 98.915896 -363.444317) (xy 98.949982 -363.400174) (xy 98.990131 -363.361465) (xy 99.035489 -363.329014)
			(xy 99.085089 -363.303513) (xy 99.137873 -363.285506) (xy 99.192716 -363.275376) (xy 99.24845 -363.273339)
			(xy 99.303887 -363.279439) (xy 99.357844 -363.293545) (xy 99.409173 -363.315357) (xy 99.456779 -363.344411)
			(xy 99.499647 -363.380086) (xy 99.536864 -363.421623) (xy 99.567637 -363.468136) (xy 99.591309 -363.518633)
			(xy 99.607377 -363.57204) (xy 99.615497 -363.627216) (xy 99.616006 -363.655102) (xy 99.615497 -363.682988)
			(xy 99.607377 -363.738164) (xy 99.591309 -363.791571) (xy 99.567637 -363.842068) (xy 99.536864 -363.888581)
			(xy 99.499647 -363.930118) (xy 99.456779 -363.965793) (xy 99.409173 -363.994847) (xy 99.357844 -364.016659)
			(xy 99.303887 -364.030765) (xy 99.24845 -364.036865) (xy 99.192716 -364.034828) (xy 99.137873 -364.024698)
			(xy 99.085089 -364.006691) (xy 99.035489 -363.98119) (xy 98.990131 -363.948739) (xy 98.949982 -363.91003)
			(xy 98.915896 -363.865887) (xy 98.8886 -363.817252) (xy 98.868677 -363.765161) (xy 98.856551 -363.710724)
			(xy 98.85248 -363.655102) (xy 81.036637 -363.655102) (xy 81.215406 -364.08995) (xy 97.5774 -364.08995)
			(xy 97.581471 -364.034328) (xy 97.593597 -363.979891) (xy 97.61352 -363.9278) (xy 97.640816 -363.879165)
			(xy 97.674902 -363.835022) (xy 97.715051 -363.796313) (xy 97.760409 -363.763862) (xy 97.810009 -363.738361)
			(xy 97.862793 -363.720354) (xy 97.917636 -363.710224) (xy 97.97337 -363.708187) (xy 98.028807 -363.714287)
			(xy 98.082764 -363.728393) (xy 98.134093 -363.750205) (xy 98.181699 -363.779259) (xy 98.224567 -363.814934)
			(xy 98.261784 -363.856471) (xy 98.292557 -363.902984) (xy 98.316229 -363.953481) (xy 98.332297 -364.006888)
			(xy 98.340417 -364.062064) (xy 98.340926 -364.08995) (xy 98.340417 -364.117836) (xy 98.332297 -364.173012)
			(xy 98.316229 -364.226419) (xy 98.292557 -364.276916) (xy 98.261784 -364.323429) (xy 98.224567 -364.364966)
			(xy 98.181699 -364.400641) (xy 98.134093 -364.429695) (xy 98.082764 -364.451507) (xy 98.028807 -364.465613)
			(xy 97.97337 -364.471713) (xy 97.917636 -364.469676) (xy 97.862793 -364.459546) (xy 97.810009 -364.441539)
			(xy 97.760409 -364.416038) (xy 97.715051 -364.383587) (xy 97.674902 -364.344878) (xy 97.640816 -364.300735)
			(xy 97.61352 -364.2521) (xy 97.593597 -364.200009) (xy 97.581471 -364.145572) (xy 97.5774 -364.08995)
			(xy 81.215406 -364.08995) (xy 81.40694 -364.555849) (xy 98.876386 -364.555849) (xy 98.876386 -364.501351)
			(xy 98.884141 -364.447408) (xy 98.899494 -364.395118) (xy 98.922131 -364.345545) (xy 98.951593 -364.299697)
			(xy 98.987279 -364.258509) (xy 99.028464 -364.222818) (xy 99.074308 -364.193351) (xy 99.123879 -364.170708)
			(xy 99.176167 -364.15535) (xy 99.230109 -364.147589) (xy 99.257358 -364.1471) (xy 99.283582 -364.147509)
			(xy 99.335533 -364.154713) (xy 99.386009 -364.168963) (xy 99.434058 -364.189991) (xy 99.478774 -364.2174)
			(xy 99.519316 -364.250675) (xy 99.554919 -364.289188) (xy 99.584913 -364.332214) (xy 99.59721 -364.35538)
			(xy 99.604539 -364.368759) (xy 99.625777 -364.390643) (xy 99.652525 -364.405289) (xy 99.682403 -364.411393)
			(xy 99.712753 -364.408413) (xy 99.740873 -364.396614) (xy 99.764262 -364.377045) (xy 99.772978 -364.364524)
			(xy 99.788181 -364.342039) (xy 99.823848 -364.301132) (xy 99.864955 -364.265695) (xy 99.91067 -364.236444)
			(xy 99.960071 -364.213969) (xy 100.012159 -364.198724) (xy 100.065882 -364.191018) (xy 100.093018 -364.190534)
			(xy 100.120271 -364.190937) (xy 100.174223 -364.198697) (xy 100.226521 -364.214055) (xy 100.276102 -364.2367)
			(xy 100.321955 -364.26617) (xy 100.363148 -364.301865) (xy 100.398841 -364.343059) (xy 100.428309 -364.388914)
			(xy 100.450951 -364.438495) (xy 100.466307 -364.490794) (xy 100.474064 -364.544747) (xy 100.474064 -364.599253)
			(xy 100.466307 -364.653206) (xy 100.450951 -364.705505) (xy 100.428309 -364.755086) (xy 100.398841 -364.800941)
			(xy 100.363148 -364.842135) (xy 100.321955 -364.87783) (xy 100.276102 -364.9073) (xy 100.226521 -364.929945)
			(xy 100.174223 -364.945303) (xy 100.120271 -364.953063) (xy 100.093018 -364.95355) (xy 100.066795 -364.953133)
			(xy 100.014845 -364.945928) (xy 99.964371 -364.931677) (xy 99.916323 -364.910649) (xy 99.871607 -364.883241)
			(xy 99.831065 -364.849968) (xy 99.795461 -364.811457) (xy 99.765465 -364.768435) (xy 99.753166 -364.74527)
			(xy 99.745729 -364.731955) (xy 99.724517 -364.710068) (xy 99.697791 -364.695415) (xy 99.667931 -364.6893)
			(xy 99.637597 -364.692269) (xy 99.609489 -364.704056) (xy 99.58611 -364.723612) (xy 99.577398 -364.736126)
			(xy 99.562228 -364.758633) (xy 99.526553 -364.799537) (xy 99.48544 -364.834971) (xy 99.439719 -364.864219)
			(xy 99.390314 -364.886691) (xy 99.338222 -364.901931) (xy 99.284496 -364.909633) (xy 99.257358 -364.910116)
			(xy 99.230109 -364.909611) (xy 99.176167 -364.90185) (xy 99.123879 -364.886492) (xy 99.074308 -364.863849)
			(xy 99.028464 -364.834382) (xy 98.987279 -364.798691) (xy 98.951593 -364.757503) (xy 98.922131 -364.711655)
			(xy 98.899494 -364.662082) (xy 98.884141 -364.609792) (xy 98.876386 -364.555849) (xy 81.40694 -364.555849)
			(xy 81.833057 -365.59236) (xy 100.41077 -365.59236) (xy 100.414841 -365.536738) (xy 100.426967 -365.482301)
			(xy 100.44689 -365.43021) (xy 100.474186 -365.381575) (xy 100.508272 -365.337432) (xy 100.548421 -365.298723)
			(xy 100.593779 -365.266272) (xy 100.643379 -365.240771) (xy 100.696163 -365.222764) (xy 100.751006 -365.212634)
			(xy 100.80674 -365.210597) (xy 100.862177 -365.216697) (xy 100.916134 -365.230803) (xy 100.967463 -365.252615)
			(xy 101.015069 -365.281669) (xy 101.057937 -365.317344) (xy 101.095154 -365.358881) (xy 101.125927 -365.405394)
			(xy 101.149599 -365.455891) (xy 101.165667 -365.509298) (xy 101.173787 -365.564474) (xy 101.174296 -365.59236)
			(xy 101.173787 -365.620246) (xy 101.165667 -365.675422) (xy 101.149599 -365.728829) (xy 101.125927 -365.779326)
			(xy 101.095154 -365.825839) (xy 101.057937 -365.867376) (xy 101.015069 -365.903051) (xy 100.967463 -365.932105)
			(xy 100.916134 -365.953917) (xy 100.906858 -365.956342) (xy 101.533958 -365.956342) (xy 101.538029 -365.90072)
			(xy 101.550155 -365.846283) (xy 101.570078 -365.794192) (xy 101.597374 -365.745557) (xy 101.63146 -365.701414)
			(xy 101.671609 -365.662705) (xy 101.716967 -365.630254) (xy 101.766567 -365.604753) (xy 101.819351 -365.586746)
			(xy 101.874194 -365.576616) (xy 101.929928 -365.574579) (xy 101.985365 -365.580679) (xy 102.039322 -365.594785)
			(xy 102.090651 -365.616597) (xy 102.138257 -365.645651) (xy 102.181125 -365.681326) (xy 102.218342 -365.722863)
			(xy 102.249115 -365.769376) (xy 102.272787 -365.819873) (xy 102.288855 -365.87328) (xy 102.296975 -365.928456)
			(xy 102.297484 -365.956342) (xy 102.296975 -365.984228) (xy 102.288855 -366.039404) (xy 102.272787 -366.092811)
			(xy 102.249115 -366.143308) (xy 102.218342 -366.189821) (xy 102.181125 -366.231358) (xy 102.138257 -366.267033)
			(xy 102.090651 -366.296087) (xy 102.039322 -366.317899) (xy 101.985365 -366.332005) (xy 101.929928 -366.338105)
			(xy 101.874194 -366.336068) (xy 101.819351 -366.325938) (xy 101.766567 -366.307931) (xy 101.716967 -366.28243)
			(xy 101.671609 -366.249979) (xy 101.63146 -366.21127) (xy 101.597374 -366.167127) (xy 101.570078 -366.118492)
			(xy 101.550155 -366.066401) (xy 101.538029 -366.011964) (xy 101.533958 -365.956342) (xy 100.906858 -365.956342)
			(xy 100.862177 -365.968023) (xy 100.80674 -365.974123) (xy 100.751006 -365.972086) (xy 100.696163 -365.961956)
			(xy 100.643379 -365.943949) (xy 100.593779 -365.918448) (xy 100.548421 -365.885997) (xy 100.508272 -365.847288)
			(xy 100.474186 -365.803145) (xy 100.44689 -365.75451) (xy 100.426967 -365.702419) (xy 100.414841 -365.647982)
			(xy 100.41077 -365.59236) (xy 81.833057 -365.59236) (xy 83.13801 -368.766598) (xy 83.143852 -368.77498)
			(xy 88.19134 -373.822468) (xy 102.912672 -373.822468)
		)
		(stroke
			(width 0)
			(type solid)
		)
		(fill yes)
		(layer "In15.Cu")
		(net "GND")
	)
	(gr_poly
		(pts
			(xy 122.239532 -288.757868) (xy 122.251714 -288.734558) (xy 122.281899 -288.691486) (xy 122.31809 -288.653323)
			(xy 122.359501 -288.620898) (xy 122.405231 -288.594917) (xy 122.454285 -288.575944) (xy 122.505596 -288.564393)
			(xy 122.558048 -288.560514) (xy 122.6105 -288.564393) (xy 122.661811 -288.575944) (xy 122.710865 -288.594917)
			(xy 122.756595 -288.620898) (xy 122.798006 -288.653323) (xy 122.834197 -288.691486) (xy 122.864382 -288.734558)
			(xy 122.876564 -288.757868) (xy 123.00204 -288.757868) (xy 123.017273 -288.757297) (xy 123.046387 -288.748317)
			(xy 123.071567 -288.731164) (xy 123.090581 -288.707359) (xy 123.101746 -288.679011) (xy 123.10407 -288.648633)
			(xy 123.097349 -288.618916) (xy 123.090178 -288.605468) (xy 123.00585 -288.459418) (xy 122.980958 -288.456116)
			(xy 122.955613 -288.452295) (xy 122.9063 -288.438321) (xy 122.8595 -288.41742) (xy 122.816181 -288.390023)
			(xy 122.777239 -288.356699) (xy 122.743478 -288.318134) (xy 122.715596 -288.275126) (xy 122.694169 -288.228565)
			(xy 122.679641 -288.179412) (xy 122.672312 -288.128684) (xy 122.67184 -288.103056) (xy 122.672338 -288.076407)
			(xy 122.680281 -288.023703) (xy 122.695991 -287.972773) (xy 122.719117 -287.924752) (xy 122.749141 -287.880715)
			(xy 122.785393 -287.841644) (xy 122.827064 -287.808413) (xy 122.873222 -287.781764) (xy 122.922836 -287.762292)
			(xy 122.974798 -287.750432) (xy 123.027948 -287.746449) (xy 123.081098 -287.750432) (xy 123.13306 -287.762292)
			(xy 123.182674 -287.781764) (xy 123.228832 -287.808413) (xy 123.270503 -287.841644) (xy 123.306755 -287.880715)
			(xy 123.336779 -287.924752) (xy 123.359905 -287.972773) (xy 123.375615 -288.023703) (xy 123.383558 -288.076407)
			(xy 123.384056 -288.103056) (xy 123.383683 -288.126301) (xy 123.377643 -288.172398) (xy 123.365659 -288.217318)
			(xy 123.357132 -288.238946) (xy 123.347734 -288.261806) (xy 123.5202 -288.560764) (xy 123.544838 -288.564066)
			(xy 123.569374 -288.567764) (xy 123.617173 -288.581075) (xy 123.66266 -288.600896) (xy 123.704954 -288.626843)
			(xy 123.743234 -288.658412) (xy 123.776758 -288.694992) (xy 123.804876 -288.735874) (xy 123.816364 -288.757868)
			(xy 124.119132 -288.757868) (xy 124.131314 -288.734558) (xy 124.161499 -288.691486) (xy 124.19769 -288.653323)
			(xy 124.239101 -288.620898) (xy 124.284831 -288.594917) (xy 124.333885 -288.575944) (xy 124.385196 -288.564393)
			(xy 124.437648 -288.560514) (xy 124.4901 -288.564393) (xy 124.541411 -288.575944) (xy 124.590465 -288.594917)
			(xy 124.636195 -288.620898) (xy 124.677606 -288.653323) (xy 124.713797 -288.691486) (xy 124.743982 -288.734558)
			(xy 124.756164 -288.757868) (xy 124.88164 -288.757868) (xy 124.896873 -288.757297) (xy 124.925987 -288.748317)
			(xy 124.951167 -288.731164) (xy 124.970181 -288.707359) (xy 124.981346 -288.679011) (xy 124.98367 -288.648633)
			(xy 124.976949 -288.618916) (xy 124.969778 -288.605468) (xy 124.88545 -288.459418) (xy 124.860558 -288.456116)
			(xy 124.835213 -288.452295) (xy 124.7859 -288.438321) (xy 124.7391 -288.41742) (xy 124.695781 -288.390023)
			(xy 124.656839 -288.356699) (xy 124.623078 -288.318134) (xy 124.595196 -288.275126) (xy 124.573769 -288.228565)
			(xy 124.559241 -288.179412) (xy 124.551912 -288.128684) (xy 124.55144 -288.103056) (xy 124.551938 -288.076407)
			(xy 124.559881 -288.023703) (xy 124.575591 -287.972773) (xy 124.598717 -287.924752) (xy 124.628741 -287.880715)
			(xy 124.664993 -287.841644) (xy 124.706664 -287.808413) (xy 124.752822 -287.781764) (xy 124.802436 -287.762292)
			(xy 124.854398 -287.750432) (xy 124.907548 -287.746449) (xy 124.960698 -287.750432) (xy 125.01266 -287.762292)
			(xy 125.062274 -287.781764) (xy 125.108432 -287.808413) (xy 125.150103 -287.841644) (xy 125.186355 -287.880715)
			(xy 125.216379 -287.924752) (xy 125.239505 -287.972773) (xy 125.255215 -288.023703) (xy 125.263158 -288.076407)
			(xy 125.263656 -288.103056) (xy 125.263283 -288.126301) (xy 125.257243 -288.172398) (xy 125.245259 -288.217318)
			(xy 125.236732 -288.238946) (xy 125.227334 -288.261806) (xy 125.3998 -288.560764) (xy 125.424438 -288.564066)
			(xy 125.448974 -288.567764) (xy 125.496773 -288.581075) (xy 125.54226 -288.600896) (xy 125.584554 -288.626843)
			(xy 125.622834 -288.658412) (xy 125.656358 -288.694992) (xy 125.684476 -288.735874) (xy 125.695964 -288.757868)
			(xy 125.998732 -288.757868) (xy 126.010914 -288.734558) (xy 126.041099 -288.691486) (xy 126.07729 -288.653323)
			(xy 126.118701 -288.620898) (xy 126.164431 -288.594917) (xy 126.213485 -288.575944) (xy 126.264796 -288.564393)
			(xy 126.317248 -288.560514) (xy 126.3697 -288.564393) (xy 126.421011 -288.575944) (xy 126.470065 -288.594917)
			(xy 126.515795 -288.620898) (xy 126.557206 -288.653323) (xy 126.593397 -288.691486) (xy 126.623582 -288.734558)
			(xy 126.635764 -288.757868) (xy 126.76124 -288.757868) (xy 126.776473 -288.757297) (xy 126.805587 -288.748317)
			(xy 126.830767 -288.731164) (xy 126.849781 -288.707359) (xy 126.860946 -288.679011) (xy 126.86327 -288.648633)
			(xy 126.856549 -288.618916) (xy 126.849378 -288.605468) (xy 126.76505 -288.459418) (xy 126.740158 -288.456116)
			(xy 126.714813 -288.452295) (xy 126.6655 -288.438321) (xy 126.6187 -288.41742) (xy 126.575381 -288.390023)
			(xy 126.536439 -288.356699) (xy 126.502678 -288.318134) (xy 126.474796 -288.275126) (xy 126.453369 -288.228565)
			(xy 126.438841 -288.179412) (xy 126.431512 -288.128684) (xy 126.43104 -288.103056) (xy 126.431538 -288.076407)
			(xy 126.439481 -288.023703) (xy 126.455191 -287.972773) (xy 126.478317 -287.924752) (xy 126.508341 -287.880715)
			(xy 126.544593 -287.841644) (xy 126.586264 -287.808413) (xy 126.632422 -287.781764) (xy 126.682036 -287.762292)
			(xy 126.733998 -287.750432) (xy 126.787148 -287.746449) (xy 126.840298 -287.750432) (xy 126.89226 -287.762292)
			(xy 126.941874 -287.781764) (xy 126.988032 -287.808413) (xy 127.029703 -287.841644) (xy 127.065955 -287.880715)
			(xy 127.095979 -287.924752) (xy 127.119105 -287.972773) (xy 127.134815 -288.023703) (xy 127.142758 -288.076407)
			(xy 127.143256 -288.103056) (xy 127.142883 -288.126301) (xy 127.136843 -288.172398) (xy 127.124859 -288.217318)
			(xy 127.116332 -288.238946) (xy 127.106934 -288.261806) (xy 127.2794 -288.560764) (xy 127.304038 -288.564066)
			(xy 127.328574 -288.567764) (xy 127.376373 -288.581075) (xy 127.42186 -288.600896) (xy 127.464154 -288.626843)
			(xy 127.502434 -288.658412) (xy 127.535958 -288.694992) (xy 127.564076 -288.735874) (xy 127.575564 -288.757868)
			(xy 127.878332 -288.757868) (xy 127.890514 -288.734558) (xy 127.920699 -288.691486) (xy 127.95689 -288.653323)
			(xy 127.998301 -288.620898) (xy 128.044031 -288.594917) (xy 128.093085 -288.575944) (xy 128.144396 -288.564393)
			(xy 128.196848 -288.560514) (xy 128.2493 -288.564393) (xy 128.300611 -288.575944) (xy 128.349665 -288.594917)
			(xy 128.395395 -288.620898) (xy 128.436806 -288.653323) (xy 128.472997 -288.691486) (xy 128.503182 -288.734558)
			(xy 128.515364 -288.757868) (xy 128.64084 -288.757868) (xy 128.656073 -288.757297) (xy 128.685187 -288.748317)
			(xy 128.710367 -288.731164) (xy 128.729381 -288.707359) (xy 128.740546 -288.679011) (xy 128.74287 -288.648633)
			(xy 128.736149 -288.618916) (xy 128.728978 -288.605468) (xy 128.64465 -288.459418) (xy 128.619758 -288.456116)
			(xy 128.594413 -288.452295) (xy 128.5451 -288.438321) (xy 128.4983 -288.41742) (xy 128.454981 -288.390023)
			(xy 128.416039 -288.356699) (xy 128.382278 -288.318134) (xy 128.354396 -288.275126) (xy 128.332969 -288.228565)
			(xy 128.318441 -288.179412) (xy 128.311112 -288.128684) (xy 128.31064 -288.103056) (xy 128.311138 -288.076407)
			(xy 128.319081 -288.023703) (xy 128.334791 -287.972773) (xy 128.357917 -287.924752) (xy 128.387941 -287.880715)
			(xy 128.424193 -287.841644) (xy 128.465864 -287.808413) (xy 128.512022 -287.781764) (xy 128.561636 -287.762292)
			(xy 128.613598 -287.750432) (xy 128.666748 -287.746449) (xy 128.719898 -287.750432) (xy 128.77186 -287.762292)
			(xy 128.821474 -287.781764) (xy 128.867632 -287.808413) (xy 128.909303 -287.841644) (xy 128.945555 -287.880715)
			(xy 128.975579 -287.924752) (xy 128.998705 -287.972773) (xy 129.014415 -288.023703) (xy 129.022358 -288.076407)
			(xy 129.022856 -288.103056) (xy 129.022483 -288.126301) (xy 129.016443 -288.172398) (xy 129.004459 -288.217318)
			(xy 128.995932 -288.238946) (xy 128.986534 -288.261806) (xy 129.159 -288.560764) (xy 129.183638 -288.564066)
			(xy 129.208174 -288.567764) (xy 129.255973 -288.581075) (xy 129.30146 -288.600896) (xy 129.343754 -288.626843)
			(xy 129.382034 -288.658412) (xy 129.415558 -288.694992) (xy 129.443676 -288.735874) (xy 129.455164 -288.757868)
			(xy 129.757932 -288.757868) (xy 129.770114 -288.734558) (xy 129.800299 -288.691486) (xy 129.83649 -288.653323)
			(xy 129.877901 -288.620898) (xy 129.923631 -288.594917) (xy 129.972685 -288.575944) (xy 130.023996 -288.564393)
			(xy 130.076448 -288.560514) (xy 130.1289 -288.564393) (xy 130.180211 -288.575944) (xy 130.229265 -288.594917)
			(xy 130.274995 -288.620898) (xy 130.316406 -288.653323) (xy 130.352597 -288.691486) (xy 130.382782 -288.734558)
			(xy 130.394964 -288.757868) (xy 130.52044 -288.757868) (xy 130.535673 -288.757297) (xy 130.564787 -288.748317)
			(xy 130.589967 -288.731164) (xy 130.608981 -288.707359) (xy 130.620146 -288.679011) (xy 130.62247 -288.648633)
			(xy 130.615749 -288.618916) (xy 130.608578 -288.605468) (xy 130.52425 -288.459418) (xy 130.499358 -288.456116)
			(xy 130.474013 -288.452295) (xy 130.4247 -288.438321) (xy 130.3779 -288.41742) (xy 130.334581 -288.390023)
			(xy 130.295639 -288.356699) (xy 130.261878 -288.318134) (xy 130.233996 -288.275126) (xy 130.212569 -288.228565)
			(xy 130.198041 -288.179412) (xy 130.190712 -288.128684) (xy 130.19024 -288.103056) (xy 130.190738 -288.076407)
			(xy 130.198681 -288.023703) (xy 130.214391 -287.972773) (xy 130.237517 -287.924752) (xy 130.267541 -287.880715)
			(xy 130.303793 -287.841644) (xy 130.345464 -287.808413) (xy 130.391622 -287.781764) (xy 130.441236 -287.762292)
			(xy 130.493198 -287.750432) (xy 130.546348 -287.746449) (xy 130.599498 -287.750432) (xy 130.65146 -287.762292)
			(xy 130.701074 -287.781764) (xy 130.747232 -287.808413) (xy 130.788903 -287.841644) (xy 130.825155 -287.880715)
			(xy 130.855179 -287.924752) (xy 130.878305 -287.972773) (xy 130.894015 -288.023703) (xy 130.901958 -288.076407)
			(xy 130.902456 -288.103056) (xy 130.902083 -288.126301) (xy 130.896043 -288.172398) (xy 130.884059 -288.217318)
			(xy 130.875532 -288.238946) (xy 130.866134 -288.261806) (xy 131.0386 -288.560764) (xy 131.063238 -288.564066)
			(xy 131.087774 -288.567764) (xy 131.135573 -288.581075) (xy 131.18106 -288.600896) (xy 131.223354 -288.626843)
			(xy 131.261634 -288.658412) (xy 131.295158 -288.694992) (xy 131.323276 -288.735874) (xy 131.334764 -288.757868)
			(xy 131.637532 -288.757868) (xy 131.649714 -288.734558) (xy 131.679899 -288.691486) (xy 131.71609 -288.653323)
			(xy 131.757501 -288.620898) (xy 131.803231 -288.594917) (xy 131.852285 -288.575944) (xy 131.903596 -288.564393)
			(xy 131.956048 -288.560514) (xy 132.0085 -288.564393) (xy 132.059811 -288.575944) (xy 132.108865 -288.594917)
			(xy 132.154595 -288.620898) (xy 132.196006 -288.653323) (xy 132.232197 -288.691486) (xy 132.262382 -288.734558)
			(xy 132.274564 -288.757868) (xy 132.40004 -288.757868) (xy 132.415273 -288.757297) (xy 132.444387 -288.748317)
			(xy 132.469567 -288.731164) (xy 132.488581 -288.707359) (xy 132.499746 -288.679011) (xy 132.50207 -288.648633)
			(xy 132.495349 -288.618916) (xy 132.488178 -288.605468) (xy 132.40385 -288.459418) (xy 132.378958 -288.456116)
			(xy 132.353613 -288.452295) (xy 132.3043 -288.438321) (xy 132.2575 -288.41742) (xy 132.214181 -288.390023)
			(xy 132.175239 -288.356699) (xy 132.141478 -288.318134) (xy 132.113596 -288.275126) (xy 132.092169 -288.228565)
			(xy 132.077641 -288.179412) (xy 132.070312 -288.128684) (xy 132.06984 -288.103056) (xy 132.070338 -288.076407)
			(xy 132.078281 -288.023703) (xy 132.093991 -287.972773) (xy 132.117117 -287.924752) (xy 132.147141 -287.880715)
			(xy 132.183393 -287.841644) (xy 132.225064 -287.808413) (xy 132.271222 -287.781764) (xy 132.320836 -287.762292)
			(xy 132.372798 -287.750432) (xy 132.425948 -287.746449) (xy 132.479098 -287.750432) (xy 132.53106 -287.762292)
			(xy 132.580674 -287.781764) (xy 132.626832 -287.808413) (xy 132.668503 -287.841644) (xy 132.704755 -287.880715)
			(xy 132.734779 -287.924752) (xy 132.757905 -287.972773) (xy 132.773615 -288.023703) (xy 132.781558 -288.076407)
			(xy 132.782056 -288.103056) (xy 132.781683 -288.126301) (xy 132.781237 -288.129705) (xy 133.949684 -288.129705)
			(xy 133.949684 -288.076407) (xy 133.957627 -288.023703) (xy 133.973337 -287.972773) (xy 133.996463 -287.924752)
			(xy 134.026487 -287.880715) (xy 134.062739 -287.841644) (xy 134.10441 -287.808413) (xy 134.150568 -287.781764)
			(xy 134.200182 -287.762292) (xy 134.252144 -287.750432) (xy 134.305294 -287.746449) (xy 134.358444 -287.750432)
			(xy 134.410406 -287.762292) (xy 134.46002 -287.781764) (xy 134.506178 -287.808413) (xy 134.547849 -287.841644)
			(xy 134.584101 -287.880715) (xy 134.614125 -287.924752) (xy 134.637251 -287.972773) (xy 134.652961 -288.023703)
			(xy 134.660904 -288.076407) (xy 134.661402 -288.103056) (xy 134.660904 -288.129705) (xy 134.652961 -288.182409)
			(xy 134.637251 -288.233339) (xy 134.614125 -288.28136) (xy 134.584101 -288.325397) (xy 134.547849 -288.364468)
			(xy 134.506178 -288.397699) (xy 134.46002 -288.424348) (xy 134.410406 -288.44382) (xy 134.358444 -288.45568)
			(xy 134.305294 -288.459664) (xy 134.252144 -288.45568) (xy 134.200182 -288.44382) (xy 134.150568 -288.424348)
			(xy 134.10441 -288.397699) (xy 134.062739 -288.364468) (xy 134.026487 -288.325397) (xy 133.996463 -288.28136)
			(xy 133.973337 -288.233339) (xy 133.957627 -288.182409) (xy 133.949684 -288.129705) (xy 132.781237 -288.129705)
			(xy 132.775643 -288.172398) (xy 132.763659 -288.217318) (xy 132.755132 -288.238946) (xy 132.745734 -288.261806)
			(xy 132.9182 -288.560764) (xy 132.942838 -288.564066) (xy 132.967374 -288.567764) (xy 133.015173 -288.581075)
			(xy 133.06066 -288.600896) (xy 133.102954 -288.626843) (xy 133.141234 -288.658412) (xy 133.174758 -288.694992)
			(xy 133.202876 -288.735874) (xy 133.214364 -288.757868) (xy 133.517132 -288.757868) (xy 133.529314 -288.734558)
			(xy 133.559499 -288.691486) (xy 133.59569 -288.653323) (xy 133.637101 -288.620898) (xy 133.682831 -288.594917)
			(xy 133.731885 -288.575944) (xy 133.783196 -288.564393) (xy 133.835648 -288.560514) (xy 133.8881 -288.564393)
			(xy 133.939411 -288.575944) (xy 133.988465 -288.594917) (xy 134.034195 -288.620898) (xy 134.075606 -288.653323)
			(xy 134.111797 -288.691486) (xy 134.141982 -288.734558) (xy 134.154164 -288.757868) (xy 134.456932 -288.757868)
			(xy 134.470013 -288.732905) (xy 134.502841 -288.687098) (xy 134.542475 -288.647035) (xy 134.587925 -288.613715)
			(xy 134.638056 -288.587971) (xy 134.691617 -288.570445) (xy 134.74727 -288.561575) (xy 134.775448 -288.561018)
			(xy 134.801046 -288.561437) (xy 134.851721 -288.568725) (xy 134.900827 -288.583201) (xy 134.947352 -288.604566)
			(xy 134.990334 -288.632379) (xy 135.00989 -288.648902) (xy 135.04545 -288.680398) (xy 135.132318 -288.59353)
			(xy 135.141977 -288.583227) (xy 135.155721 -288.558568) (xy 135.162197 -288.53109) (xy 135.160912 -288.502889)
			(xy 135.151963 -288.476114) (xy 135.136033 -288.452808) (xy 135.114337 -288.434746) (xy 135.101584 -288.428684)
			(xy 135.078234 -288.417899) (xy 135.034643 -288.3906) (xy 134.995436 -288.357311) (xy 134.961429 -288.318724)
			(xy 134.933331 -288.275644) (xy 134.911727 -288.228969) (xy 134.897066 -288.179669) (xy 134.889654 -288.128773)
			(xy 134.88924 -288.103056) (xy 134.889764 -288.075074) (xy 134.898525 -288.019801) (xy 134.915826 -287.966579)
			(xy 134.941239 -287.916718) (xy 134.974139 -287.871447) (xy 135.013717 -287.83188) (xy 135.058996 -287.798991)
			(xy 135.108864 -287.773591) (xy 135.16209 -287.756304) (xy 135.217366 -287.747557) (xy 135.245348 -287.746948)
			(xy 135.271066 -287.747398) (xy 135.321966 -287.754795) (xy 135.37127 -287.769444) (xy 135.417953 -287.791038)
			(xy 135.461039 -287.819129) (xy 135.499633 -287.85313) (xy 135.53293 -287.892333) (xy 135.560235 -287.935921)
			(xy 135.570976 -287.959292) (xy 135.577101 -287.972012) (xy 135.595142 -287.993713) (xy 135.618433 -288.009647)
			(xy 135.645196 -288.018599) (xy 135.673387 -288.019885) (xy 135.700854 -288.013407) (xy 135.725499 -287.999658)
			(xy 135.735822 -287.990026) (xy 136.31799 -287.407858) (xy 136.310624 -287.379664) (xy 136.305147 -287.357396)
			(xy 136.299287 -287.311915) (xy 136.29894 -287.288986) (xy 136.299462 -287.261003) (xy 136.308219 -287.205726)
			(xy 136.325517 -287.152499) (xy 136.350929 -287.102635) (xy 136.383829 -287.057359) (xy 136.423406 -287.017788)
			(xy 136.468687 -286.984896) (xy 136.518557 -286.959493) (xy 136.571786 -286.942205) (xy 136.627065 -286.933457)
			(xy 136.655048 -286.932878) (xy 136.677977 -286.93322) (xy 136.723458 -286.939086) (xy 136.745726 -286.944562)
			(xy 136.77392 -286.951928) (xy 136.86409 -286.861758) (xy 136.874794 -286.85023) (xy 136.889229 -286.822297)
			(xy 136.89451 -286.791301) (xy 136.89014 -286.760164) (xy 136.87653 -286.73182) (xy 136.866122 -286.720026)
			(xy 136.847914 -286.700067) (xy 136.817123 -286.655677) (xy 136.79339 -286.607146) (xy 136.777261 -286.555586)
			(xy 136.769105 -286.502182) (xy 136.768586 -286.47517) (xy 136.769137 -286.447188) (xy 136.777896 -286.391914)
			(xy 136.795193 -286.338691) (xy 136.820603 -286.288828) (xy 136.853499 -286.243554) (xy 136.893073 -286.203984)
			(xy 136.938349 -286.17109) (xy 136.988213 -286.145684) (xy 137.041438 -286.12839) (xy 137.096712 -286.119635)
			(xy 137.124694 -286.119062) (xy 137.151707 -286.119562) (xy 137.205113 -286.127721) (xy 137.256674 -286.143853)
			(xy 137.305207 -286.167588) (xy 137.349598 -286.198381) (xy 137.36955 -286.216598) (xy 137.381372 -286.226984)
			(xy 137.409704 -286.240639) (xy 137.440846 -286.245036) (xy 137.471851 -286.23976) (xy 137.499786 -286.22531)
			(xy 137.511282 -286.214566) (xy 137.550144 -286.175704) (xy 137.560589 -286.164541) (xy 137.57486 -286.137521)
			(xy 137.580512 -286.107491) (xy 137.577041 -286.077132) (xy 137.564756 -286.049153) (xy 137.544754 -286.026051)
			(xy 137.51882 -286.00989) (xy 137.50417 -286.005524) (xy 137.479135 -285.998462) (xy 137.431282 -285.978074)
			(xy 137.386905 -285.950941) (xy 137.346947 -285.91764) (xy 137.312259 -285.878881) (xy 137.283579 -285.835487)
			(xy 137.261517 -285.788382) (xy 137.246543 -285.738569) (xy 137.238976 -285.687108) (xy 137.238486 -285.6611)
			(xy 137.239035 -285.633117) (xy 137.24779 -285.577839) (xy 137.265084 -285.524612) (xy 137.290492 -285.474745)
			(xy 137.323388 -285.429467) (xy 137.362962 -285.389892) (xy 137.40824 -285.356996) (xy 137.458106 -285.331587)
			(xy 137.511333 -285.314291) (xy 137.566611 -285.305535) (xy 137.594594 -285.304992) (xy 137.622207 -285.305519)
			(xy 137.676771 -285.314057) (xy 137.729362 -285.330914) (xy 137.778722 -285.355686) (xy 137.823667 -285.387779)
			(xy 137.863121 -285.426424) (xy 137.896137 -285.470696) (xy 137.921925 -285.519533) (xy 137.939866 -285.571764)
			(xy 137.949531 -285.626139) (xy 137.950702 -285.653734) (xy 137.950956 -285.674054) (xy 138.001502 -285.724346)
			(xy 138.0617 -285.664148) (xy 138.0617 -285.206186) (xy 138.017504 -285.200344) (xy 137.990827 -285.196291)
			(xy 137.939029 -285.181185) (xy 137.890101 -285.158439) (xy 137.845165 -285.128573) (xy 137.805248 -285.09227)
			(xy 137.771263 -285.050362) (xy 137.743988 -285.003807) (xy 137.724048 -284.95367) (xy 137.711898 -284.9011)
			(xy 137.707818 -284.847298) (xy 137.711899 -284.793496) (xy 137.724049 -284.740926) (xy 137.74399 -284.690789)
			(xy 137.771265 -284.644235) (xy 137.80525 -284.602327) (xy 137.845168 -284.566025) (xy 137.890105 -284.536159)
			(xy 137.939033 -284.513413) (xy 137.990832 -284.498308) (xy 138.017504 -284.494224) (xy 138.0617 -284.488382)
			(xy 138.0617 -283.578808) (xy 138.017504 -283.572966) (xy 137.990836 -283.5689) (xy 137.939058 -283.553772)
			(xy 137.890153 -283.531011) (xy 137.845239 -283.501135) (xy 137.805343 -283.464829) (xy 137.771377 -283.422923)
			(xy 137.744119 -283.376374) (xy 137.72419 -283.326247) (xy 137.712048 -283.273689) (xy 137.70797 -283.219901)
			(xy 137.712048 -283.166112) (xy 137.72419 -283.113554) (xy 137.744118 -283.063427) (xy 137.771376 -283.016878)
			(xy 137.805342 -282.974972) (xy 137.845237 -282.938666) (xy 137.890151 -282.90879) (xy 137.939057 -282.886028)
			(xy 137.990835 -282.870901) (xy 138.017504 -282.866846) (xy 138.0617 -282.861004) (xy 138.0617 -281.950922)
			(xy 138.017504 -281.94508) (xy 137.992155 -281.941262) (xy 137.942833 -281.927294) (xy 137.896023 -281.906397)
			(xy 137.852694 -281.879004) (xy 137.81374 -281.845681) (xy 137.779968 -281.807116) (xy 137.752075 -281.764107)
			(xy 137.730637 -281.717542) (xy 137.716099 -281.668385) (xy 137.708759 -281.617651) (xy 137.708386 -281.59202)
			(xy 137.70864 -281.577542) (xy 137.709656 -281.555444) (xy 137.653776 -281.499564) (xy 137.643875 -281.490254)
			(xy 137.620289 -281.476771) (xy 137.59398 -281.469991) (xy 137.566815 -281.470395) (xy 137.54072 -281.477953)
			(xy 137.517545 -281.492131) (xy 137.498932 -281.511922) (xy 137.486203 -281.535923) (xy 137.480259 -281.562433)
			(xy 137.480548 -281.576018) (xy 137.480802 -281.59202) (xy 137.480295 -281.619099) (xy 137.472091 -281.672633)
			(xy 137.455875 -281.724307) (xy 137.432022 -281.77293) (xy 137.40108 -281.81738) (xy 137.363765 -281.856632)
			(xy 137.320937 -281.889781) (xy 137.273582 -281.916062) (xy 137.222794 -281.93487) (xy 137.169744 -281.94577)
			(xy 137.115654 -281.948511) (xy 137.061774 -281.943031) (xy 137.009345 -281.929454) (xy 136.959576 -281.908095)
			(xy 136.913615 -281.879446) (xy 136.872522 -281.844168) (xy 136.837246 -281.803074) (xy 136.808598 -281.757112)
			(xy 136.787241 -281.707342) (xy 136.773667 -281.654912) (xy 136.768188 -281.601031) (xy 136.770932 -281.546942)
			(xy 136.781834 -281.493892) (xy 136.800644 -281.443105) (xy 136.826927 -281.395752) (xy 136.860078 -281.352924)
			(xy 136.899331 -281.315611) (xy 136.943782 -281.284671) (xy 136.992406 -281.26082) (xy 137.044081 -281.244606)
			(xy 137.097615 -281.236404) (xy 137.124694 -281.235912) (xy 137.140696 -281.236166) (xy 137.154263 -281.23634)
			(xy 137.180719 -281.230362) (xy 137.204665 -281.217626) (xy 137.22441 -281.199032) (xy 137.23856 -281.175893)
			(xy 137.246114 -281.149843) (xy 137.246538 -281.122724) (xy 137.239804 -281.096451) (xy 137.226386 -281.07288)
			(xy 137.21715 -281.062938) (xy 137.110216 -280.956004) (xy 137.099159 -280.945707) (xy 137.072503 -280.931515)
			(xy 137.042861 -280.925746) (xy 137.012828 -280.928904) (xy 136.985035 -280.940714) (xy 136.961914 -280.96014)
			(xy 136.953244 -280.972514) (xy 136.939077 -280.993464) (xy 136.905764 -281.031518) (xy 136.867402 -281.064473)
			(xy 136.824761 -281.091668) (xy 136.778701 -281.112553) (xy 136.730149 -281.12671) (xy 136.680081 -281.133853)
			(xy 136.654794 -281.134312) (xy 136.626811 -281.133763) (xy 136.571534 -281.125007) (xy 136.518308 -281.107712)
			(xy 136.468442 -281.082303) (xy 136.423165 -281.049407) (xy 136.383591 -281.009833) (xy 136.350695 -280.964556)
			(xy 136.325287 -280.91469) (xy 136.307993 -280.861464) (xy 136.299237 -280.806187) (xy 136.298686 -280.778204)
			(xy 136.299128 -280.752916) (xy 136.306281 -280.702849) (xy 136.320444 -280.654297) (xy 136.341332 -280.608237)
			(xy 136.368524 -280.565593) (xy 136.401475 -280.527225) (xy 136.439521 -280.493903) (xy 136.460484 -280.479754)
			(xy 136.472815 -280.471056) (xy 136.492163 -280.447921) (xy 136.503921 -280.420149) (xy 136.507067 -280.390154)
			(xy 136.501327 -280.360546) (xy 136.487201 -280.333899) (xy 136.476994 -280.322782) (xy 136.402826 -280.248614)
			(xy 136.36879 -280.269188) (xy 136.347881 -280.281301) (xy 136.303493 -280.300397) (xy 136.256934 -280.313326)
			(xy 136.209055 -280.319849) (xy 136.184894 -280.320242) (xy 136.15691 -280.319693) (xy 136.101632 -280.310937)
			(xy 136.048403 -280.293642) (xy 135.998536 -280.268235) (xy 135.953256 -280.235339) (xy 135.913679 -280.195765)
			(xy 135.88078 -280.150488) (xy 135.855368 -280.100623) (xy 135.838069 -280.047395) (xy 135.82931 -279.992118)
			(xy 135.828786 -279.964134) (xy 135.829338 -279.935046) (xy 135.838751 -279.877638) (xy 135.857379 -279.822527)
			(xy 135.884726 -279.771181) (xy 135.901938 -279.747726) (xy 135.656066 -279.501854) (xy 135.641334 -279.498806)
			(xy 135.616277 -279.493048) (xy 135.568026 -279.475295) (xy 135.522829 -279.450788) (xy 135.481625 -279.420039)
			(xy 135.44527 -279.383685) (xy 135.414519 -279.342483) (xy 135.390011 -279.297287) (xy 135.372256 -279.249037)
			(xy 135.366506 -279.223978) (xy 135.363458 -279.209246) (xy 135.299704 -279.145492) (xy 135.289429 -279.135905)
			(xy 135.26487 -279.122267) (xy 135.237525 -279.115831) (xy 135.209461 -279.117081) (xy 135.182798 -279.125924)
			(xy 135.159548 -279.141692) (xy 135.141469 -279.163193) (xy 135.129926 -279.188804) (xy 135.127492 -279.202642)
			(xy 135.122827 -279.230439) (xy 135.105877 -279.28419) (xy 135.080671 -279.3346) (xy 135.047838 -279.380409)
			(xy 135.008198 -279.420474) (xy 134.96274 -279.453793) (xy 134.912602 -279.479534) (xy 134.859034 -279.497055)
			(xy 134.803374 -279.505918) (xy 134.775194 -279.506426) (xy 134.747211 -279.505877) (xy 134.691933 -279.497121)
			(xy 134.638706 -279.479826) (xy 134.588839 -279.454418) (xy 134.543561 -279.421522) (xy 134.503986 -279.381948)
			(xy 134.471088 -279.336671) (xy 134.445678 -279.286805) (xy 134.428382 -279.233578) (xy 134.419624 -279.178301)
			(xy 134.419086 -279.150318) (xy 134.419627 -279.122144) (xy 134.428511 -279.0665) (xy 134.446045 -279.012948)
			(xy 134.471792 -278.962825) (xy 134.505108 -278.917381) (xy 134.545164 -278.877748) (xy 134.590959 -278.844916)
			(xy 134.641353 -278.819704) (xy 134.695088 -278.80274) (xy 134.72287 -278.79802) (xy 134.736719 -278.795554)
			(xy 134.762386 -278.784071) (xy 134.783943 -278.766016) (xy 134.79975 -278.74276) (xy 134.808606 -278.716072)
			(xy 134.809838 -278.68798) (xy 134.803353 -278.660619) (xy 134.789642 -278.636069) (xy 134.78002 -278.625808)
			(xy 134.721092 -278.56688) (xy 134.711 -278.557318) (xy 134.686826 -278.543609) (xy 134.659847 -278.536938)
			(xy 134.63207 -278.537803) (xy 134.605558 -278.546138) (xy 134.582283 -278.561325) (xy 134.572756 -278.571452)
			(xy 134.555783 -278.59013) (xy 134.517473 -278.622984) (xy 134.474907 -278.650097) (xy 134.428938 -278.670926)
			(xy 134.380488 -278.685054) (xy 134.330528 -278.692195) (xy 134.305294 -278.69261) (xy 134.277311 -278.692061)
			(xy 134.222035 -278.683305) (xy 134.168808 -278.66601) (xy 134.118943 -278.640601) (xy 134.073666 -278.607705)
			(xy 134.034092 -278.568131) (xy 134.001197 -278.522854) (xy 133.975789 -278.472988) (xy 133.958494 -278.419762)
			(xy 133.949739 -278.364485) (xy 133.949186 -278.336502) (xy 133.949626 -278.311269) (xy 133.956759 -278.26131)
			(xy 133.97088 -278.212861) (xy 133.991707 -278.166893) (xy 134.018823 -278.124331) (xy 134.051681 -278.086028)
			(xy 134.070344 -278.06904) (xy 134.080445 -278.059505) (xy 134.095559 -278.036214) (xy 134.103852 -278.009715)
			(xy 134.104712 -277.981963) (xy 134.098077 -277.955002) (xy 134.084434 -277.93082) (xy 134.074916 -277.920704)
			(xy 133.996176 -277.841964) (xy 133.965188 -277.854156) (xy 133.93396 -277.865559) (xy 133.868631 -277.877837)
			(xy 133.835394 -277.87854) (xy 133.80741 -277.877991) (xy 133.752132 -277.869235) (xy 133.698904 -277.85194)
			(xy 133.649036 -277.826532) (xy 133.603757 -277.793637) (xy 133.56418 -277.754063) (xy 133.531281 -277.708786)
			(xy 133.50587 -277.65892) (xy 133.488571 -277.605693) (xy 133.479811 -277.550416) (xy 133.479286 -277.522432)
			(xy 133.480003 -277.489196) (xy 133.492276 -277.423868) (xy 133.50367 -277.392638) (xy 133.515862 -277.36165)
			(xy 133.127496 -276.973284) (xy 133.12648 -276.972522) (xy 133.101842 -276.947884) (xy 133.10108 -276.946868)
			(xy 132.932678 -276.778466) (xy 132.921825 -276.768316) (xy 132.895681 -276.754219) (xy 132.866587 -276.748242)
			(xy 132.837003 -276.750889) (xy 132.809432 -276.761937) (xy 132.786207 -276.780451) (xy 132.769291 -276.804866)
			(xy 132.764276 -276.818852) (xy 132.755097 -276.845278) (xy 132.729679 -276.895109) (xy 132.696782 -276.940353)
			(xy 132.657217 -276.979898) (xy 132.611957 -277.012772) (xy 132.562113 -277.038166) (xy 132.508913 -277.055455)
			(xy 132.453664 -277.064215) (xy 132.425694 -277.064724) (xy 132.397711 -277.064175) (xy 132.342433 -277.055419)
			(xy 132.289206 -277.038124) (xy 132.23934 -277.012716) (xy 132.194061 -276.97982) (xy 132.154487 -276.940246)
			(xy 132.121589 -276.894969) (xy 132.09618 -276.845103) (xy 132.078883 -276.791876) (xy 132.070126 -276.736599)
			(xy 132.069586 -276.708616) (xy 132.070133 -276.680647) (xy 132.078879 -276.625398) (xy 132.096158 -276.572196)
			(xy 132.121545 -276.522351) (xy 132.154415 -276.47709) (xy 132.193959 -276.437527) (xy 132.239204 -276.404635)
			(xy 132.289036 -276.379224) (xy 132.315458 -276.370034) (xy 132.329406 -276.364944) (xy 132.353782 -276.348016)
			(xy 132.372269 -276.3248) (xy 132.383309 -276.297252) (xy 132.385971 -276.267694) (xy 132.380031 -276.238617)
			(xy 132.36599 -276.212471) (xy 132.355844 -276.201632) (xy 132.32511 -276.170898) (xy 132.313963 -276.160548)
			(xy 132.287091 -276.14633) (xy 132.257224 -276.140653) (xy 132.227009 -276.14402) (xy 132.199124 -276.156132)
			(xy 132.187188 -276.165564) (xy 132.167743 -276.18159) (xy 132.125193 -276.208581) (xy 132.079265 -276.229309)
			(xy 132.030875 -276.243362) (xy 131.980988 -276.250458) (xy 131.955794 -276.250908) (xy 131.927811 -276.250359)
			(xy 131.872535 -276.241603) (xy 131.819309 -276.224308) (xy 131.769443 -276.198899) (xy 131.724166 -276.166003)
			(xy 131.684593 -276.126429) (xy 131.651698 -276.081152) (xy 131.62629 -276.031286) (xy 131.608996 -275.978059)
			(xy 131.600241 -275.922783) (xy 131.599686 -275.8948) (xy 131.600122 -275.869605) (xy 131.607221 -275.819718)
			(xy 131.621278 -275.771329) (xy 131.642012 -275.725403) (xy 131.669009 -275.682856) (xy 131.68503 -275.663406)
			(xy 131.694482 -275.651486) (xy 131.706574 -275.623589) (xy 131.709934 -275.59337) (xy 131.704264 -275.563499)
			(xy 131.690066 -275.536612) (xy 131.679696 -275.525484) (xy 131.57962 -275.425408) (xy 131.553204 -275.430488)
			(xy 131.536602 -275.433476) (xy 131.503016 -275.436652) (xy 131.486148 -275.436838) (xy 131.458159 -275.436322)
			(xy 131.40287 -275.427572) (xy 131.34963 -275.410281) (xy 131.299751 -275.384873) (xy 131.254461 -275.351976)
			(xy 131.214875 -275.312399) (xy 131.181967 -275.267115) (xy 131.156549 -275.217242) (xy 131.139246 -275.164006)
			(xy 131.130485 -275.108719) (xy 131.13004 -275.08073) (xy 131.130237 -275.063863) (xy 131.133414 -275.030278)
			(xy 131.13639 -275.013674) (xy 131.14147 -274.987258) (xy 130.556254 -274.402042) (xy 130.546234 -274.392657)
			(xy 130.522361 -274.379122) (xy 130.495745 -274.372435) (xy 130.468309 -274.373079) (xy 130.442036 -274.381007)
			(xy 130.418824 -274.395646) (xy 130.40035 -274.41594) (xy 130.393694 -274.42795) (xy 130.380561 -274.452717)
			(xy 130.347704 -274.498136) (xy 130.308131 -274.53784) (xy 130.262821 -274.570847) (xy 130.212895 -274.59634)
			(xy 130.15959 -274.613689) (xy 130.104223 -274.622463) (xy 130.076194 -274.623022) (xy 130.048211 -274.622473)
			(xy 129.992934 -274.613717) (xy 129.939706 -274.596422) (xy 129.88984 -274.571014) (xy 129.844562 -274.538118)
			(xy 129.804987 -274.498544) (xy 129.77209 -274.453267) (xy 129.746681 -274.403401) (xy 129.729385 -274.350174)
			(xy 129.720628 -274.294897) (xy 129.720086 -274.266914) (xy 129.720784 -274.235915) (xy 129.731559 -274.174858)
			(xy 129.752719 -274.11658) (xy 129.767584 -274.089368) (xy 129.774761 -274.07591) (xy 129.781532 -274.046185)
			(xy 129.779235 -274.015785) (xy 129.768074 -273.987415) (xy 129.749043 -273.963598) (xy 129.723834 -273.946454)
			(xy 129.69469 -273.937507) (xy 129.679446 -273.936968) (xy 129.533142 -273.936968) (xy 129.517914 -273.937542)
			(xy 129.488812 -273.946524) (xy 129.463644 -273.963676) (xy 129.44464 -273.987477) (xy 129.433485 -274.015817)
			(xy 129.431168 -274.046186) (xy 129.437893 -274.075891) (xy 129.445004 -274.089368) (xy 129.459903 -274.116564)
			(xy 129.481078 -274.174843) (xy 129.491818 -274.235911) (xy 129.492502 -274.266914) (xy 129.492004 -274.293563)
			(xy 129.484061 -274.346267) (xy 129.468351 -274.397197) (xy 129.445225 -274.445218) (xy 129.415201 -274.489255)
			(xy 129.378949 -274.528326) (xy 129.337278 -274.561557) (xy 129.29112 -274.588206) (xy 129.241506 -274.607678)
			(xy 129.189544 -274.619538) (xy 129.136394 -274.623522) (xy 129.083244 -274.619538) (xy 129.031282 -274.607678)
			(xy 128.981668 -274.588206) (xy 128.93551 -274.561557) (xy 128.893839 -274.528326) (xy 128.857587 -274.489255)
			(xy 128.827563 -274.445218) (xy 128.804437 -274.397197) (xy 128.788727 -274.346267) (xy 128.780784 -274.293563)
			(xy 128.780286 -274.266914) (xy 128.780984 -274.235915) (xy 128.791759 -274.174858) (xy 128.812919 -274.11658)
			(xy 128.827784 -274.089368) (xy 128.834961 -274.07591) (xy 128.841732 -274.046185) (xy 128.839435 -274.015785)
			(xy 128.828274 -273.987415) (xy 128.809243 -273.963598) (xy 128.784034 -273.946454) (xy 128.75489 -273.937507)
			(xy 128.739646 -273.936968) (xy 128.593342 -273.936968) (xy 128.578114 -273.937542) (xy 128.549012 -273.946524)
			(xy 128.523844 -273.963676) (xy 128.50484 -273.987477) (xy 128.493685 -274.015817) (xy 128.491368 -274.046186)
			(xy 128.498093 -274.075891) (xy 128.505204 -274.089368) (xy 128.520103 -274.116564) (xy 128.541278 -274.174843)
			(xy 128.552018 -274.235911) (xy 128.552702 -274.266914) (xy 128.552204 -274.293563) (xy 128.544261 -274.346267)
			(xy 128.528551 -274.397197) (xy 128.505425 -274.445218) (xy 128.475401 -274.489255) (xy 128.439149 -274.528326)
			(xy 128.397478 -274.561557) (xy 128.35132 -274.588206) (xy 128.301706 -274.607678) (xy 128.249744 -274.619538)
			(xy 128.196594 -274.623522) (xy 128.143444 -274.619538) (xy 128.091482 -274.607678) (xy 128.041868 -274.588206)
			(xy 127.99571 -274.561557) (xy 127.954039 -274.528326) (xy 127.917787 -274.489255) (xy 127.887763 -274.445218)
			(xy 127.864637 -274.397197) (xy 127.848927 -274.346267) (xy 127.840984 -274.293563) (xy 127.840486 -274.266914)
			(xy 127.841184 -274.235915) (xy 127.851959 -274.174858) (xy 127.873119 -274.11658) (xy 127.887984 -274.089368)
			(xy 127.895161 -274.07591) (xy 127.901932 -274.046185) (xy 127.899635 -274.015785) (xy 127.888474 -273.987415)
			(xy 127.869443 -273.963598) (xy 127.844234 -273.946454) (xy 127.81509 -273.937507) (xy 127.799846 -273.936968)
			(xy 127.653542 -273.936968) (xy 127.638314 -273.937542) (xy 127.609212 -273.946524) (xy 127.584044 -273.963676)
			(xy 127.56504 -273.987477) (xy 127.553885 -274.015817) (xy 127.551568 -274.046186) (xy 127.558293 -274.075891)
			(xy 127.565404 -274.089368) (xy 127.580303 -274.116564) (xy 127.601478 -274.174843) (xy 127.612218 -274.235911)
			(xy 127.612902 -274.266914) (xy 127.612404 -274.293563) (xy 127.604461 -274.346267) (xy 127.588751 -274.397197)
			(xy 127.565625 -274.445218) (xy 127.535601 -274.489255) (xy 127.499349 -274.528326) (xy 127.457678 -274.561557)
			(xy 127.41152 -274.588206) (xy 127.361906 -274.607678) (xy 127.309944 -274.619538) (xy 127.256794 -274.623522)
			(xy 127.203644 -274.619538) (xy 127.151682 -274.607678) (xy 127.102068 -274.588206) (xy 127.05591 -274.561557)
			(xy 127.014239 -274.528326) (xy 126.977987 -274.489255) (xy 126.947963 -274.445218) (xy 126.924837 -274.397197)
			(xy 126.909127 -274.346267) (xy 126.901184 -274.293563) (xy 126.900686 -274.266914) (xy 126.901384 -274.235915)
			(xy 126.912159 -274.174858) (xy 126.933319 -274.11658) (xy 126.948184 -274.089368) (xy 126.955361 -274.07591)
			(xy 126.962132 -274.046185) (xy 126.959835 -274.015785) (xy 126.948674 -273.987415) (xy 126.929643 -273.963598)
			(xy 126.904434 -273.946454) (xy 126.87529 -273.937507) (xy 126.860046 -273.936968) (xy 126.713996 -273.936968)
			(xy 126.698773 -273.937548) (xy 126.669684 -273.946538) (xy 126.644528 -273.963691) (xy 126.625534 -273.987487)
			(xy 126.614385 -274.015819) (xy 126.612067 -274.046178) (xy 126.618786 -274.075874) (xy 126.625858 -274.089368)
			(xy 126.640755 -274.116565) (xy 126.661926 -274.174844) (xy 126.672665 -274.235911) (xy 126.673356 -274.266914)
			(xy 126.672858 -274.293563) (xy 126.664915 -274.346267) (xy 126.649205 -274.397197) (xy 126.626079 -274.445218)
			(xy 126.596055 -274.489255) (xy 126.559803 -274.528326) (xy 126.518132 -274.561557) (xy 126.471974 -274.588206)
			(xy 126.42236 -274.607678) (xy 126.370398 -274.619538) (xy 126.317248 -274.623522) (xy 126.264098 -274.619538)
			(xy 126.212136 -274.607678) (xy 126.162522 -274.588206) (xy 126.116364 -274.561557) (xy 126.074693 -274.528326)
			(xy 126.038441 -274.489255) (xy 126.008417 -274.445218) (xy 125.985291 -274.397197) (xy 125.969581 -274.346267)
			(xy 125.961638 -274.293563) (xy 125.96114 -274.266914) (xy 125.961838 -274.235914) (xy 125.972612 -274.174857)
			(xy 125.993769 -274.116578) (xy 126.008638 -274.089368) (xy 126.015812 -274.075908) (xy 126.022579 -274.046179)
			(xy 126.020281 -274.015777) (xy 126.009122 -273.987403) (xy 125.990094 -273.963581) (xy 125.964888 -273.946427)
			(xy 125.935745 -273.937467) (xy 125.9205 -273.936968) (xy 125.773942 -273.936968) (xy 125.758714 -273.937542)
			(xy 125.729612 -273.946524) (xy 125.704444 -273.963676) (xy 125.68544 -273.987477) (xy 125.674285 -274.015817)
			(xy 125.671968 -274.046186) (xy 125.678693 -274.075891) (xy 125.685804 -274.089368) (xy 125.700703 -274.116564)
			(xy 125.721878 -274.174843) (xy 125.732618 -274.235911) (xy 125.733302 -274.266914) (xy 125.732804 -274.293563)
			(xy 125.724861 -274.346267) (xy 125.709151 -274.397197) (xy 125.686025 -274.445218) (xy 125.656001 -274.489255)
			(xy 125.619749 -274.528326) (xy 125.578078 -274.561557) (xy 125.53192 -274.588206) (xy 125.482306 -274.607678)
			(xy 125.430344 -274.619538) (xy 125.377194 -274.623522) (xy 125.324044 -274.619538) (xy 125.272082 -274.607678)
			(xy 125.222468 -274.588206) (xy 125.17631 -274.561557) (xy 125.134639 -274.528326) (xy 125.098387 -274.489255)
			(xy 125.068363 -274.445218) (xy 125.045237 -274.397197) (xy 125.029527 -274.346267) (xy 125.021584 -274.293563)
			(xy 125.021086 -274.266914) (xy 125.021784 -274.235915) (xy 125.032559 -274.174858) (xy 125.053719 -274.11658)
			(xy 125.068584 -274.089368) (xy 125.075761 -274.07591) (xy 125.082532 -274.046185) (xy 125.080235 -274.015785)
			(xy 125.069074 -273.987415) (xy 125.050043 -273.963598) (xy 125.024834 -273.946454) (xy 124.99569 -273.937507)
			(xy 124.980446 -273.936968) (xy 124.834142 -273.936968) (xy 124.818914 -273.937542) (xy 124.789812 -273.946524)
			(xy 124.764644 -273.963676) (xy 124.74564 -273.987477) (xy 124.734485 -274.015817) (xy 124.732168 -274.046186)
			(xy 124.738893 -274.075891) (xy 124.746004 -274.089368) (xy 124.760903 -274.116564) (xy 124.782078 -274.174843)
			(xy 124.792818 -274.235911) (xy 124.793502 -274.266914) (xy 124.793004 -274.293563) (xy 124.785061 -274.346267)
			(xy 124.769351 -274.397197) (xy 124.746225 -274.445218) (xy 124.716201 -274.489255) (xy 124.679949 -274.528326)
			(xy 124.638278 -274.561557) (xy 124.59212 -274.588206) (xy 124.542506 -274.607678) (xy 124.490544 -274.619538)
			(xy 124.437394 -274.623522) (xy 124.384244 -274.619538) (xy 124.332282 -274.607678) (xy 124.282668 -274.588206)
			(xy 124.23651 -274.561557) (xy 124.194839 -274.528326) (xy 124.158587 -274.489255) (xy 124.128563 -274.445218)
			(xy 124.105437 -274.397197) (xy 124.089727 -274.346267) (xy 124.081784 -274.293563) (xy 124.081286 -274.266914)
			(xy 124.081984 -274.235915) (xy 124.092759 -274.174858) (xy 124.113919 -274.11658) (xy 124.128784 -274.089368)
			(xy 124.135961 -274.07591) (xy 124.142732 -274.046185) (xy 124.140435 -274.015785) (xy 124.129274 -273.987415)
			(xy 124.110243 -273.963598) (xy 124.085034 -273.946454) (xy 124.05589 -273.937507) (xy 124.040646 -273.936968)
			(xy 123.894342 -273.936968) (xy 123.879114 -273.937542) (xy 123.850012 -273.946524) (xy 123.824844 -273.963676)
			(xy 123.80584 -273.987477) (xy 123.794685 -274.015817) (xy 123.792368 -274.046186) (xy 123.799093 -274.075891)
			(xy 123.806204 -274.089368) (xy 123.821103 -274.116564) (xy 123.842278 -274.174843) (xy 123.853018 -274.235911)
			(xy 123.853702 -274.266914) (xy 123.853204 -274.293563) (xy 123.845261 -274.346267) (xy 123.829551 -274.397197)
			(xy 123.806425 -274.445218) (xy 123.776401 -274.489255) (xy 123.740149 -274.528326) (xy 123.698478 -274.561557)
			(xy 123.65232 -274.588206) (xy 123.602706 -274.607678) (xy 123.550744 -274.619538) (xy 123.497594 -274.623522)
			(xy 123.444444 -274.619538) (xy 123.392482 -274.607678) (xy 123.342868 -274.588206) (xy 123.29671 -274.561557)
			(xy 123.255039 -274.528326) (xy 123.218787 -274.489255) (xy 123.188763 -274.445218) (xy 123.165637 -274.397197)
			(xy 123.149927 -274.346267) (xy 123.141984 -274.293563) (xy 123.141486 -274.266914) (xy 123.142184 -274.235915)
			(xy 123.152959 -274.174858) (xy 123.174119 -274.11658) (xy 123.188984 -274.089368) (xy 123.196161 -274.07591)
			(xy 123.202932 -274.046185) (xy 123.200635 -274.015785) (xy 123.189474 -273.987415) (xy 123.170443 -273.963598)
			(xy 123.145234 -273.946454) (xy 123.11609 -273.937507) (xy 123.100846 -273.936968) (xy 122.954542 -273.936968)
			(xy 122.939314 -273.937542) (xy 122.910212 -273.946524) (xy 122.885044 -273.963676) (xy 122.86604 -273.987477)
			(xy 122.854885 -274.015817) (xy 122.852568 -274.046186) (xy 122.859293 -274.075891) (xy 122.866404 -274.089368)
			(xy 122.881303 -274.116564) (xy 122.902478 -274.174843) (xy 122.913218 -274.235911) (xy 122.913902 -274.266914)
			(xy 122.913404 -274.293563) (xy 122.905461 -274.346267) (xy 122.889751 -274.397197) (xy 122.866625 -274.445218)
			(xy 122.836601 -274.489255) (xy 122.800349 -274.528326) (xy 122.758678 -274.561557) (xy 122.71252 -274.588206)
			(xy 122.662906 -274.607678) (xy 122.610944 -274.619538) (xy 122.557794 -274.623522) (xy 122.504644 -274.619538)
			(xy 122.452682 -274.607678) (xy 122.403068 -274.588206) (xy 122.35691 -274.561557) (xy 122.315239 -274.528326)
			(xy 122.278987 -274.489255) (xy 122.248963 -274.445218) (xy 122.225837 -274.397197) (xy 122.210127 -274.346267)
			(xy 122.202184 -274.293563) (xy 122.201686 -274.266914) (xy 122.202384 -274.235915) (xy 122.213159 -274.174858)
			(xy 122.234319 -274.11658) (xy 122.249184 -274.089368) (xy 122.256361 -274.07591) (xy 122.263132 -274.046185)
			(xy 122.260835 -274.015785) (xy 122.249674 -273.987415) (xy 122.230643 -273.963598) (xy 122.205434 -273.946454)
			(xy 122.17629 -273.937507) (xy 122.161046 -273.936968) (xy 122.014996 -273.936968) (xy 121.999773 -273.937548)
			(xy 121.970684 -273.946538) (xy 121.945528 -273.963691) (xy 121.926534 -273.987487) (xy 121.915385 -274.015819)
			(xy 121.913067 -274.046178) (xy 121.919786 -274.075874) (xy 121.926858 -274.089368) (xy 121.941755 -274.116565)
			(xy 121.962926 -274.174844) (xy 121.973665 -274.235911) (xy 121.974356 -274.266914) (xy 121.973858 -274.293563)
			(xy 121.965915 -274.346267) (xy 121.950205 -274.397197) (xy 121.927079 -274.445218) (xy 121.897055 -274.489255)
			(xy 121.860803 -274.528326) (xy 121.819132 -274.561557) (xy 121.772974 -274.588206) (xy 121.72336 -274.607678)
			(xy 121.671398 -274.619538) (xy 121.618248 -274.623522) (xy 121.565098 -274.619538) (xy 121.513136 -274.607678)
			(xy 121.463522 -274.588206) (xy 121.417364 -274.561557) (xy 121.375693 -274.528326) (xy 121.339441 -274.489255)
			(xy 121.309417 -274.445218) (xy 121.286291 -274.397197) (xy 121.270581 -274.346267) (xy 121.262638 -274.293563)
			(xy 121.26214 -274.266914) (xy 121.262838 -274.235914) (xy 121.273612 -274.174857) (xy 121.294769 -274.116578)
			(xy 121.309638 -274.089368) (xy 121.316812 -274.075908) (xy 121.323579 -274.046179) (xy 121.321281 -274.015777)
			(xy 121.310122 -273.987403) (xy 121.291094 -273.963581) (xy 121.265888 -273.946427) (xy 121.236745 -273.937467)
			(xy 121.2215 -273.936968) (xy 121.074942 -273.936968) (xy 121.059714 -273.937542) (xy 121.030612 -273.946524)
			(xy 121.005444 -273.963676) (xy 120.98644 -273.987477) (xy 120.975285 -274.015817) (xy 120.972968 -274.046186)
			(xy 120.979693 -274.075891) (xy 120.986804 -274.089368) (xy 121.001703 -274.116564) (xy 121.022878 -274.174843)
			(xy 121.033618 -274.235911) (xy 121.034302 -274.266914) (xy 121.033804 -274.293563) (xy 121.025861 -274.346267)
			(xy 121.010151 -274.397197) (xy 120.987025 -274.445218) (xy 120.957001 -274.489255) (xy 120.920749 -274.528326)
			(xy 120.879078 -274.561557) (xy 120.83292 -274.588206) (xy 120.783306 -274.607678) (xy 120.731344 -274.619538)
			(xy 120.678194 -274.623522) (xy 120.625044 -274.619538) (xy 120.573082 -274.607678) (xy 120.523468 -274.588206)
			(xy 120.47731 -274.561557) (xy 120.435639 -274.528326) (xy 120.399387 -274.489255) (xy 120.369363 -274.445218)
			(xy 120.346237 -274.397197) (xy 120.330527 -274.346267) (xy 120.322584 -274.293563) (xy 120.322086 -274.266914)
			(xy 120.322784 -274.235915) (xy 120.333559 -274.174858) (xy 120.354719 -274.11658) (xy 120.369584 -274.089368)
			(xy 120.376761 -274.07591) (xy 120.383532 -274.046185) (xy 120.381235 -274.015785) (xy 120.370074 -273.987415)
			(xy 120.351043 -273.963598) (xy 120.325834 -273.946454) (xy 120.29669 -273.937507) (xy 120.281446 -273.936968)
			(xy 120.135142 -273.936968) (xy 120.119914 -273.937542) (xy 120.090812 -273.946524) (xy 120.065644 -273.963676)
			(xy 120.04664 -273.987477) (xy 120.035485 -274.015817) (xy 120.033168 -274.046186) (xy 120.039893 -274.075891)
			(xy 120.047004 -274.089368) (xy 120.061903 -274.116564) (xy 120.083078 -274.174843) (xy 120.093818 -274.235911)
			(xy 120.094502 -274.266914) (xy 120.094004 -274.293563) (xy 120.086061 -274.346267) (xy 120.070351 -274.397197)
			(xy 120.047225 -274.445218) (xy 120.017201 -274.489255) (xy 119.980949 -274.528326) (xy 119.939278 -274.561557)
			(xy 119.89312 -274.588206) (xy 119.843506 -274.607678) (xy 119.791544 -274.619538) (xy 119.738394 -274.623522)
			(xy 119.685244 -274.619538) (xy 119.633282 -274.607678) (xy 119.583668 -274.588206) (xy 119.53751 -274.561557)
			(xy 119.495839 -274.528326) (xy 119.459587 -274.489255) (xy 119.429563 -274.445218) (xy 119.406437 -274.397197)
			(xy 119.390727 -274.346267) (xy 119.382784 -274.293563) (xy 119.382286 -274.266914) (xy 119.382984 -274.235915)
			(xy 119.393759 -274.174858) (xy 119.414919 -274.11658) (xy 119.429784 -274.089368) (xy 119.436961 -274.07591)
			(xy 119.443732 -274.046185) (xy 119.441435 -274.015785) (xy 119.430274 -273.987415) (xy 119.411243 -273.963598)
			(xy 119.386034 -273.946454) (xy 119.35689 -273.937507) (xy 119.341646 -273.936968) (xy 119.195342 -273.936968)
			(xy 119.180114 -273.937542) (xy 119.151012 -273.946524) (xy 119.125844 -273.963676) (xy 119.10684 -273.987477)
			(xy 119.095685 -274.015817) (xy 119.093368 -274.046186) (xy 119.100093 -274.075891) (xy 119.107204 -274.089368)
			(xy 119.122103 -274.116564) (xy 119.143278 -274.174843) (xy 119.154018 -274.235911) (xy 119.154702 -274.266914)
			(xy 119.154204 -274.293563) (xy 119.146261 -274.346267) (xy 119.130551 -274.397197) (xy 119.107425 -274.445218)
			(xy 119.077401 -274.489255) (xy 119.041149 -274.528326) (xy 118.999478 -274.561557) (xy 118.95332 -274.588206)
			(xy 118.903706 -274.607678) (xy 118.851744 -274.619538) (xy 118.798594 -274.623522) (xy 118.745444 -274.619538)
			(xy 118.693482 -274.607678) (xy 118.643868 -274.588206) (xy 118.59771 -274.561557) (xy 118.556039 -274.528326)
			(xy 118.519787 -274.489255) (xy 118.489763 -274.445218) (xy 118.466637 -274.397197) (xy 118.450927 -274.346267)
			(xy 118.442984 -274.293563) (xy 118.442486 -274.266914) (xy 118.443184 -274.235915) (xy 118.453959 -274.174858)
			(xy 118.475119 -274.11658) (xy 118.489984 -274.089368) (xy 118.497161 -274.07591) (xy 118.503932 -274.046185)
			(xy 118.501635 -274.015785) (xy 118.490474 -273.987415) (xy 118.471443 -273.963598) (xy 118.446234 -273.946454)
			(xy 118.41709 -273.937507) (xy 118.401846 -273.936968) (xy 118.255796 -273.936968) (xy 118.240573 -273.937548)
			(xy 118.211484 -273.946538) (xy 118.186328 -273.963691) (xy 118.167334 -273.987487) (xy 118.156185 -274.015819)
			(xy 118.153867 -274.046178) (xy 118.160586 -274.075874) (xy 118.167658 -274.089368) (xy 118.182555 -274.116565)
			(xy 118.203726 -274.174844) (xy 118.214465 -274.235911) (xy 118.215156 -274.266914) (xy 118.214658 -274.293563)
			(xy 118.206715 -274.346267) (xy 118.191005 -274.397197) (xy 118.167879 -274.445218) (xy 118.137855 -274.489255)
			(xy 118.101603 -274.528326) (xy 118.059932 -274.561557) (xy 118.013774 -274.588206) (xy 117.96416 -274.607678)
			(xy 117.912198 -274.619538) (xy 117.859048 -274.623522) (xy 117.805898 -274.619538) (xy 117.753936 -274.607678)
			(xy 117.704322 -274.588206) (xy 117.658164 -274.561557) (xy 117.616493 -274.528326) (xy 117.580241 -274.489255)
			(xy 117.550217 -274.445218) (xy 117.527091 -274.397197) (xy 117.511381 -274.346267) (xy 117.503438 -274.293563)
			(xy 117.50294 -274.266914) (xy 117.503638 -274.235914) (xy 117.514412 -274.174857) (xy 117.535569 -274.116578)
			(xy 117.550438 -274.089368) (xy 117.557612 -274.075908) (xy 117.564379 -274.046179) (xy 117.562081 -274.015777)
			(xy 117.550922 -273.987403) (xy 117.531894 -273.963581) (xy 117.506688 -273.946427) (xy 117.477545 -273.937467)
			(xy 117.4623 -273.936968) (xy 117.315996 -273.936968) (xy 117.300773 -273.937548) (xy 117.271684 -273.946538)
			(xy 117.246528 -273.963691) (xy 117.227534 -273.987487) (xy 117.216385 -274.015819) (xy 117.214067 -274.046178)
			(xy 117.220786 -274.075874) (xy 117.227858 -274.089368) (xy 117.242755 -274.116565) (xy 117.263926 -274.174844)
			(xy 117.274665 -274.235911) (xy 117.275356 -274.266914) (xy 117.274858 -274.293563) (xy 117.266915 -274.346267)
			(xy 117.251205 -274.397197) (xy 117.228079 -274.445218) (xy 117.198055 -274.489255) (xy 117.161803 -274.528326)
			(xy 117.120132 -274.561557) (xy 117.073974 -274.588206) (xy 117.02436 -274.607678) (xy 116.972398 -274.619538)
			(xy 116.919248 -274.623522) (xy 116.866098 -274.619538) (xy 116.814136 -274.607678) (xy 116.764522 -274.588206)
			(xy 116.718364 -274.561557) (xy 116.676693 -274.528326) (xy 116.640441 -274.489255) (xy 116.610417 -274.445218)
			(xy 116.587291 -274.397197) (xy 116.571581 -274.346267) (xy 116.563638 -274.293563) (xy 116.56314 -274.266914)
			(xy 116.563838 -274.235914) (xy 116.574612 -274.174857) (xy 116.595769 -274.116578) (xy 116.610638 -274.089368)
			(xy 116.617812 -274.075908) (xy 116.624579 -274.046179) (xy 116.622281 -274.015777) (xy 116.611122 -273.987403)
			(xy 116.592094 -273.963581) (xy 116.566888 -273.946427) (xy 116.537745 -273.937467) (xy 116.5225 -273.936968)
			(xy 116.376196 -273.936968) (xy 116.360973 -273.937548) (xy 116.331884 -273.946538) (xy 116.306728 -273.963691)
			(xy 116.287734 -273.987487) (xy 116.276585 -274.015819) (xy 116.274267 -274.046178) (xy 116.280986 -274.075874)
			(xy 116.288058 -274.089368) (xy 116.302955 -274.116565) (xy 116.324126 -274.174844) (xy 116.334865 -274.235911)
			(xy 116.335556 -274.266914) (xy 116.335058 -274.293563) (xy 116.327115 -274.346267) (xy 116.311405 -274.397197)
			(xy 116.288279 -274.445218) (xy 116.258255 -274.489255) (xy 116.222003 -274.528326) (xy 116.180332 -274.561557)
			(xy 116.134174 -274.588206) (xy 116.08456 -274.607678) (xy 116.032598 -274.619538) (xy 115.979448 -274.623522)
			(xy 115.926298 -274.619538) (xy 115.874336 -274.607678) (xy 115.824722 -274.588206) (xy 115.778564 -274.561557)
			(xy 115.736893 -274.528326) (xy 115.700641 -274.489255) (xy 115.670617 -274.445218) (xy 115.647491 -274.397197)
			(xy 115.631781 -274.346267) (xy 115.623838 -274.293563) (xy 115.62334 -274.266914) (xy 115.624038 -274.235914)
			(xy 115.634812 -274.174857) (xy 115.655969 -274.116578) (xy 115.670838 -274.089368) (xy 115.678012 -274.075908)
			(xy 115.684779 -274.046179) (xy 115.682481 -274.015777) (xy 115.671322 -273.987403) (xy 115.652294 -273.963581)
			(xy 115.627088 -273.946427) (xy 115.597945 -273.937467) (xy 115.5827 -273.936968) (xy 115.436142 -273.936968)
			(xy 115.420914 -273.937542) (xy 115.391812 -273.946524) (xy 115.366644 -273.963676) (xy 115.34764 -273.987477)
			(xy 115.336485 -274.015817) (xy 115.334168 -274.046186) (xy 115.340893 -274.075891) (xy 115.348004 -274.089368)
			(xy 115.362903 -274.116564) (xy 115.384078 -274.174843) (xy 115.394818 -274.235911) (xy 115.395502 -274.266914)
			(xy 115.394952 -274.294896) (xy 115.386195 -274.350171) (xy 115.368899 -274.403396) (xy 115.34349 -274.45326)
			(xy 115.310594 -274.498535) (xy 115.27102 -274.538107) (xy 115.225743 -274.571001) (xy 115.175878 -274.596407)
			(xy 115.122652 -274.6137) (xy 115.067376 -274.622454) (xy 115.039394 -274.623022) (xy 115.013424 -274.62255)
			(xy 114.962034 -274.615002) (xy 114.912287 -274.600066) (xy 114.865238 -274.57806) (xy 114.821886 -274.549451)
			(xy 114.783152 -274.514846) (xy 114.749857 -274.47498) (xy 114.735864 -274.453096) (xy 114.7274 -274.440305)
			(xy 114.704341 -274.420102) (xy 114.676332 -274.407636) (xy 114.645887 -274.404027) (xy 114.61574 -274.409599)
			(xy 114.588596 -274.423851) (xy 114.577368 -274.4343) (xy 114.497358 -274.51431) (xy 114.497358 -274.624038)
			(xy 114.497873 -274.639377) (xy 114.506961 -274.668676) (xy 114.524337 -274.693957) (xy 114.548433 -274.712942)
			(xy 114.577079 -274.723918) (xy 114.592354 -274.725384) (xy 114.619087 -274.727613) (xy 114.671487 -274.739092)
			(xy 114.721573 -274.7583) (xy 114.76821 -274.784805) (xy 114.810344 -274.818005) (xy 114.847021 -274.85715)
			(xy 114.877411 -274.901354) (xy 114.900826 -274.949616) (xy 114.916737 -275.000845) (xy 114.924784 -275.053881)
			(xy 114.924783 -275.107379) (xy 115.15343 -275.107379) (xy 115.15343 -275.054081) (xy 115.161373 -275.001377)
			(xy 115.177083 -274.950447) (xy 115.200209 -274.902426) (xy 115.230233 -274.858389) (xy 115.266485 -274.819318)
			(xy 115.308156 -274.786087) (xy 115.354314 -274.759438) (xy 115.403928 -274.739966) (xy 115.45589 -274.728106)
			(xy 115.50904 -274.724123) (xy 115.56219 -274.728106) (xy 115.614152 -274.739966) (xy 115.663766 -274.759438)
			(xy 115.709924 -274.786087) (xy 115.751595 -274.819318) (xy 115.787847 -274.858389) (xy 115.817871 -274.902426)
			(xy 115.840997 -274.950447) (xy 115.856707 -275.001377) (xy 115.86465 -275.054081) (xy 115.865148 -275.08073)
			(xy 115.86465 -275.107379) (xy 116.093484 -275.107379) (xy 116.093484 -275.054081) (xy 116.101427 -275.001377)
			(xy 116.117137 -274.950447) (xy 116.140263 -274.902426) (xy 116.170287 -274.858389) (xy 116.206539 -274.819318)
			(xy 116.24821 -274.786087) (xy 116.294368 -274.759438) (xy 116.343982 -274.739966) (xy 116.395944 -274.728106)
			(xy 116.449094 -274.724123) (xy 116.502244 -274.728106) (xy 116.554206 -274.739966) (xy 116.60382 -274.759438)
			(xy 116.649978 -274.786087) (xy 116.691649 -274.819318) (xy 116.727901 -274.858389) (xy 116.757925 -274.902426)
			(xy 116.781051 -274.950447) (xy 116.796761 -275.001377) (xy 116.804704 -275.054081) (xy 116.805202 -275.08073)
			(xy 116.804704 -275.107379) (xy 119.852938 -275.107379) (xy 119.852938 -275.054081) (xy 119.860881 -275.001377)
			(xy 119.876591 -274.950447) (xy 119.899717 -274.902426) (xy 119.929741 -274.858389) (xy 119.965993 -274.819318)
			(xy 120.007664 -274.786087) (xy 120.053822 -274.759438) (xy 120.103436 -274.739966) (xy 120.155398 -274.728106)
			(xy 120.208548 -274.724123) (xy 120.261698 -274.728106) (xy 120.31366 -274.739966) (xy 120.363274 -274.759438)
			(xy 120.409432 -274.786087) (xy 120.451103 -274.819318) (xy 120.487355 -274.858389) (xy 120.517379 -274.902426)
			(xy 120.540505 -274.950447) (xy 120.556215 -275.001377) (xy 120.564158 -275.054081) (xy 120.564656 -275.08073)
			(xy 120.564163 -275.107125) (xy 120.792484 -275.107125) (xy 120.792484 -275.053827) (xy 120.800427 -275.001123)
			(xy 120.816137 -274.950193) (xy 120.839263 -274.902172) (xy 120.869287 -274.858135) (xy 120.905539 -274.819064)
			(xy 120.94721 -274.785833) (xy 120.993368 -274.759184) (xy 121.042982 -274.739712) (xy 121.094944 -274.727852)
			(xy 121.148094 -274.723869) (xy 121.201244 -274.727852) (xy 121.253206 -274.739712) (xy 121.30282 -274.759184)
			(xy 121.348978 -274.785833) (xy 121.390649 -274.819064) (xy 121.426901 -274.858135) (xy 121.456925 -274.902172)
			(xy 121.480051 -274.950193) (xy 121.495761 -275.001123) (xy 121.503704 -275.053827) (xy 121.504202 -275.080476)
			(xy 121.503704 -275.107125) (xy 121.503666 -275.107379) (xy 121.732538 -275.107379) (xy 121.732538 -275.054081)
			(xy 121.740481 -275.001377) (xy 121.756191 -274.950447) (xy 121.779317 -274.902426) (xy 121.809341 -274.858389)
			(xy 121.845593 -274.819318) (xy 121.887264 -274.786087) (xy 121.933422 -274.759438) (xy 121.983036 -274.739966)
			(xy 122.034998 -274.728106) (xy 122.088148 -274.724123) (xy 122.141298 -274.728106) (xy 122.19326 -274.739966)
			(xy 122.242874 -274.759438) (xy 122.289032 -274.786087) (xy 122.330703 -274.819318) (xy 122.366955 -274.858389)
			(xy 122.396979 -274.902426) (xy 122.420105 -274.950447) (xy 122.435815 -275.001377) (xy 122.443758 -275.054081)
			(xy 122.444256 -275.08073) (xy 122.443758 -275.107379) (xy 122.672338 -275.107379) (xy 122.672338 -275.054081)
			(xy 122.680281 -275.001377) (xy 122.695991 -274.950447) (xy 122.719117 -274.902426) (xy 122.749141 -274.858389)
			(xy 122.785393 -274.819318) (xy 122.827064 -274.786087) (xy 122.873222 -274.759438) (xy 122.922836 -274.739966)
			(xy 122.974798 -274.728106) (xy 123.027948 -274.724123) (xy 123.081098 -274.728106) (xy 123.13306 -274.739966)
			(xy 123.182674 -274.759438) (xy 123.228832 -274.786087) (xy 123.270503 -274.819318) (xy 123.306755 -274.858389)
			(xy 123.336779 -274.902426) (xy 123.359905 -274.950447) (xy 123.375615 -275.001377) (xy 123.383558 -275.054081)
			(xy 123.384056 -275.08073) (xy 123.383558 -275.107379) (xy 123.612138 -275.107379) (xy 123.612138 -275.054081)
			(xy 123.620081 -275.001377) (xy 123.635791 -274.950447) (xy 123.658917 -274.902426) (xy 123.688941 -274.858389)
			(xy 123.725193 -274.819318) (xy 123.766864 -274.786087) (xy 123.813022 -274.759438) (xy 123.862636 -274.739966)
			(xy 123.914598 -274.728106) (xy 123.967748 -274.724123) (xy 124.020898 -274.728106) (xy 124.07286 -274.739966)
			(xy 124.122474 -274.759438) (xy 124.168632 -274.786087) (xy 124.210303 -274.819318) (xy 124.246555 -274.858389)
			(xy 124.276579 -274.902426) (xy 124.299705 -274.950447) (xy 124.315415 -275.001377) (xy 124.323358 -275.054081)
			(xy 124.323856 -275.08073) (xy 124.323358 -275.107379) (xy 124.551938 -275.107379) (xy 124.551938 -275.054081)
			(xy 124.559881 -275.001377) (xy 124.575591 -274.950447) (xy 124.598717 -274.902426) (xy 124.628741 -274.858389)
			(xy 124.664993 -274.819318) (xy 124.706664 -274.786087) (xy 124.752822 -274.759438) (xy 124.802436 -274.739966)
			(xy 124.854398 -274.728106) (xy 124.907548 -274.724123) (xy 124.960698 -274.728106) (xy 125.01266 -274.739966)
			(xy 125.062274 -274.759438) (xy 125.108432 -274.786087) (xy 125.150103 -274.819318) (xy 125.186355 -274.858389)
			(xy 125.216379 -274.902426) (xy 125.239505 -274.950447) (xy 125.255215 -275.001377) (xy 125.263158 -275.054081)
			(xy 125.263656 -275.08073) (xy 125.263158 -275.107379) (xy 125.491738 -275.107379) (xy 125.491738 -275.054081)
			(xy 125.499681 -275.001377) (xy 125.515391 -274.950447) (xy 125.538517 -274.902426) (xy 125.568541 -274.858389)
			(xy 125.604793 -274.819318) (xy 125.646464 -274.786087) (xy 125.692622 -274.759438) (xy 125.742236 -274.739966)
			(xy 125.794198 -274.728106) (xy 125.847348 -274.724123) (xy 125.900498 -274.728106) (xy 125.95246 -274.739966)
			(xy 126.002074 -274.759438) (xy 126.048232 -274.786087) (xy 126.089903 -274.819318) (xy 126.126155 -274.858389)
			(xy 126.156179 -274.902426) (xy 126.179305 -274.950447) (xy 126.195015 -275.001377) (xy 126.202958 -275.054081)
			(xy 126.203456 -275.08073) (xy 126.202958 -275.107379) (xy 126.431284 -275.107379) (xy 126.431284 -275.054081)
			(xy 126.439227 -275.001377) (xy 126.454937 -274.950447) (xy 126.478063 -274.902426) (xy 126.508087 -274.858389)
			(xy 126.544339 -274.819318) (xy 126.58601 -274.786087) (xy 126.632168 -274.759438) (xy 126.681782 -274.739966)
			(xy 126.733744 -274.728106) (xy 126.786894 -274.724123) (xy 126.840044 -274.728106) (xy 126.892006 -274.739966)
			(xy 126.94162 -274.759438) (xy 126.987778 -274.786087) (xy 127.029449 -274.819318) (xy 127.065701 -274.858389)
			(xy 127.095725 -274.902426) (xy 127.118851 -274.950447) (xy 127.134561 -275.001377) (xy 127.142504 -275.054081)
			(xy 127.143002 -275.08073) (xy 127.142504 -275.107379) (xy 127.371338 -275.107379) (xy 127.371338 -275.054081)
			(xy 127.379281 -275.001377) (xy 127.394991 -274.950447) (xy 127.418117 -274.902426) (xy 127.448141 -274.858389)
			(xy 127.484393 -274.819318) (xy 127.526064 -274.786087) (xy 127.572222 -274.759438) (xy 127.621836 -274.739966)
			(xy 127.673798 -274.728106) (xy 127.726948 -274.724123) (xy 127.780098 -274.728106) (xy 127.83206 -274.739966)
			(xy 127.881674 -274.759438) (xy 127.927832 -274.786087) (xy 127.969503 -274.819318) (xy 128.005755 -274.858389)
			(xy 128.035779 -274.902426) (xy 128.058905 -274.950447) (xy 128.074615 -275.001377) (xy 128.082558 -275.054081)
			(xy 128.083056 -275.08073) (xy 128.082558 -275.107379) (xy 128.311138 -275.107379) (xy 128.311138 -275.054081)
			(xy 128.319081 -275.001377) (xy 128.334791 -274.950447) (xy 128.357917 -274.902426) (xy 128.387941 -274.858389)
			(xy 128.424193 -274.819318) (xy 128.465864 -274.786087) (xy 128.512022 -274.759438) (xy 128.561636 -274.739966)
			(xy 128.613598 -274.728106) (xy 128.666748 -274.724123) (xy 128.719898 -274.728106) (xy 128.77186 -274.739966)
			(xy 128.821474 -274.759438) (xy 128.867632 -274.786087) (xy 128.909303 -274.819318) (xy 128.945555 -274.858389)
			(xy 128.975579 -274.902426) (xy 128.998705 -274.950447) (xy 129.014415 -275.001377) (xy 129.022358 -275.054081)
			(xy 129.022856 -275.08073) (xy 129.022358 -275.107379) (xy 129.250938 -275.107379) (xy 129.250938 -275.054081)
			(xy 129.258881 -275.001377) (xy 129.274591 -274.950447) (xy 129.297717 -274.902426) (xy 129.327741 -274.858389)
			(xy 129.363993 -274.819318) (xy 129.405664 -274.786087) (xy 129.451822 -274.759438) (xy 129.501436 -274.739966)
			(xy 129.553398 -274.728106) (xy 129.606548 -274.724123) (xy 129.659698 -274.728106) (xy 129.71166 -274.739966)
			(xy 129.761274 -274.759438) (xy 129.807432 -274.786087) (xy 129.849103 -274.819318) (xy 129.885355 -274.858389)
			(xy 129.915379 -274.902426) (xy 129.938505 -274.950447) (xy 129.954215 -275.001377) (xy 129.962158 -275.054081)
			(xy 129.962656 -275.08073) (xy 129.962158 -275.107379) (xy 130.190738 -275.107379) (xy 130.190738 -275.054081)
			(xy 130.198681 -275.001377) (xy 130.214391 -274.950447) (xy 130.237517 -274.902426) (xy 130.267541 -274.858389)
			(xy 130.303793 -274.819318) (xy 130.345464 -274.786087) (xy 130.391622 -274.759438) (xy 130.441236 -274.739966)
			(xy 130.493198 -274.728106) (xy 130.546348 -274.724123) (xy 130.599498 -274.728106) (xy 130.65146 -274.739966)
			(xy 130.701074 -274.759438) (xy 130.747232 -274.786087) (xy 130.788903 -274.819318) (xy 130.825155 -274.858389)
			(xy 130.855179 -274.902426) (xy 130.878305 -274.950447) (xy 130.894015 -275.001377) (xy 130.901958 -275.054081)
			(xy 130.902456 -275.08073) (xy 130.901958 -275.107379) (xy 130.894015 -275.160083) (xy 130.878305 -275.211013)
			(xy 130.855179 -275.259034) (xy 130.825155 -275.303071) (xy 130.788903 -275.342142) (xy 130.747232 -275.375373)
			(xy 130.701074 -275.402022) (xy 130.65146 -275.421494) (xy 130.599498 -275.433354) (xy 130.546348 -275.437338)
			(xy 130.493198 -275.433354) (xy 130.441236 -275.421494) (xy 130.391622 -275.402022) (xy 130.345464 -275.375373)
			(xy 130.303793 -275.342142) (xy 130.267541 -275.303071) (xy 130.237517 -275.259034) (xy 130.214391 -275.211013)
			(xy 130.198681 -275.160083) (xy 130.190738 -275.107379) (xy 129.962158 -275.107379) (xy 129.954215 -275.160083)
			(xy 129.938505 -275.211013) (xy 129.915379 -275.259034) (xy 129.885355 -275.303071) (xy 129.849103 -275.342142)
			(xy 129.807432 -275.375373) (xy 129.761274 -275.402022) (xy 129.71166 -275.421494) (xy 129.659698 -275.433354)
			(xy 129.606548 -275.437338) (xy 129.553398 -275.433354) (xy 129.501436 -275.421494) (xy 129.451822 -275.402022)
			(xy 129.405664 -275.375373) (xy 129.363993 -275.342142) (xy 129.327741 -275.303071) (xy 129.297717 -275.259034)
			(xy 129.274591 -275.211013) (xy 129.258881 -275.160083) (xy 129.250938 -275.107379) (xy 129.022358 -275.107379)
			(xy 129.014415 -275.160083) (xy 128.998705 -275.211013) (xy 128.975579 -275.259034) (xy 128.945555 -275.303071)
			(xy 128.909303 -275.342142) (xy 128.867632 -275.375373) (xy 128.821474 -275.402022) (xy 128.77186 -275.421494)
			(xy 128.719898 -275.433354) (xy 128.666748 -275.437338) (xy 128.613598 -275.433354) (xy 128.561636 -275.421494)
			(xy 128.512022 -275.402022) (xy 128.465864 -275.375373) (xy 128.424193 -275.342142) (xy 128.387941 -275.303071)
			(xy 128.357917 -275.259034) (xy 128.334791 -275.211013) (xy 128.319081 -275.160083) (xy 128.311138 -275.107379)
			(xy 128.082558 -275.107379) (xy 128.074615 -275.160083) (xy 128.058905 -275.211013) (xy 128.035779 -275.259034)
			(xy 128.005755 -275.303071) (xy 127.969503 -275.342142) (xy 127.927832 -275.375373) (xy 127.881674 -275.402022)
			(xy 127.83206 -275.421494) (xy 127.780098 -275.433354) (xy 127.726948 -275.437338) (xy 127.673798 -275.433354)
			(xy 127.621836 -275.421494) (xy 127.572222 -275.402022) (xy 127.526064 -275.375373) (xy 127.484393 -275.342142)
			(xy 127.448141 -275.303071) (xy 127.418117 -275.259034) (xy 127.394991 -275.211013) (xy 127.379281 -275.160083)
			(xy 127.371338 -275.107379) (xy 127.142504 -275.107379) (xy 127.134561 -275.160083) (xy 127.118851 -275.211013)
			(xy 127.095725 -275.259034) (xy 127.065701 -275.303071) (xy 127.029449 -275.342142) (xy 126.987778 -275.375373)
			(xy 126.94162 -275.402022) (xy 126.892006 -275.421494) (xy 126.840044 -275.433354) (xy 126.786894 -275.437338)
			(xy 126.733744 -275.433354) (xy 126.681782 -275.421494) (xy 126.632168 -275.402022) (xy 126.58601 -275.375373)
			(xy 126.544339 -275.342142) (xy 126.508087 -275.303071) (xy 126.478063 -275.259034) (xy 126.454937 -275.211013)
			(xy 126.439227 -275.160083) (xy 126.431284 -275.107379) (xy 126.202958 -275.107379) (xy 126.195015 -275.160083)
			(xy 126.179305 -275.211013) (xy 126.156179 -275.259034) (xy 126.126155 -275.303071) (xy 126.089903 -275.342142)
			(xy 126.048232 -275.375373) (xy 126.002074 -275.402022) (xy 125.95246 -275.421494) (xy 125.900498 -275.433354)
			(xy 125.847348 -275.437338) (xy 125.794198 -275.433354) (xy 125.742236 -275.421494) (xy 125.692622 -275.402022)
			(xy 125.646464 -275.375373) (xy 125.604793 -275.342142) (xy 125.568541 -275.303071) (xy 125.538517 -275.259034)
			(xy 125.515391 -275.211013) (xy 125.499681 -275.160083) (xy 125.491738 -275.107379) (xy 125.263158 -275.107379)
			(xy 125.255215 -275.160083) (xy 125.239505 -275.211013) (xy 125.216379 -275.259034) (xy 125.186355 -275.303071)
			(xy 125.150103 -275.342142) (xy 125.108432 -275.375373) (xy 125.062274 -275.402022) (xy 125.01266 -275.421494)
			(xy 124.960698 -275.433354) (xy 124.907548 -275.437338) (xy 124.854398 -275.433354) (xy 124.802436 -275.421494)
			(xy 124.752822 -275.402022) (xy 124.706664 -275.375373) (xy 124.664993 -275.342142) (xy 124.628741 -275.303071)
			(xy 124.598717 -275.259034) (xy 124.575591 -275.211013) (xy 124.559881 -275.160083) (xy 124.551938 -275.107379)
			(xy 124.323358 -275.107379) (xy 124.315415 -275.160083) (xy 124.299705 -275.211013) (xy 124.276579 -275.259034)
			(xy 124.246555 -275.303071) (xy 124.210303 -275.342142) (xy 124.168632 -275.375373) (xy 124.122474 -275.402022)
			(xy 124.07286 -275.421494) (xy 124.020898 -275.433354) (xy 123.967748 -275.437338) (xy 123.914598 -275.433354)
			(xy 123.862636 -275.421494) (xy 123.813022 -275.402022) (xy 123.766864 -275.375373) (xy 123.725193 -275.342142)
			(xy 123.688941 -275.303071) (xy 123.658917 -275.259034) (xy 123.635791 -275.211013) (xy 123.620081 -275.160083)
			(xy 123.612138 -275.107379) (xy 123.383558 -275.107379) (xy 123.375615 -275.160083) (xy 123.359905 -275.211013)
			(xy 123.336779 -275.259034) (xy 123.306755 -275.303071) (xy 123.270503 -275.342142) (xy 123.228832 -275.375373)
			(xy 123.182674 -275.402022) (xy 123.13306 -275.421494) (xy 123.081098 -275.433354) (xy 123.027948 -275.437338)
			(xy 122.974798 -275.433354) (xy 122.922836 -275.421494) (xy 122.873222 -275.402022) (xy 122.827064 -275.375373)
			(xy 122.785393 -275.342142) (xy 122.749141 -275.303071) (xy 122.719117 -275.259034) (xy 122.695991 -275.211013)
			(xy 122.680281 -275.160083) (xy 122.672338 -275.107379) (xy 122.443758 -275.107379) (xy 122.435815 -275.160083)
			(xy 122.420105 -275.211013) (xy 122.396979 -275.259034) (xy 122.366955 -275.303071) (xy 122.330703 -275.342142)
			(xy 122.289032 -275.375373) (xy 122.242874 -275.402022) (xy 122.19326 -275.421494) (xy 122.141298 -275.433354)
			(xy 122.088148 -275.437338) (xy 122.034998 -275.433354) (xy 121.983036 -275.421494) (xy 121.933422 -275.402022)
			(xy 121.887264 -275.375373) (xy 121.845593 -275.342142) (xy 121.809341 -275.303071) (xy 121.779317 -275.259034)
			(xy 121.756191 -275.211013) (xy 121.740481 -275.160083) (xy 121.732538 -275.107379) (xy 121.503666 -275.107379)
			(xy 121.495761 -275.159829) (xy 121.480051 -275.210759) (xy 121.456925 -275.25878) (xy 121.426901 -275.302817)
			(xy 121.390649 -275.341888) (xy 121.348978 -275.375119) (xy 121.30282 -275.401768) (xy 121.253206 -275.42124)
			(xy 121.201244 -275.4331) (xy 121.148094 -275.437084) (xy 121.094944 -275.4331) (xy 121.042982 -275.42124)
			(xy 120.993368 -275.401768) (xy 120.94721 -275.375119) (xy 120.905539 -275.341888) (xy 120.869287 -275.302817)
			(xy 120.839263 -275.25878) (xy 120.816137 -275.210759) (xy 120.800427 -275.159829) (xy 120.792484 -275.107125)
			(xy 120.564163 -275.107125) (xy 120.564158 -275.107379) (xy 120.556215 -275.160083) (xy 120.540505 -275.211013)
			(xy 120.517379 -275.259034) (xy 120.487355 -275.303071) (xy 120.451103 -275.342142) (xy 120.409432 -275.375373)
			(xy 120.363274 -275.402022) (xy 120.31366 -275.421494) (xy 120.261698 -275.433354) (xy 120.208548 -275.437338)
			(xy 120.155398 -275.433354) (xy 120.103436 -275.421494) (xy 120.053822 -275.402022) (xy 120.007664 -275.375373)
			(xy 119.965993 -275.342142) (xy 119.929741 -275.303071) (xy 119.899717 -275.259034) (xy 119.876591 -275.211013)
			(xy 119.860881 -275.160083) (xy 119.852938 -275.107379) (xy 116.804704 -275.107379) (xy 116.796761 -275.160083)
			(xy 116.781051 -275.211013) (xy 116.757925 -275.259034) (xy 116.727901 -275.303071) (xy 116.691649 -275.342142)
			(xy 116.649978 -275.375373) (xy 116.60382 -275.402022) (xy 116.554206 -275.421494) (xy 116.502244 -275.433354)
			(xy 116.449094 -275.437338) (xy 116.395944 -275.433354) (xy 116.343982 -275.421494) (xy 116.294368 -275.402022)
			(xy 116.24821 -275.375373) (xy 116.206539 -275.342142) (xy 116.170287 -275.303071) (xy 116.140263 -275.259034)
			(xy 116.117137 -275.211013) (xy 116.101427 -275.160083) (xy 116.093484 -275.107379) (xy 115.86465 -275.107379)
			(xy 115.856707 -275.160083) (xy 115.840997 -275.211013) (xy 115.817871 -275.259034) (xy 115.787847 -275.303071)
			(xy 115.751595 -275.342142) (xy 115.709924 -275.375373) (xy 115.663766 -275.402022) (xy 115.614152 -275.421494)
			(xy 115.56219 -275.433354) (xy 115.50904 -275.437338) (xy 115.45589 -275.433354) (xy 115.403928 -275.421494)
			(xy 115.354314 -275.402022) (xy 115.308156 -275.375373) (xy 115.266485 -275.342142) (xy 115.230233 -275.303071)
			(xy 115.200209 -275.259034) (xy 115.177083 -275.211013) (xy 115.161373 -275.160083) (xy 115.15343 -275.107379)
			(xy 114.924783 -275.107379) (xy 114.924783 -275.107523) (xy 114.916736 -275.160559) (xy 114.900825 -275.211787)
			(xy 114.877409 -275.260049) (xy 114.847018 -275.304253) (xy 114.810341 -275.343398) (xy 114.768207 -275.376597)
			(xy 114.721569 -275.403101) (xy 114.671483 -275.42231) (xy 114.619083 -275.433787) (xy 114.592354 -275.436076)
			(xy 114.577091 -275.437599) (xy 114.548465 -275.448582) (xy 114.524381 -275.467556) (xy 114.507002 -275.492816)
			(xy 114.497892 -275.522092) (xy 114.497358 -275.537422) (xy 114.497358 -275.921449) (xy 115.623584 -275.921449)
			(xy 115.623584 -275.868151) (xy 115.631527 -275.815447) (xy 115.647237 -275.764517) (xy 115.670363 -275.716496)
			(xy 115.700387 -275.672459) (xy 115.736639 -275.633388) (xy 115.77831 -275.600157) (xy 115.824468 -275.573508)
			(xy 115.874082 -275.554036) (xy 115.926044 -275.542176) (xy 115.979194 -275.538193) (xy 116.032344 -275.542176)
			(xy 116.084306 -275.554036) (xy 116.13392 -275.573508) (xy 116.180078 -275.600157) (xy 116.221749 -275.633388)
			(xy 116.258001 -275.672459) (xy 116.288025 -275.716496) (xy 116.311151 -275.764517) (xy 116.326861 -275.815447)
			(xy 116.334804 -275.868151) (xy 116.335302 -275.8948) (xy 116.334804 -275.921449) (xy 116.563384 -275.921449)
			(xy 116.563384 -275.868151) (xy 116.571327 -275.815447) (xy 116.587037 -275.764517) (xy 116.610163 -275.716496)
			(xy 116.640187 -275.672459) (xy 116.676439 -275.633388) (xy 116.71811 -275.600157) (xy 116.764268 -275.573508)
			(xy 116.813882 -275.554036) (xy 116.865844 -275.542176) (xy 116.918994 -275.538193) (xy 116.972144 -275.542176)
			(xy 117.024106 -275.554036) (xy 117.07372 -275.573508) (xy 117.119878 -275.600157) (xy 117.161549 -275.633388)
			(xy 117.197801 -275.672459) (xy 117.227825 -275.716496) (xy 117.250951 -275.764517) (xy 117.266661 -275.815447)
			(xy 117.274604 -275.868151) (xy 117.275102 -275.8948) (xy 117.274604 -275.921449) (xy 117.503184 -275.921449)
			(xy 117.503184 -275.868151) (xy 117.511127 -275.815447) (xy 117.526837 -275.764517) (xy 117.549963 -275.716496)
			(xy 117.579987 -275.672459) (xy 117.616239 -275.633388) (xy 117.65791 -275.600157) (xy 117.704068 -275.573508)
			(xy 117.753682 -275.554036) (xy 117.805644 -275.542176) (xy 117.858794 -275.538193) (xy 117.911944 -275.542176)
			(xy 117.963906 -275.554036) (xy 118.01352 -275.573508) (xy 118.059678 -275.600157) (xy 118.101349 -275.633388)
			(xy 118.137601 -275.672459) (xy 118.167625 -275.716496) (xy 118.190751 -275.764517) (xy 118.206461 -275.815447)
			(xy 118.214404 -275.868151) (xy 118.214902 -275.8948) (xy 118.214404 -275.921449) (xy 118.443238 -275.921449)
			(xy 118.443238 -275.868151) (xy 118.451181 -275.815447) (xy 118.466891 -275.764517) (xy 118.490017 -275.716496)
			(xy 118.520041 -275.672459) (xy 118.556293 -275.633388) (xy 118.597964 -275.600157) (xy 118.644122 -275.573508)
			(xy 118.693736 -275.554036) (xy 118.745698 -275.542176) (xy 118.798848 -275.538193) (xy 118.851998 -275.542176)
			(xy 118.90396 -275.554036) (xy 118.953574 -275.573508) (xy 118.999732 -275.600157) (xy 119.041403 -275.633388)
			(xy 119.077655 -275.672459) (xy 119.107679 -275.716496) (xy 119.130805 -275.764517) (xy 119.146515 -275.815447)
			(xy 119.154458 -275.868151) (xy 119.154956 -275.8948) (xy 119.154463 -275.921195) (xy 119.383038 -275.921195)
			(xy 119.383038 -275.867897) (xy 119.390981 -275.815193) (xy 119.406691 -275.764263) (xy 119.429817 -275.716242)
			(xy 119.459841 -275.672205) (xy 119.496093 -275.633134) (xy 119.537764 -275.599903) (xy 119.583922 -275.573254)
			(xy 119.633536 -275.553782) (xy 119.685498 -275.541922) (xy 119.738648 -275.537939) (xy 119.791798 -275.541922)
			(xy 119.84376 -275.553782) (xy 119.893374 -275.573254) (xy 119.939532 -275.599903) (xy 119.981203 -275.633134)
			(xy 120.017455 -275.672205) (xy 120.047479 -275.716242) (xy 120.070605 -275.764263) (xy 120.086315 -275.815193)
			(xy 120.094258 -275.867897) (xy 120.094756 -275.894546) (xy 120.094258 -275.921195) (xy 120.322838 -275.921195)
			(xy 120.322838 -275.867897) (xy 120.330781 -275.815193) (xy 120.346491 -275.764263) (xy 120.369617 -275.716242)
			(xy 120.399641 -275.672205) (xy 120.435893 -275.633134) (xy 120.477564 -275.599903) (xy 120.523722 -275.573254)
			(xy 120.573336 -275.553782) (xy 120.625298 -275.541922) (xy 120.678448 -275.537939) (xy 120.731598 -275.541922)
			(xy 120.78356 -275.553782) (xy 120.833174 -275.573254) (xy 120.879332 -275.599903) (xy 120.921003 -275.633134)
			(xy 120.957255 -275.672205) (xy 120.987279 -275.716242) (xy 121.010405 -275.764263) (xy 121.026115 -275.815193)
			(xy 121.034058 -275.867897) (xy 121.034556 -275.894546) (xy 121.034058 -275.921195) (xy 121.262638 -275.921195)
			(xy 121.262638 -275.867897) (xy 121.270581 -275.815193) (xy 121.286291 -275.764263) (xy 121.309417 -275.716242)
			(xy 121.339441 -275.672205) (xy 121.375693 -275.633134) (xy 121.417364 -275.599903) (xy 121.463522 -275.573254)
			(xy 121.513136 -275.553782) (xy 121.565098 -275.541922) (xy 121.618248 -275.537939) (xy 121.671398 -275.541922)
			(xy 121.72336 -275.553782) (xy 121.772974 -275.573254) (xy 121.819132 -275.599903) (xy 121.860803 -275.633134)
			(xy 121.897055 -275.672205) (xy 121.927079 -275.716242) (xy 121.950205 -275.764263) (xy 121.965915 -275.815193)
			(xy 121.973858 -275.867897) (xy 121.974356 -275.894546) (xy 121.973858 -275.921195) (xy 121.97382 -275.921449)
			(xy 122.202438 -275.921449) (xy 122.202438 -275.868151) (xy 122.210381 -275.815447) (xy 122.226091 -275.764517)
			(xy 122.249217 -275.716496) (xy 122.279241 -275.672459) (xy 122.315493 -275.633388) (xy 122.357164 -275.600157)
			(xy 122.403322 -275.573508) (xy 122.452936 -275.554036) (xy 122.504898 -275.542176) (xy 122.558048 -275.538193)
			(xy 122.611198 -275.542176) (xy 122.66316 -275.554036) (xy 122.712774 -275.573508) (xy 122.758932 -275.600157)
			(xy 122.800603 -275.633388) (xy 122.836855 -275.672459) (xy 122.866879 -275.716496) (xy 122.890005 -275.764517)
			(xy 122.905715 -275.815447) (xy 122.913658 -275.868151) (xy 122.914156 -275.8948) (xy 122.913658 -275.921449)
			(xy 123.141984 -275.921449) (xy 123.141984 -275.868151) (xy 123.149927 -275.815447) (xy 123.165637 -275.764517)
			(xy 123.188763 -275.716496) (xy 123.218787 -275.672459) (xy 123.255039 -275.633388) (xy 123.29671 -275.600157)
			(xy 123.342868 -275.573508) (xy 123.392482 -275.554036) (xy 123.444444 -275.542176) (xy 123.497594 -275.538193)
			(xy 123.550744 -275.542176) (xy 123.602706 -275.554036) (xy 123.65232 -275.573508) (xy 123.698478 -275.600157)
			(xy 123.740149 -275.633388) (xy 123.776401 -275.672459) (xy 123.806425 -275.716496) (xy 123.829551 -275.764517)
			(xy 123.845261 -275.815447) (xy 123.853204 -275.868151) (xy 123.853702 -275.8948) (xy 123.853204 -275.921449)
			(xy 124.081784 -275.921449) (xy 124.081784 -275.868151) (xy 124.089727 -275.815447) (xy 124.105437 -275.764517)
			(xy 124.128563 -275.716496) (xy 124.158587 -275.672459) (xy 124.194839 -275.633388) (xy 124.23651 -275.600157)
			(xy 124.282668 -275.573508) (xy 124.332282 -275.554036) (xy 124.384244 -275.542176) (xy 124.437394 -275.538193)
			(xy 124.490544 -275.542176) (xy 124.542506 -275.554036) (xy 124.59212 -275.573508) (xy 124.638278 -275.600157)
			(xy 124.679949 -275.633388) (xy 124.716201 -275.672459) (xy 124.746225 -275.716496) (xy 124.769351 -275.764517)
			(xy 124.785061 -275.815447) (xy 124.793004 -275.868151) (xy 124.793502 -275.8948) (xy 124.793004 -275.921449)
			(xy 125.021584 -275.921449) (xy 125.021584 -275.868151) (xy 125.029527 -275.815447) (xy 125.045237 -275.764517)
			(xy 125.068363 -275.716496) (xy 125.098387 -275.672459) (xy 125.134639 -275.633388) (xy 125.17631 -275.600157)
			(xy 125.222468 -275.573508) (xy 125.272082 -275.554036) (xy 125.324044 -275.542176) (xy 125.377194 -275.538193)
			(xy 125.430344 -275.542176) (xy 125.482306 -275.554036) (xy 125.53192 -275.573508) (xy 125.578078 -275.600157)
			(xy 125.619749 -275.633388) (xy 125.656001 -275.672459) (xy 125.686025 -275.716496) (xy 125.709151 -275.764517)
			(xy 125.724861 -275.815447) (xy 125.732804 -275.868151) (xy 125.733302 -275.8948) (xy 125.732804 -275.921449)
			(xy 125.961384 -275.921449) (xy 125.961384 -275.868151) (xy 125.969327 -275.815447) (xy 125.985037 -275.764517)
			(xy 126.008163 -275.716496) (xy 126.038187 -275.672459) (xy 126.074439 -275.633388) (xy 126.11611 -275.600157)
			(xy 126.162268 -275.573508) (xy 126.211882 -275.554036) (xy 126.263844 -275.542176) (xy 126.316994 -275.538193)
			(xy 126.370144 -275.542176) (xy 126.422106 -275.554036) (xy 126.47172 -275.573508) (xy 126.517878 -275.600157)
			(xy 126.559549 -275.633388) (xy 126.595801 -275.672459) (xy 126.625825 -275.716496) (xy 126.648951 -275.764517)
			(xy 126.664661 -275.815447) (xy 126.672604 -275.868151) (xy 126.673102 -275.8948) (xy 126.672604 -275.921449)
			(xy 126.901184 -275.921449) (xy 126.901184 -275.868151) (xy 126.909127 -275.815447) (xy 126.924837 -275.764517)
			(xy 126.947963 -275.716496) (xy 126.977987 -275.672459) (xy 127.014239 -275.633388) (xy 127.05591 -275.600157)
			(xy 127.102068 -275.573508) (xy 127.151682 -275.554036) (xy 127.203644 -275.542176) (xy 127.256794 -275.538193)
			(xy 127.309944 -275.542176) (xy 127.361906 -275.554036) (xy 127.41152 -275.573508) (xy 127.457678 -275.600157)
			(xy 127.499349 -275.633388) (xy 127.535601 -275.672459) (xy 127.565625 -275.716496) (xy 127.588751 -275.764517)
			(xy 127.604461 -275.815447) (xy 127.612404 -275.868151) (xy 127.612902 -275.8948) (xy 127.612404 -275.921449)
			(xy 127.840984 -275.921449) (xy 127.840984 -275.868151) (xy 127.848927 -275.815447) (xy 127.864637 -275.764517)
			(xy 127.887763 -275.716496) (xy 127.917787 -275.672459) (xy 127.954039 -275.633388) (xy 127.99571 -275.600157)
			(xy 128.041868 -275.573508) (xy 128.091482 -275.554036) (xy 128.143444 -275.542176) (xy 128.196594 -275.538193)
			(xy 128.249744 -275.542176) (xy 128.301706 -275.554036) (xy 128.35132 -275.573508) (xy 128.397478 -275.600157)
			(xy 128.439149 -275.633388) (xy 128.475401 -275.672459) (xy 128.505425 -275.716496) (xy 128.528551 -275.764517)
			(xy 128.544261 -275.815447) (xy 128.552204 -275.868151) (xy 128.552702 -275.8948) (xy 128.552204 -275.921449)
			(xy 128.781038 -275.921449) (xy 128.781038 -275.868151) (xy 128.788981 -275.815447) (xy 128.804691 -275.764517)
			(xy 128.827817 -275.716496) (xy 128.857841 -275.672459) (xy 128.894093 -275.633388) (xy 128.935764 -275.600157)
			(xy 128.981922 -275.573508) (xy 129.031536 -275.554036) (xy 129.083498 -275.542176) (xy 129.136648 -275.538193)
			(xy 129.189798 -275.542176) (xy 129.24176 -275.554036) (xy 129.291374 -275.573508) (xy 129.337532 -275.600157)
			(xy 129.379203 -275.633388) (xy 129.415455 -275.672459) (xy 129.445479 -275.716496) (xy 129.468605 -275.764517)
			(xy 129.484315 -275.815447) (xy 129.492258 -275.868151) (xy 129.492756 -275.8948) (xy 129.492258 -275.921449)
			(xy 129.720584 -275.921449) (xy 129.720584 -275.868151) (xy 129.728527 -275.815447) (xy 129.744237 -275.764517)
			(xy 129.767363 -275.716496) (xy 129.797387 -275.672459) (xy 129.833639 -275.633388) (xy 129.87531 -275.600157)
			(xy 129.921468 -275.573508) (xy 129.971082 -275.554036) (xy 130.023044 -275.542176) (xy 130.076194 -275.538193)
			(xy 130.129344 -275.542176) (xy 130.181306 -275.554036) (xy 130.23092 -275.573508) (xy 130.277078 -275.600157)
			(xy 130.318749 -275.633388) (xy 130.355001 -275.672459) (xy 130.385025 -275.716496) (xy 130.408151 -275.764517)
			(xy 130.423861 -275.815447) (xy 130.431804 -275.868151) (xy 130.432302 -275.8948) (xy 130.431804 -275.921449)
			(xy 130.660384 -275.921449) (xy 130.660384 -275.868151) (xy 130.668327 -275.815447) (xy 130.684037 -275.764517)
			(xy 130.707163 -275.716496) (xy 130.737187 -275.672459) (xy 130.773439 -275.633388) (xy 130.81511 -275.600157)
			(xy 130.861268 -275.573508) (xy 130.910882 -275.554036) (xy 130.962844 -275.542176) (xy 131.015994 -275.538193)
			(xy 131.069144 -275.542176) (xy 131.121106 -275.554036) (xy 131.17072 -275.573508) (xy 131.216878 -275.600157)
			(xy 131.258549 -275.633388) (xy 131.294801 -275.672459) (xy 131.324825 -275.716496) (xy 131.347951 -275.764517)
			(xy 131.363661 -275.815447) (xy 131.371604 -275.868151) (xy 131.372102 -275.8948) (xy 131.371604 -275.921449)
			(xy 131.363661 -275.974153) (xy 131.347951 -276.025083) (xy 131.324825 -276.073104) (xy 131.294801 -276.117141)
			(xy 131.258549 -276.156212) (xy 131.216878 -276.189443) (xy 131.17072 -276.216092) (xy 131.121106 -276.235564)
			(xy 131.069144 -276.247424) (xy 131.015994 -276.251408) (xy 130.962844 -276.247424) (xy 130.910882 -276.235564)
			(xy 130.861268 -276.216092) (xy 130.81511 -276.189443) (xy 130.773439 -276.156212) (xy 130.737187 -276.117141)
			(xy 130.707163 -276.073104) (xy 130.684037 -276.025083) (xy 130.668327 -275.974153) (xy 130.660384 -275.921449)
			(xy 130.431804 -275.921449) (xy 130.423861 -275.974153) (xy 130.408151 -276.025083) (xy 130.385025 -276.073104)
			(xy 130.355001 -276.117141) (xy 130.318749 -276.156212) (xy 130.277078 -276.189443) (xy 130.23092 -276.216092)
			(xy 130.181306 -276.235564) (xy 130.129344 -276.247424) (xy 130.076194 -276.251408) (xy 130.023044 -276.247424)
			(xy 129.971082 -276.235564) (xy 129.921468 -276.216092) (xy 129.87531 -276.189443) (xy 129.833639 -276.156212)
			(xy 129.797387 -276.117141) (xy 129.767363 -276.073104) (xy 129.744237 -276.025083) (xy 129.728527 -275.974153)
			(xy 129.720584 -275.921449) (xy 129.492258 -275.921449) (xy 129.484315 -275.974153) (xy 129.468605 -276.025083)
			(xy 129.445479 -276.073104) (xy 129.415455 -276.117141) (xy 129.379203 -276.156212) (xy 129.337532 -276.189443)
			(xy 129.291374 -276.216092) (xy 129.24176 -276.235564) (xy 129.189798 -276.247424) (xy 129.136648 -276.251408)
			(xy 129.083498 -276.247424) (xy 129.031536 -276.235564) (xy 128.981922 -276.216092) (xy 128.935764 -276.189443)
			(xy 128.894093 -276.156212) (xy 128.857841 -276.117141) (xy 128.827817 -276.073104) (xy 128.804691 -276.025083)
			(xy 128.788981 -275.974153) (xy 128.781038 -275.921449) (xy 128.552204 -275.921449) (xy 128.544261 -275.974153)
			(xy 128.528551 -276.025083) (xy 128.505425 -276.073104) (xy 128.475401 -276.117141) (xy 128.439149 -276.156212)
			(xy 128.397478 -276.189443) (xy 128.35132 -276.216092) (xy 128.301706 -276.235564) (xy 128.249744 -276.247424)
			(xy 128.196594 -276.251408) (xy 128.143444 -276.247424) (xy 128.091482 -276.235564) (xy 128.041868 -276.216092)
			(xy 127.99571 -276.189443) (xy 127.954039 -276.156212) (xy 127.917787 -276.117141) (xy 127.887763 -276.073104)
			(xy 127.864637 -276.025083) (xy 127.848927 -275.974153) (xy 127.840984 -275.921449) (xy 127.612404 -275.921449)
			(xy 127.604461 -275.974153) (xy 127.588751 -276.025083) (xy 127.565625 -276.073104) (xy 127.535601 -276.117141)
			(xy 127.499349 -276.156212) (xy 127.457678 -276.189443) (xy 127.41152 -276.216092) (xy 127.361906 -276.235564)
			(xy 127.309944 -276.247424) (xy 127.256794 -276.251408) (xy 127.203644 -276.247424) (xy 127.151682 -276.235564)
			(xy 127.102068 -276.216092) (xy 127.05591 -276.189443) (xy 127.014239 -276.156212) (xy 126.977987 -276.117141)
			(xy 126.947963 -276.073104) (xy 126.924837 -276.025083) (xy 126.909127 -275.974153) (xy 126.901184 -275.921449)
			(xy 126.672604 -275.921449) (xy 126.664661 -275.974153) (xy 126.648951 -276.025083) (xy 126.625825 -276.073104)
			(xy 126.595801 -276.117141) (xy 126.559549 -276.156212) (xy 126.517878 -276.189443) (xy 126.47172 -276.216092)
			(xy 126.422106 -276.235564) (xy 126.370144 -276.247424) (xy 126.316994 -276.251408) (xy 126.263844 -276.247424)
			(xy 126.211882 -276.235564) (xy 126.162268 -276.216092) (xy 126.11611 -276.189443) (xy 126.074439 -276.156212)
			(xy 126.038187 -276.117141) (xy 126.008163 -276.073104) (xy 125.985037 -276.025083) (xy 125.969327 -275.974153)
			(xy 125.961384 -275.921449) (xy 125.732804 -275.921449) (xy 125.724861 -275.974153) (xy 125.709151 -276.025083)
			(xy 125.686025 -276.073104) (xy 125.656001 -276.117141) (xy 125.619749 -276.156212) (xy 125.578078 -276.189443)
			(xy 125.53192 -276.216092) (xy 125.482306 -276.235564) (xy 125.430344 -276.247424) (xy 125.377194 -276.251408)
			(xy 125.324044 -276.247424) (xy 125.272082 -276.235564) (xy 125.222468 -276.216092) (xy 125.17631 -276.189443)
			(xy 125.134639 -276.156212) (xy 125.098387 -276.117141) (xy 125.068363 -276.073104) (xy 125.045237 -276.025083)
			(xy 125.029527 -275.974153) (xy 125.021584 -275.921449) (xy 124.793004 -275.921449) (xy 124.785061 -275.974153)
			(xy 124.769351 -276.025083) (xy 124.746225 -276.073104) (xy 124.716201 -276.117141) (xy 124.679949 -276.156212)
			(xy 124.638278 -276.189443) (xy 124.59212 -276.216092) (xy 124.542506 -276.235564) (xy 124.490544 -276.247424)
			(xy 124.437394 -276.251408) (xy 124.384244 -276.247424) (xy 124.332282 -276.235564) (xy 124.282668 -276.216092)
			(xy 124.23651 -276.189443) (xy 124.194839 -276.156212) (xy 124.158587 -276.117141) (xy 124.128563 -276.073104)
			(xy 124.105437 -276.025083) (xy 124.089727 -275.974153) (xy 124.081784 -275.921449) (xy 123.853204 -275.921449)
			(xy 123.845261 -275.974153) (xy 123.829551 -276.025083) (xy 123.806425 -276.073104) (xy 123.776401 -276.117141)
			(xy 123.740149 -276.156212) (xy 123.698478 -276.189443) (xy 123.65232 -276.216092) (xy 123.602706 -276.235564)
			(xy 123.550744 -276.247424) (xy 123.497594 -276.251408) (xy 123.444444 -276.247424) (xy 123.392482 -276.235564)
			(xy 123.342868 -276.216092) (xy 123.29671 -276.189443) (xy 123.255039 -276.156212) (xy 123.218787 -276.117141)
			(xy 123.188763 -276.073104) (xy 123.165637 -276.025083) (xy 123.149927 -275.974153) (xy 123.141984 -275.921449)
			(xy 122.913658 -275.921449) (xy 122.905715 -275.974153) (xy 122.890005 -276.025083) (xy 122.866879 -276.073104)
			(xy 122.836855 -276.117141) (xy 122.800603 -276.156212) (xy 122.758932 -276.189443) (xy 122.712774 -276.216092)
			(xy 122.66316 -276.235564) (xy 122.611198 -276.247424) (xy 122.558048 -276.251408) (xy 122.504898 -276.247424)
			(xy 122.452936 -276.235564) (xy 122.403322 -276.216092) (xy 122.357164 -276.189443) (xy 122.315493 -276.156212)
			(xy 122.279241 -276.117141) (xy 122.249217 -276.073104) (xy 122.226091 -276.025083) (xy 122.210381 -275.974153)
			(xy 122.202438 -275.921449) (xy 121.97382 -275.921449) (xy 121.965915 -275.973899) (xy 121.950205 -276.024829)
			(xy 121.927079 -276.07285) (xy 121.897055 -276.116887) (xy 121.860803 -276.155958) (xy 121.819132 -276.189189)
			(xy 121.772974 -276.215838) (xy 121.72336 -276.23531) (xy 121.671398 -276.24717) (xy 121.618248 -276.251154)
			(xy 121.565098 -276.24717) (xy 121.513136 -276.23531) (xy 121.463522 -276.215838) (xy 121.417364 -276.189189)
			(xy 121.375693 -276.155958) (xy 121.339441 -276.116887) (xy 121.309417 -276.07285) (xy 121.286291 -276.024829)
			(xy 121.270581 -275.973899) (xy 121.262638 -275.921195) (xy 121.034058 -275.921195) (xy 121.026115 -275.973899)
			(xy 121.010405 -276.024829) (xy 120.987279 -276.07285) (xy 120.957255 -276.116887) (xy 120.921003 -276.155958)
			(xy 120.879332 -276.189189) (xy 120.833174 -276.215838) (xy 120.78356 -276.23531) (xy 120.731598 -276.24717)
			(xy 120.678448 -276.251154) (xy 120.625298 -276.24717) (xy 120.573336 -276.23531) (xy 120.523722 -276.215838)
			(xy 120.477564 -276.189189) (xy 120.435893 -276.155958) (xy 120.399641 -276.116887) (xy 120.369617 -276.07285)
			(xy 120.346491 -276.024829) (xy 120.330781 -275.973899) (xy 120.322838 -275.921195) (xy 120.094258 -275.921195)
			(xy 120.086315 -275.973899) (xy 120.070605 -276.024829) (xy 120.047479 -276.07285) (xy 120.017455 -276.116887)
			(xy 119.981203 -276.155958) (xy 119.939532 -276.189189) (xy 119.893374 -276.215838) (xy 119.84376 -276.23531)
			(xy 119.791798 -276.24717) (xy 119.738648 -276.251154) (xy 119.685498 -276.24717) (xy 119.633536 -276.23531)
			(xy 119.583922 -276.215838) (xy 119.537764 -276.189189) (xy 119.496093 -276.155958) (xy 119.459841 -276.116887)
			(xy 119.429817 -276.07285) (xy 119.406691 -276.024829) (xy 119.390981 -275.973899) (xy 119.383038 -275.921195)
			(xy 119.154463 -275.921195) (xy 119.154458 -275.921449) (xy 119.146515 -275.974153) (xy 119.130805 -276.025083)
			(xy 119.107679 -276.073104) (xy 119.077655 -276.117141) (xy 119.041403 -276.156212) (xy 118.999732 -276.189443)
			(xy 118.953574 -276.216092) (xy 118.90396 -276.235564) (xy 118.851998 -276.247424) (xy 118.798848 -276.251408)
			(xy 118.745698 -276.247424) (xy 118.693736 -276.235564) (xy 118.644122 -276.216092) (xy 118.597964 -276.189443)
			(xy 118.556293 -276.156212) (xy 118.520041 -276.117141) (xy 118.490017 -276.073104) (xy 118.466891 -276.025083)
			(xy 118.451181 -275.974153) (xy 118.443238 -275.921449) (xy 118.214404 -275.921449) (xy 118.206461 -275.974153)
			(xy 118.190751 -276.025083) (xy 118.167625 -276.073104) (xy 118.137601 -276.117141) (xy 118.101349 -276.156212)
			(xy 118.059678 -276.189443) (xy 118.01352 -276.216092) (xy 117.963906 -276.235564) (xy 117.911944 -276.247424)
			(xy 117.858794 -276.251408) (xy 117.805644 -276.247424) (xy 117.753682 -276.235564) (xy 117.704068 -276.216092)
			(xy 117.65791 -276.189443) (xy 117.616239 -276.156212) (xy 117.579987 -276.117141) (xy 117.549963 -276.073104)
			(xy 117.526837 -276.025083) (xy 117.511127 -275.974153) (xy 117.503184 -275.921449) (xy 117.274604 -275.921449)
			(xy 117.266661 -275.974153) (xy 117.250951 -276.025083) (xy 117.227825 -276.073104) (xy 117.197801 -276.117141)
			(xy 117.161549 -276.156212) (xy 117.119878 -276.189443) (xy 117.07372 -276.216092) (xy 117.024106 -276.235564)
			(xy 116.972144 -276.247424) (xy 116.918994 -276.251408) (xy 116.865844 -276.247424) (xy 116.813882 -276.235564)
			(xy 116.764268 -276.216092) (xy 116.71811 -276.189443) (xy 116.676439 -276.156212) (xy 116.640187 -276.117141)
			(xy 116.610163 -276.073104) (xy 116.587037 -276.025083) (xy 116.571327 -275.974153) (xy 116.563384 -275.921449)
			(xy 116.334804 -275.921449) (xy 116.326861 -275.974153) (xy 116.311151 -276.025083) (xy 116.288025 -276.073104)
			(xy 116.258001 -276.117141) (xy 116.221749 -276.156212) (xy 116.180078 -276.189443) (xy 116.13392 -276.216092)
			(xy 116.084306 -276.235564) (xy 116.032344 -276.247424) (xy 115.979194 -276.251408) (xy 115.926044 -276.247424)
			(xy 115.874082 -276.235564) (xy 115.824468 -276.216092) (xy 115.77831 -276.189443) (xy 115.736639 -276.156212)
			(xy 115.700387 -276.117141) (xy 115.670363 -276.073104) (xy 115.647237 -276.025083) (xy 115.631527 -275.974153)
			(xy 115.623584 -275.921449) (xy 114.497358 -275.921449) (xy 114.497358 -276.251924) (xy 114.497872 -276.267264)
			(xy 114.506957 -276.296567) (xy 114.524331 -276.321852) (xy 114.548429 -276.340839) (xy 114.577076 -276.351817)
			(xy 114.592354 -276.35327) (xy 114.619117 -276.355465) (xy 114.671585 -276.366886) (xy 114.721744 -276.386055)
			(xy 114.768457 -276.412536) (xy 114.810665 -276.44573) (xy 114.847412 -276.484884) (xy 114.877864 -276.529111)
			(xy 114.901332 -276.577408) (xy 114.917283 -276.628681) (xy 114.925357 -276.681768) (xy 114.925856 -276.708616)
			(xy 114.925445 -276.733984) (xy 114.925299 -276.735011) (xy 115.153684 -276.735011) (xy 115.153684 -276.681713)
			(xy 115.161627 -276.629009) (xy 115.177337 -276.578079) (xy 115.200463 -276.530058) (xy 115.230487 -276.486021)
			(xy 115.266739 -276.44695) (xy 115.30841 -276.413719) (xy 115.354568 -276.38707) (xy 115.404182 -276.367598)
			(xy 115.456144 -276.355738) (xy 115.509294 -276.351755) (xy 115.562444 -276.355738) (xy 115.614406 -276.367598)
			(xy 115.66402 -276.38707) (xy 115.710178 -276.413719) (xy 115.751849 -276.44695) (xy 115.788101 -276.486021)
			(xy 115.818125 -276.530058) (xy 115.841251 -276.578079) (xy 115.856961 -276.629009) (xy 115.864904 -276.681713)
			(xy 115.865402 -276.708362) (xy 115.864904 -276.735011) (xy 116.093484 -276.735011) (xy 116.093484 -276.681713)
			(xy 116.101427 -276.629009) (xy 116.117137 -276.578079) (xy 116.140263 -276.530058) (xy 116.170287 -276.486021)
			(xy 116.206539 -276.44695) (xy 116.24821 -276.413719) (xy 116.294368 -276.38707) (xy 116.343982 -276.367598)
			(xy 116.395944 -276.355738) (xy 116.449094 -276.351755) (xy 116.502244 -276.355738) (xy 116.554206 -276.367598)
			(xy 116.60382 -276.38707) (xy 116.649978 -276.413719) (xy 116.691649 -276.44695) (xy 116.727901 -276.486021)
			(xy 116.757925 -276.530058) (xy 116.781051 -276.578079) (xy 116.796761 -276.629009) (xy 116.804704 -276.681713)
			(xy 116.805202 -276.708362) (xy 116.804704 -276.735011) (xy 117.033284 -276.735011) (xy 117.033284 -276.681713)
			(xy 117.041227 -276.629009) (xy 117.056937 -276.578079) (xy 117.080063 -276.530058) (xy 117.110087 -276.486021)
			(xy 117.146339 -276.44695) (xy 117.18801 -276.413719) (xy 117.234168 -276.38707) (xy 117.283782 -276.367598)
			(xy 117.335744 -276.355738) (xy 117.388894 -276.351755) (xy 117.442044 -276.355738) (xy 117.494006 -276.367598)
			(xy 117.54362 -276.38707) (xy 117.589778 -276.413719) (xy 117.631449 -276.44695) (xy 117.667701 -276.486021)
			(xy 117.697725 -276.530058) (xy 117.720851 -276.578079) (xy 117.736561 -276.629009) (xy 117.744504 -276.681713)
			(xy 117.745002 -276.708362) (xy 117.744504 -276.735011) (xy 117.973084 -276.735011) (xy 117.973084 -276.681713)
			(xy 117.981027 -276.629009) (xy 117.996737 -276.578079) (xy 118.019863 -276.530058) (xy 118.049887 -276.486021)
			(xy 118.086139 -276.44695) (xy 118.12781 -276.413719) (xy 118.173968 -276.38707) (xy 118.223582 -276.367598)
			(xy 118.275544 -276.355738) (xy 118.328694 -276.351755) (xy 118.381844 -276.355738) (xy 118.433806 -276.367598)
			(xy 118.48342 -276.38707) (xy 118.529578 -276.413719) (xy 118.571249 -276.44695) (xy 118.607501 -276.486021)
			(xy 118.637525 -276.530058) (xy 118.660651 -276.578079) (xy 118.676361 -276.629009) (xy 118.684304 -276.681713)
			(xy 118.684802 -276.708362) (xy 118.684304 -276.735011) (xy 118.684266 -276.735265) (xy 118.912884 -276.735265)
			(xy 118.912884 -276.681967) (xy 118.920827 -276.629263) (xy 118.936537 -276.578333) (xy 118.959663 -276.530312)
			(xy 118.989687 -276.486275) (xy 119.025939 -276.447204) (xy 119.06761 -276.413973) (xy 119.113768 -276.387324)
			(xy 119.163382 -276.367852) (xy 119.215344 -276.355992) (xy 119.268494 -276.352009) (xy 119.321644 -276.355992)
			(xy 119.373606 -276.367852) (xy 119.42322 -276.387324) (xy 119.469378 -276.413973) (xy 119.511049 -276.447204)
			(xy 119.547301 -276.486275) (xy 119.577325 -276.530312) (xy 119.600451 -276.578333) (xy 119.616161 -276.629263)
			(xy 119.624104 -276.681967) (xy 119.624602 -276.708616) (xy 119.624109 -276.735011) (xy 119.852684 -276.735011)
			(xy 119.852684 -276.681713) (xy 119.860627 -276.629009) (xy 119.876337 -276.578079) (xy 119.899463 -276.530058)
			(xy 119.929487 -276.486021) (xy 119.965739 -276.44695) (xy 120.00741 -276.413719) (xy 120.053568 -276.38707)
			(xy 120.103182 -276.367598) (xy 120.155144 -276.355738) (xy 120.208294 -276.351755) (xy 120.261444 -276.355738)
			(xy 120.313406 -276.367598) (xy 120.36302 -276.38707) (xy 120.409178 -276.413719) (xy 120.450849 -276.44695)
			(xy 120.487101 -276.486021) (xy 120.517125 -276.530058) (xy 120.540251 -276.578079) (xy 120.555961 -276.629009)
			(xy 120.563904 -276.681713) (xy 120.564402 -276.708362) (xy 120.563904 -276.735011) (xy 120.563866 -276.735265)
			(xy 120.792738 -276.735265) (xy 120.792738 -276.681967) (xy 120.800681 -276.629263) (xy 120.816391 -276.578333)
			(xy 120.839517 -276.530312) (xy 120.869541 -276.486275) (xy 120.905793 -276.447204) (xy 120.947464 -276.413973)
			(xy 120.993622 -276.387324) (xy 121.043236 -276.367852) (xy 121.095198 -276.355992) (xy 121.148348 -276.352009)
			(xy 121.201498 -276.355992) (xy 121.25346 -276.367852) (xy 121.303074 -276.387324) (xy 121.349232 -276.413973)
			(xy 121.390903 -276.447204) (xy 121.427155 -276.486275) (xy 121.457179 -276.530312) (xy 121.480305 -276.578333)
			(xy 121.496015 -276.629263) (xy 121.503958 -276.681967) (xy 121.504456 -276.708616) (xy 121.503958 -276.735265)
			(xy 122.672338 -276.735265) (xy 122.672338 -276.681967) (xy 122.680281 -276.629263) (xy 122.695991 -276.578333)
			(xy 122.719117 -276.530312) (xy 122.749141 -276.486275) (xy 122.785393 -276.447204) (xy 122.827064 -276.413973)
			(xy 122.873222 -276.387324) (xy 122.922836 -276.367852) (xy 122.974798 -276.355992) (xy 123.027948 -276.352009)
			(xy 123.081098 -276.355992) (xy 123.13306 -276.367852) (xy 123.182674 -276.387324) (xy 123.228832 -276.413973)
			(xy 123.270503 -276.447204) (xy 123.306755 -276.486275) (xy 123.336779 -276.530312) (xy 123.359905 -276.578333)
			(xy 123.375615 -276.629263) (xy 123.383558 -276.681967) (xy 123.384056 -276.708616) (xy 123.383558 -276.735265)
			(xy 123.612138 -276.735265) (xy 123.612138 -276.681967) (xy 123.620081 -276.629263) (xy 123.635791 -276.578333)
			(xy 123.658917 -276.530312) (xy 123.688941 -276.486275) (xy 123.725193 -276.447204) (xy 123.766864 -276.413973)
			(xy 123.813022 -276.387324) (xy 123.862636 -276.367852) (xy 123.914598 -276.355992) (xy 123.967748 -276.352009)
			(xy 124.020898 -276.355992) (xy 124.07286 -276.367852) (xy 124.122474 -276.387324) (xy 124.168632 -276.413973)
			(xy 124.210303 -276.447204) (xy 124.246555 -276.486275) (xy 124.276579 -276.530312) (xy 124.299705 -276.578333)
			(xy 124.315415 -276.629263) (xy 124.323358 -276.681967) (xy 124.323856 -276.708616) (xy 124.323358 -276.735265)
			(xy 124.551938 -276.735265) (xy 124.551938 -276.681967) (xy 124.559881 -276.629263) (xy 124.575591 -276.578333)
			(xy 124.598717 -276.530312) (xy 124.628741 -276.486275) (xy 124.664993 -276.447204) (xy 124.706664 -276.413973)
			(xy 124.752822 -276.387324) (xy 124.802436 -276.367852) (xy 124.854398 -276.355992) (xy 124.907548 -276.352009)
			(xy 124.960698 -276.355992) (xy 125.01266 -276.367852) (xy 125.062274 -276.387324) (xy 125.108432 -276.413973)
			(xy 125.150103 -276.447204) (xy 125.186355 -276.486275) (xy 125.216379 -276.530312) (xy 125.239505 -276.578333)
			(xy 125.255215 -276.629263) (xy 125.263158 -276.681967) (xy 125.263656 -276.708616) (xy 125.263158 -276.735265)
			(xy 125.491484 -276.735265) (xy 125.491484 -276.681967) (xy 125.499427 -276.629263) (xy 125.515137 -276.578333)
			(xy 125.538263 -276.530312) (xy 125.568287 -276.486275) (xy 125.604539 -276.447204) (xy 125.64621 -276.413973)
			(xy 125.692368 -276.387324) (xy 125.741982 -276.367852) (xy 125.793944 -276.355992) (xy 125.847094 -276.352009)
			(xy 125.900244 -276.355992) (xy 125.952206 -276.367852) (xy 126.00182 -276.387324) (xy 126.047978 -276.413973)
			(xy 126.089649 -276.447204) (xy 126.125901 -276.486275) (xy 126.155925 -276.530312) (xy 126.179051 -276.578333)
			(xy 126.194761 -276.629263) (xy 126.202704 -276.681967) (xy 126.203202 -276.708616) (xy 126.202704 -276.735265)
			(xy 126.431538 -276.735265) (xy 126.431538 -276.681967) (xy 126.439481 -276.629263) (xy 126.455191 -276.578333)
			(xy 126.478317 -276.530312) (xy 126.508341 -276.486275) (xy 126.544593 -276.447204) (xy 126.586264 -276.413973)
			(xy 126.632422 -276.387324) (xy 126.682036 -276.367852) (xy 126.733998 -276.355992) (xy 126.787148 -276.352009)
			(xy 126.840298 -276.355992) (xy 126.89226 -276.367852) (xy 126.941874 -276.387324) (xy 126.988032 -276.413973)
			(xy 127.029703 -276.447204) (xy 127.065955 -276.486275) (xy 127.095979 -276.530312) (xy 127.119105 -276.578333)
			(xy 127.134815 -276.629263) (xy 127.142758 -276.681967) (xy 127.143256 -276.708616) (xy 127.142758 -276.735265)
			(xy 127.371338 -276.735265) (xy 127.371338 -276.681967) (xy 127.379281 -276.629263) (xy 127.394991 -276.578333)
			(xy 127.418117 -276.530312) (xy 127.448141 -276.486275) (xy 127.484393 -276.447204) (xy 127.526064 -276.413973)
			(xy 127.572222 -276.387324) (xy 127.621836 -276.367852) (xy 127.673798 -276.355992) (xy 127.726948 -276.352009)
			(xy 127.780098 -276.355992) (xy 127.83206 -276.367852) (xy 127.881674 -276.387324) (xy 127.927832 -276.413973)
			(xy 127.969503 -276.447204) (xy 128.005755 -276.486275) (xy 128.035779 -276.530312) (xy 128.058905 -276.578333)
			(xy 128.074615 -276.629263) (xy 128.082558 -276.681967) (xy 128.083056 -276.708616) (xy 128.082558 -276.735265)
			(xy 128.311138 -276.735265) (xy 128.311138 -276.681967) (xy 128.319081 -276.629263) (xy 128.334791 -276.578333)
			(xy 128.357917 -276.530312) (xy 128.387941 -276.486275) (xy 128.424193 -276.447204) (xy 128.465864 -276.413973)
			(xy 128.512022 -276.387324) (xy 128.561636 -276.367852) (xy 128.613598 -276.355992) (xy 128.666748 -276.352009)
			(xy 128.719898 -276.355992) (xy 128.77186 -276.367852) (xy 128.821474 -276.387324) (xy 128.867632 -276.413973)
			(xy 128.909303 -276.447204) (xy 128.945555 -276.486275) (xy 128.975579 -276.530312) (xy 128.998705 -276.578333)
			(xy 129.014415 -276.629263) (xy 129.022358 -276.681967) (xy 129.022856 -276.708616) (xy 129.022358 -276.735265)
			(xy 129.250938 -276.735265) (xy 129.250938 -276.681967) (xy 129.258881 -276.629263) (xy 129.274591 -276.578333)
			(xy 129.297717 -276.530312) (xy 129.327741 -276.486275) (xy 129.363993 -276.447204) (xy 129.405664 -276.413973)
			(xy 129.451822 -276.387324) (xy 129.501436 -276.367852) (xy 129.553398 -276.355992) (xy 129.606548 -276.352009)
			(xy 129.659698 -276.355992) (xy 129.71166 -276.367852) (xy 129.761274 -276.387324) (xy 129.807432 -276.413973)
			(xy 129.849103 -276.447204) (xy 129.885355 -276.486275) (xy 129.915379 -276.530312) (xy 129.938505 -276.578333)
			(xy 129.954215 -276.629263) (xy 129.962158 -276.681967) (xy 129.962656 -276.708616) (xy 129.962158 -276.735265)
			(xy 130.190738 -276.735265) (xy 130.190738 -276.681967) (xy 130.198681 -276.629263) (xy 130.214391 -276.578333)
			(xy 130.237517 -276.530312) (xy 130.267541 -276.486275) (xy 130.303793 -276.447204) (xy 130.345464 -276.413973)
			(xy 130.391622 -276.387324) (xy 130.441236 -276.367852) (xy 130.493198 -276.355992) (xy 130.546348 -276.352009)
			(xy 130.599498 -276.355992) (xy 130.65146 -276.367852) (xy 130.701074 -276.387324) (xy 130.747232 -276.413973)
			(xy 130.788903 -276.447204) (xy 130.825155 -276.486275) (xy 130.855179 -276.530312) (xy 130.878305 -276.578333)
			(xy 130.894015 -276.629263) (xy 130.901958 -276.681967) (xy 130.902456 -276.708616) (xy 130.901958 -276.735265)
			(xy 131.130538 -276.735265) (xy 131.130538 -276.681967) (xy 131.138481 -276.629263) (xy 131.154191 -276.578333)
			(xy 131.177317 -276.530312) (xy 131.207341 -276.486275) (xy 131.243593 -276.447204) (xy 131.285264 -276.413973)
			(xy 131.331422 -276.387324) (xy 131.381036 -276.367852) (xy 131.432998 -276.355992) (xy 131.486148 -276.352009)
			(xy 131.539298 -276.355992) (xy 131.59126 -276.367852) (xy 131.640874 -276.387324) (xy 131.687032 -276.413973)
			(xy 131.728703 -276.447204) (xy 131.764955 -276.486275) (xy 131.794979 -276.530312) (xy 131.818105 -276.578333)
			(xy 131.833815 -276.629263) (xy 131.841758 -276.681967) (xy 131.842256 -276.708616) (xy 131.841758 -276.735265)
			(xy 131.833815 -276.787969) (xy 131.818105 -276.838899) (xy 131.794979 -276.88692) (xy 131.764955 -276.930957)
			(xy 131.728703 -276.970028) (xy 131.687032 -277.003259) (xy 131.640874 -277.029908) (xy 131.59126 -277.04938)
			(xy 131.539298 -277.06124) (xy 131.486148 -277.065224) (xy 131.432998 -277.06124) (xy 131.381036 -277.04938)
			(xy 131.331422 -277.029908) (xy 131.285264 -277.003259) (xy 131.243593 -276.970028) (xy 131.207341 -276.930957)
			(xy 131.177317 -276.88692) (xy 131.154191 -276.838899) (xy 131.138481 -276.787969) (xy 131.130538 -276.735265)
			(xy 130.901958 -276.735265) (xy 130.894015 -276.787969) (xy 130.878305 -276.838899) (xy 130.855179 -276.88692)
			(xy 130.825155 -276.930957) (xy 130.788903 -276.970028) (xy 130.747232 -277.003259) (xy 130.701074 -277.029908)
			(xy 130.65146 -277.04938) (xy 130.599498 -277.06124) (xy 130.546348 -277.065224) (xy 130.493198 -277.06124)
			(xy 130.441236 -277.04938) (xy 130.391622 -277.029908) (xy 130.345464 -277.003259) (xy 130.303793 -276.970028)
			(xy 130.267541 -276.930957) (xy 130.237517 -276.88692) (xy 130.214391 -276.838899) (xy 130.198681 -276.787969)
			(xy 130.190738 -276.735265) (xy 129.962158 -276.735265) (xy 129.954215 -276.787969) (xy 129.938505 -276.838899)
			(xy 129.915379 -276.88692) (xy 129.885355 -276.930957) (xy 129.849103 -276.970028) (xy 129.807432 -277.003259)
			(xy 129.761274 -277.029908) (xy 129.71166 -277.04938) (xy 129.659698 -277.06124) (xy 129.606548 -277.065224)
			(xy 129.553398 -277.06124) (xy 129.501436 -277.04938) (xy 129.451822 -277.029908) (xy 129.405664 -277.003259)
			(xy 129.363993 -276.970028) (xy 129.327741 -276.930957) (xy 129.297717 -276.88692) (xy 129.274591 -276.838899)
			(xy 129.258881 -276.787969) (xy 129.250938 -276.735265) (xy 129.022358 -276.735265) (xy 129.014415 -276.787969)
			(xy 128.998705 -276.838899) (xy 128.975579 -276.88692) (xy 128.945555 -276.930957) (xy 128.909303 -276.970028)
			(xy 128.867632 -277.003259) (xy 128.821474 -277.029908) (xy 128.77186 -277.04938) (xy 128.719898 -277.06124)
			(xy 128.666748 -277.065224) (xy 128.613598 -277.06124) (xy 128.561636 -277.04938) (xy 128.512022 -277.029908)
			(xy 128.465864 -277.003259) (xy 128.424193 -276.970028) (xy 128.387941 -276.930957) (xy 128.357917 -276.88692)
			(xy 128.334791 -276.838899) (xy 128.319081 -276.787969) (xy 128.311138 -276.735265) (xy 128.082558 -276.735265)
			(xy 128.074615 -276.787969) (xy 128.058905 -276.838899) (xy 128.035779 -276.88692) (xy 128.005755 -276.930957)
			(xy 127.969503 -276.970028) (xy 127.927832 -277.003259) (xy 127.881674 -277.029908) (xy 127.83206 -277.04938)
			(xy 127.780098 -277.06124) (xy 127.726948 -277.065224) (xy 127.673798 -277.06124) (xy 127.621836 -277.04938)
			(xy 127.572222 -277.029908) (xy 127.526064 -277.003259) (xy 127.484393 -276.970028) (xy 127.448141 -276.930957)
			(xy 127.418117 -276.88692) (xy 127.394991 -276.838899) (xy 127.379281 -276.787969) (xy 127.371338 -276.735265)
			(xy 127.142758 -276.735265) (xy 127.134815 -276.787969) (xy 127.119105 -276.838899) (xy 127.095979 -276.88692)
			(xy 127.065955 -276.930957) (xy 127.029703 -276.970028) (xy 126.988032 -277.003259) (xy 126.941874 -277.029908)
			(xy 126.89226 -277.04938) (xy 126.840298 -277.06124) (xy 126.787148 -277.065224) (xy 126.733998 -277.06124)
			(xy 126.682036 -277.04938) (xy 126.632422 -277.029908) (xy 126.586264 -277.003259) (xy 126.544593 -276.970028)
			(xy 126.508341 -276.930957) (xy 126.478317 -276.88692) (xy 126.455191 -276.838899) (xy 126.439481 -276.787969)
			(xy 126.431538 -276.735265) (xy 126.202704 -276.735265) (xy 126.194761 -276.787969) (xy 126.179051 -276.838899)
			(xy 126.155925 -276.88692) (xy 126.125901 -276.930957) (xy 126.089649 -276.970028) (xy 126.047978 -277.003259)
			(xy 126.00182 -277.029908) (xy 125.952206 -277.04938) (xy 125.900244 -277.06124) (xy 125.847094 -277.065224)
			(xy 125.793944 -277.06124) (xy 125.741982 -277.04938) (xy 125.692368 -277.029908) (xy 125.64621 -277.003259)
			(xy 125.604539 -276.970028) (xy 125.568287 -276.930957) (xy 125.538263 -276.88692) (xy 125.515137 -276.838899)
			(xy 125.499427 -276.787969) (xy 125.491484 -276.735265) (xy 125.263158 -276.735265) (xy 125.255215 -276.787969)
			(xy 125.239505 -276.838899) (xy 125.216379 -276.88692) (xy 125.186355 -276.930957) (xy 125.150103 -276.970028)
			(xy 125.108432 -277.003259) (xy 125.062274 -277.029908) (xy 125.01266 -277.04938) (xy 124.960698 -277.06124)
			(xy 124.907548 -277.065224) (xy 124.854398 -277.06124) (xy 124.802436 -277.04938) (xy 124.752822 -277.029908)
			(xy 124.706664 -277.003259) (xy 124.664993 -276.970028) (xy 124.628741 -276.930957) (xy 124.598717 -276.88692)
			(xy 124.575591 -276.838899) (xy 124.559881 -276.787969) (xy 124.551938 -276.735265) (xy 124.323358 -276.735265)
			(xy 124.315415 -276.787969) (xy 124.299705 -276.838899) (xy 124.276579 -276.88692) (xy 124.246555 -276.930957)
			(xy 124.210303 -276.970028) (xy 124.168632 -277.003259) (xy 124.122474 -277.029908) (xy 124.07286 -277.04938)
			(xy 124.020898 -277.06124) (xy 123.967748 -277.065224) (xy 123.914598 -277.06124) (xy 123.862636 -277.04938)
			(xy 123.813022 -277.029908) (xy 123.766864 -277.003259) (xy 123.725193 -276.970028) (xy 123.688941 -276.930957)
			(xy 123.658917 -276.88692) (xy 123.635791 -276.838899) (xy 123.620081 -276.787969) (xy 123.612138 -276.735265)
			(xy 123.383558 -276.735265) (xy 123.375615 -276.787969) (xy 123.359905 -276.838899) (xy 123.336779 -276.88692)
			(xy 123.306755 -276.930957) (xy 123.270503 -276.970028) (xy 123.228832 -277.003259) (xy 123.182674 -277.029908)
			(xy 123.13306 -277.04938) (xy 123.081098 -277.06124) (xy 123.027948 -277.065224) (xy 122.974798 -277.06124)
			(xy 122.922836 -277.04938) (xy 122.873222 -277.029908) (xy 122.827064 -277.003259) (xy 122.785393 -276.970028)
			(xy 122.749141 -276.930957) (xy 122.719117 -276.88692) (xy 122.695991 -276.838899) (xy 122.680281 -276.787969)
			(xy 122.672338 -276.735265) (xy 121.503958 -276.735265) (xy 121.496015 -276.787969) (xy 121.480305 -276.838899)
			(xy 121.457179 -276.88692) (xy 121.427155 -276.930957) (xy 121.390903 -276.970028) (xy 121.349232 -277.003259)
			(xy 121.303074 -277.029908) (xy 121.25346 -277.04938) (xy 121.201498 -277.06124) (xy 121.148348 -277.065224)
			(xy 121.095198 -277.06124) (xy 121.043236 -277.04938) (xy 120.993622 -277.029908) (xy 120.947464 -277.003259)
			(xy 120.905793 -276.970028) (xy 120.869541 -276.930957) (xy 120.839517 -276.88692) (xy 120.816391 -276.838899)
			(xy 120.800681 -276.787969) (xy 120.792738 -276.735265) (xy 120.563866 -276.735265) (xy 120.555961 -276.787715)
			(xy 120.540251 -276.838645) (xy 120.517125 -276.886666) (xy 120.487101 -276.930703) (xy 120.450849 -276.969774)
			(xy 120.409178 -277.003005) (xy 120.36302 -277.029654) (xy 120.313406 -277.049126) (xy 120.261444 -277.060986)
			(xy 120.208294 -277.06497) (xy 120.155144 -277.060986) (xy 120.103182 -277.049126) (xy 120.053568 -277.029654)
			(xy 120.00741 -277.003005) (xy 119.965739 -276.969774) (xy 119.929487 -276.930703) (xy 119.899463 -276.886666)
			(xy 119.876337 -276.838645) (xy 119.860627 -276.787715) (xy 119.852684 -276.735011) (xy 119.624109 -276.735011)
			(xy 119.624104 -276.735265) (xy 119.616161 -276.787969) (xy 119.600451 -276.838899) (xy 119.577325 -276.88692)
			(xy 119.547301 -276.930957) (xy 119.511049 -276.970028) (xy 119.469378 -277.003259) (xy 119.42322 -277.029908)
			(xy 119.373606 -277.04938) (xy 119.321644 -277.06124) (xy 119.268494 -277.065224) (xy 119.215344 -277.06124)
			(xy 119.163382 -277.04938) (xy 119.113768 -277.029908) (xy 119.06761 -277.003259) (xy 119.025939 -276.970028)
			(xy 118.989687 -276.930957) (xy 118.959663 -276.88692) (xy 118.936537 -276.838899) (xy 118.920827 -276.787969)
			(xy 118.912884 -276.735265) (xy 118.684266 -276.735265) (xy 118.676361 -276.787715) (xy 118.660651 -276.838645)
			(xy 118.637525 -276.886666) (xy 118.607501 -276.930703) (xy 118.571249 -276.969774) (xy 118.529578 -277.003005)
			(xy 118.48342 -277.029654) (xy 118.433806 -277.049126) (xy 118.381844 -277.060986) (xy 118.328694 -277.06497)
			(xy 118.275544 -277.060986) (xy 118.223582 -277.049126) (xy 118.173968 -277.029654) (xy 118.12781 -277.003005)
			(xy 118.086139 -276.969774) (xy 118.049887 -276.930703) (xy 118.019863 -276.886666) (xy 117.996737 -276.838645)
			(xy 117.981027 -276.787715) (xy 117.973084 -276.735011) (xy 117.744504 -276.735011) (xy 117.736561 -276.787715)
			(xy 117.720851 -276.838645) (xy 117.697725 -276.886666) (xy 117.667701 -276.930703) (xy 117.631449 -276.969774)
			(xy 117.589778 -277.003005) (xy 117.54362 -277.029654) (xy 117.494006 -277.049126) (xy 117.442044 -277.060986)
			(xy 117.388894 -277.06497) (xy 117.335744 -277.060986) (xy 117.283782 -277.049126) (xy 117.234168 -277.029654)
			(xy 117.18801 -277.003005) (xy 117.146339 -276.969774) (xy 117.110087 -276.930703) (xy 117.080063 -276.886666)
			(xy 117.056937 -276.838645) (xy 117.041227 -276.787715) (xy 117.033284 -276.735011) (xy 116.804704 -276.735011)
			(xy 116.796761 -276.787715) (xy 116.781051 -276.838645) (xy 116.757925 -276.886666) (xy 116.727901 -276.930703)
			(xy 116.691649 -276.969774) (xy 116.649978 -277.003005) (xy 116.60382 -277.029654) (xy 116.554206 -277.049126)
			(xy 116.502244 -277.060986) (xy 116.449094 -277.06497) (xy 116.395944 -277.060986) (xy 116.343982 -277.049126)
			(xy 116.294368 -277.029654) (xy 116.24821 -277.003005) (xy 116.206539 -276.969774) (xy 116.170287 -276.930703)
			(xy 116.140263 -276.886666) (xy 116.117137 -276.838645) (xy 116.101427 -276.787715) (xy 116.093484 -276.735011)
			(xy 115.864904 -276.735011) (xy 115.856961 -276.787715) (xy 115.841251 -276.838645) (xy 115.818125 -276.886666)
			(xy 115.788101 -276.930703) (xy 115.751849 -276.969774) (xy 115.710178 -277.003005) (xy 115.66402 -277.029654)
			(xy 115.614406 -277.049126) (xy 115.562444 -277.060986) (xy 115.509294 -277.06497) (xy 115.456144 -277.060986)
			(xy 115.404182 -277.049126) (xy 115.354568 -277.029654) (xy 115.30841 -277.003005) (xy 115.266739 -276.969774)
			(xy 115.230487 -276.930703) (xy 115.200463 -276.886666) (xy 115.177337 -276.838645) (xy 115.161627 -276.787715)
			(xy 115.153684 -276.735011) (xy 114.925299 -276.735011) (xy 114.918308 -276.784215) (xy 114.911632 -276.808692)
			(xy 114.902996 -276.837394) (xy 115.484656 -277.419054) (xy 115.495082 -277.428824) (xy 115.520067 -277.442661)
			(xy 115.547909 -277.449028) (xy 115.576424 -277.447425) (xy 115.603377 -277.437979) (xy 115.626654 -277.421429)
			(xy 115.64443 -277.399075) (xy 115.650264 -277.386034) (xy 115.660745 -277.361967) (xy 115.68774 -277.316947)
			(xy 115.721047 -277.276374) (xy 115.759945 -277.241126) (xy 115.803593 -277.211964) (xy 115.851046 -277.189521)
			(xy 115.901278 -277.17428) (xy 115.953202 -277.166573) (xy 115.979448 -277.16607) (xy 116.007429 -277.166623)
			(xy 116.062702 -277.175383) (xy 116.115924 -277.192682) (xy 116.165785 -277.218092) (xy 116.211058 -277.250989)
			(xy 116.250628 -277.290562) (xy 116.283521 -277.335837) (xy 116.308928 -277.3857) (xy 116.326223 -277.438923)
			(xy 116.33498 -277.494197) (xy 116.335556 -277.522178) (xy 116.33509 -277.548427) (xy 116.334993 -277.549081)
			(xy 116.563384 -277.549081) (xy 116.563384 -277.495783) (xy 116.571327 -277.443079) (xy 116.587037 -277.392149)
			(xy 116.610163 -277.344128) (xy 116.640187 -277.300091) (xy 116.676439 -277.26102) (xy 116.71811 -277.227789)
			(xy 116.764268 -277.20114) (xy 116.813882 -277.181668) (xy 116.865844 -277.169808) (xy 116.918994 -277.165825)
			(xy 116.972144 -277.169808) (xy 117.024106 -277.181668) (xy 117.07372 -277.20114) (xy 117.119878 -277.227789)
			(xy 117.161549 -277.26102) (xy 117.197801 -277.300091) (xy 117.227825 -277.344128) (xy 117.250951 -277.392149)
			(xy 117.266661 -277.443079) (xy 117.274604 -277.495783) (xy 117.275102 -277.522432) (xy 117.274609 -277.548827)
			(xy 117.503438 -277.548827) (xy 117.503438 -277.495529) (xy 117.511381 -277.442825) (xy 117.527091 -277.391895)
			(xy 117.550217 -277.343874) (xy 117.580241 -277.299837) (xy 117.616493 -277.260766) (xy 117.658164 -277.227535)
			(xy 117.704322 -277.200886) (xy 117.753936 -277.181414) (xy 117.805898 -277.169554) (xy 117.859048 -277.165571)
			(xy 117.912198 -277.169554) (xy 117.96416 -277.181414) (xy 118.013774 -277.200886) (xy 118.059932 -277.227535)
			(xy 118.101603 -277.260766) (xy 118.137855 -277.299837) (xy 118.167879 -277.343874) (xy 118.191005 -277.391895)
			(xy 118.206715 -277.442825) (xy 118.214658 -277.495529) (xy 118.215156 -277.522178) (xy 118.214658 -277.548827)
			(xy 118.21462 -277.549081) (xy 118.443238 -277.549081) (xy 118.443238 -277.495783) (xy 118.451181 -277.443079)
			(xy 118.466891 -277.392149) (xy 118.490017 -277.344128) (xy 118.520041 -277.300091) (xy 118.556293 -277.26102)
			(xy 118.597964 -277.227789) (xy 118.644122 -277.20114) (xy 118.693736 -277.181668) (xy 118.745698 -277.169808)
			(xy 118.798848 -277.165825) (xy 118.851998 -277.169808) (xy 118.90396 -277.181668) (xy 118.953574 -277.20114)
			(xy 118.999732 -277.227789) (xy 119.041403 -277.26102) (xy 119.077655 -277.300091) (xy 119.107679 -277.344128)
			(xy 119.130805 -277.392149) (xy 119.146515 -277.443079) (xy 119.154458 -277.495783) (xy 119.154956 -277.522432)
			(xy 119.154463 -277.548827) (xy 119.383038 -277.548827) (xy 119.383038 -277.495529) (xy 119.390981 -277.442825)
			(xy 119.406691 -277.391895) (xy 119.429817 -277.343874) (xy 119.459841 -277.299837) (xy 119.496093 -277.260766)
			(xy 119.537764 -277.227535) (xy 119.583922 -277.200886) (xy 119.633536 -277.181414) (xy 119.685498 -277.169554)
			(xy 119.738648 -277.165571) (xy 119.791798 -277.169554) (xy 119.84376 -277.181414) (xy 119.893374 -277.200886)
			(xy 119.939532 -277.227535) (xy 119.981203 -277.260766) (xy 120.017455 -277.299837) (xy 120.047479 -277.343874)
			(xy 120.070605 -277.391895) (xy 120.086315 -277.442825) (xy 120.094258 -277.495529) (xy 120.094756 -277.522178)
			(xy 120.094258 -277.548827) (xy 120.322838 -277.548827) (xy 120.322838 -277.495529) (xy 120.330781 -277.442825)
			(xy 120.346491 -277.391895) (xy 120.369617 -277.343874) (xy 120.399641 -277.299837) (xy 120.435893 -277.260766)
			(xy 120.477564 -277.227535) (xy 120.523722 -277.200886) (xy 120.573336 -277.181414) (xy 120.625298 -277.169554)
			(xy 120.678448 -277.165571) (xy 120.731598 -277.169554) (xy 120.78356 -277.181414) (xy 120.833174 -277.200886)
			(xy 120.879332 -277.227535) (xy 120.921003 -277.260766) (xy 120.957255 -277.299837) (xy 120.987279 -277.343874)
			(xy 121.010405 -277.391895) (xy 121.026115 -277.442825) (xy 121.034058 -277.495529) (xy 121.034556 -277.522178)
			(xy 121.034058 -277.548827) (xy 121.262638 -277.548827) (xy 121.262638 -277.495529) (xy 121.270581 -277.442825)
			(xy 121.286291 -277.391895) (xy 121.309417 -277.343874) (xy 121.339441 -277.299837) (xy 121.375693 -277.260766)
			(xy 121.417364 -277.227535) (xy 121.463522 -277.200886) (xy 121.513136 -277.181414) (xy 121.565098 -277.169554)
			(xy 121.618248 -277.165571) (xy 121.671398 -277.169554) (xy 121.72336 -277.181414) (xy 121.772974 -277.200886)
			(xy 121.819132 -277.227535) (xy 121.860803 -277.260766) (xy 121.897055 -277.299837) (xy 121.927079 -277.343874)
			(xy 121.950205 -277.391895) (xy 121.965915 -277.442825) (xy 121.973858 -277.495529) (xy 121.974356 -277.522178)
			(xy 121.973858 -277.548827) (xy 122.202438 -277.548827) (xy 122.202438 -277.495529) (xy 122.210381 -277.442825)
			(xy 122.226091 -277.391895) (xy 122.249217 -277.343874) (xy 122.279241 -277.299837) (xy 122.315493 -277.260766)
			(xy 122.357164 -277.227535) (xy 122.403322 -277.200886) (xy 122.452936 -277.181414) (xy 122.504898 -277.169554)
			(xy 122.558048 -277.165571) (xy 122.611198 -277.169554) (xy 122.66316 -277.181414) (xy 122.712774 -277.200886)
			(xy 122.758932 -277.227535) (xy 122.800603 -277.260766) (xy 122.836855 -277.299837) (xy 122.866879 -277.343874)
			(xy 122.890005 -277.391895) (xy 122.905715 -277.442825) (xy 122.913658 -277.495529) (xy 122.914156 -277.522178)
			(xy 122.913658 -277.548827) (xy 122.91362 -277.549081) (xy 123.141984 -277.549081) (xy 123.141984 -277.495783)
			(xy 123.149927 -277.443079) (xy 123.165637 -277.392149) (xy 123.188763 -277.344128) (xy 123.218787 -277.300091)
			(xy 123.255039 -277.26102) (xy 123.29671 -277.227789) (xy 123.342868 -277.20114) (xy 123.392482 -277.181668)
			(xy 123.444444 -277.169808) (xy 123.497594 -277.165825) (xy 123.550744 -277.169808) (xy 123.602706 -277.181668)
			(xy 123.65232 -277.20114) (xy 123.698478 -277.227789) (xy 123.740149 -277.26102) (xy 123.776401 -277.300091)
			(xy 123.806425 -277.344128) (xy 123.829551 -277.392149) (xy 123.845261 -277.443079) (xy 123.853204 -277.495783)
			(xy 123.853702 -277.522432) (xy 123.853204 -277.549081) (xy 124.081784 -277.549081) (xy 124.081784 -277.495783)
			(xy 124.089727 -277.443079) (xy 124.105437 -277.392149) (xy 124.128563 -277.344128) (xy 124.158587 -277.300091)
			(xy 124.194839 -277.26102) (xy 124.23651 -277.227789) (xy 124.282668 -277.20114) (xy 124.332282 -277.181668)
			(xy 124.384244 -277.169808) (xy 124.437394 -277.165825) (xy 124.490544 -277.169808) (xy 124.542506 -277.181668)
			(xy 124.59212 -277.20114) (xy 124.638278 -277.227789) (xy 124.679949 -277.26102) (xy 124.716201 -277.300091)
			(xy 124.746225 -277.344128) (xy 124.769351 -277.392149) (xy 124.785061 -277.443079) (xy 124.793004 -277.495783)
			(xy 124.793502 -277.522432) (xy 124.793004 -277.549081) (xy 125.021838 -277.549081) (xy 125.021838 -277.495783)
			(xy 125.029781 -277.443079) (xy 125.045491 -277.392149) (xy 125.068617 -277.344128) (xy 125.098641 -277.300091)
			(xy 125.134893 -277.26102) (xy 125.176564 -277.227789) (xy 125.222722 -277.20114) (xy 125.272336 -277.181668)
			(xy 125.324298 -277.169808) (xy 125.377448 -277.165825) (xy 125.430598 -277.169808) (xy 125.48256 -277.181668)
			(xy 125.532174 -277.20114) (xy 125.578332 -277.227789) (xy 125.620003 -277.26102) (xy 125.656255 -277.300091)
			(xy 125.686279 -277.344128) (xy 125.709405 -277.392149) (xy 125.725115 -277.443079) (xy 125.733058 -277.495783)
			(xy 125.733556 -277.522432) (xy 125.733058 -277.549081) (xy 125.961384 -277.549081) (xy 125.961384 -277.495783)
			(xy 125.969327 -277.443079) (xy 125.985037 -277.392149) (xy 126.008163 -277.344128) (xy 126.038187 -277.300091)
			(xy 126.074439 -277.26102) (xy 126.11611 -277.227789) (xy 126.162268 -277.20114) (xy 126.211882 -277.181668)
			(xy 126.263844 -277.169808) (xy 126.316994 -277.165825) (xy 126.370144 -277.169808) (xy 126.422106 -277.181668)
			(xy 126.47172 -277.20114) (xy 126.517878 -277.227789) (xy 126.559549 -277.26102) (xy 126.595801 -277.300091)
			(xy 126.625825 -277.344128) (xy 126.648951 -277.392149) (xy 126.664661 -277.443079) (xy 126.672604 -277.495783)
			(xy 126.673102 -277.522432) (xy 126.672604 -277.549081) (xy 126.901184 -277.549081) (xy 126.901184 -277.495783)
			(xy 126.909127 -277.443079) (xy 126.924837 -277.392149) (xy 126.947963 -277.344128) (xy 126.977987 -277.300091)
			(xy 127.014239 -277.26102) (xy 127.05591 -277.227789) (xy 127.102068 -277.20114) (xy 127.151682 -277.181668)
			(xy 127.203644 -277.169808) (xy 127.256794 -277.165825) (xy 127.309944 -277.169808) (xy 127.361906 -277.181668)
			(xy 127.41152 -277.20114) (xy 127.457678 -277.227789) (xy 127.499349 -277.26102) (xy 127.535601 -277.300091)
			(xy 127.565625 -277.344128) (xy 127.588751 -277.392149) (xy 127.604461 -277.443079) (xy 127.612404 -277.495783)
			(xy 127.612902 -277.522432) (xy 127.612404 -277.549081) (xy 127.840984 -277.549081) (xy 127.840984 -277.495783)
			(xy 127.848927 -277.443079) (xy 127.864637 -277.392149) (xy 127.887763 -277.344128) (xy 127.917787 -277.300091)
			(xy 127.954039 -277.26102) (xy 127.99571 -277.227789) (xy 128.041868 -277.20114) (xy 128.091482 -277.181668)
			(xy 128.143444 -277.169808) (xy 128.196594 -277.165825) (xy 128.249744 -277.169808) (xy 128.301706 -277.181668)
			(xy 128.35132 -277.20114) (xy 128.397478 -277.227789) (xy 128.439149 -277.26102) (xy 128.475401 -277.300091)
			(xy 128.505425 -277.344128) (xy 128.528551 -277.392149) (xy 128.544261 -277.443079) (xy 128.552204 -277.495783)
			(xy 128.552702 -277.522432) (xy 128.552204 -277.549081) (xy 128.780784 -277.549081) (xy 128.780784 -277.495783)
			(xy 128.788727 -277.443079) (xy 128.804437 -277.392149) (xy 128.827563 -277.344128) (xy 128.857587 -277.300091)
			(xy 128.893839 -277.26102) (xy 128.93551 -277.227789) (xy 128.981668 -277.20114) (xy 129.031282 -277.181668)
			(xy 129.083244 -277.169808) (xy 129.136394 -277.165825) (xy 129.189544 -277.169808) (xy 129.241506 -277.181668)
			(xy 129.29112 -277.20114) (xy 129.337278 -277.227789) (xy 129.378949 -277.26102) (xy 129.415201 -277.300091)
			(xy 129.445225 -277.344128) (xy 129.468351 -277.392149) (xy 129.484061 -277.443079) (xy 129.492004 -277.495783)
			(xy 129.492502 -277.522432) (xy 129.492004 -277.549081) (xy 129.720838 -277.549081) (xy 129.720838 -277.495783)
			(xy 129.728781 -277.443079) (xy 129.744491 -277.392149) (xy 129.767617 -277.344128) (xy 129.797641 -277.300091)
			(xy 129.833893 -277.26102) (xy 129.875564 -277.227789) (xy 129.921722 -277.20114) (xy 129.971336 -277.181668)
			(xy 130.023298 -277.169808) (xy 130.076448 -277.165825) (xy 130.129598 -277.169808) (xy 130.18156 -277.181668)
			(xy 130.231174 -277.20114) (xy 130.277332 -277.227789) (xy 130.319003 -277.26102) (xy 130.355255 -277.300091)
			(xy 130.385279 -277.344128) (xy 130.408405 -277.392149) (xy 130.424115 -277.443079) (xy 130.432058 -277.495783)
			(xy 130.432556 -277.522432) (xy 130.432058 -277.549081) (xy 130.660638 -277.549081) (xy 130.660638 -277.495783)
			(xy 130.668581 -277.443079) (xy 130.684291 -277.392149) (xy 130.707417 -277.344128) (xy 130.737441 -277.300091)
			(xy 130.773693 -277.26102) (xy 130.815364 -277.227789) (xy 130.861522 -277.20114) (xy 130.911136 -277.181668)
			(xy 130.963098 -277.169808) (xy 131.016248 -277.165825) (xy 131.069398 -277.169808) (xy 131.12136 -277.181668)
			(xy 131.170974 -277.20114) (xy 131.217132 -277.227789) (xy 131.258803 -277.26102) (xy 131.295055 -277.300091)
			(xy 131.325079 -277.344128) (xy 131.348205 -277.392149) (xy 131.363915 -277.443079) (xy 131.371858 -277.495783)
			(xy 131.372356 -277.522432) (xy 131.371858 -277.549081) (xy 131.600184 -277.549081) (xy 131.600184 -277.495783)
			(xy 131.608127 -277.443079) (xy 131.623837 -277.392149) (xy 131.646963 -277.344128) (xy 131.676987 -277.300091)
			(xy 131.713239 -277.26102) (xy 131.75491 -277.227789) (xy 131.801068 -277.20114) (xy 131.850682 -277.181668)
			(xy 131.902644 -277.169808) (xy 131.955794 -277.165825) (xy 132.008944 -277.169808) (xy 132.060906 -277.181668)
			(xy 132.11052 -277.20114) (xy 132.156678 -277.227789) (xy 132.198349 -277.26102) (xy 132.234601 -277.300091)
			(xy 132.264625 -277.344128) (xy 132.287751 -277.392149) (xy 132.303461 -277.443079) (xy 132.311404 -277.495783)
			(xy 132.311902 -277.522432) (xy 132.311404 -277.549081) (xy 132.539984 -277.549081) (xy 132.539984 -277.495783)
			(xy 132.547927 -277.443079) (xy 132.563637 -277.392149) (xy 132.586763 -277.344128) (xy 132.616787 -277.300091)
			(xy 132.653039 -277.26102) (xy 132.69471 -277.227789) (xy 132.740868 -277.20114) (xy 132.790482 -277.181668)
			(xy 132.842444 -277.169808) (xy 132.895594 -277.165825) (xy 132.948744 -277.169808) (xy 133.000706 -277.181668)
			(xy 133.05032 -277.20114) (xy 133.096478 -277.227789) (xy 133.138149 -277.26102) (xy 133.174401 -277.300091)
			(xy 133.204425 -277.344128) (xy 133.227551 -277.392149) (xy 133.243261 -277.443079) (xy 133.251204 -277.495783)
			(xy 133.251702 -277.522432) (xy 133.251204 -277.549081) (xy 133.243261 -277.601785) (xy 133.227551 -277.652715)
			(xy 133.204425 -277.700736) (xy 133.174401 -277.744773) (xy 133.138149 -277.783844) (xy 133.096478 -277.817075)
			(xy 133.05032 -277.843724) (xy 133.000706 -277.863196) (xy 132.948744 -277.875056) (xy 132.895594 -277.87904)
			(xy 132.842444 -277.875056) (xy 132.790482 -277.863196) (xy 132.740868 -277.843724) (xy 132.69471 -277.817075)
			(xy 132.653039 -277.783844) (xy 132.616787 -277.744773) (xy 132.586763 -277.700736) (xy 132.563637 -277.652715)
			(xy 132.547927 -277.601785) (xy 132.539984 -277.549081) (xy 132.311404 -277.549081) (xy 132.303461 -277.601785)
			(xy 132.287751 -277.652715) (xy 132.264625 -277.700736) (xy 132.234601 -277.744773) (xy 132.198349 -277.783844)
			(xy 132.156678 -277.817075) (xy 132.11052 -277.843724) (xy 132.060906 -277.863196) (xy 132.008944 -277.875056)
			(xy 131.955794 -277.87904) (xy 131.902644 -277.875056) (xy 131.850682 -277.863196) (xy 131.801068 -277.843724)
			(xy 131.75491 -277.817075) (xy 131.713239 -277.783844) (xy 131.676987 -277.744773) (xy 131.646963 -277.700736)
			(xy 131.623837 -277.652715) (xy 131.608127 -277.601785) (xy 131.600184 -277.549081) (xy 131.371858 -277.549081)
			(xy 131.363915 -277.601785) (xy 131.348205 -277.652715) (xy 131.325079 -277.700736) (xy 131.295055 -277.744773)
			(xy 131.258803 -277.783844) (xy 131.217132 -277.817075) (xy 131.170974 -277.843724) (xy 131.12136 -277.863196)
			(xy 131.069398 -277.875056) (xy 131.016248 -277.87904) (xy 130.963098 -277.875056) (xy 130.911136 -277.863196)
			(xy 130.861522 -277.843724) (xy 130.815364 -277.817075) (xy 130.773693 -277.783844) (xy 130.737441 -277.744773)
			(xy 130.707417 -277.700736) (xy 130.684291 -277.652715) (xy 130.668581 -277.601785) (xy 130.660638 -277.549081)
			(xy 130.432058 -277.549081) (xy 130.424115 -277.601785) (xy 130.408405 -277.652715) (xy 130.385279 -277.700736)
			(xy 130.355255 -277.744773) (xy 130.319003 -277.783844) (xy 130.277332 -277.817075) (xy 130.231174 -277.843724)
			(xy 130.18156 -277.863196) (xy 130.129598 -277.875056) (xy 130.076448 -277.87904) (xy 130.023298 -277.875056)
			(xy 129.971336 -277.863196) (xy 129.921722 -277.843724) (xy 129.875564 -277.817075) (xy 129.833893 -277.783844)
			(xy 129.797641 -277.744773) (xy 129.767617 -277.700736) (xy 129.744491 -277.652715) (xy 129.728781 -277.601785)
			(xy 129.720838 -277.549081) (xy 129.492004 -277.549081) (xy 129.484061 -277.601785) (xy 129.468351 -277.652715)
			(xy 129.445225 -277.700736) (xy 129.415201 -277.744773) (xy 129.378949 -277.783844) (xy 129.337278 -277.817075)
			(xy 129.29112 -277.843724) (xy 129.241506 -277.863196) (xy 129.189544 -277.875056) (xy 129.136394 -277.87904)
			(xy 129.083244 -277.875056) (xy 129.031282 -277.863196) (xy 128.981668 -277.843724) (xy 128.93551 -277.817075)
			(xy 128.893839 -277.783844) (xy 128.857587 -277.744773) (xy 128.827563 -277.700736) (xy 128.804437 -277.652715)
			(xy 128.788727 -277.601785) (xy 128.780784 -277.549081) (xy 128.552204 -277.549081) (xy 128.544261 -277.601785)
			(xy 128.528551 -277.652715) (xy 128.505425 -277.700736) (xy 128.475401 -277.744773) (xy 128.439149 -277.783844)
			(xy 128.397478 -277.817075) (xy 128.35132 -277.843724) (xy 128.301706 -277.863196) (xy 128.249744 -277.875056)
			(xy 128.196594 -277.87904) (xy 128.143444 -277.875056) (xy 128.091482 -277.863196) (xy 128.041868 -277.843724)
			(xy 127.99571 -277.817075) (xy 127.954039 -277.783844) (xy 127.917787 -277.744773) (xy 127.887763 -277.700736)
			(xy 127.864637 -277.652715) (xy 127.848927 -277.601785) (xy 127.840984 -277.549081) (xy 127.612404 -277.549081)
			(xy 127.604461 -277.601785) (xy 127.588751 -277.652715) (xy 127.565625 -277.700736) (xy 127.535601 -277.744773)
			(xy 127.499349 -277.783844) (xy 127.457678 -277.817075) (xy 127.41152 -277.843724) (xy 127.361906 -277.863196)
			(xy 127.309944 -277.875056) (xy 127.256794 -277.87904) (xy 127.203644 -277.875056) (xy 127.151682 -277.863196)
			(xy 127.102068 -277.843724) (xy 127.05591 -277.817075) (xy 127.014239 -277.783844) (xy 126.977987 -277.744773)
			(xy 126.947963 -277.700736) (xy 126.924837 -277.652715) (xy 126.909127 -277.601785) (xy 126.901184 -277.549081)
			(xy 126.672604 -277.549081) (xy 126.664661 -277.601785) (xy 126.648951 -277.652715) (xy 126.625825 -277.700736)
			(xy 126.595801 -277.744773) (xy 126.559549 -277.783844) (xy 126.517878 -277.817075) (xy 126.47172 -277.843724)
			(xy 126.422106 -277.863196) (xy 126.370144 -277.875056) (xy 126.316994 -277.87904) (xy 126.263844 -277.875056)
			(xy 126.211882 -277.863196) (xy 126.162268 -277.843724) (xy 126.11611 -277.817075) (xy 126.074439 -277.783844)
			(xy 126.038187 -277.744773) (xy 126.008163 -277.700736) (xy 125.985037 -277.652715) (xy 125.969327 -277.601785)
			(xy 125.961384 -277.549081) (xy 125.733058 -277.549081) (xy 125.725115 -277.601785) (xy 125.709405 -277.652715)
			(xy 125.686279 -277.700736) (xy 125.656255 -277.744773) (xy 125.620003 -277.783844) (xy 125.578332 -277.817075)
			(xy 125.532174 -277.843724) (xy 125.48256 -277.863196) (xy 125.430598 -277.875056) (xy 125.377448 -277.87904)
			(xy 125.324298 -277.875056) (xy 125.272336 -277.863196) (xy 125.222722 -277.843724) (xy 125.176564 -277.817075)
			(xy 125.134893 -277.783844) (xy 125.098641 -277.744773) (xy 125.068617 -277.700736) (xy 125.045491 -277.652715)
			(xy 125.029781 -277.601785) (xy 125.021838 -277.549081) (xy 124.793004 -277.549081) (xy 124.785061 -277.601785)
			(xy 124.769351 -277.652715) (xy 124.746225 -277.700736) (xy 124.716201 -277.744773) (xy 124.679949 -277.783844)
			(xy 124.638278 -277.817075) (xy 124.59212 -277.843724) (xy 124.542506 -277.863196) (xy 124.490544 -277.875056)
			(xy 124.437394 -277.87904) (xy 124.384244 -277.875056) (xy 124.332282 -277.863196) (xy 124.282668 -277.843724)
			(xy 124.23651 -277.817075) (xy 124.194839 -277.783844) (xy 124.158587 -277.744773) (xy 124.128563 -277.700736)
			(xy 124.105437 -277.652715) (xy 124.089727 -277.601785) (xy 124.081784 -277.549081) (xy 123.853204 -277.549081)
			(xy 123.845261 -277.601785) (xy 123.829551 -277.652715) (xy 123.806425 -277.700736) (xy 123.776401 -277.744773)
			(xy 123.740149 -277.783844) (xy 123.698478 -277.817075) (xy 123.65232 -277.843724) (xy 123.602706 -277.863196)
			(xy 123.550744 -277.875056) (xy 123.497594 -277.87904) (xy 123.444444 -277.875056) (xy 123.392482 -277.863196)
			(xy 123.342868 -277.843724) (xy 123.29671 -277.817075) (xy 123.255039 -277.783844) (xy 123.218787 -277.744773)
			(xy 123.188763 -277.700736) (xy 123.165637 -277.652715) (xy 123.149927 -277.601785) (xy 123.141984 -277.549081)
			(xy 122.91362 -277.549081) (xy 122.905715 -277.601531) (xy 122.890005 -277.652461) (xy 122.866879 -277.700482)
			(xy 122.836855 -277.744519) (xy 122.800603 -277.78359) (xy 122.758932 -277.816821) (xy 122.712774 -277.84347)
			(xy 122.66316 -277.862942) (xy 122.611198 -277.874802) (xy 122.558048 -277.878786) (xy 122.504898 -277.874802)
			(xy 122.452936 -277.862942) (xy 122.403322 -277.84347) (xy 122.357164 -277.816821) (xy 122.315493 -277.78359)
			(xy 122.279241 -277.744519) (xy 122.249217 -277.700482) (xy 122.226091 -277.652461) (xy 122.210381 -277.601531)
			(xy 122.202438 -277.548827) (xy 121.973858 -277.548827) (xy 121.965915 -277.601531) (xy 121.950205 -277.652461)
			(xy 121.927079 -277.700482) (xy 121.897055 -277.744519) (xy 121.860803 -277.78359) (xy 121.819132 -277.816821)
			(xy 121.772974 -277.84347) (xy 121.72336 -277.862942) (xy 121.671398 -277.874802) (xy 121.618248 -277.878786)
			(xy 121.565098 -277.874802) (xy 121.513136 -277.862942) (xy 121.463522 -277.84347) (xy 121.417364 -277.816821)
			(xy 121.375693 -277.78359) (xy 121.339441 -277.744519) (xy 121.309417 -277.700482) (xy 121.286291 -277.652461)
			(xy 121.270581 -277.601531) (xy 121.262638 -277.548827) (xy 121.034058 -277.548827) (xy 121.026115 -277.601531)
			(xy 121.010405 -277.652461) (xy 120.987279 -277.700482) (xy 120.957255 -277.744519) (xy 120.921003 -277.78359)
			(xy 120.879332 -277.816821) (xy 120.833174 -277.84347) (xy 120.78356 -277.862942) (xy 120.731598 -277.874802)
			(xy 120.678448 -277.878786) (xy 120.625298 -277.874802) (xy 120.573336 -277.862942) (xy 120.523722 -277.84347)
			(xy 120.477564 -277.816821) (xy 120.435893 -277.78359) (xy 120.399641 -277.744519) (xy 120.369617 -277.700482)
			(xy 120.346491 -277.652461) (xy 120.330781 -277.601531) (xy 120.322838 -277.548827) (xy 120.094258 -277.548827)
			(xy 120.086315 -277.601531) (xy 120.070605 -277.652461) (xy 120.047479 -277.700482) (xy 120.017455 -277.744519)
			(xy 119.981203 -277.78359) (xy 119.939532 -277.816821) (xy 119.893374 -277.84347) (xy 119.84376 -277.862942)
			(xy 119.791798 -277.874802) (xy 119.738648 -277.878786) (xy 119.685498 -277.874802) (xy 119.633536 -277.862942)
			(xy 119.583922 -277.84347) (xy 119.537764 -277.816821) (xy 119.496093 -277.78359) (xy 119.459841 -277.744519)
			(xy 119.429817 -277.700482) (xy 119.406691 -277.652461) (xy 119.390981 -277.601531) (xy 119.383038 -277.548827)
			(xy 119.154463 -277.548827) (xy 119.154458 -277.549081) (xy 119.146515 -277.601785) (xy 119.130805 -277.652715)
			(xy 119.107679 -277.700736) (xy 119.077655 -277.744773) (xy 119.041403 -277.783844) (xy 118.999732 -277.817075)
			(xy 118.953574 -277.843724) (xy 118.90396 -277.863196) (xy 118.851998 -277.875056) (xy 118.798848 -277.87904)
			(xy 118.745698 -277.875056) (xy 118.693736 -277.863196) (xy 118.644122 -277.843724) (xy 118.597964 -277.817075)
			(xy 118.556293 -277.783844) (xy 118.520041 -277.744773) (xy 118.490017 -277.700736) (xy 118.466891 -277.652715)
			(xy 118.451181 -277.601785) (xy 118.443238 -277.549081) (xy 118.21462 -277.549081) (xy 118.206715 -277.601531)
			(xy 118.191005 -277.652461) (xy 118.167879 -277.700482) (xy 118.137855 -277.744519) (xy 118.101603 -277.78359)
			(xy 118.059932 -277.816821) (xy 118.013774 -277.84347) (xy 117.96416 -277.862942) (xy 117.912198 -277.874802)
			(xy 117.859048 -277.878786) (xy 117.805898 -277.874802) (xy 117.753936 -277.862942) (xy 117.704322 -277.84347)
			(xy 117.658164 -277.816821) (xy 117.616493 -277.78359) (xy 117.580241 -277.744519) (xy 117.550217 -277.700482)
			(xy 117.527091 -277.652461) (xy 117.511381 -277.601531) (xy 117.503438 -277.548827) (xy 117.274609 -277.548827)
			(xy 117.274604 -277.549081) (xy 117.266661 -277.601785) (xy 117.250951 -277.652715) (xy 117.227825 -277.700736)
			(xy 117.197801 -277.744773) (xy 117.161549 -277.783844) (xy 117.119878 -277.817075) (xy 117.07372 -277.843724)
			(xy 117.024106 -277.863196) (xy 116.972144 -277.875056) (xy 116.918994 -277.87904) (xy 116.865844 -277.875056)
			(xy 116.813882 -277.863196) (xy 116.764268 -277.843724) (xy 116.71811 -277.817075) (xy 116.676439 -277.783844)
			(xy 116.640187 -277.744773) (xy 116.610163 -277.700736) (xy 116.587037 -277.652715) (xy 116.571327 -277.601785)
			(xy 116.563384 -277.549081) (xy 116.334993 -277.549081) (xy 116.327389 -277.600357) (xy 116.31215 -277.650594)
			(xy 116.289704 -277.698051) (xy 116.260536 -277.741701) (xy 116.225279 -277.780597) (xy 116.184695 -277.813898)
			(xy 116.139663 -277.840882) (xy 116.115592 -277.851362) (xy 116.102611 -277.857275) (xy 116.080332 -277.875072)
			(xy 116.063841 -277.898333) (xy 116.054423 -277.925246) (xy 116.05281 -277.953714) (xy 116.059129 -277.981519)
			(xy 116.072888 -278.006493) (xy 116.082572 -278.01697) (xy 116.172488 -278.106886) (xy 116.208302 -278.073866)
			(xy 116.228119 -278.056333) (xy 116.271966 -278.026719) (xy 116.319713 -278.003921) (xy 116.370309 -277.988443)
			(xy 116.422639 -277.980625) (xy 116.449094 -277.98014) (xy 116.477078 -277.98066) (xy 116.532358 -277.989415)
			(xy 116.585587 -278.006711) (xy 116.635454 -278.032122) (xy 116.680732 -278.065021) (xy 116.720306 -278.1046)
			(xy 116.7532 -278.149881) (xy 116.778605 -278.199752) (xy 116.795894 -278.252983) (xy 116.804643 -278.308264)
			(xy 116.805202 -278.336248) (xy 116.804716 -278.362702) (xy 116.804687 -278.362897) (xy 117.033284 -278.362897)
			(xy 117.033284 -278.309599) (xy 117.041227 -278.256895) (xy 117.056937 -278.205965) (xy 117.080063 -278.157944)
			(xy 117.110087 -278.113907) (xy 117.146339 -278.074836) (xy 117.18801 -278.041605) (xy 117.234168 -278.014956)
			(xy 117.283782 -277.995484) (xy 117.335744 -277.983624) (xy 117.388894 -277.979641) (xy 117.442044 -277.983624)
			(xy 117.494006 -277.995484) (xy 117.54362 -278.014956) (xy 117.589778 -278.041605) (xy 117.631449 -278.074836)
			(xy 117.667701 -278.113907) (xy 117.697725 -278.157944) (xy 117.720851 -278.205965) (xy 117.736561 -278.256895)
			(xy 117.744504 -278.309599) (xy 117.745002 -278.336248) (xy 117.744504 -278.362897) (xy 117.973084 -278.362897)
			(xy 117.973084 -278.309599) (xy 117.981027 -278.256895) (xy 117.996737 -278.205965) (xy 118.019863 -278.157944)
			(xy 118.049887 -278.113907) (xy 118.086139 -278.074836) (xy 118.12781 -278.041605) (xy 118.173968 -278.014956)
			(xy 118.223582 -277.995484) (xy 118.275544 -277.983624) (xy 118.328694 -277.979641) (xy 118.381844 -277.983624)
			(xy 118.433806 -277.995484) (xy 118.48342 -278.014956) (xy 118.529578 -278.041605) (xy 118.571249 -278.074836)
			(xy 118.607501 -278.113907) (xy 118.637525 -278.157944) (xy 118.660651 -278.205965) (xy 118.676361 -278.256895)
			(xy 118.684304 -278.309599) (xy 118.684802 -278.336248) (xy 118.684304 -278.362897) (xy 118.684266 -278.363151)
			(xy 118.913138 -278.363151) (xy 118.913138 -278.309853) (xy 118.921081 -278.257149) (xy 118.936791 -278.206219)
			(xy 118.959917 -278.158198) (xy 118.989941 -278.114161) (xy 119.026193 -278.07509) (xy 119.067864 -278.041859)
			(xy 119.114022 -278.01521) (xy 119.163636 -277.995738) (xy 119.215598 -277.983878) (xy 119.268748 -277.979895)
			(xy 119.321898 -277.983878) (xy 119.37386 -277.995738) (xy 119.423474 -278.01521) (xy 119.469632 -278.041859)
			(xy 119.511303 -278.07509) (xy 119.547555 -278.114161) (xy 119.577579 -278.158198) (xy 119.600705 -278.206219)
			(xy 119.616415 -278.257149) (xy 119.624358 -278.309853) (xy 119.624856 -278.336502) (xy 119.624363 -278.362897)
			(xy 120.792484 -278.362897) (xy 120.792484 -278.309599) (xy 120.800427 -278.256895) (xy 120.816137 -278.205965)
			(xy 120.839263 -278.157944) (xy 120.869287 -278.113907) (xy 120.905539 -278.074836) (xy 120.94721 -278.041605)
			(xy 120.993368 -278.014956) (xy 121.042982 -277.995484) (xy 121.094944 -277.983624) (xy 121.148094 -277.979641)
			(xy 121.201244 -277.983624) (xy 121.253206 -277.995484) (xy 121.30282 -278.014956) (xy 121.348978 -278.041605)
			(xy 121.390649 -278.074836) (xy 121.426901 -278.113907) (xy 121.456925 -278.157944) (xy 121.480051 -278.205965)
			(xy 121.495761 -278.256895) (xy 121.503704 -278.309599) (xy 121.504202 -278.336248) (xy 121.503704 -278.362897)
			(xy 121.503666 -278.363151) (xy 121.732284 -278.363151) (xy 121.732284 -278.309853) (xy 121.740227 -278.257149)
			(xy 121.755937 -278.206219) (xy 121.779063 -278.158198) (xy 121.809087 -278.114161) (xy 121.845339 -278.07509)
			(xy 121.88701 -278.041859) (xy 121.933168 -278.01521) (xy 121.982782 -277.995738) (xy 122.034744 -277.983878)
			(xy 122.087894 -277.979895) (xy 122.141044 -277.983878) (xy 122.193006 -277.995738) (xy 122.24262 -278.01521)
			(xy 122.288778 -278.041859) (xy 122.330449 -278.07509) (xy 122.366701 -278.114161) (xy 122.396725 -278.158198)
			(xy 122.419851 -278.206219) (xy 122.435561 -278.257149) (xy 122.443504 -278.309853) (xy 122.444002 -278.336502)
			(xy 122.443504 -278.363151) (xy 122.672338 -278.363151) (xy 122.672338 -278.309853) (xy 122.680281 -278.257149)
			(xy 122.695991 -278.206219) (xy 122.719117 -278.158198) (xy 122.749141 -278.114161) (xy 122.785393 -278.07509)
			(xy 122.827064 -278.041859) (xy 122.873222 -278.01521) (xy 122.922836 -277.995738) (xy 122.974798 -277.983878)
			(xy 123.027948 -277.979895) (xy 123.081098 -277.983878) (xy 123.13306 -277.995738) (xy 123.182674 -278.01521)
			(xy 123.228832 -278.041859) (xy 123.270503 -278.07509) (xy 123.306755 -278.114161) (xy 123.336779 -278.158198)
			(xy 123.359905 -278.206219) (xy 123.375615 -278.257149) (xy 123.383558 -278.309853) (xy 123.384056 -278.336502)
			(xy 123.383558 -278.363151) (xy 124.551938 -278.363151) (xy 124.551938 -278.309853) (xy 124.559881 -278.257149)
			(xy 124.575591 -278.206219) (xy 124.598717 -278.158198) (xy 124.628741 -278.114161) (xy 124.664993 -278.07509)
			(xy 124.706664 -278.041859) (xy 124.752822 -278.01521) (xy 124.802436 -277.995738) (xy 124.854398 -277.983878)
			(xy 124.907548 -277.979895) (xy 124.960698 -277.983878) (xy 125.01266 -277.995738) (xy 125.062274 -278.01521)
			(xy 125.108432 -278.041859) (xy 125.150103 -278.07509) (xy 125.186355 -278.114161) (xy 125.216379 -278.158198)
			(xy 125.239505 -278.206219) (xy 125.255215 -278.257149) (xy 125.263158 -278.309853) (xy 125.263656 -278.336502)
			(xy 125.263158 -278.363151) (xy 125.491738 -278.363151) (xy 125.491738 -278.309853) (xy 125.499681 -278.257149)
			(xy 125.515391 -278.206219) (xy 125.538517 -278.158198) (xy 125.568541 -278.114161) (xy 125.604793 -278.07509)
			(xy 125.646464 -278.041859) (xy 125.692622 -278.01521) (xy 125.742236 -277.995738) (xy 125.794198 -277.983878)
			(xy 125.847348 -277.979895) (xy 125.900498 -277.983878) (xy 125.95246 -277.995738) (xy 126.002074 -278.01521)
			(xy 126.048232 -278.041859) (xy 126.089903 -278.07509) (xy 126.126155 -278.114161) (xy 126.156179 -278.158198)
			(xy 126.179305 -278.206219) (xy 126.195015 -278.257149) (xy 126.202958 -278.309853) (xy 126.203456 -278.336502)
			(xy 126.202958 -278.363151) (xy 126.431538 -278.363151) (xy 126.431538 -278.309853) (xy 126.439481 -278.257149)
			(xy 126.455191 -278.206219) (xy 126.478317 -278.158198) (xy 126.508341 -278.114161) (xy 126.544593 -278.07509)
			(xy 126.586264 -278.041859) (xy 126.632422 -278.01521) (xy 126.682036 -277.995738) (xy 126.733998 -277.983878)
			(xy 126.787148 -277.979895) (xy 126.840298 -277.983878) (xy 126.89226 -277.995738) (xy 126.941874 -278.01521)
			(xy 126.988032 -278.041859) (xy 127.029703 -278.07509) (xy 127.065955 -278.114161) (xy 127.095979 -278.158198)
			(xy 127.119105 -278.206219) (xy 127.134815 -278.257149) (xy 127.142758 -278.309853) (xy 127.143256 -278.336502)
			(xy 127.142758 -278.363151) (xy 127.371338 -278.363151) (xy 127.371338 -278.309853) (xy 127.379281 -278.257149)
			(xy 127.394991 -278.206219) (xy 127.418117 -278.158198) (xy 127.448141 -278.114161) (xy 127.484393 -278.07509)
			(xy 127.526064 -278.041859) (xy 127.572222 -278.01521) (xy 127.621836 -277.995738) (xy 127.673798 -277.983878)
			(xy 127.726948 -277.979895) (xy 127.780098 -277.983878) (xy 127.83206 -277.995738) (xy 127.881674 -278.01521)
			(xy 127.927832 -278.041859) (xy 127.969503 -278.07509) (xy 128.005755 -278.114161) (xy 128.035779 -278.158198)
			(xy 128.058905 -278.206219) (xy 128.074615 -278.257149) (xy 128.082558 -278.309853) (xy 128.083056 -278.336502)
			(xy 128.082558 -278.363151) (xy 128.310884 -278.363151) (xy 128.310884 -278.309853) (xy 128.318827 -278.257149)
			(xy 128.334537 -278.206219) (xy 128.357663 -278.158198) (xy 128.387687 -278.114161) (xy 128.423939 -278.07509)
			(xy 128.46561 -278.041859) (xy 128.511768 -278.01521) (xy 128.561382 -277.995738) (xy 128.613344 -277.983878)
			(xy 128.666494 -277.979895) (xy 128.719644 -277.983878) (xy 128.771606 -277.995738) (xy 128.82122 -278.01521)
			(xy 128.867378 -278.041859) (xy 128.909049 -278.07509) (xy 128.945301 -278.114161) (xy 128.975325 -278.158198)
			(xy 128.998451 -278.206219) (xy 129.014161 -278.257149) (xy 129.022104 -278.309853) (xy 129.022602 -278.336502)
			(xy 129.022104 -278.363151) (xy 129.250938 -278.363151) (xy 129.250938 -278.309853) (xy 129.258881 -278.257149)
			(xy 129.274591 -278.206219) (xy 129.297717 -278.158198) (xy 129.327741 -278.114161) (xy 129.363993 -278.07509)
			(xy 129.405664 -278.041859) (xy 129.451822 -278.01521) (xy 129.501436 -277.995738) (xy 129.553398 -277.983878)
			(xy 129.606548 -277.979895) (xy 129.659698 -277.983878) (xy 129.71166 -277.995738) (xy 129.761274 -278.01521)
			(xy 129.807432 -278.041859) (xy 129.849103 -278.07509) (xy 129.885355 -278.114161) (xy 129.915379 -278.158198)
			(xy 129.938505 -278.206219) (xy 129.954215 -278.257149) (xy 129.962158 -278.309853) (xy 129.962656 -278.336502)
			(xy 129.962158 -278.363151) (xy 130.190484 -278.363151) (xy 130.190484 -278.309853) (xy 130.198427 -278.257149)
			(xy 130.214137 -278.206219) (xy 130.237263 -278.158198) (xy 130.267287 -278.114161) (xy 130.303539 -278.07509)
			(xy 130.34521 -278.041859) (xy 130.391368 -278.01521) (xy 130.440982 -277.995738) (xy 130.492944 -277.983878)
			(xy 130.546094 -277.979895) (xy 130.599244 -277.983878) (xy 130.651206 -277.995738) (xy 130.70082 -278.01521)
			(xy 130.746978 -278.041859) (xy 130.788649 -278.07509) (xy 130.824901 -278.114161) (xy 130.854925 -278.158198)
			(xy 130.878051 -278.206219) (xy 130.893761 -278.257149) (xy 130.901704 -278.309853) (xy 130.902202 -278.336502)
			(xy 130.901704 -278.363151) (xy 131.130538 -278.363151) (xy 131.130538 -278.309853) (xy 131.138481 -278.257149)
			(xy 131.154191 -278.206219) (xy 131.177317 -278.158198) (xy 131.207341 -278.114161) (xy 131.243593 -278.07509)
			(xy 131.285264 -278.041859) (xy 131.331422 -278.01521) (xy 131.381036 -277.995738) (xy 131.432998 -277.983878)
			(xy 131.486148 -277.979895) (xy 131.539298 -277.983878) (xy 131.59126 -277.995738) (xy 131.640874 -278.01521)
			(xy 131.687032 -278.041859) (xy 131.728703 -278.07509) (xy 131.764955 -278.114161) (xy 131.794979 -278.158198)
			(xy 131.818105 -278.206219) (xy 131.833815 -278.257149) (xy 131.841758 -278.309853) (xy 131.842256 -278.336502)
			(xy 131.841758 -278.363151) (xy 132.070338 -278.363151) (xy 132.070338 -278.309853) (xy 132.078281 -278.257149)
			(xy 132.093991 -278.206219) (xy 132.117117 -278.158198) (xy 132.147141 -278.114161) (xy 132.183393 -278.07509)
			(xy 132.225064 -278.041859) (xy 132.271222 -278.01521) (xy 132.320836 -277.995738) (xy 132.372798 -277.983878)
			(xy 132.425948 -277.979895) (xy 132.479098 -277.983878) (xy 132.53106 -277.995738) (xy 132.580674 -278.01521)
			(xy 132.626832 -278.041859) (xy 132.668503 -278.07509) (xy 132.704755 -278.114161) (xy 132.734779 -278.158198)
			(xy 132.757905 -278.206219) (xy 132.773615 -278.257149) (xy 132.781558 -278.309853) (xy 132.782056 -278.336502)
			(xy 132.781558 -278.363151) (xy 133.010138 -278.363151) (xy 133.010138 -278.309853) (xy 133.018081 -278.257149)
			(xy 133.033791 -278.206219) (xy 133.056917 -278.158198) (xy 133.086941 -278.114161) (xy 133.123193 -278.07509)
			(xy 133.164864 -278.041859) (xy 133.211022 -278.01521) (xy 133.260636 -277.995738) (xy 133.312598 -277.983878)
			(xy 133.365748 -277.979895) (xy 133.418898 -277.983878) (xy 133.47086 -277.995738) (xy 133.520474 -278.01521)
			(xy 133.566632 -278.041859) (xy 133.608303 -278.07509) (xy 133.644555 -278.114161) (xy 133.674579 -278.158198)
			(xy 133.697705 -278.206219) (xy 133.713415 -278.257149) (xy 133.721358 -278.309853) (xy 133.721856 -278.336502)
			(xy 133.721358 -278.363151) (xy 133.713415 -278.415855) (xy 133.697705 -278.466785) (xy 133.674579 -278.514806)
			(xy 133.644555 -278.558843) (xy 133.608303 -278.597914) (xy 133.566632 -278.631145) (xy 133.520474 -278.657794)
			(xy 133.47086 -278.677266) (xy 133.418898 -278.689126) (xy 133.365748 -278.69311) (xy 133.312598 -278.689126)
			(xy 133.260636 -278.677266) (xy 133.211022 -278.657794) (xy 133.164864 -278.631145) (xy 133.123193 -278.597914)
			(xy 133.086941 -278.558843) (xy 133.056917 -278.514806) (xy 133.033791 -278.466785) (xy 133.018081 -278.415855)
			(xy 133.010138 -278.363151) (xy 132.781558 -278.363151) (xy 132.773615 -278.415855) (xy 132.757905 -278.466785)
			(xy 132.734779 -278.514806) (xy 132.704755 -278.558843) (xy 132.668503 -278.597914) (xy 132.626832 -278.631145)
			(xy 132.580674 -278.657794) (xy 132.53106 -278.677266) (xy 132.479098 -278.689126) (xy 132.425948 -278.69311)
			(xy 132.372798 -278.689126) (xy 132.320836 -278.677266) (xy 132.271222 -278.657794) (xy 132.225064 -278.631145)
			(xy 132.183393 -278.597914) (xy 132.147141 -278.558843) (xy 132.117117 -278.514806) (xy 132.093991 -278.466785)
			(xy 132.078281 -278.415855) (xy 132.070338 -278.363151) (xy 131.841758 -278.363151) (xy 131.833815 -278.415855)
			(xy 131.818105 -278.466785) (xy 131.794979 -278.514806) (xy 131.764955 -278.558843) (xy 131.728703 -278.597914)
			(xy 131.687032 -278.631145) (xy 131.640874 -278.657794) (xy 131.59126 -278.677266) (xy 131.539298 -278.689126)
			(xy 131.486148 -278.69311) (xy 131.432998 -278.689126) (xy 131.381036 -278.677266) (xy 131.331422 -278.657794)
			(xy 131.285264 -278.631145) (xy 131.243593 -278.597914) (xy 131.207341 -278.558843) (xy 131.177317 -278.514806)
			(xy 131.154191 -278.466785) (xy 131.138481 -278.415855) (xy 131.130538 -278.363151) (xy 130.901704 -278.363151)
			(xy 130.893761 -278.415855) (xy 130.878051 -278.466785) (xy 130.854925 -278.514806) (xy 130.824901 -278.558843)
			(xy 130.788649 -278.597914) (xy 130.746978 -278.631145) (xy 130.70082 -278.657794) (xy 130.651206 -278.677266)
			(xy 130.599244 -278.689126) (xy 130.546094 -278.69311) (xy 130.492944 -278.689126) (xy 130.440982 -278.677266)
			(xy 130.391368 -278.657794) (xy 130.34521 -278.631145) (xy 130.303539 -278.597914) (xy 130.267287 -278.558843)
			(xy 130.237263 -278.514806) (xy 130.214137 -278.466785) (xy 130.198427 -278.415855) (xy 130.190484 -278.363151)
			(xy 129.962158 -278.363151) (xy 129.954215 -278.415855) (xy 129.938505 -278.466785) (xy 129.915379 -278.514806)
			(xy 129.885355 -278.558843) (xy 129.849103 -278.597914) (xy 129.807432 -278.631145) (xy 129.761274 -278.657794)
			(xy 129.71166 -278.677266) (xy 129.659698 -278.689126) (xy 129.606548 -278.69311) (xy 129.553398 -278.689126)
			(xy 129.501436 -278.677266) (xy 129.451822 -278.657794) (xy 129.405664 -278.631145) (xy 129.363993 -278.597914)
			(xy 129.327741 -278.558843) (xy 129.297717 -278.514806) (xy 129.274591 -278.466785) (xy 129.258881 -278.415855)
			(xy 129.250938 -278.363151) (xy 129.022104 -278.363151) (xy 129.014161 -278.415855) (xy 128.998451 -278.466785)
			(xy 128.975325 -278.514806) (xy 128.945301 -278.558843) (xy 128.909049 -278.597914) (xy 128.867378 -278.631145)
			(xy 128.82122 -278.657794) (xy 128.771606 -278.677266) (xy 128.719644 -278.689126) (xy 128.666494 -278.69311)
			(xy 128.613344 -278.689126) (xy 128.561382 -278.677266) (xy 128.511768 -278.657794) (xy 128.46561 -278.631145)
			(xy 128.423939 -278.597914) (xy 128.387687 -278.558843) (xy 128.357663 -278.514806) (xy 128.334537 -278.466785)
			(xy 128.318827 -278.415855) (xy 128.310884 -278.363151) (xy 128.082558 -278.363151) (xy 128.074615 -278.415855)
			(xy 128.058905 -278.466785) (xy 128.035779 -278.514806) (xy 128.005755 -278.558843) (xy 127.969503 -278.597914)
			(xy 127.927832 -278.631145) (xy 127.881674 -278.657794) (xy 127.83206 -278.677266) (xy 127.780098 -278.689126)
			(xy 127.726948 -278.69311) (xy 127.673798 -278.689126) (xy 127.621836 -278.677266) (xy 127.572222 -278.657794)
			(xy 127.526064 -278.631145) (xy 127.484393 -278.597914) (xy 127.448141 -278.558843) (xy 127.418117 -278.514806)
			(xy 127.394991 -278.466785) (xy 127.379281 -278.415855) (xy 127.371338 -278.363151) (xy 127.142758 -278.363151)
			(xy 127.134815 -278.415855) (xy 127.119105 -278.466785) (xy 127.095979 -278.514806) (xy 127.065955 -278.558843)
			(xy 127.029703 -278.597914) (xy 126.988032 -278.631145) (xy 126.941874 -278.657794) (xy 126.89226 -278.677266)
			(xy 126.840298 -278.689126) (xy 126.787148 -278.69311) (xy 126.733998 -278.689126) (xy 126.682036 -278.677266)
			(xy 126.632422 -278.657794) (xy 126.586264 -278.631145) (xy 126.544593 -278.597914) (xy 126.508341 -278.558843)
			(xy 126.478317 -278.514806) (xy 126.455191 -278.466785) (xy 126.439481 -278.415855) (xy 126.431538 -278.363151)
			(xy 126.202958 -278.363151) (xy 126.195015 -278.415855) (xy 126.179305 -278.466785) (xy 126.156179 -278.514806)
			(xy 126.126155 -278.558843) (xy 126.089903 -278.597914) (xy 126.048232 -278.631145) (xy 126.002074 -278.657794)
			(xy 125.95246 -278.677266) (xy 125.900498 -278.689126) (xy 125.847348 -278.69311) (xy 125.794198 -278.689126)
			(xy 125.742236 -278.677266) (xy 125.692622 -278.657794) (xy 125.646464 -278.631145) (xy 125.604793 -278.597914)
			(xy 125.568541 -278.558843) (xy 125.538517 -278.514806) (xy 125.515391 -278.466785) (xy 125.499681 -278.415855)
			(xy 125.491738 -278.363151) (xy 125.263158 -278.363151) (xy 125.255215 -278.415855) (xy 125.239505 -278.466785)
			(xy 125.216379 -278.514806) (xy 125.186355 -278.558843) (xy 125.150103 -278.597914) (xy 125.108432 -278.631145)
			(xy 125.062274 -278.657794) (xy 125.01266 -278.677266) (xy 124.960698 -278.689126) (xy 124.907548 -278.69311)
			(xy 124.854398 -278.689126) (xy 124.802436 -278.677266) (xy 124.752822 -278.657794) (xy 124.706664 -278.631145)
			(xy 124.664993 -278.597914) (xy 124.628741 -278.558843) (xy 124.598717 -278.514806) (xy 124.575591 -278.466785)
			(xy 124.559881 -278.415855) (xy 124.551938 -278.363151) (xy 123.383558 -278.363151) (xy 123.375615 -278.415855)
			(xy 123.359905 -278.466785) (xy 123.336779 -278.514806) (xy 123.306755 -278.558843) (xy 123.270503 -278.597914)
			(xy 123.228832 -278.631145) (xy 123.182674 -278.657794) (xy 123.13306 -278.677266) (xy 123.081098 -278.689126)
			(xy 123.027948 -278.69311) (xy 122.974798 -278.689126) (xy 122.922836 -278.677266) (xy 122.873222 -278.657794)
			(xy 122.827064 -278.631145) (xy 122.785393 -278.597914) (xy 122.749141 -278.558843) (xy 122.719117 -278.514806)
			(xy 122.695991 -278.466785) (xy 122.680281 -278.415855) (xy 122.672338 -278.363151) (xy 122.443504 -278.363151)
			(xy 122.435561 -278.415855) (xy 122.419851 -278.466785) (xy 122.396725 -278.514806) (xy 122.366701 -278.558843)
			(xy 122.330449 -278.597914) (xy 122.288778 -278.631145) (xy 122.24262 -278.657794) (xy 122.193006 -278.677266)
			(xy 122.141044 -278.689126) (xy 122.087894 -278.69311) (xy 122.034744 -278.689126) (xy 121.982782 -278.677266)
			(xy 121.933168 -278.657794) (xy 121.88701 -278.631145) (xy 121.845339 -278.597914) (xy 121.809087 -278.558843)
			(xy 121.779063 -278.514806) (xy 121.755937 -278.466785) (xy 121.740227 -278.415855) (xy 121.732284 -278.363151)
			(xy 121.503666 -278.363151) (xy 121.495761 -278.415601) (xy 121.480051 -278.466531) (xy 121.456925 -278.514552)
			(xy 121.426901 -278.558589) (xy 121.390649 -278.59766) (xy 121.348978 -278.630891) (xy 121.30282 -278.65754)
			(xy 121.253206 -278.677012) (xy 121.201244 -278.688872) (xy 121.148094 -278.692856) (xy 121.094944 -278.688872)
			(xy 121.042982 -278.677012) (xy 120.993368 -278.65754) (xy 120.94721 -278.630891) (xy 120.905539 -278.59766)
			(xy 120.869287 -278.558589) (xy 120.839263 -278.514552) (xy 120.816137 -278.466531) (xy 120.800427 -278.415601)
			(xy 120.792484 -278.362897) (xy 119.624363 -278.362897) (xy 119.624358 -278.363151) (xy 119.616415 -278.415855)
			(xy 119.600705 -278.466785) (xy 119.577579 -278.514806) (xy 119.547555 -278.558843) (xy 119.511303 -278.597914)
			(xy 119.469632 -278.631145) (xy 119.423474 -278.657794) (xy 119.37386 -278.677266) (xy 119.321898 -278.689126)
			(xy 119.268748 -278.69311) (xy 119.215598 -278.689126) (xy 119.163636 -278.677266) (xy 119.114022 -278.657794)
			(xy 119.067864 -278.631145) (xy 119.026193 -278.597914) (xy 118.989941 -278.558843) (xy 118.959917 -278.514806)
			(xy 118.936791 -278.466785) (xy 118.921081 -278.415855) (xy 118.913138 -278.363151) (xy 118.684266 -278.363151)
			(xy 118.676361 -278.415601) (xy 118.660651 -278.466531) (xy 118.637525 -278.514552) (xy 118.607501 -278.558589)
			(xy 118.571249 -278.59766) (xy 118.529578 -278.630891) (xy 118.48342 -278.65754) (xy 118.433806 -278.677012)
			(xy 118.381844 -278.688872) (xy 118.328694 -278.692856) (xy 118.275544 -278.688872) (xy 118.223582 -278.677012)
			(xy 118.173968 -278.65754) (xy 118.12781 -278.630891) (xy 118.086139 -278.59766) (xy 118.049887 -278.558589)
			(xy 118.019863 -278.514552) (xy 117.996737 -278.466531) (xy 117.981027 -278.415601) (xy 117.973084 -278.362897)
			(xy 117.744504 -278.362897) (xy 117.736561 -278.415601) (xy 117.720851 -278.466531) (xy 117.697725 -278.514552)
			(xy 117.667701 -278.558589) (xy 117.631449 -278.59766) (xy 117.589778 -278.630891) (xy 117.54362 -278.65754)
			(xy 117.494006 -278.677012) (xy 117.442044 -278.688872) (xy 117.388894 -278.692856) (xy 117.335744 -278.688872)
			(xy 117.283782 -278.677012) (xy 117.234168 -278.65754) (xy 117.18801 -278.630891) (xy 117.146339 -278.59766)
			(xy 117.110087 -278.558589) (xy 117.080063 -278.514552) (xy 117.056937 -278.466531) (xy 117.041227 -278.415601)
			(xy 117.033284 -278.362897) (xy 116.804687 -278.362897) (xy 116.796883 -278.415026) (xy 116.781396 -278.465616)
			(xy 116.758597 -278.51336) (xy 116.728987 -278.557205) (xy 116.711476 -278.57704) (xy 116.705225 -278.584525)
			(xy 116.698378 -278.602768) (xy 116.698805 -278.622249) (xy 116.706446 -278.640174) (xy 116.713 -278.647398)
			(xy 116.863114 -278.797512) (xy 116.88699 -278.79548) (xy 116.919248 -278.793956) (xy 116.94723 -278.794509)
			(xy 117.002503 -278.803269) (xy 117.055726 -278.820568) (xy 117.105588 -278.845978) (xy 117.150862 -278.878874)
			(xy 117.190434 -278.918447) (xy 117.223329 -278.963722) (xy 117.248737 -279.013585) (xy 117.266034 -279.066809)
			(xy 117.274792 -279.122082) (xy 117.275356 -279.150064) (xy 117.274857 -279.176967) (xy 117.503438 -279.176967)
			(xy 117.503438 -279.123669) (xy 117.511381 -279.070965) (xy 117.527091 -279.020035) (xy 117.550217 -278.972014)
			(xy 117.580241 -278.927977) (xy 117.616493 -278.888906) (xy 117.658164 -278.855675) (xy 117.704322 -278.829026)
			(xy 117.753936 -278.809554) (xy 117.805898 -278.797694) (xy 117.859048 -278.793711) (xy 117.912198 -278.797694)
			(xy 117.96416 -278.809554) (xy 118.013774 -278.829026) (xy 118.059932 -278.855675) (xy 118.101603 -278.888906)
			(xy 118.137855 -278.927977) (xy 118.167879 -278.972014) (xy 118.191005 -279.020035) (xy 118.206715 -279.070965)
			(xy 118.214658 -279.123669) (xy 118.215156 -279.150318) (xy 118.214658 -279.176967) (xy 119.382784 -279.176967)
			(xy 119.382784 -279.123669) (xy 119.390727 -279.070965) (xy 119.406437 -279.020035) (xy 119.429563 -278.972014)
			(xy 119.459587 -278.927977) (xy 119.495839 -278.888906) (xy 119.53751 -278.855675) (xy 119.583668 -278.829026)
			(xy 119.633282 -278.809554) (xy 119.685244 -278.797694) (xy 119.738394 -278.793711) (xy 119.791544 -278.797694)
			(xy 119.843506 -278.809554) (xy 119.89312 -278.829026) (xy 119.939278 -278.855675) (xy 119.980949 -278.888906)
			(xy 120.017201 -278.927977) (xy 120.047225 -278.972014) (xy 120.070351 -279.020035) (xy 120.086061 -279.070965)
			(xy 120.094004 -279.123669) (xy 120.094502 -279.150318) (xy 120.094004 -279.176967) (xy 120.322838 -279.176967)
			(xy 120.322838 -279.123669) (xy 120.330781 -279.070965) (xy 120.346491 -279.020035) (xy 120.369617 -278.972014)
			(xy 120.399641 -278.927977) (xy 120.435893 -278.888906) (xy 120.477564 -278.855675) (xy 120.523722 -278.829026)
			(xy 120.573336 -278.809554) (xy 120.625298 -278.797694) (xy 120.678448 -278.793711) (xy 120.731598 -278.797694)
			(xy 120.78356 -278.809554) (xy 120.833174 -278.829026) (xy 120.879332 -278.855675) (xy 120.921003 -278.888906)
			(xy 120.957255 -278.927977) (xy 120.987279 -278.972014) (xy 121.010405 -279.020035) (xy 121.026115 -279.070965)
			(xy 121.034058 -279.123669) (xy 121.034556 -279.150318) (xy 121.034058 -279.176967) (xy 121.262384 -279.176967)
			(xy 121.262384 -279.123669) (xy 121.270327 -279.070965) (xy 121.286037 -279.020035) (xy 121.309163 -278.972014)
			(xy 121.339187 -278.927977) (xy 121.375439 -278.888906) (xy 121.41711 -278.855675) (xy 121.463268 -278.829026)
			(xy 121.512882 -278.809554) (xy 121.564844 -278.797694) (xy 121.617994 -278.793711) (xy 121.671144 -278.797694)
			(xy 121.723106 -278.809554) (xy 121.77272 -278.829026) (xy 121.818878 -278.855675) (xy 121.860549 -278.888906)
			(xy 121.896801 -278.927977) (xy 121.926825 -278.972014) (xy 121.949951 -279.020035) (xy 121.965661 -279.070965)
			(xy 121.973604 -279.123669) (xy 121.974102 -279.150318) (xy 121.973604 -279.176967) (xy 122.202184 -279.176967)
			(xy 122.202184 -279.123669) (xy 122.210127 -279.070965) (xy 122.225837 -279.020035) (xy 122.248963 -278.972014)
			(xy 122.278987 -278.927977) (xy 122.315239 -278.888906) (xy 122.35691 -278.855675) (xy 122.403068 -278.829026)
			(xy 122.452682 -278.809554) (xy 122.504644 -278.797694) (xy 122.557794 -278.793711) (xy 122.610944 -278.797694)
			(xy 122.662906 -278.809554) (xy 122.71252 -278.829026) (xy 122.758678 -278.855675) (xy 122.800349 -278.888906)
			(xy 122.836601 -278.927977) (xy 122.866625 -278.972014) (xy 122.889751 -279.020035) (xy 122.905461 -279.070965)
			(xy 122.913404 -279.123669) (xy 122.913902 -279.150318) (xy 122.913404 -279.176967) (xy 123.142238 -279.176967)
			(xy 123.142238 -279.123669) (xy 123.150181 -279.070965) (xy 123.165891 -279.020035) (xy 123.189017 -278.972014)
			(xy 123.219041 -278.927977) (xy 123.255293 -278.888906) (xy 123.296964 -278.855675) (xy 123.343122 -278.829026)
			(xy 123.392736 -278.809554) (xy 123.444698 -278.797694) (xy 123.497848 -278.793711) (xy 123.550998 -278.797694)
			(xy 123.60296 -278.809554) (xy 123.652574 -278.829026) (xy 123.698732 -278.855675) (xy 123.740403 -278.888906)
			(xy 123.776655 -278.927977) (xy 123.806679 -278.972014) (xy 123.829805 -279.020035) (xy 123.845515 -279.070965)
			(xy 123.853458 -279.123669) (xy 123.853956 -279.150318) (xy 123.853458 -279.176967) (xy 124.081784 -279.176967)
			(xy 124.081784 -279.123669) (xy 124.089727 -279.070965) (xy 124.105437 -279.020035) (xy 124.128563 -278.972014)
			(xy 124.158587 -278.927977) (xy 124.194839 -278.888906) (xy 124.23651 -278.855675) (xy 124.282668 -278.829026)
			(xy 124.332282 -278.809554) (xy 124.384244 -278.797694) (xy 124.437394 -278.793711) (xy 124.490544 -278.797694)
			(xy 124.542506 -278.809554) (xy 124.59212 -278.829026) (xy 124.638278 -278.855675) (xy 124.679949 -278.888906)
			(xy 124.716201 -278.927977) (xy 124.746225 -278.972014) (xy 124.769351 -279.020035) (xy 124.785061 -279.070965)
			(xy 124.793004 -279.123669) (xy 124.793502 -279.150318) (xy 124.793004 -279.176967) (xy 125.021584 -279.176967)
			(xy 125.021584 -279.123669) (xy 125.029527 -279.070965) (xy 125.045237 -279.020035) (xy 125.068363 -278.972014)
			(xy 125.098387 -278.927977) (xy 125.134639 -278.888906) (xy 125.17631 -278.855675) (xy 125.222468 -278.829026)
			(xy 125.272082 -278.809554) (xy 125.324044 -278.797694) (xy 125.377194 -278.793711) (xy 125.430344 -278.797694)
			(xy 125.482306 -278.809554) (xy 125.53192 -278.829026) (xy 125.578078 -278.855675) (xy 125.619749 -278.888906)
			(xy 125.656001 -278.927977) (xy 125.686025 -278.972014) (xy 125.709151 -279.020035) (xy 125.724861 -279.070965)
			(xy 125.732804 -279.123669) (xy 125.733302 -279.150318) (xy 125.732804 -279.176967) (xy 125.961384 -279.176967)
			(xy 125.961384 -279.123669) (xy 125.969327 -279.070965) (xy 125.985037 -279.020035) (xy 126.008163 -278.972014)
			(xy 126.038187 -278.927977) (xy 126.074439 -278.888906) (xy 126.11611 -278.855675) (xy 126.162268 -278.829026)
			(xy 126.211882 -278.809554) (xy 126.263844 -278.797694) (xy 126.316994 -278.793711) (xy 126.370144 -278.797694)
			(xy 126.422106 -278.809554) (xy 126.47172 -278.829026) (xy 126.517878 -278.855675) (xy 126.559549 -278.888906)
			(xy 126.595801 -278.927977) (xy 126.625825 -278.972014) (xy 126.648951 -279.020035) (xy 126.664661 -279.070965)
			(xy 126.672604 -279.123669) (xy 126.673102 -279.150318) (xy 126.672604 -279.176967) (xy 126.901184 -279.176967)
			(xy 126.901184 -279.123669) (xy 126.909127 -279.070965) (xy 126.924837 -279.020035) (xy 126.947963 -278.972014)
			(xy 126.977987 -278.927977) (xy 127.014239 -278.888906) (xy 127.05591 -278.855675) (xy 127.102068 -278.829026)
			(xy 127.151682 -278.809554) (xy 127.203644 -278.797694) (xy 127.256794 -278.793711) (xy 127.309944 -278.797694)
			(xy 127.361906 -278.809554) (xy 127.41152 -278.829026) (xy 127.457678 -278.855675) (xy 127.499349 -278.888906)
			(xy 127.535601 -278.927977) (xy 127.565625 -278.972014) (xy 127.588751 -279.020035) (xy 127.604461 -279.070965)
			(xy 127.612404 -279.123669) (xy 127.612902 -279.150318) (xy 127.612404 -279.176967) (xy 127.840984 -279.176967)
			(xy 127.840984 -279.123669) (xy 127.848927 -279.070965) (xy 127.864637 -279.020035) (xy 127.887763 -278.972014)
			(xy 127.917787 -278.927977) (xy 127.954039 -278.888906) (xy 127.99571 -278.855675) (xy 128.041868 -278.829026)
			(xy 128.091482 -278.809554) (xy 128.143444 -278.797694) (xy 128.196594 -278.793711) (xy 128.249744 -278.797694)
			(xy 128.301706 -278.809554) (xy 128.35132 -278.829026) (xy 128.397478 -278.855675) (xy 128.439149 -278.888906)
			(xy 128.475401 -278.927977) (xy 128.505425 -278.972014) (xy 128.528551 -279.020035) (xy 128.544261 -279.070965)
			(xy 128.552204 -279.123669) (xy 128.552702 -279.150318) (xy 128.552204 -279.176967) (xy 128.780784 -279.176967)
			(xy 128.780784 -279.123669) (xy 128.788727 -279.070965) (xy 128.804437 -279.020035) (xy 128.827563 -278.972014)
			(xy 128.857587 -278.927977) (xy 128.893839 -278.888906) (xy 128.93551 -278.855675) (xy 128.981668 -278.829026)
			(xy 129.031282 -278.809554) (xy 129.083244 -278.797694) (xy 129.136394 -278.793711) (xy 129.189544 -278.797694)
			(xy 129.241506 -278.809554) (xy 129.29112 -278.829026) (xy 129.337278 -278.855675) (xy 129.378949 -278.888906)
			(xy 129.415201 -278.927977) (xy 129.445225 -278.972014) (xy 129.468351 -279.020035) (xy 129.484061 -279.070965)
			(xy 129.492004 -279.123669) (xy 129.492502 -279.150318) (xy 129.492004 -279.176967) (xy 129.720838 -279.176967)
			(xy 129.720838 -279.123669) (xy 129.728781 -279.070965) (xy 129.744491 -279.020035) (xy 129.767617 -278.972014)
			(xy 129.797641 -278.927977) (xy 129.833893 -278.888906) (xy 129.875564 -278.855675) (xy 129.921722 -278.829026)
			(xy 129.971336 -278.809554) (xy 130.023298 -278.797694) (xy 130.076448 -278.793711) (xy 130.129598 -278.797694)
			(xy 130.18156 -278.809554) (xy 130.231174 -278.829026) (xy 130.277332 -278.855675) (xy 130.319003 -278.888906)
			(xy 130.355255 -278.927977) (xy 130.385279 -278.972014) (xy 130.408405 -279.020035) (xy 130.424115 -279.070965)
			(xy 130.432058 -279.123669) (xy 130.432556 -279.150318) (xy 130.432058 -279.176967) (xy 130.660384 -279.176967)
			(xy 130.660384 -279.123669) (xy 130.668327 -279.070965) (xy 130.684037 -279.020035) (xy 130.707163 -278.972014)
			(xy 130.737187 -278.927977) (xy 130.773439 -278.888906) (xy 130.81511 -278.855675) (xy 130.861268 -278.829026)
			(xy 130.910882 -278.809554) (xy 130.962844 -278.797694) (xy 131.015994 -278.793711) (xy 131.069144 -278.797694)
			(xy 131.121106 -278.809554) (xy 131.17072 -278.829026) (xy 131.216878 -278.855675) (xy 131.258549 -278.888906)
			(xy 131.294801 -278.927977) (xy 131.324825 -278.972014) (xy 131.347951 -279.020035) (xy 131.363661 -279.070965)
			(xy 131.371604 -279.123669) (xy 131.372102 -279.150318) (xy 131.371604 -279.176967) (xy 131.600438 -279.176967)
			(xy 131.600438 -279.123669) (xy 131.608381 -279.070965) (xy 131.624091 -279.020035) (xy 131.647217 -278.972014)
			(xy 131.677241 -278.927977) (xy 131.713493 -278.888906) (xy 131.755164 -278.855675) (xy 131.801322 -278.829026)
			(xy 131.850936 -278.809554) (xy 131.902898 -278.797694) (xy 131.956048 -278.793711) (xy 132.009198 -278.797694)
			(xy 132.06116 -278.809554) (xy 132.110774 -278.829026) (xy 132.156932 -278.855675) (xy 132.198603 -278.888906)
			(xy 132.234855 -278.927977) (xy 132.264879 -278.972014) (xy 132.288005 -279.020035) (xy 132.303715 -279.070965)
			(xy 132.311658 -279.123669) (xy 132.312156 -279.150318) (xy 132.311658 -279.176967) (xy 133.479784 -279.176967)
			(xy 133.479784 -279.123669) (xy 133.487727 -279.070965) (xy 133.503437 -279.020035) (xy 133.526563 -278.972014)
			(xy 133.556587 -278.927977) (xy 133.592839 -278.888906) (xy 133.63451 -278.855675) (xy 133.680668 -278.829026)
			(xy 133.730282 -278.809554) (xy 133.782244 -278.797694) (xy 133.835394 -278.793711) (xy 133.888544 -278.797694)
			(xy 133.940506 -278.809554) (xy 133.99012 -278.829026) (xy 134.036278 -278.855675) (xy 134.077949 -278.888906)
			(xy 134.114201 -278.927977) (xy 134.144225 -278.972014) (xy 134.167351 -279.020035) (xy 134.183061 -279.070965)
			(xy 134.191004 -279.123669) (xy 134.191502 -279.150318) (xy 134.191004 -279.176967) (xy 134.183061 -279.229671)
			(xy 134.167351 -279.280601) (xy 134.144225 -279.328622) (xy 134.114201 -279.372659) (xy 134.077949 -279.41173)
			(xy 134.036278 -279.444961) (xy 133.99012 -279.47161) (xy 133.940506 -279.491082) (xy 133.888544 -279.502942)
			(xy 133.835394 -279.506926) (xy 133.782244 -279.502942) (xy 133.730282 -279.491082) (xy 133.680668 -279.47161)
			(xy 133.63451 -279.444961) (xy 133.592839 -279.41173) (xy 133.556587 -279.372659) (xy 133.526563 -279.328622)
			(xy 133.503437 -279.280601) (xy 133.487727 -279.229671) (xy 133.479784 -279.176967) (xy 132.311658 -279.176967)
			(xy 132.303715 -279.229671) (xy 132.288005 -279.280601) (xy 132.264879 -279.328622) (xy 132.234855 -279.372659)
			(xy 132.198603 -279.41173) (xy 132.156932 -279.444961) (xy 132.110774 -279.47161) (xy 132.06116 -279.491082)
			(xy 132.009198 -279.502942) (xy 131.956048 -279.506926) (xy 131.902898 -279.502942) (xy 131.850936 -279.491082)
			(xy 131.801322 -279.47161) (xy 131.755164 -279.444961) (xy 131.713493 -279.41173) (xy 131.677241 -279.372659)
			(xy 131.647217 -279.328622) (xy 131.624091 -279.280601) (xy 131.608381 -279.229671) (xy 131.600438 -279.176967)
			(xy 131.371604 -279.176967) (xy 131.363661 -279.229671) (xy 131.347951 -279.280601) (xy 131.324825 -279.328622)
			(xy 131.294801 -279.372659) (xy 131.258549 -279.41173) (xy 131.216878 -279.444961) (xy 131.17072 -279.47161)
			(xy 131.121106 -279.491082) (xy 131.069144 -279.502942) (xy 131.015994 -279.506926) (xy 130.962844 -279.502942)
			(xy 130.910882 -279.491082) (xy 130.861268 -279.47161) (xy 130.81511 -279.444961) (xy 130.773439 -279.41173)
			(xy 130.737187 -279.372659) (xy 130.707163 -279.328622) (xy 130.684037 -279.280601) (xy 130.668327 -279.229671)
			(xy 130.660384 -279.176967) (xy 130.432058 -279.176967) (xy 130.424115 -279.229671) (xy 130.408405 -279.280601)
			(xy 130.385279 -279.328622) (xy 130.355255 -279.372659) (xy 130.319003 -279.41173) (xy 130.277332 -279.444961)
			(xy 130.231174 -279.47161) (xy 130.18156 -279.491082) (xy 130.129598 -279.502942) (xy 130.076448 -279.506926)
			(xy 130.023298 -279.502942) (xy 129.971336 -279.491082) (xy 129.921722 -279.47161) (xy 129.875564 -279.444961)
			(xy 129.833893 -279.41173) (xy 129.797641 -279.372659) (xy 129.767617 -279.328622) (xy 129.744491 -279.280601)
			(xy 129.728781 -279.229671) (xy 129.720838 -279.176967) (xy 129.492004 -279.176967) (xy 129.484061 -279.229671)
			(xy 129.468351 -279.280601) (xy 129.445225 -279.328622) (xy 129.415201 -279.372659) (xy 129.378949 -279.41173)
			(xy 129.337278 -279.444961) (xy 129.29112 -279.47161) (xy 129.241506 -279.491082) (xy 129.189544 -279.502942)
			(xy 129.136394 -279.506926) (xy 129.083244 -279.502942) (xy 129.031282 -279.491082) (xy 128.981668 -279.47161)
			(xy 128.93551 -279.444961) (xy 128.893839 -279.41173) (xy 128.857587 -279.372659) (xy 128.827563 -279.328622)
			(xy 128.804437 -279.280601) (xy 128.788727 -279.229671) (xy 128.780784 -279.176967) (xy 128.552204 -279.176967)
			(xy 128.544261 -279.229671) (xy 128.528551 -279.280601) (xy 128.505425 -279.328622) (xy 128.475401 -279.372659)
			(xy 128.439149 -279.41173) (xy 128.397478 -279.444961) (xy 128.35132 -279.47161) (xy 128.301706 -279.491082)
			(xy 128.249744 -279.502942) (xy 128.196594 -279.506926) (xy 128.143444 -279.502942) (xy 128.091482 -279.491082)
			(xy 128.041868 -279.47161) (xy 127.99571 -279.444961) (xy 127.954039 -279.41173) (xy 127.917787 -279.372659)
			(xy 127.887763 -279.328622) (xy 127.864637 -279.280601) (xy 127.848927 -279.229671) (xy 127.840984 -279.176967)
			(xy 127.612404 -279.176967) (xy 127.604461 -279.229671) (xy 127.588751 -279.280601) (xy 127.565625 -279.328622)
			(xy 127.535601 -279.372659) (xy 127.499349 -279.41173) (xy 127.457678 -279.444961) (xy 127.41152 -279.47161)
			(xy 127.361906 -279.491082) (xy 127.309944 -279.502942) (xy 127.256794 -279.506926) (xy 127.203644 -279.502942)
			(xy 127.151682 -279.491082) (xy 127.102068 -279.47161) (xy 127.05591 -279.444961) (xy 127.014239 -279.41173)
			(xy 126.977987 -279.372659) (xy 126.947963 -279.328622) (xy 126.924837 -279.280601) (xy 126.909127 -279.229671)
			(xy 126.901184 -279.176967) (xy 126.672604 -279.176967) (xy 126.664661 -279.229671) (xy 126.648951 -279.280601)
			(xy 126.625825 -279.328622) (xy 126.595801 -279.372659) (xy 126.559549 -279.41173) (xy 126.517878 -279.444961)
			(xy 126.47172 -279.47161) (xy 126.422106 -279.491082) (xy 126.370144 -279.502942) (xy 126.316994 -279.506926)
			(xy 126.263844 -279.502942) (xy 126.211882 -279.491082) (xy 126.162268 -279.47161) (xy 126.11611 -279.444961)
			(xy 126.074439 -279.41173) (xy 126.038187 -279.372659) (xy 126.008163 -279.328622) (xy 125.985037 -279.280601)
			(xy 125.969327 -279.229671) (xy 125.961384 -279.176967) (xy 125.732804 -279.176967) (xy 125.724861 -279.229671)
			(xy 125.709151 -279.280601) (xy 125.686025 -279.328622) (xy 125.656001 -279.372659) (xy 125.619749 -279.41173)
			(xy 125.578078 -279.444961) (xy 125.53192 -279.47161) (xy 125.482306 -279.491082) (xy 125.430344 -279.502942)
			(xy 125.377194 -279.506926) (xy 125.324044 -279.502942) (xy 125.272082 -279.491082) (xy 125.222468 -279.47161)
			(xy 125.17631 -279.444961) (xy 125.134639 -279.41173) (xy 125.098387 -279.372659) (xy 125.068363 -279.328622)
			(xy 125.045237 -279.280601) (xy 125.029527 -279.229671) (xy 125.021584 -279.176967) (xy 124.793004 -279.176967)
			(xy 124.785061 -279.229671) (xy 124.769351 -279.280601) (xy 124.746225 -279.328622) (xy 124.716201 -279.372659)
			(xy 124.679949 -279.41173) (xy 124.638278 -279.444961) (xy 124.59212 -279.47161) (xy 124.542506 -279.491082)
			(xy 124.490544 -279.502942) (xy 124.437394 -279.506926) (xy 124.384244 -279.502942) (xy 124.332282 -279.491082)
			(xy 124.282668 -279.47161) (xy 124.23651 -279.444961) (xy 124.194839 -279.41173) (xy 124.158587 -279.372659)
			(xy 124.128563 -279.328622) (xy 124.105437 -279.280601) (xy 124.089727 -279.229671) (xy 124.081784 -279.176967)
			(xy 123.853458 -279.176967) (xy 123.845515 -279.229671) (xy 123.829805 -279.280601) (xy 123.806679 -279.328622)
			(xy 123.776655 -279.372659) (xy 123.740403 -279.41173) (xy 123.698732 -279.444961) (xy 123.652574 -279.47161)
			(xy 123.60296 -279.491082) (xy 123.550998 -279.502942) (xy 123.497848 -279.506926) (xy 123.444698 -279.502942)
			(xy 123.392736 -279.491082) (xy 123.343122 -279.47161) (xy 123.296964 -279.444961) (xy 123.255293 -279.41173)
			(xy 123.219041 -279.372659) (xy 123.189017 -279.328622) (xy 123.165891 -279.280601) (xy 123.150181 -279.229671)
			(xy 123.142238 -279.176967) (xy 122.913404 -279.176967) (xy 122.905461 -279.229671) (xy 122.889751 -279.280601)
			(xy 122.866625 -279.328622) (xy 122.836601 -279.372659) (xy 122.800349 -279.41173) (xy 122.758678 -279.444961)
			(xy 122.71252 -279.47161) (xy 122.662906 -279.491082) (xy 122.610944 -279.502942) (xy 122.557794 -279.506926)
			(xy 122.504644 -279.502942) (xy 122.452682 -279.491082) (xy 122.403068 -279.47161) (xy 122.35691 -279.444961)
			(xy 122.315239 -279.41173) (xy 122.278987 -279.372659) (xy 122.248963 -279.328622) (xy 122.225837 -279.280601)
			(xy 122.210127 -279.229671) (xy 122.202184 -279.176967) (xy 121.973604 -279.176967) (xy 121.965661 -279.229671)
			(xy 121.949951 -279.280601) (xy 121.926825 -279.328622) (xy 121.896801 -279.372659) (xy 121.860549 -279.41173)
			(xy 121.818878 -279.444961) (xy 121.77272 -279.47161) (xy 121.723106 -279.491082) (xy 121.671144 -279.502942)
			(xy 121.617994 -279.506926) (xy 121.564844 -279.502942) (xy 121.512882 -279.491082) (xy 121.463268 -279.47161)
			(xy 121.41711 -279.444961) (xy 121.375439 -279.41173) (xy 121.339187 -279.372659) (xy 121.309163 -279.328622)
			(xy 121.286037 -279.280601) (xy 121.270327 -279.229671) (xy 121.262384 -279.176967) (xy 121.034058 -279.176967)
			(xy 121.026115 -279.229671) (xy 121.010405 -279.280601) (xy 120.987279 -279.328622) (xy 120.957255 -279.372659)
			(xy 120.921003 -279.41173) (xy 120.879332 -279.444961) (xy 120.833174 -279.47161) (xy 120.78356 -279.491082)
			(xy 120.731598 -279.502942) (xy 120.678448 -279.506926) (xy 120.625298 -279.502942) (xy 120.573336 -279.491082)
			(xy 120.523722 -279.47161) (xy 120.477564 -279.444961) (xy 120.435893 -279.41173) (xy 120.399641 -279.372659)
			(xy 120.369617 -279.328622) (xy 120.346491 -279.280601) (xy 120.330781 -279.229671) (xy 120.322838 -279.176967)
			(xy 120.094004 -279.176967) (xy 120.086061 -279.229671) (xy 120.070351 -279.280601) (xy 120.047225 -279.328622)
			(xy 120.017201 -279.372659) (xy 119.980949 -279.41173) (xy 119.939278 -279.444961) (xy 119.89312 -279.47161)
			(xy 119.843506 -279.491082) (xy 119.791544 -279.502942) (xy 119.738394 -279.506926) (xy 119.685244 -279.502942)
			(xy 119.633282 -279.491082) (xy 119.583668 -279.47161) (xy 119.53751 -279.444961) (xy 119.495839 -279.41173)
			(xy 119.459587 -279.372659) (xy 119.429563 -279.328622) (xy 119.406437 -279.280601) (xy 119.390727 -279.229671)
			(xy 119.382784 -279.176967) (xy 118.214658 -279.176967) (xy 118.206715 -279.229671) (xy 118.191005 -279.280601)
			(xy 118.167879 -279.328622) (xy 118.137855 -279.372659) (xy 118.101603 -279.41173) (xy 118.059932 -279.444961)
			(xy 118.013774 -279.47161) (xy 117.96416 -279.491082) (xy 117.912198 -279.502942) (xy 117.859048 -279.506926)
			(xy 117.805898 -279.502942) (xy 117.753936 -279.491082) (xy 117.704322 -279.47161) (xy 117.658164 -279.444961)
			(xy 117.616493 -279.41173) (xy 117.580241 -279.372659) (xy 117.550217 -279.328622) (xy 117.527091 -279.280601)
			(xy 117.511381 -279.229671) (xy 117.503438 -279.176967) (xy 117.274857 -279.176967) (xy 117.274854 -279.177121)
			(xy 117.266666 -279.230613) (xy 117.250473 -279.282248) (xy 117.22665 -279.330836) (xy 117.195744 -279.375257)
			(xy 117.158469 -279.414486) (xy 117.115685 -279.44762) (xy 117.068377 -279.473893) (xy 117.0432 -279.48382)
			(xy 117.01018 -279.496266) (xy 117.01018 -279.990783) (xy 117.973084 -279.990783) (xy 117.973084 -279.937485)
			(xy 117.981027 -279.884781) (xy 117.996737 -279.833851) (xy 118.019863 -279.78583) (xy 118.049887 -279.741793)
			(xy 118.086139 -279.702722) (xy 118.12781 -279.669491) (xy 118.173968 -279.642842) (xy 118.223582 -279.62337)
			(xy 118.275544 -279.61151) (xy 118.328694 -279.607527) (xy 118.381844 -279.61151) (xy 118.433806 -279.62337)
			(xy 118.48342 -279.642842) (xy 118.529578 -279.669491) (xy 118.571249 -279.702722) (xy 118.607501 -279.741793)
			(xy 118.637525 -279.78583) (xy 118.660651 -279.833851) (xy 118.676361 -279.884781) (xy 118.684304 -279.937485)
			(xy 118.684802 -279.964134) (xy 118.684304 -279.990783) (xy 118.913138 -279.990783) (xy 118.913138 -279.937485)
			(xy 118.921081 -279.884781) (xy 118.936791 -279.833851) (xy 118.959917 -279.78583) (xy 118.989941 -279.741793)
			(xy 119.026193 -279.702722) (xy 119.067864 -279.669491) (xy 119.114022 -279.642842) (xy 119.163636 -279.62337)
			(xy 119.215598 -279.61151) (xy 119.268748 -279.607527) (xy 119.321898 -279.61151) (xy 119.37386 -279.62337)
			(xy 119.423474 -279.642842) (xy 119.469632 -279.669491) (xy 119.511303 -279.702722) (xy 119.547555 -279.741793)
			(xy 119.577579 -279.78583) (xy 119.600705 -279.833851) (xy 119.616415 -279.884781) (xy 119.624358 -279.937485)
			(xy 119.624856 -279.964134) (xy 119.624358 -279.990783) (xy 119.852938 -279.990783) (xy 119.852938 -279.937485)
			(xy 119.860881 -279.884781) (xy 119.876591 -279.833851) (xy 119.899717 -279.78583) (xy 119.929741 -279.741793)
			(xy 119.965993 -279.702722) (xy 120.007664 -279.669491) (xy 120.053822 -279.642842) (xy 120.103436 -279.62337)
			(xy 120.155398 -279.61151) (xy 120.208548 -279.607527) (xy 120.261698 -279.61151) (xy 120.31366 -279.62337)
			(xy 120.363274 -279.642842) (xy 120.409432 -279.669491) (xy 120.451103 -279.702722) (xy 120.487355 -279.741793)
			(xy 120.517379 -279.78583) (xy 120.540505 -279.833851) (xy 120.556215 -279.884781) (xy 120.564158 -279.937485)
			(xy 120.564656 -279.964134) (xy 120.564158 -279.990783) (xy 120.792738 -279.990783) (xy 120.792738 -279.937485)
			(xy 120.800681 -279.884781) (xy 120.816391 -279.833851) (xy 120.839517 -279.78583) (xy 120.869541 -279.741793)
			(xy 120.905793 -279.702722) (xy 120.947464 -279.669491) (xy 120.993622 -279.642842) (xy 121.043236 -279.62337)
			(xy 121.095198 -279.61151) (xy 121.148348 -279.607527) (xy 121.201498 -279.61151) (xy 121.25346 -279.62337)
			(xy 121.303074 -279.642842) (xy 121.349232 -279.669491) (xy 121.390903 -279.702722) (xy 121.427155 -279.741793)
			(xy 121.457179 -279.78583) (xy 121.480305 -279.833851) (xy 121.496015 -279.884781) (xy 121.503958 -279.937485)
			(xy 121.504456 -279.964134) (xy 121.503958 -279.990783) (xy 122.672338 -279.990783) (xy 122.672338 -279.937485)
			(xy 122.680281 -279.884781) (xy 122.695991 -279.833851) (xy 122.719117 -279.78583) (xy 122.749141 -279.741793)
			(xy 122.785393 -279.702722) (xy 122.827064 -279.669491) (xy 122.873222 -279.642842) (xy 122.922836 -279.62337)
			(xy 122.974798 -279.61151) (xy 123.027948 -279.607527) (xy 123.081098 -279.61151) (xy 123.13306 -279.62337)
			(xy 123.182674 -279.642842) (xy 123.228832 -279.669491) (xy 123.270503 -279.702722) (xy 123.306755 -279.741793)
			(xy 123.336779 -279.78583) (xy 123.359905 -279.833851) (xy 123.375615 -279.884781) (xy 123.383558 -279.937485)
			(xy 123.384056 -279.964134) (xy 123.383558 -279.990783) (xy 123.611884 -279.990783) (xy 123.611884 -279.937485)
			(xy 123.619827 -279.884781) (xy 123.635537 -279.833851) (xy 123.658663 -279.78583) (xy 123.688687 -279.741793)
			(xy 123.724939 -279.702722) (xy 123.76661 -279.669491) (xy 123.812768 -279.642842) (xy 123.862382 -279.62337)
			(xy 123.914344 -279.61151) (xy 123.967494 -279.607527) (xy 124.020644 -279.61151) (xy 124.072606 -279.62337)
			(xy 124.12222 -279.642842) (xy 124.168378 -279.669491) (xy 124.210049 -279.702722) (xy 124.246301 -279.741793)
			(xy 124.276325 -279.78583) (xy 124.299451 -279.833851) (xy 124.315161 -279.884781) (xy 124.323104 -279.937485)
			(xy 124.323602 -279.964134) (xy 124.323104 -279.990783) (xy 124.551938 -279.990783) (xy 124.551938 -279.937485)
			(xy 124.559881 -279.884781) (xy 124.575591 -279.833851) (xy 124.598717 -279.78583) (xy 124.628741 -279.741793)
			(xy 124.664993 -279.702722) (xy 124.706664 -279.669491) (xy 124.752822 -279.642842) (xy 124.802436 -279.62337)
			(xy 124.854398 -279.61151) (xy 124.907548 -279.607527) (xy 124.960698 -279.61151) (xy 125.01266 -279.62337)
			(xy 125.062274 -279.642842) (xy 125.108432 -279.669491) (xy 125.150103 -279.702722) (xy 125.186355 -279.741793)
			(xy 125.216379 -279.78583) (xy 125.239505 -279.833851) (xy 125.255215 -279.884781) (xy 125.263158 -279.937485)
			(xy 125.263656 -279.964134) (xy 125.263158 -279.990783) (xy 125.491738 -279.990783) (xy 125.491738 -279.937485)
			(xy 125.499681 -279.884781) (xy 125.515391 -279.833851) (xy 125.538517 -279.78583) (xy 125.568541 -279.741793)
			(xy 125.604793 -279.702722) (xy 125.646464 -279.669491) (xy 125.692622 -279.642842) (xy 125.742236 -279.62337)
			(xy 125.794198 -279.61151) (xy 125.847348 -279.607527) (xy 125.900498 -279.61151) (xy 125.95246 -279.62337)
			(xy 126.002074 -279.642842) (xy 126.048232 -279.669491) (xy 126.089903 -279.702722) (xy 126.126155 -279.741793)
			(xy 126.156179 -279.78583) (xy 126.179305 -279.833851) (xy 126.195015 -279.884781) (xy 126.202958 -279.937485)
			(xy 126.203456 -279.964134) (xy 126.202958 -279.990783) (xy 126.431284 -279.990783) (xy 126.431284 -279.937485)
			(xy 126.439227 -279.884781) (xy 126.454937 -279.833851) (xy 126.478063 -279.78583) (xy 126.508087 -279.741793)
			(xy 126.544339 -279.702722) (xy 126.58601 -279.669491) (xy 126.632168 -279.642842) (xy 126.681782 -279.62337)
			(xy 126.733744 -279.61151) (xy 126.786894 -279.607527) (xy 126.840044 -279.61151) (xy 126.892006 -279.62337)
			(xy 126.94162 -279.642842) (xy 126.987778 -279.669491) (xy 127.029449 -279.702722) (xy 127.065701 -279.741793)
			(xy 127.095725 -279.78583) (xy 127.118851 -279.833851) (xy 127.134561 -279.884781) (xy 127.142504 -279.937485)
			(xy 127.143002 -279.964134) (xy 127.142504 -279.990783) (xy 127.371338 -279.990783) (xy 127.371338 -279.937485)
			(xy 127.379281 -279.884781) (xy 127.394991 -279.833851) (xy 127.418117 -279.78583) (xy 127.448141 -279.741793)
			(xy 127.484393 -279.702722) (xy 127.526064 -279.669491) (xy 127.572222 -279.642842) (xy 127.621836 -279.62337)
			(xy 127.673798 -279.61151) (xy 127.726948 -279.607527) (xy 127.780098 -279.61151) (xy 127.83206 -279.62337)
			(xy 127.881674 -279.642842) (xy 127.927832 -279.669491) (xy 127.969503 -279.702722) (xy 128.005755 -279.741793)
			(xy 128.035779 -279.78583) (xy 128.058905 -279.833851) (xy 128.074615 -279.884781) (xy 128.082558 -279.937485)
			(xy 128.083056 -279.964134) (xy 128.082563 -279.990529) (xy 128.310884 -279.990529) (xy 128.310884 -279.937231)
			(xy 128.318827 -279.884527) (xy 128.334537 -279.833597) (xy 128.357663 -279.785576) (xy 128.387687 -279.741539)
			(xy 128.423939 -279.702468) (xy 128.46561 -279.669237) (xy 128.511768 -279.642588) (xy 128.561382 -279.623116)
			(xy 128.613344 -279.611256) (xy 128.666494 -279.607273) (xy 128.719644 -279.611256) (xy 128.771606 -279.623116)
			(xy 128.82122 -279.642588) (xy 128.867378 -279.669237) (xy 128.909049 -279.702468) (xy 128.945301 -279.741539)
			(xy 128.975325 -279.785576) (xy 128.998451 -279.833597) (xy 129.014161 -279.884527) (xy 129.022104 -279.937231)
			(xy 129.022602 -279.96388) (xy 129.022104 -279.990529) (xy 129.022066 -279.990783) (xy 130.190738 -279.990783)
			(xy 130.190738 -279.937485) (xy 130.198681 -279.884781) (xy 130.214391 -279.833851) (xy 130.237517 -279.78583)
			(xy 130.267541 -279.741793) (xy 130.303793 -279.702722) (xy 130.345464 -279.669491) (xy 130.391622 -279.642842)
			(xy 130.441236 -279.62337) (xy 130.493198 -279.61151) (xy 130.546348 -279.607527) (xy 130.599498 -279.61151)
			(xy 130.65146 -279.62337) (xy 130.701074 -279.642842) (xy 130.747232 -279.669491) (xy 130.788903 -279.702722)
			(xy 130.825155 -279.741793) (xy 130.855179 -279.78583) (xy 130.878305 -279.833851) (xy 130.894015 -279.884781)
			(xy 130.901958 -279.937485) (xy 130.902456 -279.964134) (xy 130.901958 -279.990783) (xy 131.130538 -279.990783)
			(xy 131.130538 -279.937485) (xy 131.138481 -279.884781) (xy 131.154191 -279.833851) (xy 131.177317 -279.78583)
			(xy 131.207341 -279.741793) (xy 131.243593 -279.702722) (xy 131.285264 -279.669491) (xy 131.331422 -279.642842)
			(xy 131.381036 -279.62337) (xy 131.432998 -279.61151) (xy 131.486148 -279.607527) (xy 131.539298 -279.61151)
			(xy 131.59126 -279.62337) (xy 131.640874 -279.642842) (xy 131.687032 -279.669491) (xy 131.728703 -279.702722)
			(xy 131.764955 -279.741793) (xy 131.794979 -279.78583) (xy 131.818105 -279.833851) (xy 131.833815 -279.884781)
			(xy 131.841758 -279.937485) (xy 131.842256 -279.964134) (xy 131.841758 -279.990783) (xy 132.070084 -279.990783)
			(xy 132.070084 -279.937485) (xy 132.078027 -279.884781) (xy 132.093737 -279.833851) (xy 132.116863 -279.78583)
			(xy 132.146887 -279.741793) (xy 132.183139 -279.702722) (xy 132.22481 -279.669491) (xy 132.270968 -279.642842)
			(xy 132.320582 -279.62337) (xy 132.372544 -279.61151) (xy 132.425694 -279.607527) (xy 132.478844 -279.61151)
			(xy 132.530806 -279.62337) (xy 132.58042 -279.642842) (xy 132.626578 -279.669491) (xy 132.668249 -279.702722)
			(xy 132.704501 -279.741793) (xy 132.734525 -279.78583) (xy 132.757651 -279.833851) (xy 132.773361 -279.884781)
			(xy 132.781304 -279.937485) (xy 132.781802 -279.964134) (xy 132.781304 -279.990783) (xy 134.88923 -279.990783)
			(xy 134.88923 -279.937485) (xy 134.897173 -279.884781) (xy 134.912883 -279.833851) (xy 134.936009 -279.78583)
			(xy 134.966033 -279.741793) (xy 135.002285 -279.702722) (xy 135.043956 -279.669491) (xy 135.090114 -279.642842)
			(xy 135.139728 -279.62337) (xy 135.19169 -279.61151) (xy 135.24484 -279.607527) (xy 135.29799 -279.61151)
			(xy 135.349952 -279.62337) (xy 135.399566 -279.642842) (xy 135.445724 -279.669491) (xy 135.487395 -279.702722)
			(xy 135.523647 -279.741793) (xy 135.553671 -279.78583) (xy 135.576797 -279.833851) (xy 135.592507 -279.884781)
			(xy 135.60045 -279.937485) (xy 135.600948 -279.964134) (xy 135.60045 -279.990783) (xy 135.592507 -280.043487)
			(xy 135.576797 -280.094417) (xy 135.553671 -280.142438) (xy 135.523647 -280.186475) (xy 135.487395 -280.225546)
			(xy 135.445724 -280.258777) (xy 135.399566 -280.285426) (xy 135.349952 -280.304898) (xy 135.29799 -280.316758)
			(xy 135.24484 -280.320742) (xy 135.19169 -280.316758) (xy 135.139728 -280.304898) (xy 135.090114 -280.285426)
			(xy 135.043956 -280.258777) (xy 135.002285 -280.225546) (xy 134.966033 -280.186475) (xy 134.936009 -280.142438)
			(xy 134.912883 -280.094417) (xy 134.897173 -280.043487) (xy 134.88923 -279.990783) (xy 132.781304 -279.990783)
			(xy 132.773361 -280.043487) (xy 132.757651 -280.094417) (xy 132.734525 -280.142438) (xy 132.704501 -280.186475)
			(xy 132.668249 -280.225546) (xy 132.626578 -280.258777) (xy 132.58042 -280.285426) (xy 132.530806 -280.304898)
			(xy 132.478844 -280.316758) (xy 132.425694 -280.320742) (xy 132.372544 -280.316758) (xy 132.320582 -280.304898)
			(xy 132.270968 -280.285426) (xy 132.22481 -280.258777) (xy 132.183139 -280.225546) (xy 132.146887 -280.186475)
			(xy 132.116863 -280.142438) (xy 132.093737 -280.094417) (xy 132.078027 -280.043487) (xy 132.070084 -279.990783)
			(xy 131.841758 -279.990783) (xy 131.833815 -280.043487) (xy 131.818105 -280.094417) (xy 131.794979 -280.142438)
			(xy 131.764955 -280.186475) (xy 131.728703 -280.225546) (xy 131.687032 -280.258777) (xy 131.640874 -280.285426)
			(xy 131.59126 -280.304898) (xy 131.539298 -280.316758) (xy 131.486148 -280.320742) (xy 131.432998 -280.316758)
			(xy 131.381036 -280.304898) (xy 131.331422 -280.285426) (xy 131.285264 -280.258777) (xy 131.243593 -280.225546)
			(xy 131.207341 -280.186475) (xy 131.177317 -280.142438) (xy 131.154191 -280.094417) (xy 131.138481 -280.043487)
			(xy 131.130538 -279.990783) (xy 130.901958 -279.990783) (xy 130.894015 -280.043487) (xy 130.878305 -280.094417)
			(xy 130.855179 -280.142438) (xy 130.825155 -280.186475) (xy 130.788903 -280.225546) (xy 130.747232 -280.258777)
			(xy 130.701074 -280.285426) (xy 130.65146 -280.304898) (xy 130.599498 -280.316758) (xy 130.546348 -280.320742)
			(xy 130.493198 -280.316758) (xy 130.441236 -280.304898) (xy 130.391622 -280.285426) (xy 130.345464 -280.258777)
			(xy 130.303793 -280.225546) (xy 130.267541 -280.186475) (xy 130.237517 -280.142438) (xy 130.214391 -280.094417)
			(xy 130.198681 -280.043487) (xy 130.190738 -279.990783) (xy 129.022066 -279.990783) (xy 129.014161 -280.043233)
			(xy 128.998451 -280.094163) (xy 128.975325 -280.142184) (xy 128.945301 -280.186221) (xy 128.909049 -280.225292)
			(xy 128.867378 -280.258523) (xy 128.82122 -280.285172) (xy 128.771606 -280.304644) (xy 128.719644 -280.316504)
			(xy 128.666494 -280.320488) (xy 128.613344 -280.316504) (xy 128.561382 -280.304644) (xy 128.511768 -280.285172)
			(xy 128.46561 -280.258523) (xy 128.423939 -280.225292) (xy 128.387687 -280.186221) (xy 128.357663 -280.142184)
			(xy 128.334537 -280.094163) (xy 128.318827 -280.043233) (xy 128.310884 -279.990529) (xy 128.082563 -279.990529)
			(xy 128.082558 -279.990783) (xy 128.074615 -280.043487) (xy 128.058905 -280.094417) (xy 128.035779 -280.142438)
			(xy 128.005755 -280.186475) (xy 127.969503 -280.225546) (xy 127.927832 -280.258777) (xy 127.881674 -280.285426)
			(xy 127.83206 -280.304898) (xy 127.780098 -280.316758) (xy 127.726948 -280.320742) (xy 127.673798 -280.316758)
			(xy 127.621836 -280.304898) (xy 127.572222 -280.285426) (xy 127.526064 -280.258777) (xy 127.484393 -280.225546)
			(xy 127.448141 -280.186475) (xy 127.418117 -280.142438) (xy 127.394991 -280.094417) (xy 127.379281 -280.043487)
			(xy 127.371338 -279.990783) (xy 127.142504 -279.990783) (xy 127.134561 -280.043487) (xy 127.118851 -280.094417)
			(xy 127.095725 -280.142438) (xy 127.065701 -280.186475) (xy 127.029449 -280.225546) (xy 126.987778 -280.258777)
			(xy 126.94162 -280.285426) (xy 126.892006 -280.304898) (xy 126.840044 -280.316758) (xy 126.786894 -280.320742)
			(xy 126.733744 -280.316758) (xy 126.681782 -280.304898) (xy 126.632168 -280.285426) (xy 126.58601 -280.258777)
			(xy 126.544339 -280.225546) (xy 126.508087 -280.186475) (xy 126.478063 -280.142438) (xy 126.454937 -280.094417)
			(xy 126.439227 -280.043487) (xy 126.431284 -279.990783) (xy 126.202958 -279.990783) (xy 126.195015 -280.043487)
			(xy 126.179305 -280.094417) (xy 126.156179 -280.142438) (xy 126.126155 -280.186475) (xy 126.089903 -280.225546)
			(xy 126.048232 -280.258777) (xy 126.002074 -280.285426) (xy 125.95246 -280.304898) (xy 125.900498 -280.316758)
			(xy 125.847348 -280.320742) (xy 125.794198 -280.316758) (xy 125.742236 -280.304898) (xy 125.692622 -280.285426)
			(xy 125.646464 -280.258777) (xy 125.604793 -280.225546) (xy 125.568541 -280.186475) (xy 125.538517 -280.142438)
			(xy 125.515391 -280.094417) (xy 125.499681 -280.043487) (xy 125.491738 -279.990783) (xy 125.263158 -279.990783)
			(xy 125.255215 -280.043487) (xy 125.239505 -280.094417) (xy 125.216379 -280.142438) (xy 125.186355 -280.186475)
			(xy 125.150103 -280.225546) (xy 125.108432 -280.258777) (xy 125.062274 -280.285426) (xy 125.01266 -280.304898)
			(xy 124.960698 -280.316758) (xy 124.907548 -280.320742) (xy 124.854398 -280.316758) (xy 124.802436 -280.304898)
			(xy 124.752822 -280.285426) (xy 124.706664 -280.258777) (xy 124.664993 -280.225546) (xy 124.628741 -280.186475)
			(xy 124.598717 -280.142438) (xy 124.575591 -280.094417) (xy 124.559881 -280.043487) (xy 124.551938 -279.990783)
			(xy 124.323104 -279.990783) (xy 124.315161 -280.043487) (xy 124.299451 -280.094417) (xy 124.276325 -280.142438)
			(xy 124.246301 -280.186475) (xy 124.210049 -280.225546) (xy 124.168378 -280.258777) (xy 124.12222 -280.285426)
			(xy 124.072606 -280.304898) (xy 124.020644 -280.316758) (xy 123.967494 -280.320742) (xy 123.914344 -280.316758)
			(xy 123.862382 -280.304898) (xy 123.812768 -280.285426) (xy 123.76661 -280.258777) (xy 123.724939 -280.225546)
			(xy 123.688687 -280.186475) (xy 123.658663 -280.142438) (xy 123.635537 -280.094417) (xy 123.619827 -280.043487)
			(xy 123.611884 -279.990783) (xy 123.383558 -279.990783) (xy 123.375615 -280.043487) (xy 123.359905 -280.094417)
			(xy 123.336779 -280.142438) (xy 123.306755 -280.186475) (xy 123.270503 -280.225546) (xy 123.228832 -280.258777)
			(xy 123.182674 -280.285426) (xy 123.13306 -280.304898) (xy 123.081098 -280.316758) (xy 123.027948 -280.320742)
			(xy 122.974798 -280.316758) (xy 122.922836 -280.304898) (xy 122.873222 -280.285426) (xy 122.827064 -280.258777)
			(xy 122.785393 -280.225546) (xy 122.749141 -280.186475) (xy 122.719117 -280.142438) (xy 122.695991 -280.094417)
			(xy 122.680281 -280.043487) (xy 122.672338 -279.990783) (xy 121.503958 -279.990783) (xy 121.496015 -280.043487)
			(xy 121.480305 -280.094417) (xy 121.457179 -280.142438) (xy 121.427155 -280.186475) (xy 121.390903 -280.225546)
			(xy 121.349232 -280.258777) (xy 121.303074 -280.285426) (xy 121.25346 -280.304898) (xy 121.201498 -280.316758)
			(xy 121.148348 -280.320742) (xy 121.095198 -280.316758) (xy 121.043236 -280.304898) (xy 120.993622 -280.285426)
			(xy 120.947464 -280.258777) (xy 120.905793 -280.225546) (xy 120.869541 -280.186475) (xy 120.839517 -280.142438)
			(xy 120.816391 -280.094417) (xy 120.800681 -280.043487) (xy 120.792738 -279.990783) (xy 120.564158 -279.990783)
			(xy 120.556215 -280.043487) (xy 120.540505 -280.094417) (xy 120.517379 -280.142438) (xy 120.487355 -280.186475)
			(xy 120.451103 -280.225546) (xy 120.409432 -280.258777) (xy 120.363274 -280.285426) (xy 120.31366 -280.304898)
			(xy 120.261698 -280.316758) (xy 120.208548 -280.320742) (xy 120.155398 -280.316758) (xy 120.103436 -280.304898)
			(xy 120.053822 -280.285426) (xy 120.007664 -280.258777) (xy 119.965993 -280.225546) (xy 119.929741 -280.186475)
			(xy 119.899717 -280.142438) (xy 119.876591 -280.094417) (xy 119.860881 -280.043487) (xy 119.852938 -279.990783)
			(xy 119.624358 -279.990783) (xy 119.616415 -280.043487) (xy 119.600705 -280.094417) (xy 119.577579 -280.142438)
			(xy 119.547555 -280.186475) (xy 119.511303 -280.225546) (xy 119.469632 -280.258777) (xy 119.423474 -280.285426)
			(xy 119.37386 -280.304898) (xy 119.321898 -280.316758) (xy 119.268748 -280.320742) (xy 119.215598 -280.316758)
			(xy 119.163636 -280.304898) (xy 119.114022 -280.285426) (xy 119.067864 -280.258777) (xy 119.026193 -280.225546)
			(xy 118.989941 -280.186475) (xy 118.959917 -280.142438) (xy 118.936791 -280.094417) (xy 118.921081 -280.043487)
			(xy 118.913138 -279.990783) (xy 118.684304 -279.990783) (xy 118.676361 -280.043487) (xy 118.660651 -280.094417)
			(xy 118.637525 -280.142438) (xy 118.607501 -280.186475) (xy 118.571249 -280.225546) (xy 118.529578 -280.258777)
			(xy 118.48342 -280.285426) (xy 118.433806 -280.304898) (xy 118.381844 -280.316758) (xy 118.328694 -280.320742)
			(xy 118.275544 -280.316758) (xy 118.223582 -280.304898) (xy 118.173968 -280.285426) (xy 118.12781 -280.258777)
			(xy 118.086139 -280.225546) (xy 118.049887 -280.186475) (xy 118.019863 -280.142438) (xy 117.996737 -280.094417)
			(xy 117.981027 -280.043487) (xy 117.973084 -279.990783) (xy 117.01018 -279.990783) (xy 117.01018 -280.432002)
			(xy 117.0432 -280.444448) (xy 117.068386 -280.454344) (xy 117.115674 -280.480647) (xy 117.158441 -280.513797)
			(xy 117.195702 -280.553035) (xy 117.226602 -280.597455) (xy 117.250429 -280.646038) (xy 117.266634 -280.697665)
			(xy 117.274847 -280.751149) (xy 117.275356 -280.778204) (xy 117.274781 -280.804853) (xy 117.503438 -280.804853)
			(xy 117.503438 -280.751555) (xy 117.511381 -280.698851) (xy 117.527091 -280.647921) (xy 117.550217 -280.5999)
			(xy 117.580241 -280.555863) (xy 117.616493 -280.516792) (xy 117.658164 -280.483561) (xy 117.704322 -280.456912)
			(xy 117.753936 -280.43744) (xy 117.805898 -280.42558) (xy 117.859048 -280.421597) (xy 117.912198 -280.42558)
			(xy 117.96416 -280.43744) (xy 118.013774 -280.456912) (xy 118.059932 -280.483561) (xy 118.101603 -280.516792)
			(xy 118.137855 -280.555863) (xy 118.167879 -280.5999) (xy 118.191005 -280.647921) (xy 118.206715 -280.698851)
			(xy 118.214658 -280.751555) (xy 118.215156 -280.778204) (xy 118.214658 -280.804853) (xy 118.442984 -280.804853)
			(xy 118.442984 -280.751555) (xy 118.450927 -280.698851) (xy 118.466637 -280.647921) (xy 118.489763 -280.5999)
			(xy 118.519787 -280.555863) (xy 118.556039 -280.516792) (xy 118.59771 -280.483561) (xy 118.643868 -280.456912)
			(xy 118.693482 -280.43744) (xy 118.745444 -280.42558) (xy 118.798594 -280.421597) (xy 118.851744 -280.42558)
			(xy 118.903706 -280.43744) (xy 118.95332 -280.456912) (xy 118.999478 -280.483561) (xy 119.041149 -280.516792)
			(xy 119.077401 -280.555863) (xy 119.107425 -280.5999) (xy 119.130551 -280.647921) (xy 119.146261 -280.698851)
			(xy 119.154204 -280.751555) (xy 119.154702 -280.778204) (xy 119.154204 -280.804853) (xy 119.382784 -280.804853)
			(xy 119.382784 -280.751555) (xy 119.390727 -280.698851) (xy 119.406437 -280.647921) (xy 119.429563 -280.5999)
			(xy 119.459587 -280.555863) (xy 119.495839 -280.516792) (xy 119.53751 -280.483561) (xy 119.583668 -280.456912)
			(xy 119.633282 -280.43744) (xy 119.685244 -280.42558) (xy 119.738394 -280.421597) (xy 119.791544 -280.42558)
			(xy 119.843506 -280.43744) (xy 119.89312 -280.456912) (xy 119.939278 -280.483561) (xy 119.980949 -280.516792)
			(xy 120.017201 -280.555863) (xy 120.047225 -280.5999) (xy 120.070351 -280.647921) (xy 120.086061 -280.698851)
			(xy 120.094004 -280.751555) (xy 120.094502 -280.778204) (xy 120.094004 -280.804853) (xy 120.322584 -280.804853)
			(xy 120.322584 -280.751555) (xy 120.330527 -280.698851) (xy 120.346237 -280.647921) (xy 120.369363 -280.5999)
			(xy 120.399387 -280.555863) (xy 120.435639 -280.516792) (xy 120.47731 -280.483561) (xy 120.523468 -280.456912)
			(xy 120.573082 -280.43744) (xy 120.625044 -280.42558) (xy 120.678194 -280.421597) (xy 120.731344 -280.42558)
			(xy 120.783306 -280.43744) (xy 120.83292 -280.456912) (xy 120.879078 -280.483561) (xy 120.920749 -280.516792)
			(xy 120.957001 -280.555863) (xy 120.987025 -280.5999) (xy 121.010151 -280.647921) (xy 121.025861 -280.698851)
			(xy 121.033804 -280.751555) (xy 121.034302 -280.778204) (xy 121.033804 -280.804853) (xy 121.262384 -280.804853)
			(xy 121.262384 -280.751555) (xy 121.270327 -280.698851) (xy 121.286037 -280.647921) (xy 121.309163 -280.5999)
			(xy 121.339187 -280.555863) (xy 121.375439 -280.516792) (xy 121.41711 -280.483561) (xy 121.463268 -280.456912)
			(xy 121.512882 -280.43744) (xy 121.564844 -280.42558) (xy 121.617994 -280.421597) (xy 121.671144 -280.42558)
			(xy 121.723106 -280.43744) (xy 121.77272 -280.456912) (xy 121.818878 -280.483561) (xy 121.860549 -280.516792)
			(xy 121.896801 -280.555863) (xy 121.926825 -280.5999) (xy 121.949951 -280.647921) (xy 121.965661 -280.698851)
			(xy 121.973604 -280.751555) (xy 121.974102 -280.778204) (xy 121.973604 -280.804853) (xy 122.202184 -280.804853)
			(xy 122.202184 -280.751555) (xy 122.210127 -280.698851) (xy 122.225837 -280.647921) (xy 122.248963 -280.5999)
			(xy 122.278987 -280.555863) (xy 122.315239 -280.516792) (xy 122.35691 -280.483561) (xy 122.403068 -280.456912)
			(xy 122.452682 -280.43744) (xy 122.504644 -280.42558) (xy 122.557794 -280.421597) (xy 122.610944 -280.42558)
			(xy 122.662906 -280.43744) (xy 122.71252 -280.456912) (xy 122.758678 -280.483561) (xy 122.800349 -280.516792)
			(xy 122.836601 -280.555863) (xy 122.866625 -280.5999) (xy 122.889751 -280.647921) (xy 122.905461 -280.698851)
			(xy 122.913404 -280.751555) (xy 122.913902 -280.778204) (xy 122.913404 -280.804853) (xy 123.141984 -280.804853)
			(xy 123.141984 -280.751555) (xy 123.149927 -280.698851) (xy 123.165637 -280.647921) (xy 123.188763 -280.5999)
			(xy 123.218787 -280.555863) (xy 123.255039 -280.516792) (xy 123.29671 -280.483561) (xy 123.342868 -280.456912)
			(xy 123.392482 -280.43744) (xy 123.444444 -280.42558) (xy 123.497594 -280.421597) (xy 123.550744 -280.42558)
			(xy 123.602706 -280.43744) (xy 123.65232 -280.456912) (xy 123.698478 -280.483561) (xy 123.740149 -280.516792)
			(xy 123.776401 -280.555863) (xy 123.806425 -280.5999) (xy 123.829551 -280.647921) (xy 123.845261 -280.698851)
			(xy 123.853204 -280.751555) (xy 123.853702 -280.778204) (xy 123.853204 -280.804853) (xy 124.081784 -280.804853)
			(xy 124.081784 -280.751555) (xy 124.089727 -280.698851) (xy 124.105437 -280.647921) (xy 124.128563 -280.5999)
			(xy 124.158587 -280.555863) (xy 124.194839 -280.516792) (xy 124.23651 -280.483561) (xy 124.282668 -280.456912)
			(xy 124.332282 -280.43744) (xy 124.384244 -280.42558) (xy 124.437394 -280.421597) (xy 124.490544 -280.42558)
			(xy 124.542506 -280.43744) (xy 124.59212 -280.456912) (xy 124.638278 -280.483561) (xy 124.679949 -280.516792)
			(xy 124.716201 -280.555863) (xy 124.746225 -280.5999) (xy 124.769351 -280.647921) (xy 124.785061 -280.698851)
			(xy 124.793004 -280.751555) (xy 124.793502 -280.778204) (xy 124.793004 -280.804853) (xy 125.021584 -280.804853)
			(xy 125.021584 -280.751555) (xy 125.029527 -280.698851) (xy 125.045237 -280.647921) (xy 125.068363 -280.5999)
			(xy 125.098387 -280.555863) (xy 125.134639 -280.516792) (xy 125.17631 -280.483561) (xy 125.222468 -280.456912)
			(xy 125.272082 -280.43744) (xy 125.324044 -280.42558) (xy 125.377194 -280.421597) (xy 125.430344 -280.42558)
			(xy 125.482306 -280.43744) (xy 125.53192 -280.456912) (xy 125.578078 -280.483561) (xy 125.619749 -280.516792)
			(xy 125.656001 -280.555863) (xy 125.686025 -280.5999) (xy 125.709151 -280.647921) (xy 125.724861 -280.698851)
			(xy 125.732804 -280.751555) (xy 125.733302 -280.778204) (xy 125.732804 -280.804853) (xy 125.961638 -280.804853)
			(xy 125.961638 -280.751555) (xy 125.969581 -280.698851) (xy 125.985291 -280.647921) (xy 126.008417 -280.5999)
			(xy 126.038441 -280.555863) (xy 126.074693 -280.516792) (xy 126.116364 -280.483561) (xy 126.162522 -280.456912)
			(xy 126.212136 -280.43744) (xy 126.264098 -280.42558) (xy 126.317248 -280.421597) (xy 126.370398 -280.42558)
			(xy 126.42236 -280.43744) (xy 126.471974 -280.456912) (xy 126.518132 -280.483561) (xy 126.559803 -280.516792)
			(xy 126.596055 -280.555863) (xy 126.626079 -280.5999) (xy 126.649205 -280.647921) (xy 126.664915 -280.698851)
			(xy 126.672858 -280.751555) (xy 126.673356 -280.778204) (xy 126.672858 -280.804853) (xy 126.901438 -280.804853)
			(xy 126.901438 -280.751555) (xy 126.909381 -280.698851) (xy 126.925091 -280.647921) (xy 126.948217 -280.5999)
			(xy 126.978241 -280.555863) (xy 127.014493 -280.516792) (xy 127.056164 -280.483561) (xy 127.102322 -280.456912)
			(xy 127.151936 -280.43744) (xy 127.203898 -280.42558) (xy 127.257048 -280.421597) (xy 127.310198 -280.42558)
			(xy 127.36216 -280.43744) (xy 127.411774 -280.456912) (xy 127.457932 -280.483561) (xy 127.499603 -280.516792)
			(xy 127.535855 -280.555863) (xy 127.565879 -280.5999) (xy 127.589005 -280.647921) (xy 127.604715 -280.698851)
			(xy 127.612658 -280.751555) (xy 127.613156 -280.778204) (xy 127.612658 -280.804853) (xy 127.841238 -280.804853)
			(xy 127.841238 -280.751555) (xy 127.849181 -280.698851) (xy 127.864891 -280.647921) (xy 127.888017 -280.5999)
			(xy 127.918041 -280.555863) (xy 127.954293 -280.516792) (xy 127.995964 -280.483561) (xy 128.042122 -280.456912)
			(xy 128.091736 -280.43744) (xy 128.143698 -280.42558) (xy 128.196848 -280.421597) (xy 128.249998 -280.42558)
			(xy 128.30196 -280.43744) (xy 128.351574 -280.456912) (xy 128.397732 -280.483561) (xy 128.439403 -280.516792)
			(xy 128.475655 -280.555863) (xy 128.505679 -280.5999) (xy 128.528805 -280.647921) (xy 128.544515 -280.698851)
			(xy 128.552458 -280.751555) (xy 128.552956 -280.778204) (xy 128.552458 -280.804853) (xy 128.781038 -280.804853)
			(xy 128.781038 -280.751555) (xy 128.788981 -280.698851) (xy 128.804691 -280.647921) (xy 128.827817 -280.5999)
			(xy 128.857841 -280.555863) (xy 128.894093 -280.516792) (xy 128.935764 -280.483561) (xy 128.981922 -280.456912)
			(xy 129.031536 -280.43744) (xy 129.083498 -280.42558) (xy 129.136648 -280.421597) (xy 129.189798 -280.42558)
			(xy 129.24176 -280.43744) (xy 129.291374 -280.456912) (xy 129.337532 -280.483561) (xy 129.379203 -280.516792)
			(xy 129.415455 -280.555863) (xy 129.445479 -280.5999) (xy 129.468605 -280.647921) (xy 129.484315 -280.698851)
			(xy 129.492258 -280.751555) (xy 129.492756 -280.778204) (xy 129.492258 -280.804853) (xy 129.720838 -280.804853)
			(xy 129.720838 -280.751555) (xy 129.728781 -280.698851) (xy 129.744491 -280.647921) (xy 129.767617 -280.5999)
			(xy 129.797641 -280.555863) (xy 129.833893 -280.516792) (xy 129.875564 -280.483561) (xy 129.921722 -280.456912)
			(xy 129.971336 -280.43744) (xy 130.023298 -280.42558) (xy 130.076448 -280.421597) (xy 130.129598 -280.42558)
			(xy 130.18156 -280.43744) (xy 130.231174 -280.456912) (xy 130.277332 -280.483561) (xy 130.319003 -280.516792)
			(xy 130.355255 -280.555863) (xy 130.385279 -280.5999) (xy 130.408405 -280.647921) (xy 130.424115 -280.698851)
			(xy 130.432058 -280.751555) (xy 130.432556 -280.778204) (xy 130.432058 -280.804853) (xy 130.660384 -280.804853)
			(xy 130.660384 -280.751555) (xy 130.668327 -280.698851) (xy 130.684037 -280.647921) (xy 130.707163 -280.5999)
			(xy 130.737187 -280.555863) (xy 130.773439 -280.516792) (xy 130.81511 -280.483561) (xy 130.861268 -280.456912)
			(xy 130.910882 -280.43744) (xy 130.962844 -280.42558) (xy 131.015994 -280.421597) (xy 131.069144 -280.42558)
			(xy 131.121106 -280.43744) (xy 131.17072 -280.456912) (xy 131.216878 -280.483561) (xy 131.258549 -280.516792)
			(xy 131.294801 -280.555863) (xy 131.324825 -280.5999) (xy 131.347951 -280.647921) (xy 131.363661 -280.698851)
			(xy 131.371604 -280.751555) (xy 131.372102 -280.778204) (xy 131.371604 -280.804853) (xy 131.600184 -280.804853)
			(xy 131.600184 -280.751555) (xy 131.608127 -280.698851) (xy 131.623837 -280.647921) (xy 131.646963 -280.5999)
			(xy 131.676987 -280.555863) (xy 131.713239 -280.516792) (xy 131.75491 -280.483561) (xy 131.801068 -280.456912)
			(xy 131.850682 -280.43744) (xy 131.902644 -280.42558) (xy 131.955794 -280.421597) (xy 132.008944 -280.42558)
			(xy 132.060906 -280.43744) (xy 132.11052 -280.456912) (xy 132.156678 -280.483561) (xy 132.198349 -280.516792)
			(xy 132.234601 -280.555863) (xy 132.264625 -280.5999) (xy 132.287751 -280.647921) (xy 132.303461 -280.698851)
			(xy 132.311404 -280.751555) (xy 132.311902 -280.778204) (xy 132.311404 -280.804853) (xy 132.539984 -280.804853)
			(xy 132.539984 -280.751555) (xy 132.547927 -280.698851) (xy 132.563637 -280.647921) (xy 132.586763 -280.5999)
			(xy 132.616787 -280.555863) (xy 132.653039 -280.516792) (xy 132.69471 -280.483561) (xy 132.740868 -280.456912)
			(xy 132.790482 -280.43744) (xy 132.842444 -280.42558) (xy 132.895594 -280.421597) (xy 132.948744 -280.42558)
			(xy 133.000706 -280.43744) (xy 133.05032 -280.456912) (xy 133.096478 -280.483561) (xy 133.138149 -280.516792)
			(xy 133.174401 -280.555863) (xy 133.204425 -280.5999) (xy 133.227551 -280.647921) (xy 133.243261 -280.698851)
			(xy 133.251204 -280.751555) (xy 133.251702 -280.778204) (xy 133.251204 -280.804853) (xy 133.479784 -280.804853)
			(xy 133.479784 -280.751555) (xy 133.487727 -280.698851) (xy 133.503437 -280.647921) (xy 133.526563 -280.5999)
			(xy 133.556587 -280.555863) (xy 133.592839 -280.516792) (xy 133.63451 -280.483561) (xy 133.680668 -280.456912)
			(xy 133.730282 -280.43744) (xy 133.782244 -280.42558) (xy 133.835394 -280.421597) (xy 133.888544 -280.42558)
			(xy 133.940506 -280.43744) (xy 133.99012 -280.456912) (xy 134.036278 -280.483561) (xy 134.077949 -280.516792)
			(xy 134.114201 -280.555863) (xy 134.144225 -280.5999) (xy 134.167351 -280.647921) (xy 134.183061 -280.698851)
			(xy 134.191004 -280.751555) (xy 134.191502 -280.778204) (xy 134.191004 -280.804853) (xy 135.359384 -280.804853)
			(xy 135.359384 -280.751555) (xy 135.367327 -280.698851) (xy 135.383037 -280.647921) (xy 135.406163 -280.5999)
			(xy 135.436187 -280.555863) (xy 135.472439 -280.516792) (xy 135.51411 -280.483561) (xy 135.560268 -280.456912)
			(xy 135.609882 -280.43744) (xy 135.661844 -280.42558) (xy 135.714994 -280.421597) (xy 135.768144 -280.42558)
			(xy 135.820106 -280.43744) (xy 135.86972 -280.456912) (xy 135.915878 -280.483561) (xy 135.957549 -280.516792)
			(xy 135.993801 -280.555863) (xy 136.023825 -280.5999) (xy 136.046951 -280.647921) (xy 136.062661 -280.698851)
			(xy 136.070604 -280.751555) (xy 136.071102 -280.778204) (xy 136.070604 -280.804853) (xy 136.062661 -280.857557)
			(xy 136.046951 -280.908487) (xy 136.023825 -280.956508) (xy 135.993801 -281.000545) (xy 135.957549 -281.039616)
			(xy 135.915878 -281.072847) (xy 135.86972 -281.099496) (xy 135.820106 -281.118968) (xy 135.768144 -281.130828)
			(xy 135.714994 -281.134812) (xy 135.661844 -281.130828) (xy 135.609882 -281.118968) (xy 135.560268 -281.099496)
			(xy 135.51411 -281.072847) (xy 135.472439 -281.039616) (xy 135.436187 -281.000545) (xy 135.406163 -280.956508)
			(xy 135.383037 -280.908487) (xy 135.367327 -280.857557) (xy 135.359384 -280.804853) (xy 134.191004 -280.804853)
			(xy 134.183061 -280.857557) (xy 134.167351 -280.908487) (xy 134.144225 -280.956508) (xy 134.114201 -281.000545)
			(xy 134.077949 -281.039616) (xy 134.036278 -281.072847) (xy 133.99012 -281.099496) (xy 133.940506 -281.118968)
			(xy 133.888544 -281.130828) (xy 133.835394 -281.134812) (xy 133.782244 -281.130828) (xy 133.730282 -281.118968)
			(xy 133.680668 -281.099496) (xy 133.63451 -281.072847) (xy 133.592839 -281.039616) (xy 133.556587 -281.000545)
			(xy 133.526563 -280.956508) (xy 133.503437 -280.908487) (xy 133.487727 -280.857557) (xy 133.479784 -280.804853)
			(xy 133.251204 -280.804853) (xy 133.243261 -280.857557) (xy 133.227551 -280.908487) (xy 133.204425 -280.956508)
			(xy 133.174401 -281.000545) (xy 133.138149 -281.039616) (xy 133.096478 -281.072847) (xy 133.05032 -281.099496)
			(xy 133.000706 -281.118968) (xy 132.948744 -281.130828) (xy 132.895594 -281.134812) (xy 132.842444 -281.130828)
			(xy 132.790482 -281.118968) (xy 132.740868 -281.099496) (xy 132.69471 -281.072847) (xy 132.653039 -281.039616)
			(xy 132.616787 -281.000545) (xy 132.586763 -280.956508) (xy 132.563637 -280.908487) (xy 132.547927 -280.857557)
			(xy 132.539984 -280.804853) (xy 132.311404 -280.804853) (xy 132.303461 -280.857557) (xy 132.287751 -280.908487)
			(xy 132.264625 -280.956508) (xy 132.234601 -281.000545) (xy 132.198349 -281.039616) (xy 132.156678 -281.072847)
			(xy 132.11052 -281.099496) (xy 132.060906 -281.118968) (xy 132.008944 -281.130828) (xy 131.955794 -281.134812)
			(xy 131.902644 -281.130828) (xy 131.850682 -281.118968) (xy 131.801068 -281.099496) (xy 131.75491 -281.072847)
			(xy 131.713239 -281.039616) (xy 131.676987 -281.000545) (xy 131.646963 -280.956508) (xy 131.623837 -280.908487)
			(xy 131.608127 -280.857557) (xy 131.600184 -280.804853) (xy 131.371604 -280.804853) (xy 131.363661 -280.857557)
			(xy 131.347951 -280.908487) (xy 131.324825 -280.956508) (xy 131.294801 -281.000545) (xy 131.258549 -281.039616)
			(xy 131.216878 -281.072847) (xy 131.17072 -281.099496) (xy 131.121106 -281.118968) (xy 131.069144 -281.130828)
			(xy 131.015994 -281.134812) (xy 130.962844 -281.130828) (xy 130.910882 -281.118968) (xy 130.861268 -281.099496)
			(xy 130.81511 -281.072847) (xy 130.773439 -281.039616) (xy 130.737187 -281.000545) (xy 130.707163 -280.956508)
			(xy 130.684037 -280.908487) (xy 130.668327 -280.857557) (xy 130.660384 -280.804853) (xy 130.432058 -280.804853)
			(xy 130.424115 -280.857557) (xy 130.408405 -280.908487) (xy 130.385279 -280.956508) (xy 130.355255 -281.000545)
			(xy 130.319003 -281.039616) (xy 130.277332 -281.072847) (xy 130.231174 -281.099496) (xy 130.18156 -281.118968)
			(xy 130.129598 -281.130828) (xy 130.076448 -281.134812) (xy 130.023298 -281.130828) (xy 129.971336 -281.118968)
			(xy 129.921722 -281.099496) (xy 129.875564 -281.072847) (xy 129.833893 -281.039616) (xy 129.797641 -281.000545)
			(xy 129.767617 -280.956508) (xy 129.744491 -280.908487) (xy 129.728781 -280.857557) (xy 129.720838 -280.804853)
			(xy 129.492258 -280.804853) (xy 129.484315 -280.857557) (xy 129.468605 -280.908487) (xy 129.445479 -280.956508)
			(xy 129.415455 -281.000545) (xy 129.379203 -281.039616) (xy 129.337532 -281.072847) (xy 129.291374 -281.099496)
			(xy 129.24176 -281.118968) (xy 129.189798 -281.130828) (xy 129.136648 -281.134812) (xy 129.083498 -281.130828)
			(xy 129.031536 -281.118968) (xy 128.981922 -281.099496) (xy 128.935764 -281.072847) (xy 128.894093 -281.039616)
			(xy 128.857841 -281.000545) (xy 128.827817 -280.956508) (xy 128.804691 -280.908487) (xy 128.788981 -280.857557)
			(xy 128.781038 -280.804853) (xy 128.552458 -280.804853) (xy 128.544515 -280.857557) (xy 128.528805 -280.908487)
			(xy 128.505679 -280.956508) (xy 128.475655 -281.000545) (xy 128.439403 -281.039616) (xy 128.397732 -281.072847)
			(xy 128.351574 -281.099496) (xy 128.30196 -281.118968) (xy 128.249998 -281.130828) (xy 128.196848 -281.134812)
			(xy 128.143698 -281.130828) (xy 128.091736 -281.118968) (xy 128.042122 -281.099496) (xy 127.995964 -281.072847)
			(xy 127.954293 -281.039616) (xy 127.918041 -281.000545) (xy 127.888017 -280.956508) (xy 127.864891 -280.908487)
			(xy 127.849181 -280.857557) (xy 127.841238 -280.804853) (xy 127.612658 -280.804853) (xy 127.604715 -280.857557)
			(xy 127.589005 -280.908487) (xy 127.565879 -280.956508) (xy 127.535855 -281.000545) (xy 127.499603 -281.039616)
			(xy 127.457932 -281.072847) (xy 127.411774 -281.099496) (xy 127.36216 -281.118968) (xy 127.310198 -281.130828)
			(xy 127.257048 -281.134812) (xy 127.203898 -281.130828) (xy 127.151936 -281.118968) (xy 127.102322 -281.099496)
			(xy 127.056164 -281.072847) (xy 127.014493 -281.039616) (xy 126.978241 -281.000545) (xy 126.948217 -280.956508)
			(xy 126.925091 -280.908487) (xy 126.909381 -280.857557) (xy 126.901438 -280.804853) (xy 126.672858 -280.804853)
			(xy 126.664915 -280.857557) (xy 126.649205 -280.908487) (xy 126.626079 -280.956508) (xy 126.596055 -281.000545)
			(xy 126.559803 -281.039616) (xy 126.518132 -281.072847) (xy 126.471974 -281.099496) (xy 126.42236 -281.118968)
			(xy 126.370398 -281.130828) (xy 126.317248 -281.134812) (xy 126.264098 -281.130828) (xy 126.212136 -281.118968)
			(xy 126.162522 -281.099496) (xy 126.116364 -281.072847) (xy 126.074693 -281.039616) (xy 126.038441 -281.000545)
			(xy 126.008417 -280.956508) (xy 125.985291 -280.908487) (xy 125.969581 -280.857557) (xy 125.961638 -280.804853)
			(xy 125.732804 -280.804853) (xy 125.724861 -280.857557) (xy 125.709151 -280.908487) (xy 125.686025 -280.956508)
			(xy 125.656001 -281.000545) (xy 125.619749 -281.039616) (xy 125.578078 -281.072847) (xy 125.53192 -281.099496)
			(xy 125.482306 -281.118968) (xy 125.430344 -281.130828) (xy 125.377194 -281.134812) (xy 125.324044 -281.130828)
			(xy 125.272082 -281.118968) (xy 125.222468 -281.099496) (xy 125.17631 -281.072847) (xy 125.134639 -281.039616)
			(xy 125.098387 -281.000545) (xy 125.068363 -280.956508) (xy 125.045237 -280.908487) (xy 125.029527 -280.857557)
			(xy 125.021584 -280.804853) (xy 124.793004 -280.804853) (xy 124.785061 -280.857557) (xy 124.769351 -280.908487)
			(xy 124.746225 -280.956508) (xy 124.716201 -281.000545) (xy 124.679949 -281.039616) (xy 124.638278 -281.072847)
			(xy 124.59212 -281.099496) (xy 124.542506 -281.118968) (xy 124.490544 -281.130828) (xy 124.437394 -281.134812)
			(xy 124.384244 -281.130828) (xy 124.332282 -281.118968) (xy 124.282668 -281.099496) (xy 124.23651 -281.072847)
			(xy 124.194839 -281.039616) (xy 124.158587 -281.000545) (xy 124.128563 -280.956508) (xy 124.105437 -280.908487)
			(xy 124.089727 -280.857557) (xy 124.081784 -280.804853) (xy 123.853204 -280.804853) (xy 123.845261 -280.857557)
			(xy 123.829551 -280.908487) (xy 123.806425 -280.956508) (xy 123.776401 -281.000545) (xy 123.740149 -281.039616)
			(xy 123.698478 -281.072847) (xy 123.65232 -281.099496) (xy 123.602706 -281.118968) (xy 123.550744 -281.130828)
			(xy 123.497594 -281.134812) (xy 123.444444 -281.130828) (xy 123.392482 -281.118968) (xy 123.342868 -281.099496)
			(xy 123.29671 -281.072847) (xy 123.255039 -281.039616) (xy 123.218787 -281.000545) (xy 123.188763 -280.956508)
			(xy 123.165637 -280.908487) (xy 123.149927 -280.857557) (xy 123.141984 -280.804853) (xy 122.913404 -280.804853)
			(xy 122.905461 -280.857557) (xy 122.889751 -280.908487) (xy 122.866625 -280.956508) (xy 122.836601 -281.000545)
			(xy 122.800349 -281.039616) (xy 122.758678 -281.072847) (xy 122.71252 -281.099496) (xy 122.662906 -281.118968)
			(xy 122.610944 -281.130828) (xy 122.557794 -281.134812) (xy 122.504644 -281.130828) (xy 122.452682 -281.118968)
			(xy 122.403068 -281.099496) (xy 122.35691 -281.072847) (xy 122.315239 -281.039616) (xy 122.278987 -281.000545)
			(xy 122.248963 -280.956508) (xy 122.225837 -280.908487) (xy 122.210127 -280.857557) (xy 122.202184 -280.804853)
			(xy 121.973604 -280.804853) (xy 121.965661 -280.857557) (xy 121.949951 -280.908487) (xy 121.926825 -280.956508)
			(xy 121.896801 -281.000545) (xy 121.860549 -281.039616) (xy 121.818878 -281.072847) (xy 121.77272 -281.099496)
			(xy 121.723106 -281.118968) (xy 121.671144 -281.130828) (xy 121.617994 -281.134812) (xy 121.564844 -281.130828)
			(xy 121.512882 -281.118968) (xy 121.463268 -281.099496) (xy 121.41711 -281.072847) (xy 121.375439 -281.039616)
			(xy 121.339187 -281.000545) (xy 121.309163 -280.956508) (xy 121.286037 -280.908487) (xy 121.270327 -280.857557)
			(xy 121.262384 -280.804853) (xy 121.033804 -280.804853) (xy 121.025861 -280.857557) (xy 121.010151 -280.908487)
			(xy 120.987025 -280.956508) (xy 120.957001 -281.000545) (xy 120.920749 -281.039616) (xy 120.879078 -281.072847)
			(xy 120.83292 -281.099496) (xy 120.783306 -281.118968) (xy 120.731344 -281.130828) (xy 120.678194 -281.134812)
			(xy 120.625044 -281.130828) (xy 120.573082 -281.118968) (xy 120.523468 -281.099496) (xy 120.47731 -281.072847)
			(xy 120.435639 -281.039616) (xy 120.399387 -281.000545) (xy 120.369363 -280.956508) (xy 120.346237 -280.908487)
			(xy 120.330527 -280.857557) (xy 120.322584 -280.804853) (xy 120.094004 -280.804853) (xy 120.086061 -280.857557)
			(xy 120.070351 -280.908487) (xy 120.047225 -280.956508) (xy 120.017201 -281.000545) (xy 119.980949 -281.039616)
			(xy 119.939278 -281.072847) (xy 119.89312 -281.099496) (xy 119.843506 -281.118968) (xy 119.791544 -281.130828)
			(xy 119.738394 -281.134812) (xy 119.685244 -281.130828) (xy 119.633282 -281.118968) (xy 119.583668 -281.099496)
			(xy 119.53751 -281.072847) (xy 119.495839 -281.039616) (xy 119.459587 -281.000545) (xy 119.429563 -280.956508)
			(xy 119.406437 -280.908487) (xy 119.390727 -280.857557) (xy 119.382784 -280.804853) (xy 119.154204 -280.804853)
			(xy 119.146261 -280.857557) (xy 119.130551 -280.908487) (xy 119.107425 -280.956508) (xy 119.077401 -281.000545)
			(xy 119.041149 -281.039616) (xy 118.999478 -281.072847) (xy 118.95332 -281.099496) (xy 118.903706 -281.118968)
			(xy 118.851744 -281.130828) (xy 118.798594 -281.134812) (xy 118.745444 -281.130828) (xy 118.693482 -281.118968)
			(xy 118.643868 -281.099496) (xy 118.59771 -281.072847) (xy 118.556039 -281.039616) (xy 118.519787 -281.000545)
			(xy 118.489763 -280.956508) (xy 118.466637 -280.908487) (xy 118.450927 -280.857557) (xy 118.442984 -280.804853)
			(xy 118.214658 -280.804853) (xy 118.206715 -280.857557) (xy 118.191005 -280.908487) (xy 118.167879 -280.956508)
			(xy 118.137855 -281.000545) (xy 118.101603 -281.039616) (xy 118.059932 -281.072847) (xy 118.013774 -281.099496)
			(xy 117.96416 -281.118968) (xy 117.912198 -281.130828) (xy 117.859048 -281.134812) (xy 117.805898 -281.130828)
			(xy 117.753936 -281.118968) (xy 117.704322 -281.099496) (xy 117.658164 -281.072847) (xy 117.616493 -281.039616)
			(xy 117.580241 -281.000545) (xy 117.550217 -280.956508) (xy 117.527091 -280.908487) (xy 117.511381 -280.857557)
			(xy 117.503438 -280.804853) (xy 117.274781 -280.804853) (xy 117.274687 -280.809198) (xy 117.263959 -280.870251)
			(xy 117.25402 -280.899616) (xy 117.243098 -280.930096) (xy 117.825012 -281.51201) (xy 117.835725 -281.52206)
			(xy 117.86152 -281.536088) (xy 117.890241 -281.542195) (xy 117.919512 -281.539878) (xy 117.946913 -281.529326)
			(xy 117.970179 -281.511414) (xy 117.987386 -281.487621) (xy 117.992652 -281.47391) (xy 118.002254 -281.448185)
			(xy 118.028227 -281.399809) (xy 118.06131 -281.355986) (xy 118.100721 -281.317755) (xy 118.145527 -281.286018)
			(xy 118.19467 -281.261525) (xy 118.246987 -281.244857) (xy 118.30124 -281.236407) (xy 118.328694 -281.235912)
			(xy 118.356679 -281.236432) (xy 118.41196 -281.245187) (xy 118.465191 -281.262483) (xy 118.515061 -281.287893)
			(xy 118.560341 -281.320792) (xy 118.599917 -281.36037) (xy 118.632814 -281.405651) (xy 118.658223 -281.455522)
			(xy 118.675516 -281.508753) (xy 118.684269 -281.564035) (xy 118.684802 -281.59202) (xy 118.684315 -281.618669)
			(xy 118.913138 -281.618669) (xy 118.913138 -281.565371) (xy 118.921081 -281.512667) (xy 118.936791 -281.461737)
			(xy 118.959917 -281.413716) (xy 118.989941 -281.369679) (xy 119.026193 -281.330608) (xy 119.067864 -281.297377)
			(xy 119.114022 -281.270728) (xy 119.163636 -281.251256) (xy 119.215598 -281.239396) (xy 119.268748 -281.235413)
			(xy 119.321898 -281.239396) (xy 119.37386 -281.251256) (xy 119.423474 -281.270728) (xy 119.469632 -281.297377)
			(xy 119.511303 -281.330608) (xy 119.547555 -281.369679) (xy 119.577579 -281.413716) (xy 119.600705 -281.461737)
			(xy 119.616415 -281.512667) (xy 119.624358 -281.565371) (xy 119.624856 -281.59202) (xy 119.624358 -281.618669)
			(xy 119.852938 -281.618669) (xy 119.852938 -281.565371) (xy 119.860881 -281.512667) (xy 119.876591 -281.461737)
			(xy 119.899717 -281.413716) (xy 119.929741 -281.369679) (xy 119.965993 -281.330608) (xy 120.007664 -281.297377)
			(xy 120.053822 -281.270728) (xy 120.103436 -281.251256) (xy 120.155398 -281.239396) (xy 120.208548 -281.235413)
			(xy 120.261698 -281.239396) (xy 120.31366 -281.251256) (xy 120.363274 -281.270728) (xy 120.409432 -281.297377)
			(xy 120.451103 -281.330608) (xy 120.487355 -281.369679) (xy 120.517379 -281.413716) (xy 120.540505 -281.461737)
			(xy 120.556215 -281.512667) (xy 120.564158 -281.565371) (xy 120.564656 -281.59202) (xy 120.564158 -281.618669)
			(xy 120.792738 -281.618669) (xy 120.792738 -281.565371) (xy 120.800681 -281.512667) (xy 120.816391 -281.461737)
			(xy 120.839517 -281.413716) (xy 120.869541 -281.369679) (xy 120.905793 -281.330608) (xy 120.947464 -281.297377)
			(xy 120.993622 -281.270728) (xy 121.043236 -281.251256) (xy 121.095198 -281.239396) (xy 121.148348 -281.235413)
			(xy 121.201498 -281.239396) (xy 121.25346 -281.251256) (xy 121.303074 -281.270728) (xy 121.349232 -281.297377)
			(xy 121.390903 -281.330608) (xy 121.427155 -281.369679) (xy 121.457179 -281.413716) (xy 121.480305 -281.461737)
			(xy 121.496015 -281.512667) (xy 121.503958 -281.565371) (xy 121.504456 -281.59202) (xy 121.503958 -281.618669)
			(xy 121.732538 -281.618669) (xy 121.732538 -281.565371) (xy 121.740481 -281.512667) (xy 121.756191 -281.461737)
			(xy 121.779317 -281.413716) (xy 121.809341 -281.369679) (xy 121.845593 -281.330608) (xy 121.887264 -281.297377)
			(xy 121.933422 -281.270728) (xy 121.983036 -281.251256) (xy 122.034998 -281.239396) (xy 122.088148 -281.235413)
			(xy 122.141298 -281.239396) (xy 122.19326 -281.251256) (xy 122.242874 -281.270728) (xy 122.289032 -281.297377)
			(xy 122.330703 -281.330608) (xy 122.366955 -281.369679) (xy 122.396979 -281.413716) (xy 122.420105 -281.461737)
			(xy 122.435815 -281.512667) (xy 122.443758 -281.565371) (xy 122.444256 -281.59202) (xy 122.443758 -281.618669)
			(xy 122.672338 -281.618669) (xy 122.672338 -281.565371) (xy 122.680281 -281.512667) (xy 122.695991 -281.461737)
			(xy 122.719117 -281.413716) (xy 122.749141 -281.369679) (xy 122.785393 -281.330608) (xy 122.827064 -281.297377)
			(xy 122.873222 -281.270728) (xy 122.922836 -281.251256) (xy 122.974798 -281.239396) (xy 123.027948 -281.235413)
			(xy 123.081098 -281.239396) (xy 123.13306 -281.251256) (xy 123.182674 -281.270728) (xy 123.228832 -281.297377)
			(xy 123.270503 -281.330608) (xy 123.306755 -281.369679) (xy 123.336779 -281.413716) (xy 123.359905 -281.461737)
			(xy 123.375615 -281.512667) (xy 123.383558 -281.565371) (xy 123.384056 -281.59202) (xy 123.383558 -281.618669)
			(xy 123.612138 -281.618669) (xy 123.612138 -281.565371) (xy 123.620081 -281.512667) (xy 123.635791 -281.461737)
			(xy 123.658917 -281.413716) (xy 123.688941 -281.369679) (xy 123.725193 -281.330608) (xy 123.766864 -281.297377)
			(xy 123.813022 -281.270728) (xy 123.862636 -281.251256) (xy 123.914598 -281.239396) (xy 123.967748 -281.235413)
			(xy 124.020898 -281.239396) (xy 124.07286 -281.251256) (xy 124.122474 -281.270728) (xy 124.168632 -281.297377)
			(xy 124.210303 -281.330608) (xy 124.246555 -281.369679) (xy 124.276579 -281.413716) (xy 124.299705 -281.461737)
			(xy 124.315415 -281.512667) (xy 124.323358 -281.565371) (xy 124.323856 -281.59202) (xy 124.323358 -281.618669)
			(xy 124.551938 -281.618669) (xy 124.551938 -281.565371) (xy 124.559881 -281.512667) (xy 124.575591 -281.461737)
			(xy 124.598717 -281.413716) (xy 124.628741 -281.369679) (xy 124.664993 -281.330608) (xy 124.706664 -281.297377)
			(xy 124.752822 -281.270728) (xy 124.802436 -281.251256) (xy 124.854398 -281.239396) (xy 124.907548 -281.235413)
			(xy 124.960698 -281.239396) (xy 125.01266 -281.251256) (xy 125.062274 -281.270728) (xy 125.108432 -281.297377)
			(xy 125.150103 -281.330608) (xy 125.186355 -281.369679) (xy 125.216379 -281.413716) (xy 125.239505 -281.461737)
			(xy 125.255215 -281.512667) (xy 125.263158 -281.565371) (xy 125.263656 -281.59202) (xy 125.263158 -281.618669)
			(xy 125.491738 -281.618669) (xy 125.491738 -281.565371) (xy 125.499681 -281.512667) (xy 125.515391 -281.461737)
			(xy 125.538517 -281.413716) (xy 125.568541 -281.369679) (xy 125.604793 -281.330608) (xy 125.646464 -281.297377)
			(xy 125.692622 -281.270728) (xy 125.742236 -281.251256) (xy 125.794198 -281.239396) (xy 125.847348 -281.235413)
			(xy 125.900498 -281.239396) (xy 125.95246 -281.251256) (xy 126.002074 -281.270728) (xy 126.048232 -281.297377)
			(xy 126.089903 -281.330608) (xy 126.126155 -281.369679) (xy 126.156179 -281.413716) (xy 126.179305 -281.461737)
			(xy 126.195015 -281.512667) (xy 126.202958 -281.565371) (xy 126.203456 -281.59202) (xy 126.202958 -281.618669)
			(xy 126.431284 -281.618669) (xy 126.431284 -281.565371) (xy 126.439227 -281.512667) (xy 126.454937 -281.461737)
			(xy 126.478063 -281.413716) (xy 126.508087 -281.369679) (xy 126.544339 -281.330608) (xy 126.58601 -281.297377)
			(xy 126.632168 -281.270728) (xy 126.681782 -281.251256) (xy 126.733744 -281.239396) (xy 126.786894 -281.235413)
			(xy 126.840044 -281.239396) (xy 126.892006 -281.251256) (xy 126.94162 -281.270728) (xy 126.987778 -281.297377)
			(xy 127.029449 -281.330608) (xy 127.065701 -281.369679) (xy 127.095725 -281.413716) (xy 127.118851 -281.461737)
			(xy 127.134561 -281.512667) (xy 127.142504 -281.565371) (xy 127.143002 -281.59202) (xy 127.142509 -281.618415)
			(xy 127.371084 -281.618415) (xy 127.371084 -281.565117) (xy 127.379027 -281.512413) (xy 127.394737 -281.461483)
			(xy 127.417863 -281.413462) (xy 127.447887 -281.369425) (xy 127.484139 -281.330354) (xy 127.52581 -281.297123)
			(xy 127.571968 -281.270474) (xy 127.621582 -281.251002) (xy 127.673544 -281.239142) (xy 127.726694 -281.235159)
			(xy 127.779844 -281.239142) (xy 127.831806 -281.251002) (xy 127.88142 -281.270474) (xy 127.927578 -281.297123)
			(xy 127.969249 -281.330354) (xy 128.005501 -281.369425) (xy 128.035525 -281.413462) (xy 128.058651 -281.461483)
			(xy 128.074361 -281.512413) (xy 128.082304 -281.565117) (xy 128.082802 -281.591766) (xy 128.082304 -281.618415)
			(xy 128.082266 -281.618669) (xy 128.311138 -281.618669) (xy 128.311138 -281.565371) (xy 128.319081 -281.512667)
			(xy 128.334791 -281.461737) (xy 128.357917 -281.413716) (xy 128.387941 -281.369679) (xy 128.424193 -281.330608)
			(xy 128.465864 -281.297377) (xy 128.512022 -281.270728) (xy 128.561636 -281.251256) (xy 128.613598 -281.239396)
			(xy 128.666748 -281.235413) (xy 128.719898 -281.239396) (xy 128.77186 -281.251256) (xy 128.821474 -281.270728)
			(xy 128.867632 -281.297377) (xy 128.909303 -281.330608) (xy 128.945555 -281.369679) (xy 128.975579 -281.413716)
			(xy 128.998705 -281.461737) (xy 129.014415 -281.512667) (xy 129.022358 -281.565371) (xy 129.022856 -281.59202)
			(xy 129.022358 -281.618669) (xy 129.250684 -281.618669) (xy 129.250684 -281.565371) (xy 129.258627 -281.512667)
			(xy 129.274337 -281.461737) (xy 129.297463 -281.413716) (xy 129.327487 -281.369679) (xy 129.363739 -281.330608)
			(xy 129.40541 -281.297377) (xy 129.451568 -281.270728) (xy 129.501182 -281.251256) (xy 129.553144 -281.239396)
			(xy 129.606294 -281.235413) (xy 129.659444 -281.239396) (xy 129.711406 -281.251256) (xy 129.76102 -281.270728)
			(xy 129.807178 -281.297377) (xy 129.848849 -281.330608) (xy 129.885101 -281.369679) (xy 129.915125 -281.413716)
			(xy 129.938251 -281.461737) (xy 129.953961 -281.512667) (xy 129.961904 -281.565371) (xy 129.962402 -281.59202)
			(xy 129.961904 -281.618669) (xy 130.190738 -281.618669) (xy 130.190738 -281.565371) (xy 130.198681 -281.512667)
			(xy 130.214391 -281.461737) (xy 130.237517 -281.413716) (xy 130.267541 -281.369679) (xy 130.303793 -281.330608)
			(xy 130.345464 -281.297377) (xy 130.391622 -281.270728) (xy 130.441236 -281.251256) (xy 130.493198 -281.239396)
			(xy 130.546348 -281.235413) (xy 130.599498 -281.239396) (xy 130.65146 -281.251256) (xy 130.701074 -281.270728)
			(xy 130.747232 -281.297377) (xy 130.788903 -281.330608) (xy 130.825155 -281.369679) (xy 130.855179 -281.413716)
			(xy 130.878305 -281.461737) (xy 130.894015 -281.512667) (xy 130.901958 -281.565371) (xy 130.902456 -281.59202)
			(xy 130.901958 -281.618669) (xy 131.130538 -281.618669) (xy 131.130538 -281.565371) (xy 131.138481 -281.512667)
			(xy 131.154191 -281.461737) (xy 131.177317 -281.413716) (xy 131.207341 -281.369679) (xy 131.243593 -281.330608)
			(xy 131.285264 -281.297377) (xy 131.331422 -281.270728) (xy 131.381036 -281.251256) (xy 131.432998 -281.239396)
			(xy 131.486148 -281.235413) (xy 131.539298 -281.239396) (xy 131.59126 -281.251256) (xy 131.640874 -281.270728)
			(xy 131.687032 -281.297377) (xy 131.728703 -281.330608) (xy 131.764955 -281.369679) (xy 131.794979 -281.413716)
			(xy 131.818105 -281.461737) (xy 131.833815 -281.512667) (xy 131.841758 -281.565371) (xy 131.842256 -281.59202)
			(xy 131.841758 -281.618669) (xy 132.070338 -281.618669) (xy 132.070338 -281.565371) (xy 132.078281 -281.512667)
			(xy 132.093991 -281.461737) (xy 132.117117 -281.413716) (xy 132.147141 -281.369679) (xy 132.183393 -281.330608)
			(xy 132.225064 -281.297377) (xy 132.271222 -281.270728) (xy 132.320836 -281.251256) (xy 132.372798 -281.239396)
			(xy 132.425948 -281.235413) (xy 132.479098 -281.239396) (xy 132.53106 -281.251256) (xy 132.580674 -281.270728)
			(xy 132.626832 -281.297377) (xy 132.668503 -281.330608) (xy 132.704755 -281.369679) (xy 132.734779 -281.413716)
			(xy 132.757905 -281.461737) (xy 132.773615 -281.512667) (xy 132.781558 -281.565371) (xy 132.782056 -281.59202)
			(xy 132.781558 -281.618669) (xy 133.010138 -281.618669) (xy 133.010138 -281.565371) (xy 133.018081 -281.512667)
			(xy 133.033791 -281.461737) (xy 133.056917 -281.413716) (xy 133.086941 -281.369679) (xy 133.123193 -281.330608)
			(xy 133.164864 -281.297377) (xy 133.211022 -281.270728) (xy 133.260636 -281.251256) (xy 133.312598 -281.239396)
			(xy 133.365748 -281.235413) (xy 133.418898 -281.239396) (xy 133.47086 -281.251256) (xy 133.520474 -281.270728)
			(xy 133.566632 -281.297377) (xy 133.608303 -281.330608) (xy 133.644555 -281.369679) (xy 133.674579 -281.413716)
			(xy 133.697705 -281.461737) (xy 133.713415 -281.512667) (xy 133.721358 -281.565371) (xy 133.721856 -281.59202)
			(xy 133.721358 -281.618669) (xy 133.949938 -281.618669) (xy 133.949938 -281.565371) (xy 133.957881 -281.512667)
			(xy 133.973591 -281.461737) (xy 133.996717 -281.413716) (xy 134.026741 -281.369679) (xy 134.062993 -281.330608)
			(xy 134.104664 -281.297377) (xy 134.150822 -281.270728) (xy 134.200436 -281.251256) (xy 134.252398 -281.239396)
			(xy 134.305548 -281.235413) (xy 134.358698 -281.239396) (xy 134.41066 -281.251256) (xy 134.460274 -281.270728)
			(xy 134.506432 -281.297377) (xy 134.548103 -281.330608) (xy 134.584355 -281.369679) (xy 134.614379 -281.413716)
			(xy 134.637505 -281.461737) (xy 134.653215 -281.512667) (xy 134.661158 -281.565371) (xy 134.661656 -281.59202)
			(xy 134.661158 -281.618669) (xy 134.889484 -281.618669) (xy 134.889484 -281.565371) (xy 134.897427 -281.512667)
			(xy 134.913137 -281.461737) (xy 134.936263 -281.413716) (xy 134.966287 -281.369679) (xy 135.002539 -281.330608)
			(xy 135.04421 -281.297377) (xy 135.090368 -281.270728) (xy 135.139982 -281.251256) (xy 135.191944 -281.239396)
			(xy 135.245094 -281.235413) (xy 135.298244 -281.239396) (xy 135.350206 -281.251256) (xy 135.39982 -281.270728)
			(xy 135.445978 -281.297377) (xy 135.487649 -281.330608) (xy 135.523901 -281.369679) (xy 135.553925 -281.413716)
			(xy 135.577051 -281.461737) (xy 135.592761 -281.512667) (xy 135.600704 -281.565371) (xy 135.601202 -281.59202)
			(xy 135.600704 -281.618669) (xy 135.829284 -281.618669) (xy 135.829284 -281.565371) (xy 135.837227 -281.512667)
			(xy 135.852937 -281.461737) (xy 135.876063 -281.413716) (xy 135.906087 -281.369679) (xy 135.942339 -281.330608)
			(xy 135.98401 -281.297377) (xy 136.030168 -281.270728) (xy 136.079782 -281.251256) (xy 136.131744 -281.239396)
			(xy 136.184894 -281.235413) (xy 136.238044 -281.239396) (xy 136.290006 -281.251256) (xy 136.33962 -281.270728)
			(xy 136.385778 -281.297377) (xy 136.427449 -281.330608) (xy 136.463701 -281.369679) (xy 136.493725 -281.413716)
			(xy 136.516851 -281.461737) (xy 136.532561 -281.512667) (xy 136.540504 -281.565371) (xy 136.541002 -281.59202)
			(xy 136.540504 -281.618669) (xy 136.532561 -281.671373) (xy 136.516851 -281.722303) (xy 136.493725 -281.770324)
			(xy 136.463701 -281.814361) (xy 136.427449 -281.853432) (xy 136.385778 -281.886663) (xy 136.33962 -281.913312)
			(xy 136.290006 -281.932784) (xy 136.238044 -281.944644) (xy 136.184894 -281.948628) (xy 136.131744 -281.944644)
			(xy 136.079782 -281.932784) (xy 136.030168 -281.913312) (xy 135.98401 -281.886663) (xy 135.942339 -281.853432)
			(xy 135.906087 -281.814361) (xy 135.876063 -281.770324) (xy 135.852937 -281.722303) (xy 135.837227 -281.671373)
			(xy 135.829284 -281.618669) (xy 135.600704 -281.618669) (xy 135.592761 -281.671373) (xy 135.577051 -281.722303)
			(xy 135.553925 -281.770324) (xy 135.523901 -281.814361) (xy 135.487649 -281.853432) (xy 135.445978 -281.886663)
			(xy 135.39982 -281.913312) (xy 135.350206 -281.932784) (xy 135.298244 -281.944644) (xy 135.245094 -281.948628)
			(xy 135.191944 -281.944644) (xy 135.139982 -281.932784) (xy 135.090368 -281.913312) (xy 135.04421 -281.886663)
			(xy 135.002539 -281.853432) (xy 134.966287 -281.814361) (xy 134.936263 -281.770324) (xy 134.913137 -281.722303)
			(xy 134.897427 -281.671373) (xy 134.889484 -281.618669) (xy 134.661158 -281.618669) (xy 134.653215 -281.671373)
			(xy 134.637505 -281.722303) (xy 134.614379 -281.770324) (xy 134.584355 -281.814361) (xy 134.548103 -281.853432)
			(xy 134.506432 -281.886663) (xy 134.460274 -281.913312) (xy 134.41066 -281.932784) (xy 134.358698 -281.944644)
			(xy 134.305548 -281.948628) (xy 134.252398 -281.944644) (xy 134.200436 -281.932784) (xy 134.150822 -281.913312)
			(xy 134.104664 -281.886663) (xy 134.062993 -281.853432) (xy 134.026741 -281.814361) (xy 133.996717 -281.770324)
			(xy 133.973591 -281.722303) (xy 133.957881 -281.671373) (xy 133.949938 -281.618669) (xy 133.721358 -281.618669)
			(xy 133.713415 -281.671373) (xy 133.697705 -281.722303) (xy 133.674579 -281.770324) (xy 133.644555 -281.814361)
			(xy 133.608303 -281.853432) (xy 133.566632 -281.886663) (xy 133.520474 -281.913312) (xy 133.47086 -281.932784)
			(xy 133.418898 -281.944644) (xy 133.365748 -281.948628) (xy 133.312598 -281.944644) (xy 133.260636 -281.932784)
			(xy 133.211022 -281.913312) (xy 133.164864 -281.886663) (xy 133.123193 -281.853432) (xy 133.086941 -281.814361)
			(xy 133.056917 -281.770324) (xy 133.033791 -281.722303) (xy 133.018081 -281.671373) (xy 133.010138 -281.618669)
			(xy 132.781558 -281.618669) (xy 132.773615 -281.671373) (xy 132.757905 -281.722303) (xy 132.734779 -281.770324)
			(xy 132.704755 -281.814361) (xy 132.668503 -281.853432) (xy 132.626832 -281.886663) (xy 132.580674 -281.913312)
			(xy 132.53106 -281.932784) (xy 132.479098 -281.944644) (xy 132.425948 -281.948628) (xy 132.372798 -281.944644)
			(xy 132.320836 -281.932784) (xy 132.271222 -281.913312) (xy 132.225064 -281.886663) (xy 132.183393 -281.853432)
			(xy 132.147141 -281.814361) (xy 132.117117 -281.770324) (xy 132.093991 -281.722303) (xy 132.078281 -281.671373)
			(xy 132.070338 -281.618669) (xy 131.841758 -281.618669) (xy 131.833815 -281.671373) (xy 131.818105 -281.722303)
			(xy 131.794979 -281.770324) (xy 131.764955 -281.814361) (xy 131.728703 -281.853432) (xy 131.687032 -281.886663)
			(xy 131.640874 -281.913312) (xy 131.59126 -281.932784) (xy 131.539298 -281.944644) (xy 131.486148 -281.948628)
			(xy 131.432998 -281.944644) (xy 131.381036 -281.932784) (xy 131.331422 -281.913312) (xy 131.285264 -281.886663)
			(xy 131.243593 -281.853432) (xy 131.207341 -281.814361) (xy 131.177317 -281.770324) (xy 131.154191 -281.722303)
			(xy 131.138481 -281.671373) (xy 131.130538 -281.618669) (xy 130.901958 -281.618669) (xy 130.894015 -281.671373)
			(xy 130.878305 -281.722303) (xy 130.855179 -281.770324) (xy 130.825155 -281.814361) (xy 130.788903 -281.853432)
			(xy 130.747232 -281.886663) (xy 130.701074 -281.913312) (xy 130.65146 -281.932784) (xy 130.599498 -281.944644)
			(xy 130.546348 -281.948628) (xy 130.493198 -281.944644) (xy 130.441236 -281.932784) (xy 130.391622 -281.913312)
			(xy 130.345464 -281.886663) (xy 130.303793 -281.853432) (xy 130.267541 -281.814361) (xy 130.237517 -281.770324)
			(xy 130.214391 -281.722303) (xy 130.198681 -281.671373) (xy 130.190738 -281.618669) (xy 129.961904 -281.618669)
			(xy 129.953961 -281.671373) (xy 129.938251 -281.722303) (xy 129.915125 -281.770324) (xy 129.885101 -281.814361)
			(xy 129.848849 -281.853432) (xy 129.807178 -281.886663) (xy 129.76102 -281.913312) (xy 129.711406 -281.932784)
			(xy 129.659444 -281.944644) (xy 129.606294 -281.948628) (xy 129.553144 -281.944644) (xy 129.501182 -281.932784)
			(xy 129.451568 -281.913312) (xy 129.40541 -281.886663) (xy 129.363739 -281.853432) (xy 129.327487 -281.814361)
			(xy 129.297463 -281.770324) (xy 129.274337 -281.722303) (xy 129.258627 -281.671373) (xy 129.250684 -281.618669)
			(xy 129.022358 -281.618669) (xy 129.014415 -281.671373) (xy 128.998705 -281.722303) (xy 128.975579 -281.770324)
			(xy 128.945555 -281.814361) (xy 128.909303 -281.853432) (xy 128.867632 -281.886663) (xy 128.821474 -281.913312)
			(xy 128.77186 -281.932784) (xy 128.719898 -281.944644) (xy 128.666748 -281.948628) (xy 128.613598 -281.944644)
			(xy 128.561636 -281.932784) (xy 128.512022 -281.913312) (xy 128.465864 -281.886663) (xy 128.424193 -281.853432)
			(xy 128.387941 -281.814361) (xy 128.357917 -281.770324) (xy 128.334791 -281.722303) (xy 128.319081 -281.671373)
			(xy 128.311138 -281.618669) (xy 128.082266 -281.618669) (xy 128.074361 -281.671119) (xy 128.058651 -281.722049)
			(xy 128.035525 -281.77007) (xy 128.005501 -281.814107) (xy 127.969249 -281.853178) (xy 127.927578 -281.886409)
			(xy 127.88142 -281.913058) (xy 127.831806 -281.93253) (xy 127.779844 -281.94439) (xy 127.726694 -281.948374)
			(xy 127.673544 -281.94439) (xy 127.621582 -281.93253) (xy 127.571968 -281.913058) (xy 127.52581 -281.886409)
			(xy 127.484139 -281.853178) (xy 127.447887 -281.814107) (xy 127.417863 -281.77007) (xy 127.394737 -281.722049)
			(xy 127.379027 -281.671119) (xy 127.371084 -281.618415) (xy 127.142509 -281.618415) (xy 127.142504 -281.618669)
			(xy 127.134561 -281.671373) (xy 127.118851 -281.722303) (xy 127.095725 -281.770324) (xy 127.065701 -281.814361)
			(xy 127.029449 -281.853432) (xy 126.987778 -281.886663) (xy 126.94162 -281.913312) (xy 126.892006 -281.932784)
			(xy 126.840044 -281.944644) (xy 126.786894 -281.948628) (xy 126.733744 -281.944644) (xy 126.681782 -281.932784)
			(xy 126.632168 -281.913312) (xy 126.58601 -281.886663) (xy 126.544339 -281.853432) (xy 126.508087 -281.814361)
			(xy 126.478063 -281.770324) (xy 126.454937 -281.722303) (xy 126.439227 -281.671373) (xy 126.431284 -281.618669)
			(xy 126.202958 -281.618669) (xy 126.195015 -281.671373) (xy 126.179305 -281.722303) (xy 126.156179 -281.770324)
			(xy 126.126155 -281.814361) (xy 126.089903 -281.853432) (xy 126.048232 -281.886663) (xy 126.002074 -281.913312)
			(xy 125.95246 -281.932784) (xy 125.900498 -281.944644) (xy 125.847348 -281.948628) (xy 125.794198 -281.944644)
			(xy 125.742236 -281.932784) (xy 125.692622 -281.913312) (xy 125.646464 -281.886663) (xy 125.604793 -281.853432)
			(xy 125.568541 -281.814361) (xy 125.538517 -281.770324) (xy 125.515391 -281.722303) (xy 125.499681 -281.671373)
			(xy 125.491738 -281.618669) (xy 125.263158 -281.618669) (xy 125.255215 -281.671373) (xy 125.239505 -281.722303)
			(xy 125.216379 -281.770324) (xy 125.186355 -281.814361) (xy 125.150103 -281.853432) (xy 125.108432 -281.886663)
			(xy 125.062274 -281.913312) (xy 125.01266 -281.932784) (xy 124.960698 -281.944644) (xy 124.907548 -281.948628)
			(xy 124.854398 -281.944644) (xy 124.802436 -281.932784) (xy 124.752822 -281.913312) (xy 124.706664 -281.886663)
			(xy 124.664993 -281.853432) (xy 124.628741 -281.814361) (xy 124.598717 -281.770324) (xy 124.575591 -281.722303)
			(xy 124.559881 -281.671373) (xy 124.551938 -281.618669) (xy 124.323358 -281.618669) (xy 124.315415 -281.671373)
			(xy 124.299705 -281.722303) (xy 124.276579 -281.770324) (xy 124.246555 -281.814361) (xy 124.210303 -281.853432)
			(xy 124.168632 -281.886663) (xy 124.122474 -281.913312) (xy 124.07286 -281.932784) (xy 124.020898 -281.944644)
			(xy 123.967748 -281.948628) (xy 123.914598 -281.944644) (xy 123.862636 -281.932784) (xy 123.813022 -281.913312)
			(xy 123.766864 -281.886663) (xy 123.725193 -281.853432) (xy 123.688941 -281.814361) (xy 123.658917 -281.770324)
			(xy 123.635791 -281.722303) (xy 123.620081 -281.671373) (xy 123.612138 -281.618669) (xy 123.383558 -281.618669)
			(xy 123.375615 -281.671373) (xy 123.359905 -281.722303) (xy 123.336779 -281.770324) (xy 123.306755 -281.814361)
			(xy 123.270503 -281.853432) (xy 123.228832 -281.886663) (xy 123.182674 -281.913312) (xy 123.13306 -281.932784)
			(xy 123.081098 -281.944644) (xy 123.027948 -281.948628) (xy 122.974798 -281.944644) (xy 122.922836 -281.932784)
			(xy 122.873222 -281.913312) (xy 122.827064 -281.886663) (xy 122.785393 -281.853432) (xy 122.749141 -281.814361)
			(xy 122.719117 -281.770324) (xy 122.695991 -281.722303) (xy 122.680281 -281.671373) (xy 122.672338 -281.618669)
			(xy 122.443758 -281.618669) (xy 122.435815 -281.671373) (xy 122.420105 -281.722303) (xy 122.396979 -281.770324)
			(xy 122.366955 -281.814361) (xy 122.330703 -281.853432) (xy 122.289032 -281.886663) (xy 122.242874 -281.913312)
			(xy 122.19326 -281.932784) (xy 122.141298 -281.944644) (xy 122.088148 -281.948628) (xy 122.034998 -281.944644)
			(xy 121.983036 -281.932784) (xy 121.933422 -281.913312) (xy 121.887264 -281.886663) (xy 121.845593 -281.853432)
			(xy 121.809341 -281.814361) (xy 121.779317 -281.770324) (xy 121.756191 -281.722303) (xy 121.740481 -281.671373)
			(xy 121.732538 -281.618669) (xy 121.503958 -281.618669) (xy 121.496015 -281.671373) (xy 121.480305 -281.722303)
			(xy 121.457179 -281.770324) (xy 121.427155 -281.814361) (xy 121.390903 -281.853432) (xy 121.349232 -281.886663)
			(xy 121.303074 -281.913312) (xy 121.25346 -281.932784) (xy 121.201498 -281.944644) (xy 121.148348 -281.948628)
			(xy 121.095198 -281.944644) (xy 121.043236 -281.932784) (xy 120.993622 -281.913312) (xy 120.947464 -281.886663)
			(xy 120.905793 -281.853432) (xy 120.869541 -281.814361) (xy 120.839517 -281.770324) (xy 120.816391 -281.722303)
			(xy 120.800681 -281.671373) (xy 120.792738 -281.618669) (xy 120.564158 -281.618669) (xy 120.556215 -281.671373)
			(xy 120.540505 -281.722303) (xy 120.517379 -281.770324) (xy 120.487355 -281.814361) (xy 120.451103 -281.853432)
			(xy 120.409432 -281.886663) (xy 120.363274 -281.913312) (xy 120.31366 -281.932784) (xy 120.261698 -281.944644)
			(xy 120.208548 -281.948628) (xy 120.155398 -281.944644) (xy 120.103436 -281.932784) (xy 120.053822 -281.913312)
			(xy 120.007664 -281.886663) (xy 119.965993 -281.853432) (xy 119.929741 -281.814361) (xy 119.899717 -281.770324)
			(xy 119.876591 -281.722303) (xy 119.860881 -281.671373) (xy 119.852938 -281.618669) (xy 119.624358 -281.618669)
			(xy 119.616415 -281.671373) (xy 119.600705 -281.722303) (xy 119.577579 -281.770324) (xy 119.547555 -281.814361)
			(xy 119.511303 -281.853432) (xy 119.469632 -281.886663) (xy 119.423474 -281.913312) (xy 119.37386 -281.932784)
			(xy 119.321898 -281.944644) (xy 119.268748 -281.948628) (xy 119.215598 -281.944644) (xy 119.163636 -281.932784)
			(xy 119.114022 -281.913312) (xy 119.067864 -281.886663) (xy 119.026193 -281.853432) (xy 118.989941 -281.814361)
			(xy 118.959917 -281.770324) (xy 118.936791 -281.722303) (xy 118.921081 -281.671373) (xy 118.913138 -281.618669)
			(xy 118.684315 -281.618669) (xy 118.6843 -281.619477) (xy 118.675882 -281.673741) (xy 118.659234 -281.726071)
			(xy 118.63475 -281.775224) (xy 118.603011 -281.820036) (xy 118.564768 -281.859444) (xy 118.520929 -281.892514)
			(xy 118.472534 -281.918463) (xy 118.446804 -281.928062) (xy 118.433142 -281.933406) (xy 118.409409 -281.95063)
			(xy 118.391542 -281.973883) (xy 118.381011 -282.001252) (xy 118.378683 -282.030483) (xy 118.384749 -282.059174)
			(xy 118.39871 -282.084962) (xy 118.408704 -282.095702) (xy 118.507002 -282.194) (xy 118.54307 -282.157678)
			(xy 118.543324 -282.157424) (xy 118.563591 -282.137419) (xy 118.609306 -282.103467) (xy 118.659839 -282.077217)
			(xy 118.713903 -282.059336) (xy 118.770122 -282.05028) (xy 118.798594 -282.049728) (xy 118.826579 -282.050248)
			(xy 118.881859 -282.059003) (xy 118.935089 -282.076299) (xy 118.984957 -282.10171) (xy 119.030236 -282.134609)
			(xy 119.069811 -282.174187) (xy 119.102706 -282.219469) (xy 119.128112 -282.269339) (xy 119.145404 -282.32257)
			(xy 119.154154 -282.377851) (xy 119.154702 -282.405836) (xy 119.154177 -282.432485) (xy 119.382784 -282.432485)
			(xy 119.382784 -282.379187) (xy 119.390727 -282.326483) (xy 119.406437 -282.275553) (xy 119.429563 -282.227532)
			(xy 119.459587 -282.183495) (xy 119.495839 -282.144424) (xy 119.53751 -282.111193) (xy 119.583668 -282.084544)
			(xy 119.633282 -282.065072) (xy 119.685244 -282.053212) (xy 119.738394 -282.049229) (xy 119.791544 -282.053212)
			(xy 119.843506 -282.065072) (xy 119.89312 -282.084544) (xy 119.939278 -282.111193) (xy 119.980949 -282.144424)
			(xy 120.017201 -282.183495) (xy 120.047225 -282.227532) (xy 120.070351 -282.275553) (xy 120.086061 -282.326483)
			(xy 120.094004 -282.379187) (xy 120.094502 -282.405836) (xy 120.094004 -282.432485) (xy 120.322584 -282.432485)
			(xy 120.322584 -282.379187) (xy 120.330527 -282.326483) (xy 120.346237 -282.275553) (xy 120.369363 -282.227532)
			(xy 120.399387 -282.183495) (xy 120.435639 -282.144424) (xy 120.47731 -282.111193) (xy 120.523468 -282.084544)
			(xy 120.573082 -282.065072) (xy 120.625044 -282.053212) (xy 120.678194 -282.049229) (xy 120.731344 -282.053212)
			(xy 120.783306 -282.065072) (xy 120.83292 -282.084544) (xy 120.879078 -282.111193) (xy 120.920749 -282.144424)
			(xy 120.957001 -282.183495) (xy 120.987025 -282.227532) (xy 121.010151 -282.275553) (xy 121.025861 -282.326483)
			(xy 121.033804 -282.379187) (xy 121.034302 -282.405836) (xy 121.033804 -282.432485) (xy 121.262384 -282.432485)
			(xy 121.262384 -282.379187) (xy 121.270327 -282.326483) (xy 121.286037 -282.275553) (xy 121.309163 -282.227532)
			(xy 121.339187 -282.183495) (xy 121.375439 -282.144424) (xy 121.41711 -282.111193) (xy 121.463268 -282.084544)
			(xy 121.512882 -282.065072) (xy 121.564844 -282.053212) (xy 121.617994 -282.049229) (xy 121.671144 -282.053212)
			(xy 121.723106 -282.065072) (xy 121.77272 -282.084544) (xy 121.818878 -282.111193) (xy 121.860549 -282.144424)
			(xy 121.896801 -282.183495) (xy 121.926825 -282.227532) (xy 121.949951 -282.275553) (xy 121.965661 -282.326483)
			(xy 121.973604 -282.379187) (xy 121.974102 -282.405836) (xy 121.973604 -282.432485) (xy 122.202184 -282.432485)
			(xy 122.202184 -282.379187) (xy 122.210127 -282.326483) (xy 122.225837 -282.275553) (xy 122.248963 -282.227532)
			(xy 122.278987 -282.183495) (xy 122.315239 -282.144424) (xy 122.35691 -282.111193) (xy 122.403068 -282.084544)
			(xy 122.452682 -282.065072) (xy 122.504644 -282.053212) (xy 122.557794 -282.049229) (xy 122.610944 -282.053212)
			(xy 122.662906 -282.065072) (xy 122.71252 -282.084544) (xy 122.758678 -282.111193) (xy 122.800349 -282.144424)
			(xy 122.836601 -282.183495) (xy 122.866625 -282.227532) (xy 122.889751 -282.275553) (xy 122.905461 -282.326483)
			(xy 122.913404 -282.379187) (xy 122.913902 -282.405836) (xy 122.913404 -282.432485) (xy 123.141984 -282.432485)
			(xy 123.141984 -282.379187) (xy 123.149927 -282.326483) (xy 123.165637 -282.275553) (xy 123.188763 -282.227532)
			(xy 123.218787 -282.183495) (xy 123.255039 -282.144424) (xy 123.29671 -282.111193) (xy 123.342868 -282.084544)
			(xy 123.392482 -282.065072) (xy 123.444444 -282.053212) (xy 123.497594 -282.049229) (xy 123.550744 -282.053212)
			(xy 123.602706 -282.065072) (xy 123.65232 -282.084544) (xy 123.698478 -282.111193) (xy 123.740149 -282.144424)
			(xy 123.776401 -282.183495) (xy 123.806425 -282.227532) (xy 123.829551 -282.275553) (xy 123.845261 -282.326483)
			(xy 123.853204 -282.379187) (xy 123.853702 -282.405836) (xy 123.853204 -282.432485) (xy 124.081784 -282.432485)
			(xy 124.081784 -282.379187) (xy 124.089727 -282.326483) (xy 124.105437 -282.275553) (xy 124.128563 -282.227532)
			(xy 124.158587 -282.183495) (xy 124.194839 -282.144424) (xy 124.23651 -282.111193) (xy 124.282668 -282.084544)
			(xy 124.332282 -282.065072) (xy 124.384244 -282.053212) (xy 124.437394 -282.049229) (xy 124.490544 -282.053212)
			(xy 124.542506 -282.065072) (xy 124.59212 -282.084544) (xy 124.638278 -282.111193) (xy 124.679949 -282.144424)
			(xy 124.716201 -282.183495) (xy 124.746225 -282.227532) (xy 124.769351 -282.275553) (xy 124.785061 -282.326483)
			(xy 124.793004 -282.379187) (xy 124.793502 -282.405836) (xy 124.793004 -282.432485) (xy 125.021584 -282.432485)
			(xy 125.021584 -282.379187) (xy 125.029527 -282.326483) (xy 125.045237 -282.275553) (xy 125.068363 -282.227532)
			(xy 125.098387 -282.183495) (xy 125.134639 -282.144424) (xy 125.17631 -282.111193) (xy 125.222468 -282.084544)
			(xy 125.272082 -282.065072) (xy 125.324044 -282.053212) (xy 125.377194 -282.049229) (xy 125.430344 -282.053212)
			(xy 125.482306 -282.065072) (xy 125.53192 -282.084544) (xy 125.578078 -282.111193) (xy 125.619749 -282.144424)
			(xy 125.656001 -282.183495) (xy 125.686025 -282.227532) (xy 125.709151 -282.275553) (xy 125.724861 -282.326483)
			(xy 125.732804 -282.379187) (xy 125.733302 -282.405836) (xy 125.732804 -282.432485) (xy 125.961638 -282.432485)
			(xy 125.961638 -282.379187) (xy 125.969581 -282.326483) (xy 125.985291 -282.275553) (xy 126.008417 -282.227532)
			(xy 126.038441 -282.183495) (xy 126.074693 -282.144424) (xy 126.116364 -282.111193) (xy 126.162522 -282.084544)
			(xy 126.212136 -282.065072) (xy 126.264098 -282.053212) (xy 126.317248 -282.049229) (xy 126.370398 -282.053212)
			(xy 126.42236 -282.065072) (xy 126.471974 -282.084544) (xy 126.518132 -282.111193) (xy 126.559803 -282.144424)
			(xy 126.596055 -282.183495) (xy 126.626079 -282.227532) (xy 126.649205 -282.275553) (xy 126.664915 -282.326483)
			(xy 126.672858 -282.379187) (xy 126.673356 -282.405836) (xy 126.672863 -282.432231) (xy 126.901438 -282.432231)
			(xy 126.901438 -282.378933) (xy 126.909381 -282.326229) (xy 126.925091 -282.275299) (xy 126.948217 -282.227278)
			(xy 126.978241 -282.183241) (xy 127.014493 -282.14417) (xy 127.056164 -282.110939) (xy 127.102322 -282.08429)
			(xy 127.151936 -282.064818) (xy 127.203898 -282.052958) (xy 127.257048 -282.048975) (xy 127.310198 -282.052958)
			(xy 127.36216 -282.064818) (xy 127.411774 -282.08429) (xy 127.457932 -282.110939) (xy 127.499603 -282.14417)
			(xy 127.535855 -282.183241) (xy 127.565879 -282.227278) (xy 127.589005 -282.275299) (xy 127.604715 -282.326229)
			(xy 127.612658 -282.378933) (xy 127.613156 -282.405582) (xy 127.612658 -282.432231) (xy 127.841238 -282.432231)
			(xy 127.841238 -282.378933) (xy 127.849181 -282.326229) (xy 127.864891 -282.275299) (xy 127.888017 -282.227278)
			(xy 127.918041 -282.183241) (xy 127.954293 -282.14417) (xy 127.995964 -282.110939) (xy 128.042122 -282.08429)
			(xy 128.091736 -282.064818) (xy 128.143698 -282.052958) (xy 128.196848 -282.048975) (xy 128.249998 -282.052958)
			(xy 128.30196 -282.064818) (xy 128.351574 -282.08429) (xy 128.397732 -282.110939) (xy 128.439403 -282.14417)
			(xy 128.475655 -282.183241) (xy 128.505679 -282.227278) (xy 128.528805 -282.275299) (xy 128.544515 -282.326229)
			(xy 128.552458 -282.378933) (xy 128.552956 -282.405582) (xy 128.552458 -282.432231) (xy 128.781038 -282.432231)
			(xy 128.781038 -282.378933) (xy 128.788981 -282.326229) (xy 128.804691 -282.275299) (xy 128.827817 -282.227278)
			(xy 128.857841 -282.183241) (xy 128.894093 -282.14417) (xy 128.935764 -282.110939) (xy 128.981922 -282.08429)
			(xy 129.031536 -282.064818) (xy 129.083498 -282.052958) (xy 129.136648 -282.048975) (xy 129.189798 -282.052958)
			(xy 129.24176 -282.064818) (xy 129.291374 -282.08429) (xy 129.337532 -282.110939) (xy 129.379203 -282.14417)
			(xy 129.415455 -282.183241) (xy 129.445479 -282.227278) (xy 129.468605 -282.275299) (xy 129.484315 -282.326229)
			(xy 129.492258 -282.378933) (xy 129.492756 -282.405582) (xy 129.492258 -282.432231) (xy 129.720838 -282.432231)
			(xy 129.720838 -282.378933) (xy 129.728781 -282.326229) (xy 129.744491 -282.275299) (xy 129.767617 -282.227278)
			(xy 129.797641 -282.183241) (xy 129.833893 -282.14417) (xy 129.875564 -282.110939) (xy 129.921722 -282.08429)
			(xy 129.971336 -282.064818) (xy 130.023298 -282.052958) (xy 130.076448 -282.048975) (xy 130.129598 -282.052958)
			(xy 130.18156 -282.064818) (xy 130.231174 -282.08429) (xy 130.277332 -282.110939) (xy 130.319003 -282.14417)
			(xy 130.355255 -282.183241) (xy 130.385279 -282.227278) (xy 130.408405 -282.275299) (xy 130.424115 -282.326229)
			(xy 130.432058 -282.378933) (xy 130.432556 -282.405582) (xy 130.432058 -282.432231) (xy 130.43202 -282.432485)
			(xy 130.660384 -282.432485) (xy 130.660384 -282.379187) (xy 130.668327 -282.326483) (xy 130.684037 -282.275553)
			(xy 130.707163 -282.227532) (xy 130.737187 -282.183495) (xy 130.773439 -282.144424) (xy 130.81511 -282.111193)
			(xy 130.861268 -282.084544) (xy 130.910882 -282.065072) (xy 130.962844 -282.053212) (xy 131.015994 -282.049229)
			(xy 131.069144 -282.053212) (xy 131.121106 -282.065072) (xy 131.17072 -282.084544) (xy 131.216878 -282.111193)
			(xy 131.258549 -282.144424) (xy 131.294801 -282.183495) (xy 131.324825 -282.227532) (xy 131.347951 -282.275553)
			(xy 131.363661 -282.326483) (xy 131.371604 -282.379187) (xy 131.372102 -282.405836) (xy 131.371604 -282.432485)
			(xy 131.600184 -282.432485) (xy 131.600184 -282.379187) (xy 131.608127 -282.326483) (xy 131.623837 -282.275553)
			(xy 131.646963 -282.227532) (xy 131.676987 -282.183495) (xy 131.713239 -282.144424) (xy 131.75491 -282.111193)
			(xy 131.801068 -282.084544) (xy 131.850682 -282.065072) (xy 131.902644 -282.053212) (xy 131.955794 -282.049229)
			(xy 132.008944 -282.053212) (xy 132.060906 -282.065072) (xy 132.11052 -282.084544) (xy 132.156678 -282.111193)
			(xy 132.198349 -282.144424) (xy 132.234601 -282.183495) (xy 132.264625 -282.227532) (xy 132.287751 -282.275553)
			(xy 132.303461 -282.326483) (xy 132.311404 -282.379187) (xy 132.311902 -282.405836) (xy 132.311404 -282.432485)
			(xy 132.539984 -282.432485) (xy 132.539984 -282.379187) (xy 132.547927 -282.326483) (xy 132.563637 -282.275553)
			(xy 132.586763 -282.227532) (xy 132.616787 -282.183495) (xy 132.653039 -282.144424) (xy 132.69471 -282.111193)
			(xy 132.740868 -282.084544) (xy 132.790482 -282.065072) (xy 132.842444 -282.053212) (xy 132.895594 -282.049229)
			(xy 132.948744 -282.053212) (xy 133.000706 -282.065072) (xy 133.05032 -282.084544) (xy 133.096478 -282.111193)
			(xy 133.138149 -282.144424) (xy 133.174401 -282.183495) (xy 133.204425 -282.227532) (xy 133.227551 -282.275553)
			(xy 133.243261 -282.326483) (xy 133.251204 -282.379187) (xy 133.251702 -282.405836) (xy 133.251204 -282.432485)
			(xy 133.479784 -282.432485) (xy 133.479784 -282.379187) (xy 133.487727 -282.326483) (xy 133.503437 -282.275553)
			(xy 133.526563 -282.227532) (xy 133.556587 -282.183495) (xy 133.592839 -282.144424) (xy 133.63451 -282.111193)
			(xy 133.680668 -282.084544) (xy 133.730282 -282.065072) (xy 133.782244 -282.053212) (xy 133.835394 -282.049229)
			(xy 133.888544 -282.053212) (xy 133.940506 -282.065072) (xy 133.99012 -282.084544) (xy 134.036278 -282.111193)
			(xy 134.077949 -282.144424) (xy 134.114201 -282.183495) (xy 134.144225 -282.227532) (xy 134.167351 -282.275553)
			(xy 134.183061 -282.326483) (xy 134.191004 -282.379187) (xy 134.191502 -282.405836) (xy 134.191004 -282.432485)
			(xy 134.419838 -282.432485) (xy 134.419838 -282.379187) (xy 134.427781 -282.326483) (xy 134.443491 -282.275553)
			(xy 134.466617 -282.227532) (xy 134.496641 -282.183495) (xy 134.532893 -282.144424) (xy 134.574564 -282.111193)
			(xy 134.620722 -282.084544) (xy 134.670336 -282.065072) (xy 134.722298 -282.053212) (xy 134.775448 -282.049229)
			(xy 134.828598 -282.053212) (xy 134.88056 -282.065072) (xy 134.930174 -282.084544) (xy 134.976332 -282.111193)
			(xy 135.018003 -282.144424) (xy 135.054255 -282.183495) (xy 135.084279 -282.227532) (xy 135.107405 -282.275553)
			(xy 135.123115 -282.326483) (xy 135.131058 -282.379187) (xy 135.131556 -282.405836) (xy 135.131058 -282.432485)
			(xy 135.359384 -282.432485) (xy 135.359384 -282.379187) (xy 135.367327 -282.326483) (xy 135.383037 -282.275553)
			(xy 135.406163 -282.227532) (xy 135.436187 -282.183495) (xy 135.472439 -282.144424) (xy 135.51411 -282.111193)
			(xy 135.560268 -282.084544) (xy 135.609882 -282.065072) (xy 135.661844 -282.053212) (xy 135.714994 -282.049229)
			(xy 135.768144 -282.053212) (xy 135.820106 -282.065072) (xy 135.86972 -282.084544) (xy 135.915878 -282.111193)
			(xy 135.957549 -282.144424) (xy 135.993801 -282.183495) (xy 136.023825 -282.227532) (xy 136.046951 -282.275553)
			(xy 136.062661 -282.326483) (xy 136.070604 -282.379187) (xy 136.071102 -282.405836) (xy 136.070604 -282.432485)
			(xy 136.299184 -282.432485) (xy 136.299184 -282.379187) (xy 136.307127 -282.326483) (xy 136.322837 -282.275553)
			(xy 136.345963 -282.227532) (xy 136.375987 -282.183495) (xy 136.412239 -282.144424) (xy 136.45391 -282.111193)
			(xy 136.500068 -282.084544) (xy 136.549682 -282.065072) (xy 136.601644 -282.053212) (xy 136.654794 -282.049229)
			(xy 136.707944 -282.053212) (xy 136.759906 -282.065072) (xy 136.80952 -282.084544) (xy 136.855678 -282.111193)
			(xy 136.897349 -282.144424) (xy 136.933601 -282.183495) (xy 136.963625 -282.227532) (xy 136.986751 -282.275553)
			(xy 137.002461 -282.326483) (xy 137.010404 -282.379187) (xy 137.010902 -282.405836) (xy 137.010404 -282.432485)
			(xy 137.238984 -282.432485) (xy 137.238984 -282.379187) (xy 137.246927 -282.326483) (xy 137.262637 -282.275553)
			(xy 137.285763 -282.227532) (xy 137.315787 -282.183495) (xy 137.352039 -282.144424) (xy 137.39371 -282.111193)
			(xy 137.439868 -282.084544) (xy 137.489482 -282.065072) (xy 137.541444 -282.053212) (xy 137.594594 -282.049229)
			(xy 137.647744 -282.053212) (xy 137.699706 -282.065072) (xy 137.74932 -282.084544) (xy 137.795478 -282.111193)
			(xy 137.837149 -282.144424) (xy 137.873401 -282.183495) (xy 137.903425 -282.227532) (xy 137.926551 -282.275553)
			(xy 137.942261 -282.326483) (xy 137.950204 -282.379187) (xy 137.950702 -282.405836) (xy 137.950204 -282.432485)
			(xy 137.942261 -282.485189) (xy 137.926551 -282.536119) (xy 137.903425 -282.58414) (xy 137.873401 -282.628177)
			(xy 137.837149 -282.667248) (xy 137.795478 -282.700479) (xy 137.74932 -282.727128) (xy 137.699706 -282.7466)
			(xy 137.647744 -282.75846) (xy 137.594594 -282.762444) (xy 137.541444 -282.75846) (xy 137.489482 -282.7466)
			(xy 137.439868 -282.727128) (xy 137.39371 -282.700479) (xy 137.352039 -282.667248) (xy 137.315787 -282.628177)
			(xy 137.285763 -282.58414) (xy 137.262637 -282.536119) (xy 137.246927 -282.485189) (xy 137.238984 -282.432485)
			(xy 137.010404 -282.432485) (xy 137.002461 -282.485189) (xy 136.986751 -282.536119) (xy 136.963625 -282.58414)
			(xy 136.933601 -282.628177) (xy 136.897349 -282.667248) (xy 136.855678 -282.700479) (xy 136.80952 -282.727128)
			(xy 136.759906 -282.7466) (xy 136.707944 -282.75846) (xy 136.654794 -282.762444) (xy 136.601644 -282.75846)
			(xy 136.549682 -282.7466) (xy 136.500068 -282.727128) (xy 136.45391 -282.700479) (xy 136.412239 -282.667248)
			(xy 136.375987 -282.628177) (xy 136.345963 -282.58414) (xy 136.322837 -282.536119) (xy 136.307127 -282.485189)
			(xy 136.299184 -282.432485) (xy 136.070604 -282.432485) (xy 136.062661 -282.485189) (xy 136.046951 -282.536119)
			(xy 136.023825 -282.58414) (xy 135.993801 -282.628177) (xy 135.957549 -282.667248) (xy 135.915878 -282.700479)
			(xy 135.86972 -282.727128) (xy 135.820106 -282.7466) (xy 135.768144 -282.75846) (xy 135.714994 -282.762444)
			(xy 135.661844 -282.75846) (xy 135.609882 -282.7466) (xy 135.560268 -282.727128) (xy 135.51411 -282.700479)
			(xy 135.472439 -282.667248) (xy 135.436187 -282.628177) (xy 135.406163 -282.58414) (xy 135.383037 -282.536119)
			(xy 135.367327 -282.485189) (xy 135.359384 -282.432485) (xy 135.131058 -282.432485) (xy 135.123115 -282.485189)
			(xy 135.107405 -282.536119) (xy 135.084279 -282.58414) (xy 135.054255 -282.628177) (xy 135.018003 -282.667248)
			(xy 134.976332 -282.700479) (xy 134.930174 -282.727128) (xy 134.88056 -282.7466) (xy 134.828598 -282.75846)
			(xy 134.775448 -282.762444) (xy 134.722298 -282.75846) (xy 134.670336 -282.7466) (xy 134.620722 -282.727128)
			(xy 134.574564 -282.700479) (xy 134.532893 -282.667248) (xy 134.496641 -282.628177) (xy 134.466617 -282.58414)
			(xy 134.443491 -282.536119) (xy 134.427781 -282.485189) (xy 134.419838 -282.432485) (xy 134.191004 -282.432485)
			(xy 134.183061 -282.485189) (xy 134.167351 -282.536119) (xy 134.144225 -282.58414) (xy 134.114201 -282.628177)
			(xy 134.077949 -282.667248) (xy 134.036278 -282.700479) (xy 133.99012 -282.727128) (xy 133.940506 -282.7466)
			(xy 133.888544 -282.75846) (xy 133.835394 -282.762444) (xy 133.782244 -282.75846) (xy 133.730282 -282.7466)
			(xy 133.680668 -282.727128) (xy 133.63451 -282.700479) (xy 133.592839 -282.667248) (xy 133.556587 -282.628177)
			(xy 133.526563 -282.58414) (xy 133.503437 -282.536119) (xy 133.487727 -282.485189) (xy 133.479784 -282.432485)
			(xy 133.251204 -282.432485) (xy 133.243261 -282.485189) (xy 133.227551 -282.536119) (xy 133.204425 -282.58414)
			(xy 133.174401 -282.628177) (xy 133.138149 -282.667248) (xy 133.096478 -282.700479) (xy 133.05032 -282.727128)
			(xy 133.000706 -282.7466) (xy 132.948744 -282.75846) (xy 132.895594 -282.762444) (xy 132.842444 -282.75846)
			(xy 132.790482 -282.7466) (xy 132.740868 -282.727128) (xy 132.69471 -282.700479) (xy 132.653039 -282.667248)
			(xy 132.616787 -282.628177) (xy 132.586763 -282.58414) (xy 132.563637 -282.536119) (xy 132.547927 -282.485189)
			(xy 132.539984 -282.432485) (xy 132.311404 -282.432485) (xy 132.303461 -282.485189) (xy 132.287751 -282.536119)
			(xy 132.264625 -282.58414) (xy 132.234601 -282.628177) (xy 132.198349 -282.667248) (xy 132.156678 -282.700479)
			(xy 132.11052 -282.727128) (xy 132.060906 -282.7466) (xy 132.008944 -282.75846) (xy 131.955794 -282.762444)
			(xy 131.902644 -282.75846) (xy 131.850682 -282.7466) (xy 131.801068 -282.727128) (xy 131.75491 -282.700479)
			(xy 131.713239 -282.667248) (xy 131.676987 -282.628177) (xy 131.646963 -282.58414) (xy 131.623837 -282.536119)
			(xy 131.608127 -282.485189) (xy 131.600184 -282.432485) (xy 131.371604 -282.432485) (xy 131.363661 -282.485189)
			(xy 131.347951 -282.536119) (xy 131.324825 -282.58414) (xy 131.294801 -282.628177) (xy 131.258549 -282.667248)
			(xy 131.216878 -282.700479) (xy 131.17072 -282.727128) (xy 131.121106 -282.7466) (xy 131.069144 -282.75846)
			(xy 131.015994 -282.762444) (xy 130.962844 -282.75846) (xy 130.910882 -282.7466) (xy 130.861268 -282.727128)
			(xy 130.81511 -282.700479) (xy 130.773439 -282.667248) (xy 130.737187 -282.628177) (xy 130.707163 -282.58414)
			(xy 130.684037 -282.536119) (xy 130.668327 -282.485189) (xy 130.660384 -282.432485) (xy 130.43202 -282.432485)
			(xy 130.424115 -282.484935) (xy 130.408405 -282.535865) (xy 130.385279 -282.583886) (xy 130.355255 -282.627923)
			(xy 130.319003 -282.666994) (xy 130.277332 -282.700225) (xy 130.231174 -282.726874) (xy 130.18156 -282.746346)
			(xy 130.129598 -282.758206) (xy 130.076448 -282.76219) (xy 130.023298 -282.758206) (xy 129.971336 -282.746346)
			(xy 129.921722 -282.726874) (xy 129.875564 -282.700225) (xy 129.833893 -282.666994) (xy 129.797641 -282.627923)
			(xy 129.767617 -282.583886) (xy 129.744491 -282.535865) (xy 129.728781 -282.484935) (xy 129.720838 -282.432231)
			(xy 129.492258 -282.432231) (xy 129.484315 -282.484935) (xy 129.468605 -282.535865) (xy 129.445479 -282.583886)
			(xy 129.415455 -282.627923) (xy 129.379203 -282.666994) (xy 129.337532 -282.700225) (xy 129.291374 -282.726874)
			(xy 129.24176 -282.746346) (xy 129.189798 -282.758206) (xy 129.136648 -282.76219) (xy 129.083498 -282.758206)
			(xy 129.031536 -282.746346) (xy 128.981922 -282.726874) (xy 128.935764 -282.700225) (xy 128.894093 -282.666994)
			(xy 128.857841 -282.627923) (xy 128.827817 -282.583886) (xy 128.804691 -282.535865) (xy 128.788981 -282.484935)
			(xy 128.781038 -282.432231) (xy 128.552458 -282.432231) (xy 128.544515 -282.484935) (xy 128.528805 -282.535865)
			(xy 128.505679 -282.583886) (xy 128.475655 -282.627923) (xy 128.439403 -282.666994) (xy 128.397732 -282.700225)
			(xy 128.351574 -282.726874) (xy 128.30196 -282.746346) (xy 128.249998 -282.758206) (xy 128.196848 -282.76219)
			(xy 128.143698 -282.758206) (xy 128.091736 -282.746346) (xy 128.042122 -282.726874) (xy 127.995964 -282.700225)
			(xy 127.954293 -282.666994) (xy 127.918041 -282.627923) (xy 127.888017 -282.583886) (xy 127.864891 -282.535865)
			(xy 127.849181 -282.484935) (xy 127.841238 -282.432231) (xy 127.612658 -282.432231) (xy 127.604715 -282.484935)
			(xy 127.589005 -282.535865) (xy 127.565879 -282.583886) (xy 127.535855 -282.627923) (xy 127.499603 -282.666994)
			(xy 127.457932 -282.700225) (xy 127.411774 -282.726874) (xy 127.36216 -282.746346) (xy 127.310198 -282.758206)
			(xy 127.257048 -282.76219) (xy 127.203898 -282.758206) (xy 127.151936 -282.746346) (xy 127.102322 -282.726874)
			(xy 127.056164 -282.700225) (xy 127.014493 -282.666994) (xy 126.978241 -282.627923) (xy 126.948217 -282.583886)
			(xy 126.925091 -282.535865) (xy 126.909381 -282.484935) (xy 126.901438 -282.432231) (xy 126.672863 -282.432231)
			(xy 126.672858 -282.432485) (xy 126.664915 -282.485189) (xy 126.649205 -282.536119) (xy 126.626079 -282.58414)
			(xy 126.596055 -282.628177) (xy 126.559803 -282.667248) (xy 126.518132 -282.700479) (xy 126.471974 -282.727128)
			(xy 126.42236 -282.7466) (xy 126.370398 -282.75846) (xy 126.317248 -282.762444) (xy 126.264098 -282.75846)
			(xy 126.212136 -282.7466) (xy 126.162522 -282.727128) (xy 126.116364 -282.700479) (xy 126.074693 -282.667248)
			(xy 126.038441 -282.628177) (xy 126.008417 -282.58414) (xy 125.985291 -282.536119) (xy 125.969581 -282.485189)
			(xy 125.961638 -282.432485) (xy 125.732804 -282.432485) (xy 125.724861 -282.485189) (xy 125.709151 -282.536119)
			(xy 125.686025 -282.58414) (xy 125.656001 -282.628177) (xy 125.619749 -282.667248) (xy 125.578078 -282.700479)
			(xy 125.53192 -282.727128) (xy 125.482306 -282.7466) (xy 125.430344 -282.75846) (xy 125.377194 -282.762444)
			(xy 125.324044 -282.75846) (xy 125.272082 -282.7466) (xy 125.222468 -282.727128) (xy 125.17631 -282.700479)
			(xy 125.134639 -282.667248) (xy 125.098387 -282.628177) (xy 125.068363 -282.58414) (xy 125.045237 -282.536119)
			(xy 125.029527 -282.485189) (xy 125.021584 -282.432485) (xy 124.793004 -282.432485) (xy 124.785061 -282.485189)
			(xy 124.769351 -282.536119) (xy 124.746225 -282.58414) (xy 124.716201 -282.628177) (xy 124.679949 -282.667248)
			(xy 124.638278 -282.700479) (xy 124.59212 -282.727128) (xy 124.542506 -282.7466) (xy 124.490544 -282.75846)
			(xy 124.437394 -282.762444) (xy 124.384244 -282.75846) (xy 124.332282 -282.7466) (xy 124.282668 -282.727128)
			(xy 124.23651 -282.700479) (xy 124.194839 -282.667248) (xy 124.158587 -282.628177) (xy 124.128563 -282.58414)
			(xy 124.105437 -282.536119) (xy 124.089727 -282.485189) (xy 124.081784 -282.432485) (xy 123.853204 -282.432485)
			(xy 123.845261 -282.485189) (xy 123.829551 -282.536119) (xy 123.806425 -282.58414) (xy 123.776401 -282.628177)
			(xy 123.740149 -282.667248) (xy 123.698478 -282.700479) (xy 123.65232 -282.727128) (xy 123.602706 -282.7466)
			(xy 123.550744 -282.75846) (xy 123.497594 -282.762444) (xy 123.444444 -282.75846) (xy 123.392482 -282.7466)
			(xy 123.342868 -282.727128) (xy 123.29671 -282.700479) (xy 123.255039 -282.667248) (xy 123.218787 -282.628177)
			(xy 123.188763 -282.58414) (xy 123.165637 -282.536119) (xy 123.149927 -282.485189) (xy 123.141984 -282.432485)
			(xy 122.913404 -282.432485) (xy 122.905461 -282.485189) (xy 122.889751 -282.536119) (xy 122.866625 -282.58414)
			(xy 122.836601 -282.628177) (xy 122.800349 -282.667248) (xy 122.758678 -282.700479) (xy 122.71252 -282.727128)
			(xy 122.662906 -282.7466) (xy 122.610944 -282.75846) (xy 122.557794 -282.762444) (xy 122.504644 -282.75846)
			(xy 122.452682 -282.7466) (xy 122.403068 -282.727128) (xy 122.35691 -282.700479) (xy 122.315239 -282.667248)
			(xy 122.278987 -282.628177) (xy 122.248963 -282.58414) (xy 122.225837 -282.536119) (xy 122.210127 -282.485189)
			(xy 122.202184 -282.432485) (xy 121.973604 -282.432485) (xy 121.965661 -282.485189) (xy 121.949951 -282.536119)
			(xy 121.926825 -282.58414) (xy 121.896801 -282.628177) (xy 121.860549 -282.667248) (xy 121.818878 -282.700479)
			(xy 121.77272 -282.727128) (xy 121.723106 -282.7466) (xy 121.671144 -282.75846) (xy 121.617994 -282.762444)
			(xy 121.564844 -282.75846) (xy 121.512882 -282.7466) (xy 121.463268 -282.727128) (xy 121.41711 -282.700479)
			(xy 121.375439 -282.667248) (xy 121.339187 -282.628177) (xy 121.309163 -282.58414) (xy 121.286037 -282.536119)
			(xy 121.270327 -282.485189) (xy 121.262384 -282.432485) (xy 121.033804 -282.432485) (xy 121.025861 -282.485189)
			(xy 121.010151 -282.536119) (xy 120.987025 -282.58414) (xy 120.957001 -282.628177) (xy 120.920749 -282.667248)
			(xy 120.879078 -282.700479) (xy 120.83292 -282.727128) (xy 120.783306 -282.7466) (xy 120.731344 -282.75846)
			(xy 120.678194 -282.762444) (xy 120.625044 -282.75846) (xy 120.573082 -282.7466) (xy 120.523468 -282.727128)
			(xy 120.47731 -282.700479) (xy 120.435639 -282.667248) (xy 120.399387 -282.628177) (xy 120.369363 -282.58414)
			(xy 120.346237 -282.536119) (xy 120.330527 -282.485189) (xy 120.322584 -282.432485) (xy 120.094004 -282.432485)
			(xy 120.086061 -282.485189) (xy 120.070351 -282.536119) (xy 120.047225 -282.58414) (xy 120.017201 -282.628177)
			(xy 119.980949 -282.667248) (xy 119.939278 -282.700479) (xy 119.89312 -282.727128) (xy 119.843506 -282.7466)
			(xy 119.791544 -282.75846) (xy 119.738394 -282.762444) (xy 119.685244 -282.75846) (xy 119.633282 -282.7466)
			(xy 119.583668 -282.727128) (xy 119.53751 -282.700479) (xy 119.495839 -282.667248) (xy 119.459587 -282.628177)
			(xy 119.429563 -282.58414) (xy 119.406437 -282.536119) (xy 119.390727 -282.485189) (xy 119.382784 -282.432485)
			(xy 119.154177 -282.432485) (xy 119.154141 -282.434307) (xy 119.145082 -282.490523) (xy 119.127199 -282.544584)
			(xy 119.100949 -282.595114) (xy 119.066998 -282.640826) (xy 119.047006 -282.661106) (xy 119.046752 -282.66136)
			(xy 119.01043 -282.697428) (xy 119.18569 -282.872688) (xy 119.211344 -282.86837) (xy 119.225533 -282.866216)
			(xy 119.254143 -282.863928) (xy 119.268494 -282.863798) (xy 119.296479 -282.864318) (xy 119.351761 -282.873073)
			(xy 119.404993 -282.890369) (xy 119.454864 -282.915779) (xy 119.500145 -282.948677) (xy 119.539723 -282.988255)
			(xy 119.572621 -283.033536) (xy 119.598031 -283.083407) (xy 119.615327 -283.136639) (xy 119.624082 -283.191921)
			(xy 119.624602 -283.219906) (xy 119.624469 -283.234257) (xy 119.623487 -283.246555) (xy 119.852938 -283.246555)
			(xy 119.852938 -283.193257) (xy 119.860881 -283.140553) (xy 119.876591 -283.089623) (xy 119.899717 -283.041602)
			(xy 119.929741 -282.997565) (xy 119.965993 -282.958494) (xy 120.007664 -282.925263) (xy 120.053822 -282.898614)
			(xy 120.103436 -282.879142) (xy 120.155398 -282.867282) (xy 120.208548 -282.863299) (xy 120.261698 -282.867282)
			(xy 120.31366 -282.879142) (xy 120.363274 -282.898614) (xy 120.409432 -282.925263) (xy 120.451103 -282.958494)
			(xy 120.487355 -282.997565) (xy 120.517379 -283.041602) (xy 120.540505 -283.089623) (xy 120.556215 -283.140553)
			(xy 120.564158 -283.193257) (xy 120.564656 -283.219906) (xy 120.564158 -283.246555) (xy 120.792484 -283.246555)
			(xy 120.792484 -283.193257) (xy 120.800427 -283.140553) (xy 120.816137 -283.089623) (xy 120.839263 -283.041602)
			(xy 120.869287 -282.997565) (xy 120.905539 -282.958494) (xy 120.94721 -282.925263) (xy 120.993368 -282.898614)
			(xy 121.042982 -282.879142) (xy 121.094944 -282.867282) (xy 121.148094 -282.863299) (xy 121.201244 -282.867282)
			(xy 121.253206 -282.879142) (xy 121.30282 -282.898614) (xy 121.348978 -282.925263) (xy 121.390649 -282.958494)
			(xy 121.426901 -282.997565) (xy 121.456925 -283.041602) (xy 121.480051 -283.089623) (xy 121.495761 -283.140553)
			(xy 121.503704 -283.193257) (xy 121.504202 -283.219906) (xy 121.503704 -283.246555) (xy 121.732284 -283.246555)
			(xy 121.732284 -283.193257) (xy 121.740227 -283.140553) (xy 121.755937 -283.089623) (xy 121.779063 -283.041602)
			(xy 121.809087 -282.997565) (xy 121.845339 -282.958494) (xy 121.88701 -282.925263) (xy 121.933168 -282.898614)
			(xy 121.982782 -282.879142) (xy 122.034744 -282.867282) (xy 122.087894 -282.863299) (xy 122.141044 -282.867282)
			(xy 122.193006 -282.879142) (xy 122.24262 -282.898614) (xy 122.288778 -282.925263) (xy 122.330449 -282.958494)
			(xy 122.366701 -282.997565) (xy 122.396725 -283.041602) (xy 122.419851 -283.089623) (xy 122.435561 -283.140553)
			(xy 122.443504 -283.193257) (xy 122.444002 -283.219906) (xy 122.443504 -283.246555) (xy 122.672338 -283.246555)
			(xy 122.672338 -283.193257) (xy 122.680281 -283.140553) (xy 122.695991 -283.089623) (xy 122.719117 -283.041602)
			(xy 122.749141 -282.997565) (xy 122.785393 -282.958494) (xy 122.827064 -282.925263) (xy 122.873222 -282.898614)
			(xy 122.922836 -282.879142) (xy 122.974798 -282.867282) (xy 123.027948 -282.863299) (xy 123.081098 -282.867282)
			(xy 123.13306 -282.879142) (xy 123.182674 -282.898614) (xy 123.228832 -282.925263) (xy 123.270503 -282.958494)
			(xy 123.306755 -282.997565) (xy 123.336779 -283.041602) (xy 123.359905 -283.089623) (xy 123.375615 -283.140553)
			(xy 123.383558 -283.193257) (xy 123.384056 -283.219906) (xy 123.383558 -283.246555) (xy 124.551938 -283.246555)
			(xy 124.551938 -283.193257) (xy 124.559881 -283.140553) (xy 124.575591 -283.089623) (xy 124.598717 -283.041602)
			(xy 124.628741 -282.997565) (xy 124.664993 -282.958494) (xy 124.706664 -282.925263) (xy 124.752822 -282.898614)
			(xy 124.802436 -282.879142) (xy 124.854398 -282.867282) (xy 124.907548 -282.863299) (xy 124.960698 -282.867282)
			(xy 125.01266 -282.879142) (xy 125.062274 -282.898614) (xy 125.108432 -282.925263) (xy 125.150103 -282.958494)
			(xy 125.186355 -282.997565) (xy 125.216379 -283.041602) (xy 125.239505 -283.089623) (xy 125.255215 -283.140553)
			(xy 125.263158 -283.193257) (xy 125.263656 -283.219906) (xy 125.263158 -283.246555) (xy 125.491738 -283.246555)
			(xy 125.491738 -283.193257) (xy 125.499681 -283.140553) (xy 125.515391 -283.089623) (xy 125.538517 -283.041602)
			(xy 125.568541 -282.997565) (xy 125.604793 -282.958494) (xy 125.646464 -282.925263) (xy 125.692622 -282.898614)
			(xy 125.742236 -282.879142) (xy 125.794198 -282.867282) (xy 125.847348 -282.863299) (xy 125.900498 -282.867282)
			(xy 125.95246 -282.879142) (xy 126.002074 -282.898614) (xy 126.048232 -282.925263) (xy 126.089903 -282.958494)
			(xy 126.126155 -282.997565) (xy 126.156179 -283.041602) (xy 126.179305 -283.089623) (xy 126.195015 -283.140553)
			(xy 126.202958 -283.193257) (xy 126.203456 -283.219906) (xy 126.202958 -283.246555) (xy 126.431284 -283.246555)
			(xy 126.431284 -283.193257) (xy 126.439227 -283.140553) (xy 126.454937 -283.089623) (xy 126.478063 -283.041602)
			(xy 126.508087 -282.997565) (xy 126.544339 -282.958494) (xy 126.58601 -282.925263) (xy 126.632168 -282.898614)
			(xy 126.681782 -282.879142) (xy 126.733744 -282.867282) (xy 126.786894 -282.863299) (xy 126.840044 -282.867282)
			(xy 126.892006 -282.879142) (xy 126.94162 -282.898614) (xy 126.987778 -282.925263) (xy 127.029449 -282.958494)
			(xy 127.065701 -282.997565) (xy 127.095725 -283.041602) (xy 127.118851 -283.089623) (xy 127.134561 -283.140553)
			(xy 127.142504 -283.193257) (xy 127.143002 -283.219906) (xy 127.142509 -283.246301) (xy 128.310884 -283.246301)
			(xy 128.310884 -283.193003) (xy 128.318827 -283.140299) (xy 128.334537 -283.089369) (xy 128.357663 -283.041348)
			(xy 128.387687 -282.997311) (xy 128.423939 -282.95824) (xy 128.46561 -282.925009) (xy 128.511768 -282.89836)
			(xy 128.561382 -282.878888) (xy 128.613344 -282.867028) (xy 128.666494 -282.863045) (xy 128.719644 -282.867028)
			(xy 128.771606 -282.878888) (xy 128.82122 -282.89836) (xy 128.867378 -282.925009) (xy 128.909049 -282.95824)
			(xy 128.945301 -282.997311) (xy 128.975325 -283.041348) (xy 128.998451 -283.089369) (xy 129.014161 -283.140299)
			(xy 129.022104 -283.193003) (xy 129.022602 -283.219652) (xy 129.022104 -283.246301) (xy 129.022066 -283.246555)
			(xy 129.250684 -283.246555) (xy 129.250684 -283.193257) (xy 129.258627 -283.140553) (xy 129.274337 -283.089623)
			(xy 129.297463 -283.041602) (xy 129.327487 -282.997565) (xy 129.363739 -282.958494) (xy 129.40541 -282.925263)
			(xy 129.451568 -282.898614) (xy 129.501182 -282.879142) (xy 129.553144 -282.867282) (xy 129.606294 -282.863299)
			(xy 129.659444 -282.867282) (xy 129.711406 -282.879142) (xy 129.76102 -282.898614) (xy 129.807178 -282.925263)
			(xy 129.848849 -282.958494) (xy 129.885101 -282.997565) (xy 129.915125 -283.041602) (xy 129.938251 -283.089623)
			(xy 129.953961 -283.140553) (xy 129.961904 -283.193257) (xy 129.962402 -283.219906) (xy 129.961904 -283.246555)
			(xy 130.190484 -283.246555) (xy 130.190484 -283.193257) (xy 130.198427 -283.140553) (xy 130.214137 -283.089623)
			(xy 130.237263 -283.041602) (xy 130.267287 -282.997565) (xy 130.303539 -282.958494) (xy 130.34521 -282.925263)
			(xy 130.391368 -282.898614) (xy 130.440982 -282.879142) (xy 130.492944 -282.867282) (xy 130.546094 -282.863299)
			(xy 130.599244 -282.867282) (xy 130.651206 -282.879142) (xy 130.70082 -282.898614) (xy 130.746978 -282.925263)
			(xy 130.788649 -282.958494) (xy 130.824901 -282.997565) (xy 130.854925 -283.041602) (xy 130.878051 -283.089623)
			(xy 130.893761 -283.140553) (xy 130.901704 -283.193257) (xy 130.902202 -283.219906) (xy 130.901704 -283.246555)
			(xy 131.130538 -283.246555) (xy 131.130538 -283.193257) (xy 131.138481 -283.140553) (xy 131.154191 -283.089623)
			(xy 131.177317 -283.041602) (xy 131.207341 -282.997565) (xy 131.243593 -282.958494) (xy 131.285264 -282.925263)
			(xy 131.331422 -282.898614) (xy 131.381036 -282.879142) (xy 131.432998 -282.867282) (xy 131.486148 -282.863299)
			(xy 131.539298 -282.867282) (xy 131.59126 -282.879142) (xy 131.640874 -282.898614) (xy 131.687032 -282.925263)
			(xy 131.728703 -282.958494) (xy 131.764955 -282.997565) (xy 131.794979 -283.041602) (xy 131.818105 -283.089623)
			(xy 131.833815 -283.140553) (xy 131.841758 -283.193257) (xy 131.842256 -283.219906) (xy 131.841758 -283.246555)
			(xy 132.070084 -283.246555) (xy 132.070084 -283.193257) (xy 132.078027 -283.140553) (xy 132.093737 -283.089623)
			(xy 132.116863 -283.041602) (xy 132.146887 -282.997565) (xy 132.183139 -282.958494) (xy 132.22481 -282.925263)
			(xy 132.270968 -282.898614) (xy 132.320582 -282.879142) (xy 132.372544 -282.867282) (xy 132.425694 -282.863299)
			(xy 132.478844 -282.867282) (xy 132.530806 -282.879142) (xy 132.58042 -282.898614) (xy 132.626578 -282.925263)
			(xy 132.668249 -282.958494) (xy 132.704501 -282.997565) (xy 132.734525 -283.041602) (xy 132.757651 -283.089623)
			(xy 132.773361 -283.140553) (xy 132.781304 -283.193257) (xy 132.781802 -283.219906) (xy 132.781304 -283.246555)
			(xy 133.010138 -283.246555) (xy 133.010138 -283.193257) (xy 133.018081 -283.140553) (xy 133.033791 -283.089623)
			(xy 133.056917 -283.041602) (xy 133.086941 -282.997565) (xy 133.123193 -282.958494) (xy 133.164864 -282.925263)
			(xy 133.211022 -282.898614) (xy 133.260636 -282.879142) (xy 133.312598 -282.867282) (xy 133.365748 -282.863299)
			(xy 133.418898 -282.867282) (xy 133.47086 -282.879142) (xy 133.520474 -282.898614) (xy 133.566632 -282.925263)
			(xy 133.608303 -282.958494) (xy 133.644555 -282.997565) (xy 133.674579 -283.041602) (xy 133.697705 -283.089623)
			(xy 133.713415 -283.140553) (xy 133.721358 -283.193257) (xy 133.721856 -283.219906) (xy 133.721358 -283.246555)
			(xy 133.949938 -283.246555) (xy 133.949938 -283.193257) (xy 133.957881 -283.140553) (xy 133.973591 -283.089623)
			(xy 133.996717 -283.041602) (xy 134.026741 -282.997565) (xy 134.062993 -282.958494) (xy 134.104664 -282.925263)
			(xy 134.150822 -282.898614) (xy 134.200436 -282.879142) (xy 134.252398 -282.867282) (xy 134.305548 -282.863299)
			(xy 134.358698 -282.867282) (xy 134.41066 -282.879142) (xy 134.460274 -282.898614) (xy 134.506432 -282.925263)
			(xy 134.548103 -282.958494) (xy 134.584355 -282.997565) (xy 134.614379 -283.041602) (xy 134.637505 -283.089623)
			(xy 134.653215 -283.140553) (xy 134.661158 -283.193257) (xy 134.661656 -283.219906) (xy 134.661158 -283.246555)
			(xy 134.889484 -283.246555) (xy 134.889484 -283.193257) (xy 134.897427 -283.140553) (xy 134.913137 -283.089623)
			(xy 134.936263 -283.041602) (xy 134.966287 -282.997565) (xy 135.002539 -282.958494) (xy 135.04421 -282.925263)
			(xy 135.090368 -282.898614) (xy 135.139982 -282.879142) (xy 135.191944 -282.867282) (xy 135.245094 -282.863299)
			(xy 135.298244 -282.867282) (xy 135.350206 -282.879142) (xy 135.39982 -282.898614) (xy 135.445978 -282.925263)
			(xy 135.487649 -282.958494) (xy 135.523901 -282.997565) (xy 135.553925 -283.041602) (xy 135.577051 -283.089623)
			(xy 135.592761 -283.140553) (xy 135.600704 -283.193257) (xy 135.601202 -283.219906) (xy 135.600704 -283.246555)
			(xy 135.829284 -283.246555) (xy 135.829284 -283.193257) (xy 135.837227 -283.140553) (xy 135.852937 -283.089623)
			(xy 135.876063 -283.041602) (xy 135.906087 -282.997565) (xy 135.942339 -282.958494) (xy 135.98401 -282.925263)
			(xy 136.030168 -282.898614) (xy 136.079782 -282.879142) (xy 136.131744 -282.867282) (xy 136.184894 -282.863299)
			(xy 136.238044 -282.867282) (xy 136.290006 -282.879142) (xy 136.33962 -282.898614) (xy 136.385778 -282.925263)
			(xy 136.427449 -282.958494) (xy 136.463701 -282.997565) (xy 136.493725 -283.041602) (xy 136.516851 -283.089623)
			(xy 136.532561 -283.140553) (xy 136.540504 -283.193257) (xy 136.541002 -283.219906) (xy 136.540504 -283.246555)
			(xy 136.769338 -283.246555) (xy 136.769338 -283.193257) (xy 136.777281 -283.140553) (xy 136.792991 -283.089623)
			(xy 136.816117 -283.041602) (xy 136.846141 -282.997565) (xy 136.882393 -282.958494) (xy 136.924064 -282.925263)
			(xy 136.970222 -282.898614) (xy 137.019836 -282.879142) (xy 137.071798 -282.867282) (xy 137.124948 -282.863299)
			(xy 137.178098 -282.867282) (xy 137.23006 -282.879142) (xy 137.279674 -282.898614) (xy 137.325832 -282.925263)
			(xy 137.367503 -282.958494) (xy 137.403755 -282.997565) (xy 137.433779 -283.041602) (xy 137.456905 -283.089623)
			(xy 137.472615 -283.140553) (xy 137.480558 -283.193257) (xy 137.481056 -283.219906) (xy 137.480558 -283.246555)
			(xy 137.472615 -283.299259) (xy 137.456905 -283.350189) (xy 137.433779 -283.39821) (xy 137.403755 -283.442247)
			(xy 137.367503 -283.481318) (xy 137.325832 -283.514549) (xy 137.279674 -283.541198) (xy 137.23006 -283.56067)
			(xy 137.178098 -283.57253) (xy 137.124948 -283.576514) (xy 137.071798 -283.57253) (xy 137.019836 -283.56067)
			(xy 136.970222 -283.541198) (xy 136.924064 -283.514549) (xy 136.882393 -283.481318) (xy 136.846141 -283.442247)
			(xy 136.816117 -283.39821) (xy 136.792991 -283.350189) (xy 136.777281 -283.299259) (xy 136.769338 -283.246555)
			(xy 136.540504 -283.246555) (xy 136.532561 -283.299259) (xy 136.516851 -283.350189) (xy 136.493725 -283.39821)
			(xy 136.463701 -283.442247) (xy 136.427449 -283.481318) (xy 136.385778 -283.514549) (xy 136.33962 -283.541198)
			(xy 136.290006 -283.56067) (xy 136.238044 -283.57253) (xy 136.184894 -283.576514) (xy 136.131744 -283.57253)
			(xy 136.079782 -283.56067) (xy 136.030168 -283.541198) (xy 135.98401 -283.514549) (xy 135.942339 -283.481318)
			(xy 135.906087 -283.442247) (xy 135.876063 -283.39821) (xy 135.852937 -283.350189) (xy 135.837227 -283.299259)
			(xy 135.829284 -283.246555) (xy 135.600704 -283.246555) (xy 135.592761 -283.299259) (xy 135.577051 -283.350189)
			(xy 135.553925 -283.39821) (xy 135.523901 -283.442247) (xy 135.487649 -283.481318) (xy 135.445978 -283.514549)
			(xy 135.39982 -283.541198) (xy 135.350206 -283.56067) (xy 135.298244 -283.57253) (xy 135.245094 -283.576514)
			(xy 135.191944 -283.57253) (xy 135.139982 -283.56067) (xy 135.090368 -283.541198) (xy 135.04421 -283.514549)
			(xy 135.002539 -283.481318) (xy 134.966287 -283.442247) (xy 134.936263 -283.39821) (xy 134.913137 -283.350189)
			(xy 134.897427 -283.299259) (xy 134.889484 -283.246555) (xy 134.661158 -283.246555) (xy 134.653215 -283.299259)
			(xy 134.637505 -283.350189) (xy 134.614379 -283.39821) (xy 134.584355 -283.442247) (xy 134.548103 -283.481318)
			(xy 134.506432 -283.514549) (xy 134.460274 -283.541198) (xy 134.41066 -283.56067) (xy 134.358698 -283.57253)
			(xy 134.305548 -283.576514) (xy 134.252398 -283.57253) (xy 134.200436 -283.56067) (xy 134.150822 -283.541198)
			(xy 134.104664 -283.514549) (xy 134.062993 -283.481318) (xy 134.026741 -283.442247) (xy 133.996717 -283.39821)
			(xy 133.973591 -283.350189) (xy 133.957881 -283.299259) (xy 133.949938 -283.246555) (xy 133.721358 -283.246555)
			(xy 133.713415 -283.299259) (xy 133.697705 -283.350189) (xy 133.674579 -283.39821) (xy 133.644555 -283.442247)
			(xy 133.608303 -283.481318) (xy 133.566632 -283.514549) (xy 133.520474 -283.541198) (xy 133.47086 -283.56067)
			(xy 133.418898 -283.57253) (xy 133.365748 -283.576514) (xy 133.312598 -283.57253) (xy 133.260636 -283.56067)
			(xy 133.211022 -283.541198) (xy 133.164864 -283.514549) (xy 133.123193 -283.481318) (xy 133.086941 -283.442247)
			(xy 133.056917 -283.39821) (xy 133.033791 -283.350189) (xy 133.018081 -283.299259) (xy 133.010138 -283.246555)
			(xy 132.781304 -283.246555) (xy 132.773361 -283.299259) (xy 132.757651 -283.350189) (xy 132.734525 -283.39821)
			(xy 132.704501 -283.442247) (xy 132.668249 -283.481318) (xy 132.626578 -283.514549) (xy 132.58042 -283.541198)
			(xy 132.530806 -283.56067) (xy 132.478844 -283.57253) (xy 132.425694 -283.576514) (xy 132.372544 -283.57253)
			(xy 132.320582 -283.56067) (xy 132.270968 -283.541198) (xy 132.22481 -283.514549) (xy 132.183139 -283.481318)
			(xy 132.146887 -283.442247) (xy 132.116863 -283.39821) (xy 132.093737 -283.350189) (xy 132.078027 -283.299259)
			(xy 132.070084 -283.246555) (xy 131.841758 -283.246555) (xy 131.833815 -283.299259) (xy 131.818105 -283.350189)
			(xy 131.794979 -283.39821) (xy 131.764955 -283.442247) (xy 131.728703 -283.481318) (xy 131.687032 -283.514549)
			(xy 131.640874 -283.541198) (xy 131.59126 -283.56067) (xy 131.539298 -283.57253) (xy 131.486148 -283.576514)
			(xy 131.432998 -283.57253) (xy 131.381036 -283.56067) (xy 131.331422 -283.541198) (xy 131.285264 -283.514549)
			(xy 131.243593 -283.481318) (xy 131.207341 -283.442247) (xy 131.177317 -283.39821) (xy 131.154191 -283.350189)
			(xy 131.138481 -283.299259) (xy 131.130538 -283.246555) (xy 130.901704 -283.246555) (xy 130.893761 -283.299259)
			(xy 130.878051 -283.350189) (xy 130.854925 -283.39821) (xy 130.824901 -283.442247) (xy 130.788649 -283.481318)
			(xy 130.746978 -283.514549) (xy 130.70082 -283.541198) (xy 130.651206 -283.56067) (xy 130.599244 -283.57253)
			(xy 130.546094 -283.576514) (xy 130.492944 -283.57253) (xy 130.440982 -283.56067) (xy 130.391368 -283.541198)
			(xy 130.34521 -283.514549) (xy 130.303539 -283.481318) (xy 130.267287 -283.442247) (xy 130.237263 -283.39821)
			(xy 130.214137 -283.350189) (xy 130.198427 -283.299259) (xy 130.190484 -283.246555) (xy 129.961904 -283.246555)
			(xy 129.953961 -283.299259) (xy 129.938251 -283.350189) (xy 129.915125 -283.39821) (xy 129.885101 -283.442247)
			(xy 129.848849 -283.481318) (xy 129.807178 -283.514549) (xy 129.76102 -283.541198) (xy 129.711406 -283.56067)
			(xy 129.659444 -283.57253) (xy 129.606294 -283.576514) (xy 129.553144 -283.57253) (xy 129.501182 -283.56067)
			(xy 129.451568 -283.541198) (xy 129.40541 -283.514549) (xy 129.363739 -283.481318) (xy 129.327487 -283.442247)
			(xy 129.297463 -283.39821) (xy 129.274337 -283.350189) (xy 129.258627 -283.299259) (xy 129.250684 -283.246555)
			(xy 129.022066 -283.246555) (xy 129.014161 -283.299005) (xy 128.998451 -283.349935) (xy 128.975325 -283.397956)
			(xy 128.945301 -283.441993) (xy 128.909049 -283.481064) (xy 128.867378 -283.514295) (xy 128.82122 -283.540944)
			(xy 128.771606 -283.560416) (xy 128.719644 -283.572276) (xy 128.666494 -283.57626) (xy 128.613344 -283.572276)
			(xy 128.561382 -283.560416) (xy 128.511768 -283.540944) (xy 128.46561 -283.514295) (xy 128.423939 -283.481064)
			(xy 128.387687 -283.441993) (xy 128.357663 -283.397956) (xy 128.334537 -283.349935) (xy 128.318827 -283.299005)
			(xy 128.310884 -283.246301) (xy 127.142509 -283.246301) (xy 127.142504 -283.246555) (xy 127.134561 -283.299259)
			(xy 127.118851 -283.350189) (xy 127.095725 -283.39821) (xy 127.065701 -283.442247) (xy 127.029449 -283.481318)
			(xy 126.987778 -283.514549) (xy 126.94162 -283.541198) (xy 126.892006 -283.56067) (xy 126.840044 -283.57253)
			(xy 126.786894 -283.576514) (xy 126.733744 -283.57253) (xy 126.681782 -283.56067) (xy 126.632168 -283.541198)
			(xy 126.58601 -283.514549) (xy 126.544339 -283.481318) (xy 126.508087 -283.442247) (xy 126.478063 -283.39821)
			(xy 126.454937 -283.350189) (xy 126.439227 -283.299259) (xy 126.431284 -283.246555) (xy 126.202958 -283.246555)
			(xy 126.195015 -283.299259) (xy 126.179305 -283.350189) (xy 126.156179 -283.39821) (xy 126.126155 -283.442247)
			(xy 126.089903 -283.481318) (xy 126.048232 -283.514549) (xy 126.002074 -283.541198) (xy 125.95246 -283.56067)
			(xy 125.900498 -283.57253) (xy 125.847348 -283.576514) (xy 125.794198 -283.57253) (xy 125.742236 -283.56067)
			(xy 125.692622 -283.541198) (xy 125.646464 -283.514549) (xy 125.604793 -283.481318) (xy 125.568541 -283.442247)
			(xy 125.538517 -283.39821) (xy 125.515391 -283.350189) (xy 125.499681 -283.299259) (xy 125.491738 -283.246555)
			(xy 125.263158 -283.246555) (xy 125.255215 -283.299259) (xy 125.239505 -283.350189) (xy 125.216379 -283.39821)
			(xy 125.186355 -283.442247) (xy 125.150103 -283.481318) (xy 125.108432 -283.514549) (xy 125.062274 -283.541198)
			(xy 125.01266 -283.56067) (xy 124.960698 -283.57253) (xy 124.907548 -283.576514) (xy 124.854398 -283.57253)
			(xy 124.802436 -283.56067) (xy 124.752822 -283.541198) (xy 124.706664 -283.514549) (xy 124.664993 -283.481318)
			(xy 124.628741 -283.442247) (xy 124.598717 -283.39821) (xy 124.575591 -283.350189) (xy 124.559881 -283.299259)
			(xy 124.551938 -283.246555) (xy 123.383558 -283.246555) (xy 123.375615 -283.299259) (xy 123.359905 -283.350189)
			(xy 123.336779 -283.39821) (xy 123.306755 -283.442247) (xy 123.270503 -283.481318) (xy 123.228832 -283.514549)
			(xy 123.182674 -283.541198) (xy 123.13306 -283.56067) (xy 123.081098 -283.57253) (xy 123.027948 -283.576514)
			(xy 122.974798 -283.57253) (xy 122.922836 -283.56067) (xy 122.873222 -283.541198) (xy 122.827064 -283.514549)
			(xy 122.785393 -283.481318) (xy 122.749141 -283.442247) (xy 122.719117 -283.39821) (xy 122.695991 -283.350189)
			(xy 122.680281 -283.299259) (xy 122.672338 -283.246555) (xy 122.443504 -283.246555) (xy 122.435561 -283.299259)
			(xy 122.419851 -283.350189) (xy 122.396725 -283.39821) (xy 122.366701 -283.442247) (xy 122.330449 -283.481318)
			(xy 122.288778 -283.514549) (xy 122.24262 -283.541198) (xy 122.193006 -283.56067) (xy 122.141044 -283.57253)
			(xy 122.087894 -283.576514) (xy 122.034744 -283.57253) (xy 121.982782 -283.56067) (xy 121.933168 -283.541198)
			(xy 121.88701 -283.514549) (xy 121.845339 -283.481318) (xy 121.809087 -283.442247) (xy 121.779063 -283.39821)
			(xy 121.755937 -283.350189) (xy 121.740227 -283.299259) (xy 121.732284 -283.246555) (xy 121.503704 -283.246555)
			(xy 121.495761 -283.299259) (xy 121.480051 -283.350189) (xy 121.456925 -283.39821) (xy 121.426901 -283.442247)
			(xy 121.390649 -283.481318) (xy 121.348978 -283.514549) (xy 121.30282 -283.541198) (xy 121.253206 -283.56067)
			(xy 121.201244 -283.57253) (xy 121.148094 -283.576514) (xy 121.094944 -283.57253) (xy 121.042982 -283.56067)
			(xy 120.993368 -283.541198) (xy 120.94721 -283.514549) (xy 120.905539 -283.481318) (xy 120.869287 -283.442247)
			(xy 120.839263 -283.39821) (xy 120.816137 -283.350189) (xy 120.800427 -283.299259) (xy 120.792484 -283.246555)
			(xy 120.564158 -283.246555) (xy 120.556215 -283.299259) (xy 120.540505 -283.350189) (xy 120.517379 -283.39821)
			(xy 120.487355 -283.442247) (xy 120.451103 -283.481318) (xy 120.409432 -283.514549) (xy 120.363274 -283.541198)
			(xy 120.31366 -283.56067) (xy 120.261698 -283.57253) (xy 120.208548 -283.576514) (xy 120.155398 -283.57253)
			(xy 120.103436 -283.56067) (xy 120.053822 -283.541198) (xy 120.007664 -283.514549) (xy 119.965993 -283.481318)
			(xy 119.929741 -283.442247) (xy 119.899717 -283.39821) (xy 119.876591 -283.350189) (xy 119.860881 -283.299259)
			(xy 119.852938 -283.246555) (xy 119.623487 -283.246555) (xy 119.622184 -283.262867) (xy 119.62003 -283.277056)
			(xy 119.615712 -283.30271) (xy 119.83466 -283.521658) (xy 119.83466 -283.689044) (xy 119.867172 -283.701744)
			(xy 119.891924 -283.71186) (xy 119.938324 -283.738436) (xy 119.980228 -283.771651) (xy 120.016694 -283.810759)
			(xy 120.046902 -283.85488) (xy 120.070173 -283.903022) (xy 120.085984 -283.954102) (xy 120.093978 -284.006972)
			(xy 120.093977 -284.060371) (xy 120.322584 -284.060371) (xy 120.322584 -284.007073) (xy 120.330527 -283.954369)
			(xy 120.346237 -283.903439) (xy 120.369363 -283.855418) (xy 120.399387 -283.811381) (xy 120.435639 -283.77231)
			(xy 120.47731 -283.739079) (xy 120.523468 -283.71243) (xy 120.573082 -283.692958) (xy 120.625044 -283.681098)
			(xy 120.678194 -283.677115) (xy 120.731344 -283.681098) (xy 120.783306 -283.692958) (xy 120.83292 -283.71243)
			(xy 120.879078 -283.739079) (xy 120.920749 -283.77231) (xy 120.957001 -283.811381) (xy 120.987025 -283.855418)
			(xy 121.010151 -283.903439) (xy 121.025861 -283.954369) (xy 121.033804 -284.007073) (xy 121.034302 -284.033722)
			(xy 121.033804 -284.060371) (xy 121.262384 -284.060371) (xy 121.262384 -284.007073) (xy 121.270327 -283.954369)
			(xy 121.286037 -283.903439) (xy 121.309163 -283.855418) (xy 121.339187 -283.811381) (xy 121.375439 -283.77231)
			(xy 121.41711 -283.739079) (xy 121.463268 -283.71243) (xy 121.512882 -283.692958) (xy 121.564844 -283.681098)
			(xy 121.617994 -283.677115) (xy 121.671144 -283.681098) (xy 121.723106 -283.692958) (xy 121.77272 -283.71243)
			(xy 121.818878 -283.739079) (xy 121.860549 -283.77231) (xy 121.896801 -283.811381) (xy 121.926825 -283.855418)
			(xy 121.949951 -283.903439) (xy 121.965661 -283.954369) (xy 121.973604 -284.007073) (xy 121.974102 -284.033722)
			(xy 121.973604 -284.060371) (xy 122.202184 -284.060371) (xy 122.202184 -284.007073) (xy 122.210127 -283.954369)
			(xy 122.225837 -283.903439) (xy 122.248963 -283.855418) (xy 122.278987 -283.811381) (xy 122.315239 -283.77231)
			(xy 122.35691 -283.739079) (xy 122.403068 -283.71243) (xy 122.452682 -283.692958) (xy 122.504644 -283.681098)
			(xy 122.557794 -283.677115) (xy 122.610944 -283.681098) (xy 122.662906 -283.692958) (xy 122.71252 -283.71243)
			(xy 122.758678 -283.739079) (xy 122.800349 -283.77231) (xy 122.836601 -283.811381) (xy 122.866625 -283.855418)
			(xy 122.889751 -283.903439) (xy 122.905461 -283.954369) (xy 122.913404 -284.007073) (xy 122.913902 -284.033722)
			(xy 122.913404 -284.060371) (xy 123.141984 -284.060371) (xy 123.141984 -284.007073) (xy 123.149927 -283.954369)
			(xy 123.165637 -283.903439) (xy 123.188763 -283.855418) (xy 123.218787 -283.811381) (xy 123.255039 -283.77231)
			(xy 123.29671 -283.739079) (xy 123.342868 -283.71243) (xy 123.392482 -283.692958) (xy 123.444444 -283.681098)
			(xy 123.497594 -283.677115) (xy 123.550744 -283.681098) (xy 123.602706 -283.692958) (xy 123.65232 -283.71243)
			(xy 123.698478 -283.739079) (xy 123.740149 -283.77231) (xy 123.776401 -283.811381) (xy 123.806425 -283.855418)
			(xy 123.829551 -283.903439) (xy 123.845261 -283.954369) (xy 123.853204 -284.007073) (xy 123.853702 -284.033722)
			(xy 123.853204 -284.060371) (xy 124.081784 -284.060371) (xy 124.081784 -284.007073) (xy 124.089727 -283.954369)
			(xy 124.105437 -283.903439) (xy 124.128563 -283.855418) (xy 124.158587 -283.811381) (xy 124.194839 -283.77231)
			(xy 124.23651 -283.739079) (xy 124.282668 -283.71243) (xy 124.332282 -283.692958) (xy 124.384244 -283.681098)
			(xy 124.437394 -283.677115) (xy 124.490544 -283.681098) (xy 124.542506 -283.692958) (xy 124.59212 -283.71243)
			(xy 124.638278 -283.739079) (xy 124.679949 -283.77231) (xy 124.716201 -283.811381) (xy 124.746225 -283.855418)
			(xy 124.769351 -283.903439) (xy 124.785061 -283.954369) (xy 124.793004 -284.007073) (xy 124.793502 -284.033722)
			(xy 124.793004 -284.060371) (xy 125.021838 -284.060371) (xy 125.021838 -284.007073) (xy 125.029781 -283.954369)
			(xy 125.045491 -283.903439) (xy 125.068617 -283.855418) (xy 125.098641 -283.811381) (xy 125.134893 -283.77231)
			(xy 125.176564 -283.739079) (xy 125.222722 -283.71243) (xy 125.272336 -283.692958) (xy 125.324298 -283.681098)
			(xy 125.377448 -283.677115) (xy 125.430598 -283.681098) (xy 125.48256 -283.692958) (xy 125.532174 -283.71243)
			(xy 125.578332 -283.739079) (xy 125.620003 -283.77231) (xy 125.656255 -283.811381) (xy 125.686279 -283.855418)
			(xy 125.709405 -283.903439) (xy 125.725115 -283.954369) (xy 125.733058 -284.007073) (xy 125.733556 -284.033722)
			(xy 125.733058 -284.060371) (xy 125.961384 -284.060371) (xy 125.961384 -284.007073) (xy 125.969327 -283.954369)
			(xy 125.985037 -283.903439) (xy 126.008163 -283.855418) (xy 126.038187 -283.811381) (xy 126.074439 -283.77231)
			(xy 126.11611 -283.739079) (xy 126.162268 -283.71243) (xy 126.211882 -283.692958) (xy 126.263844 -283.681098)
			(xy 126.316994 -283.677115) (xy 126.370144 -283.681098) (xy 126.422106 -283.692958) (xy 126.47172 -283.71243)
			(xy 126.517878 -283.739079) (xy 126.559549 -283.77231) (xy 126.595801 -283.811381) (xy 126.625825 -283.855418)
			(xy 126.648951 -283.903439) (xy 126.664661 -283.954369) (xy 126.672604 -284.007073) (xy 126.673102 -284.033722)
			(xy 126.672604 -284.060371) (xy 126.901184 -284.060371) (xy 126.901184 -284.007073) (xy 126.909127 -283.954369)
			(xy 126.924837 -283.903439) (xy 126.947963 -283.855418) (xy 126.977987 -283.811381) (xy 127.014239 -283.77231)
			(xy 127.05591 -283.739079) (xy 127.102068 -283.71243) (xy 127.151682 -283.692958) (xy 127.203644 -283.681098)
			(xy 127.256794 -283.677115) (xy 127.309944 -283.681098) (xy 127.361906 -283.692958) (xy 127.41152 -283.71243)
			(xy 127.457678 -283.739079) (xy 127.499349 -283.77231) (xy 127.535601 -283.811381) (xy 127.565625 -283.855418)
			(xy 127.588751 -283.903439) (xy 127.604461 -283.954369) (xy 127.612404 -284.007073) (xy 127.612902 -284.033722)
			(xy 127.612404 -284.060371) (xy 127.840984 -284.060371) (xy 127.840984 -284.007073) (xy 127.848927 -283.954369)
			(xy 127.864637 -283.903439) (xy 127.887763 -283.855418) (xy 127.917787 -283.811381) (xy 127.954039 -283.77231)
			(xy 127.99571 -283.739079) (xy 128.041868 -283.71243) (xy 128.091482 -283.692958) (xy 128.143444 -283.681098)
			(xy 128.196594 -283.677115) (xy 128.249744 -283.681098) (xy 128.301706 -283.692958) (xy 128.35132 -283.71243)
			(xy 128.397478 -283.739079) (xy 128.439149 -283.77231) (xy 128.475401 -283.811381) (xy 128.505425 -283.855418)
			(xy 128.528551 -283.903439) (xy 128.544261 -283.954369) (xy 128.552204 -284.007073) (xy 128.552702 -284.033722)
			(xy 128.552204 -284.060371) (xy 128.780784 -284.060371) (xy 128.780784 -284.007073) (xy 128.788727 -283.954369)
			(xy 128.804437 -283.903439) (xy 128.827563 -283.855418) (xy 128.857587 -283.811381) (xy 128.893839 -283.77231)
			(xy 128.93551 -283.739079) (xy 128.981668 -283.71243) (xy 129.031282 -283.692958) (xy 129.083244 -283.681098)
			(xy 129.136394 -283.677115) (xy 129.189544 -283.681098) (xy 129.241506 -283.692958) (xy 129.29112 -283.71243)
			(xy 129.337278 -283.739079) (xy 129.378949 -283.77231) (xy 129.415201 -283.811381) (xy 129.445225 -283.855418)
			(xy 129.468351 -283.903439) (xy 129.484061 -283.954369) (xy 129.492004 -284.007073) (xy 129.492502 -284.033722)
			(xy 129.492004 -284.060371) (xy 129.720584 -284.060371) (xy 129.720584 -284.007073) (xy 129.728527 -283.954369)
			(xy 129.744237 -283.903439) (xy 129.767363 -283.855418) (xy 129.797387 -283.811381) (xy 129.833639 -283.77231)
			(xy 129.87531 -283.739079) (xy 129.921468 -283.71243) (xy 129.971082 -283.692958) (xy 130.023044 -283.681098)
			(xy 130.076194 -283.677115) (xy 130.129344 -283.681098) (xy 130.181306 -283.692958) (xy 130.23092 -283.71243)
			(xy 130.277078 -283.739079) (xy 130.318749 -283.77231) (xy 130.355001 -283.811381) (xy 130.385025 -283.855418)
			(xy 130.408151 -283.903439) (xy 130.423861 -283.954369) (xy 130.431804 -284.007073) (xy 130.432302 -284.033722)
			(xy 130.431804 -284.060371) (xy 130.660384 -284.060371) (xy 130.660384 -284.007073) (xy 130.668327 -283.954369)
			(xy 130.684037 -283.903439) (xy 130.707163 -283.855418) (xy 130.737187 -283.811381) (xy 130.773439 -283.77231)
			(xy 130.81511 -283.739079) (xy 130.861268 -283.71243) (xy 130.910882 -283.692958) (xy 130.962844 -283.681098)
			(xy 131.015994 -283.677115) (xy 131.069144 -283.681098) (xy 131.121106 -283.692958) (xy 131.17072 -283.71243)
			(xy 131.216878 -283.739079) (xy 131.258549 -283.77231) (xy 131.294801 -283.811381) (xy 131.324825 -283.855418)
			(xy 131.347951 -283.903439) (xy 131.363661 -283.954369) (xy 131.371604 -284.007073) (xy 131.372102 -284.033722)
			(xy 131.371604 -284.060371) (xy 131.600184 -284.060371) (xy 131.600184 -284.007073) (xy 131.608127 -283.954369)
			(xy 131.623837 -283.903439) (xy 131.646963 -283.855418) (xy 131.676987 -283.811381) (xy 131.713239 -283.77231)
			(xy 131.75491 -283.739079) (xy 131.801068 -283.71243) (xy 131.850682 -283.692958) (xy 131.902644 -283.681098)
			(xy 131.955794 -283.677115) (xy 132.008944 -283.681098) (xy 132.060906 -283.692958) (xy 132.11052 -283.71243)
			(xy 132.156678 -283.739079) (xy 132.198349 -283.77231) (xy 132.234601 -283.811381) (xy 132.264625 -283.855418)
			(xy 132.287751 -283.903439) (xy 132.303461 -283.954369) (xy 132.311404 -284.007073) (xy 132.311902 -284.033722)
			(xy 132.311404 -284.060371) (xy 132.539984 -284.060371) (xy 132.539984 -284.007073) (xy 132.547927 -283.954369)
			(xy 132.563637 -283.903439) (xy 132.586763 -283.855418) (xy 132.616787 -283.811381) (xy 132.653039 -283.77231)
			(xy 132.69471 -283.739079) (xy 132.740868 -283.71243) (xy 132.790482 -283.692958) (xy 132.842444 -283.681098)
			(xy 132.895594 -283.677115) (xy 132.948744 -283.681098) (xy 133.000706 -283.692958) (xy 133.05032 -283.71243)
			(xy 133.096478 -283.739079) (xy 133.138149 -283.77231) (xy 133.174401 -283.811381) (xy 133.204425 -283.855418)
			(xy 133.227551 -283.903439) (xy 133.243261 -283.954369) (xy 133.251204 -284.007073) (xy 133.251702 -284.033722)
			(xy 133.251204 -284.060371) (xy 134.419584 -284.060371) (xy 134.419584 -284.007073) (xy 134.427527 -283.954369)
			(xy 134.443237 -283.903439) (xy 134.466363 -283.855418) (xy 134.496387 -283.811381) (xy 134.532639 -283.77231)
			(xy 134.57431 -283.739079) (xy 134.620468 -283.71243) (xy 134.670082 -283.692958) (xy 134.722044 -283.681098)
			(xy 134.775194 -283.677115) (xy 134.828344 -283.681098) (xy 134.880306 -283.692958) (xy 134.92992 -283.71243)
			(xy 134.976078 -283.739079) (xy 135.017749 -283.77231) (xy 135.054001 -283.811381) (xy 135.084025 -283.855418)
			(xy 135.107151 -283.903439) (xy 135.122861 -283.954369) (xy 135.130804 -284.007073) (xy 135.131302 -284.033722)
			(xy 135.130809 -284.060117) (xy 136.29893 -284.060117) (xy 136.29893 -284.006819) (xy 136.306873 -283.954115)
			(xy 136.322583 -283.903185) (xy 136.345709 -283.855164) (xy 136.375733 -283.811127) (xy 136.411985 -283.772056)
			(xy 136.453656 -283.738825) (xy 136.499814 -283.712176) (xy 136.549428 -283.692704) (xy 136.60139 -283.680844)
			(xy 136.65454 -283.676861) (xy 136.70769 -283.680844) (xy 136.759652 -283.692704) (xy 136.809266 -283.712176)
			(xy 136.855424 -283.738825) (xy 136.897095 -283.772056) (xy 136.933347 -283.811127) (xy 136.963371 -283.855164)
			(xy 136.986497 -283.903185) (xy 137.002207 -283.954115) (xy 137.01015 -284.006819) (xy 137.010648 -284.033468)
			(xy 137.01015 -284.060117) (xy 137.002207 -284.112821) (xy 136.986497 -284.163751) (xy 136.963371 -284.211772)
			(xy 136.933347 -284.255809) (xy 136.897095 -284.29488) (xy 136.855424 -284.328111) (xy 136.809266 -284.35476)
			(xy 136.759652 -284.374232) (xy 136.70769 -284.386092) (xy 136.65454 -284.390076) (xy 136.60139 -284.386092)
			(xy 136.549428 -284.374232) (xy 136.499814 -284.35476) (xy 136.453656 -284.328111) (xy 136.411985 -284.29488)
			(xy 136.375733 -284.255809) (xy 136.345709 -284.211772) (xy 136.322583 -284.163751) (xy 136.306873 -284.112821)
			(xy 136.29893 -284.060117) (xy 135.130809 -284.060117) (xy 135.130804 -284.060371) (xy 135.122861 -284.113075)
			(xy 135.107151 -284.164005) (xy 135.084025 -284.212026) (xy 135.054001 -284.256063) (xy 135.017749 -284.295134)
			(xy 134.976078 -284.328365) (xy 134.92992 -284.355014) (xy 134.880306 -284.374486) (xy 134.828344 -284.386346)
			(xy 134.775194 -284.39033) (xy 134.722044 -284.386346) (xy 134.670082 -284.374486) (xy 134.620468 -284.355014)
			(xy 134.57431 -284.328365) (xy 134.532639 -284.295134) (xy 134.496387 -284.256063) (xy 134.466363 -284.212026)
			(xy 134.443237 -284.164005) (xy 134.427527 -284.113075) (xy 134.419584 -284.060371) (xy 133.251204 -284.060371)
			(xy 133.243261 -284.113075) (xy 133.227551 -284.164005) (xy 133.204425 -284.212026) (xy 133.174401 -284.256063)
			(xy 133.138149 -284.295134) (xy 133.096478 -284.328365) (xy 133.05032 -284.355014) (xy 133.000706 -284.374486)
			(xy 132.948744 -284.386346) (xy 132.895594 -284.39033) (xy 132.842444 -284.386346) (xy 132.790482 -284.374486)
			(xy 132.740868 -284.355014) (xy 132.69471 -284.328365) (xy 132.653039 -284.295134) (xy 132.616787 -284.256063)
			(xy 132.586763 -284.212026) (xy 132.563637 -284.164005) (xy 132.547927 -284.113075) (xy 132.539984 -284.060371)
			(xy 132.311404 -284.060371) (xy 132.303461 -284.113075) (xy 132.287751 -284.164005) (xy 132.264625 -284.212026)
			(xy 132.234601 -284.256063) (xy 132.198349 -284.295134) (xy 132.156678 -284.328365) (xy 132.11052 -284.355014)
			(xy 132.060906 -284.374486) (xy 132.008944 -284.386346) (xy 131.955794 -284.39033) (xy 131.902644 -284.386346)
			(xy 131.850682 -284.374486) (xy 131.801068 -284.355014) (xy 131.75491 -284.328365) (xy 131.713239 -284.295134)
			(xy 131.676987 -284.256063) (xy 131.646963 -284.212026) (xy 131.623837 -284.164005) (xy 131.608127 -284.113075)
			(xy 131.600184 -284.060371) (xy 131.371604 -284.060371) (xy 131.363661 -284.113075) (xy 131.347951 -284.164005)
			(xy 131.324825 -284.212026) (xy 131.294801 -284.256063) (xy 131.258549 -284.295134) (xy 131.216878 -284.328365)
			(xy 131.17072 -284.355014) (xy 131.121106 -284.374486) (xy 131.069144 -284.386346) (xy 131.015994 -284.39033)
			(xy 130.962844 -284.386346) (xy 130.910882 -284.374486) (xy 130.861268 -284.355014) (xy 130.81511 -284.328365)
			(xy 130.773439 -284.295134) (xy 130.737187 -284.256063) (xy 130.707163 -284.212026) (xy 130.684037 -284.164005)
			(xy 130.668327 -284.113075) (xy 130.660384 -284.060371) (xy 130.431804 -284.060371) (xy 130.423861 -284.113075)
			(xy 130.408151 -284.164005) (xy 130.385025 -284.212026) (xy 130.355001 -284.256063) (xy 130.318749 -284.295134)
			(xy 130.277078 -284.328365) (xy 130.23092 -284.355014) (xy 130.181306 -284.374486) (xy 130.129344 -284.386346)
			(xy 130.076194 -284.39033) (xy 130.023044 -284.386346) (xy 129.971082 -284.374486) (xy 129.921468 -284.355014)
			(xy 129.87531 -284.328365) (xy 129.833639 -284.295134) (xy 129.797387 -284.256063) (xy 129.767363 -284.212026)
			(xy 129.744237 -284.164005) (xy 129.728527 -284.113075) (xy 129.720584 -284.060371) (xy 129.492004 -284.060371)
			(xy 129.484061 -284.113075) (xy 129.468351 -284.164005) (xy 129.445225 -284.212026) (xy 129.415201 -284.256063)
			(xy 129.378949 -284.295134) (xy 129.337278 -284.328365) (xy 129.29112 -284.355014) (xy 129.241506 -284.374486)
			(xy 129.189544 -284.386346) (xy 129.136394 -284.39033) (xy 129.083244 -284.386346) (xy 129.031282 -284.374486)
			(xy 128.981668 -284.355014) (xy 128.93551 -284.328365) (xy 128.893839 -284.295134) (xy 128.857587 -284.256063)
			(xy 128.827563 -284.212026) (xy 128.804437 -284.164005) (xy 128.788727 -284.113075) (xy 128.780784 -284.060371)
			(xy 128.552204 -284.060371) (xy 128.544261 -284.113075) (xy 128.528551 -284.164005) (xy 128.505425 -284.212026)
			(xy 128.475401 -284.256063) (xy 128.439149 -284.295134) (xy 128.397478 -284.328365) (xy 128.35132 -284.355014)
			(xy 128.301706 -284.374486) (xy 128.249744 -284.386346) (xy 128.196594 -284.39033) (xy 128.143444 -284.386346)
			(xy 128.091482 -284.374486) (xy 128.041868 -284.355014) (xy 127.99571 -284.328365) (xy 127.954039 -284.295134)
			(xy 127.917787 -284.256063) (xy 127.887763 -284.212026) (xy 127.864637 -284.164005) (xy 127.848927 -284.113075)
			(xy 127.840984 -284.060371) (xy 127.612404 -284.060371) (xy 127.604461 -284.113075) (xy 127.588751 -284.164005)
			(xy 127.565625 -284.212026) (xy 127.535601 -284.256063) (xy 127.499349 -284.295134) (xy 127.457678 -284.328365)
			(xy 127.41152 -284.355014) (xy 127.361906 -284.374486) (xy 127.309944 -284.386346) (xy 127.256794 -284.39033)
			(xy 127.203644 -284.386346) (xy 127.151682 -284.374486) (xy 127.102068 -284.355014) (xy 127.05591 -284.328365)
			(xy 127.014239 -284.295134) (xy 126.977987 -284.256063) (xy 126.947963 -284.212026) (xy 126.924837 -284.164005)
			(xy 126.909127 -284.113075) (xy 126.901184 -284.060371) (xy 126.672604 -284.060371) (xy 126.664661 -284.113075)
			(xy 126.648951 -284.164005) (xy 126.625825 -284.212026) (xy 126.595801 -284.256063) (xy 126.559549 -284.295134)
			(xy 126.517878 -284.328365) (xy 126.47172 -284.355014) (xy 126.422106 -284.374486) (xy 126.370144 -284.386346)
			(xy 126.316994 -284.39033) (xy 126.263844 -284.386346) (xy 126.211882 -284.374486) (xy 126.162268 -284.355014)
			(xy 126.11611 -284.328365) (xy 126.074439 -284.295134) (xy 126.038187 -284.256063) (xy 126.008163 -284.212026)
			(xy 125.985037 -284.164005) (xy 125.969327 -284.113075) (xy 125.961384 -284.060371) (xy 125.733058 -284.060371)
			(xy 125.725115 -284.113075) (xy 125.709405 -284.164005) (xy 125.686279 -284.212026) (xy 125.656255 -284.256063)
			(xy 125.620003 -284.295134) (xy 125.578332 -284.328365) (xy 125.532174 -284.355014) (xy 125.48256 -284.374486)
			(xy 125.430598 -284.386346) (xy 125.377448 -284.39033) (xy 125.324298 -284.386346) (xy 125.272336 -284.374486)
			(xy 125.222722 -284.355014) (xy 125.176564 -284.328365) (xy 125.134893 -284.295134) (xy 125.098641 -284.256063)
			(xy 125.068617 -284.212026) (xy 125.045491 -284.164005) (xy 125.029781 -284.113075) (xy 125.021838 -284.060371)
			(xy 124.793004 -284.060371) (xy 124.785061 -284.113075) (xy 124.769351 -284.164005) (xy 124.746225 -284.212026)
			(xy 124.716201 -284.256063) (xy 124.679949 -284.295134) (xy 124.638278 -284.328365) (xy 124.59212 -284.355014)
			(xy 124.542506 -284.374486) (xy 124.490544 -284.386346) (xy 124.437394 -284.39033) (xy 124.384244 -284.386346)
			(xy 124.332282 -284.374486) (xy 124.282668 -284.355014) (xy 124.23651 -284.328365) (xy 124.194839 -284.295134)
			(xy 124.158587 -284.256063) (xy 124.128563 -284.212026) (xy 124.105437 -284.164005) (xy 124.089727 -284.113075)
			(xy 124.081784 -284.060371) (xy 123.853204 -284.060371) (xy 123.845261 -284.113075) (xy 123.829551 -284.164005)
			(xy 123.806425 -284.212026) (xy 123.776401 -284.256063) (xy 123.740149 -284.295134) (xy 123.698478 -284.328365)
			(xy 123.65232 -284.355014) (xy 123.602706 -284.374486) (xy 123.550744 -284.386346) (xy 123.497594 -284.39033)
			(xy 123.444444 -284.386346) (xy 123.392482 -284.374486) (xy 123.342868 -284.355014) (xy 123.29671 -284.328365)
			(xy 123.255039 -284.295134) (xy 123.218787 -284.256063) (xy 123.188763 -284.212026) (xy 123.165637 -284.164005)
			(xy 123.149927 -284.113075) (xy 123.141984 -284.060371) (xy 122.913404 -284.060371) (xy 122.905461 -284.113075)
			(xy 122.889751 -284.164005) (xy 122.866625 -284.212026) (xy 122.836601 -284.256063) (xy 122.800349 -284.295134)
			(xy 122.758678 -284.328365) (xy 122.71252 -284.355014) (xy 122.662906 -284.374486) (xy 122.610944 -284.386346)
			(xy 122.557794 -284.39033) (xy 122.504644 -284.386346) (xy 122.452682 -284.374486) (xy 122.403068 -284.355014)
			(xy 122.35691 -284.328365) (xy 122.315239 -284.295134) (xy 122.278987 -284.256063) (xy 122.248963 -284.212026)
			(xy 122.225837 -284.164005) (xy 122.210127 -284.113075) (xy 122.202184 -284.060371) (xy 121.973604 -284.060371)
			(xy 121.965661 -284.113075) (xy 121.949951 -284.164005) (xy 121.926825 -284.212026) (xy 121.896801 -284.256063)
			(xy 121.860549 -284.295134) (xy 121.818878 -284.328365) (xy 121.77272 -284.355014) (xy 121.723106 -284.374486)
			(xy 121.671144 -284.386346) (xy 121.617994 -284.39033) (xy 121.564844 -284.386346) (xy 121.512882 -284.374486)
			(xy 121.463268 -284.355014) (xy 121.41711 -284.328365) (xy 121.375439 -284.295134) (xy 121.339187 -284.256063)
			(xy 121.309163 -284.212026) (xy 121.286037 -284.164005) (xy 121.270327 -284.113075) (xy 121.262384 -284.060371)
			(xy 121.033804 -284.060371) (xy 121.025861 -284.113075) (xy 121.010151 -284.164005) (xy 120.987025 -284.212026)
			(xy 120.957001 -284.256063) (xy 120.920749 -284.295134) (xy 120.879078 -284.328365) (xy 120.83292 -284.355014)
			(xy 120.783306 -284.374486) (xy 120.731344 -284.386346) (xy 120.678194 -284.39033) (xy 120.625044 -284.386346)
			(xy 120.573082 -284.374486) (xy 120.523468 -284.355014) (xy 120.47731 -284.328365) (xy 120.435639 -284.295134)
			(xy 120.399387 -284.256063) (xy 120.369363 -284.212026) (xy 120.346237 -284.164005) (xy 120.330527 -284.113075)
			(xy 120.322584 -284.060371) (xy 120.093977 -284.060371) (xy 120.093977 -284.060444) (xy 120.08598 -284.113314)
			(xy 120.070168 -284.164393) (xy 120.046894 -284.212534) (xy 120.016684 -284.256654) (xy 119.980216 -284.29576)
			(xy 119.938311 -284.328973) (xy 119.89191 -284.355546) (xy 119.867172 -284.3657) (xy 119.83466 -284.3784)
			(xy 119.83466 -284.847538) (xy 120.79224 -284.847538) (xy 120.792738 -284.820889) (xy 120.800681 -284.768185)
			(xy 120.816391 -284.717255) (xy 120.839517 -284.669234) (xy 120.869541 -284.625197) (xy 120.905793 -284.586126)
			(xy 120.947464 -284.552895) (xy 120.993622 -284.526246) (xy 121.043236 -284.506774) (xy 121.095198 -284.494914)
			(xy 121.148348 -284.490931) (xy 121.201498 -284.494914) (xy 121.25346 -284.506774) (xy 121.303074 -284.526246)
			(xy 121.349232 -284.552895) (xy 121.390903 -284.586126) (xy 121.427155 -284.625197) (xy 121.457179 -284.669234)
			(xy 121.480305 -284.717255) (xy 121.496015 -284.768185) (xy 121.503958 -284.820889) (xy 121.504456 -284.847538)
			(xy 122.67184 -284.847538) (xy 122.672338 -284.820889) (xy 122.680281 -284.768185) (xy 122.695991 -284.717255)
			(xy 122.719117 -284.669234) (xy 122.749141 -284.625197) (xy 122.785393 -284.586126) (xy 122.827064 -284.552895)
			(xy 122.873222 -284.526246) (xy 122.922836 -284.506774) (xy 122.974798 -284.494914) (xy 123.027948 -284.490931)
			(xy 123.081098 -284.494914) (xy 123.13306 -284.506774) (xy 123.182674 -284.526246) (xy 123.228832 -284.552895)
			(xy 123.270503 -284.586126) (xy 123.306755 -284.625197) (xy 123.336779 -284.669234) (xy 123.359905 -284.717255)
			(xy 123.375615 -284.768185) (xy 123.383558 -284.820889) (xy 123.384056 -284.847538) (xy 124.55144 -284.847538)
			(xy 124.551938 -284.820889) (xy 124.559881 -284.768185) (xy 124.575591 -284.717255) (xy 124.598717 -284.669234)
			(xy 124.628741 -284.625197) (xy 124.664993 -284.586126) (xy 124.706664 -284.552895) (xy 124.752822 -284.526246)
			(xy 124.802436 -284.506774) (xy 124.854398 -284.494914) (xy 124.907548 -284.490931) (xy 124.960698 -284.494914)
			(xy 125.01266 -284.506774) (xy 125.062274 -284.526246) (xy 125.108432 -284.552895) (xy 125.150103 -284.586126)
			(xy 125.186355 -284.625197) (xy 125.216379 -284.669234) (xy 125.239505 -284.717255) (xy 125.255215 -284.768185)
			(xy 125.263158 -284.820889) (xy 125.263656 -284.847538) (xy 125.26327 -284.870783) (xy 125.262824 -284.874187)
			(xy 125.491738 -284.874187) (xy 125.491738 -284.820889) (xy 125.499681 -284.768185) (xy 125.515391 -284.717255)
			(xy 125.538517 -284.669234) (xy 125.568541 -284.625197) (xy 125.604793 -284.586126) (xy 125.646464 -284.552895)
			(xy 125.692622 -284.526246) (xy 125.742236 -284.506774) (xy 125.794198 -284.494914) (xy 125.847348 -284.490931)
			(xy 125.900498 -284.494914) (xy 125.95246 -284.506774) (xy 126.002074 -284.526246) (xy 126.048232 -284.552895)
			(xy 126.089903 -284.586126) (xy 126.126155 -284.625197) (xy 126.156179 -284.669234) (xy 126.179305 -284.717255)
			(xy 126.195015 -284.768185) (xy 126.202958 -284.820889) (xy 126.203456 -284.847538) (xy 126.43104 -284.847538)
			(xy 126.431538 -284.820889) (xy 126.439481 -284.768185) (xy 126.455191 -284.717255) (xy 126.478317 -284.669234)
			(xy 126.508341 -284.625197) (xy 126.544593 -284.586126) (xy 126.586264 -284.552895) (xy 126.632422 -284.526246)
			(xy 126.682036 -284.506774) (xy 126.733998 -284.494914) (xy 126.787148 -284.490931) (xy 126.840298 -284.494914)
			(xy 126.89226 -284.506774) (xy 126.941874 -284.526246) (xy 126.988032 -284.552895) (xy 127.029703 -284.586126)
			(xy 127.065955 -284.625197) (xy 127.095979 -284.669234) (xy 127.119105 -284.717255) (xy 127.134815 -284.768185)
			(xy 127.142758 -284.820889) (xy 127.143256 -284.847538) (xy 128.31064 -284.847538) (xy 128.311138 -284.820889)
			(xy 128.319081 -284.768185) (xy 128.334791 -284.717255) (xy 128.357917 -284.669234) (xy 128.387941 -284.625197)
			(xy 128.424193 -284.586126) (xy 128.465864 -284.552895) (xy 128.512022 -284.526246) (xy 128.561636 -284.506774)
			(xy 128.613598 -284.494914) (xy 128.666748 -284.490931) (xy 128.719898 -284.494914) (xy 128.77186 -284.506774)
			(xy 128.821474 -284.526246) (xy 128.867632 -284.552895) (xy 128.909303 -284.586126) (xy 128.945555 -284.625197)
			(xy 128.975579 -284.669234) (xy 128.998705 -284.717255) (xy 129.014415 -284.768185) (xy 129.022358 -284.820889)
			(xy 129.022856 -284.847538) (xy 130.19024 -284.847538) (xy 130.190738 -284.820889) (xy 130.198681 -284.768185)
			(xy 130.214391 -284.717255) (xy 130.237517 -284.669234) (xy 130.267541 -284.625197) (xy 130.303793 -284.586126)
			(xy 130.345464 -284.552895) (xy 130.391622 -284.526246) (xy 130.441236 -284.506774) (xy 130.493198 -284.494914)
			(xy 130.546348 -284.490931) (xy 130.599498 -284.494914) (xy 130.65146 -284.506774) (xy 130.701074 -284.526246)
			(xy 130.747232 -284.552895) (xy 130.788903 -284.586126) (xy 130.825155 -284.625197) (xy 130.855179 -284.669234)
			(xy 130.878305 -284.717255) (xy 130.894015 -284.768185) (xy 130.901958 -284.820889) (xy 130.902456 -284.847538)
			(xy 132.06984 -284.847538) (xy 132.070338 -284.820889) (xy 132.078281 -284.768185) (xy 132.093991 -284.717255)
			(xy 132.117117 -284.669234) (xy 132.147141 -284.625197) (xy 132.183393 -284.586126) (xy 132.225064 -284.552895)
			(xy 132.271222 -284.526246) (xy 132.320836 -284.506774) (xy 132.372798 -284.494914) (xy 132.425948 -284.490931)
			(xy 132.479098 -284.494914) (xy 132.53106 -284.506774) (xy 132.580674 -284.526246) (xy 132.626832 -284.552895)
			(xy 132.668503 -284.586126) (xy 132.704755 -284.625197) (xy 132.734779 -284.669234) (xy 132.757905 -284.717255)
			(xy 132.773615 -284.768185) (xy 132.781558 -284.820889) (xy 132.782056 -284.847538) (xy 132.78167 -284.870783)
			(xy 132.781224 -284.874187) (xy 133.949938 -284.874187) (xy 133.949938 -284.820889) (xy 133.957881 -284.768185)
			(xy 133.973591 -284.717255) (xy 133.996717 -284.669234) (xy 134.026741 -284.625197) (xy 134.062993 -284.586126)
			(xy 134.104664 -284.552895) (xy 134.150822 -284.526246) (xy 134.200436 -284.506774) (xy 134.252398 -284.494914)
			(xy 134.305548 -284.490931) (xy 134.358698 -284.494914) (xy 134.41066 -284.506774) (xy 134.460274 -284.526246)
			(xy 134.506432 -284.552895) (xy 134.548103 -284.586126) (xy 134.584355 -284.625197) (xy 134.614379 -284.669234)
			(xy 134.637505 -284.717255) (xy 134.653215 -284.768185) (xy 134.661158 -284.820889) (xy 134.661656 -284.847538)
			(xy 134.661163 -284.873933) (xy 134.889484 -284.873933) (xy 134.889484 -284.820635) (xy 134.897427 -284.767931)
			(xy 134.913137 -284.717001) (xy 134.936263 -284.66898) (xy 134.966287 -284.624943) (xy 135.002539 -284.585872)
			(xy 135.04421 -284.552641) (xy 135.090368 -284.525992) (xy 135.139982 -284.50652) (xy 135.191944 -284.49466)
			(xy 135.245094 -284.490677) (xy 135.298244 -284.49466) (xy 135.350206 -284.50652) (xy 135.39982 -284.525992)
			(xy 135.445978 -284.552641) (xy 135.487649 -284.585872) (xy 135.523901 -284.624943) (xy 135.553925 -284.66898)
			(xy 135.577051 -284.717001) (xy 135.592761 -284.767931) (xy 135.600704 -284.820635) (xy 135.601202 -284.847284)
			(xy 135.600704 -284.873933) (xy 135.829284 -284.873933) (xy 135.829284 -284.820635) (xy 135.837227 -284.767931)
			(xy 135.852937 -284.717001) (xy 135.876063 -284.66898) (xy 135.906087 -284.624943) (xy 135.942339 -284.585872)
			(xy 135.98401 -284.552641) (xy 136.030168 -284.525992) (xy 136.079782 -284.50652) (xy 136.131744 -284.49466)
			(xy 136.184894 -284.490677) (xy 136.238044 -284.49466) (xy 136.290006 -284.50652) (xy 136.33962 -284.525992)
			(xy 136.385778 -284.552641) (xy 136.427449 -284.585872) (xy 136.463701 -284.624943) (xy 136.493725 -284.66898)
			(xy 136.516851 -284.717001) (xy 136.532561 -284.767931) (xy 136.540504 -284.820635) (xy 136.541002 -284.847284)
			(xy 136.540504 -284.873933) (xy 136.769084 -284.873933) (xy 136.769084 -284.820635) (xy 136.777027 -284.767931)
			(xy 136.792737 -284.717001) (xy 136.815863 -284.66898) (xy 136.845887 -284.624943) (xy 136.882139 -284.585872)
			(xy 136.92381 -284.552641) (xy 136.969968 -284.525992) (xy 137.019582 -284.50652) (xy 137.071544 -284.49466)
			(xy 137.124694 -284.490677) (xy 137.177844 -284.49466) (xy 137.229806 -284.50652) (xy 137.27942 -284.525992)
			(xy 137.325578 -284.552641) (xy 137.367249 -284.585872) (xy 137.403501 -284.624943) (xy 137.433525 -284.66898)
			(xy 137.456651 -284.717001) (xy 137.472361 -284.767931) (xy 137.480304 -284.820635) (xy 137.480802 -284.847284)
			(xy 137.480304 -284.873933) (xy 137.472361 -284.926637) (xy 137.456651 -284.977567) (xy 137.433525 -285.025588)
			(xy 137.403501 -285.069625) (xy 137.367249 -285.108696) (xy 137.325578 -285.141927) (xy 137.27942 -285.168576)
			(xy 137.229806 -285.188048) (xy 137.177844 -285.199908) (xy 137.124694 -285.203892) (xy 137.071544 -285.199908)
			(xy 137.019582 -285.188048) (xy 136.969968 -285.168576) (xy 136.92381 -285.141927) (xy 136.882139 -285.108696)
			(xy 136.845887 -285.069625) (xy 136.815863 -285.025588) (xy 136.792737 -284.977567) (xy 136.777027 -284.926637)
			(xy 136.769084 -284.873933) (xy 136.540504 -284.873933) (xy 136.532561 -284.926637) (xy 136.516851 -284.977567)
			(xy 136.493725 -285.025588) (xy 136.463701 -285.069625) (xy 136.427449 -285.108696) (xy 136.385778 -285.141927)
			(xy 136.33962 -285.168576) (xy 136.290006 -285.188048) (xy 136.238044 -285.199908) (xy 136.184894 -285.203892)
			(xy 136.131744 -285.199908) (xy 136.079782 -285.188048) (xy 136.030168 -285.168576) (xy 135.98401 -285.141927)
			(xy 135.942339 -285.108696) (xy 135.906087 -285.069625) (xy 135.876063 -285.025588) (xy 135.852937 -284.977567)
			(xy 135.837227 -284.926637) (xy 135.829284 -284.873933) (xy 135.600704 -284.873933) (xy 135.592761 -284.926637)
			(xy 135.577051 -284.977567) (xy 135.553925 -285.025588) (xy 135.523901 -285.069625) (xy 135.487649 -285.108696)
			(xy 135.445978 -285.141927) (xy 135.39982 -285.168576) (xy 135.350206 -285.188048) (xy 135.298244 -285.199908)
			(xy 135.245094 -285.203892) (xy 135.191944 -285.199908) (xy 135.139982 -285.188048) (xy 135.090368 -285.168576)
			(xy 135.04421 -285.141927) (xy 135.002539 -285.108696) (xy 134.966287 -285.069625) (xy 134.936263 -285.025588)
			(xy 134.913137 -284.977567) (xy 134.897427 -284.926637) (xy 134.889484 -284.873933) (xy 134.661163 -284.873933)
			(xy 134.661158 -284.874187) (xy 134.653215 -284.926891) (xy 134.637505 -284.977821) (xy 134.614379 -285.025842)
			(xy 134.584355 -285.069879) (xy 134.548103 -285.10895) (xy 134.506432 -285.142181) (xy 134.460274 -285.16883)
			(xy 134.41066 -285.188302) (xy 134.358698 -285.200162) (xy 134.305548 -285.204146) (xy 134.252398 -285.200162)
			(xy 134.200436 -285.188302) (xy 134.150822 -285.16883) (xy 134.104664 -285.142181) (xy 134.062993 -285.10895)
			(xy 134.026741 -285.069879) (xy 133.996717 -285.025842) (xy 133.973591 -284.977821) (xy 133.957881 -284.926891)
			(xy 133.949938 -284.874187) (xy 132.781224 -284.874187) (xy 132.775631 -284.916878) (xy 132.763647 -284.961796)
			(xy 132.755132 -284.983428) (xy 132.74548 -285.006542) (xy 132.917946 -285.304992) (xy 132.942584 -285.308294)
			(xy 132.967921 -285.312151) (xy 133.017227 -285.326136) (xy 133.064019 -285.347042) (xy 133.107331 -285.374438)
			(xy 133.146271 -285.407759) (xy 133.180033 -285.446317) (xy 133.20792 -285.489315) (xy 133.229358 -285.535866)
			(xy 133.243902 -285.585009) (xy 133.251254 -285.635729) (xy 133.251702 -285.661354) (xy 133.251204 -285.688003)
			(xy 133.243261 -285.740707) (xy 133.227551 -285.791637) (xy 133.204425 -285.839658) (xy 133.174401 -285.883695)
			(xy 133.138149 -285.922766) (xy 133.096478 -285.955997) (xy 133.05032 -285.982646) (xy 133.000706 -286.002118)
			(xy 132.948744 -286.013978) (xy 132.895594 -286.017962) (xy 132.842444 -286.013978) (xy 132.790482 -286.002118)
			(xy 132.740868 -285.982646) (xy 132.69471 -285.955997) (xy 132.653039 -285.922766) (xy 132.616787 -285.883695)
			(xy 132.586763 -285.839658) (xy 132.563637 -285.791637) (xy 132.547927 -285.740707) (xy 132.539984 -285.688003)
			(xy 132.539486 -285.661354) (xy 132.539873 -285.638109) (xy 132.545912 -285.592014) (xy 132.557896 -285.547096)
			(xy 132.56641 -285.525464) (xy 132.576062 -285.50235) (xy 132.403596 -285.2039) (xy 132.378958 -285.200598)
			(xy 132.353612 -285.196794) (xy 132.304306 -285.182801) (xy 132.257513 -285.161888) (xy 132.214201 -285.134484)
			(xy 132.175263 -285.101157) (xy 132.141502 -285.062593) (xy 132.113617 -285.01959) (xy 132.092181 -284.973035)
			(xy 132.077638 -284.923888) (xy 132.070288 -284.873165) (xy 132.06984 -284.847538) (xy 130.902456 -284.847538)
			(xy 130.90207 -284.870783) (xy 130.896031 -284.916878) (xy 130.884047 -284.961796) (xy 130.875532 -284.983428)
			(xy 130.86588 -285.006542) (xy 131.038346 -285.304992) (xy 131.062984 -285.308294) (xy 131.088321 -285.312151)
			(xy 131.137627 -285.326136) (xy 131.184419 -285.347042) (xy 131.227731 -285.374438) (xy 131.266671 -285.407759)
			(xy 131.300433 -285.446317) (xy 131.32832 -285.489315) (xy 131.349758 -285.535866) (xy 131.364302 -285.585009)
			(xy 131.371654 -285.635729) (xy 131.372102 -285.661354) (xy 131.371604 -285.688003) (xy 131.363661 -285.740707)
			(xy 131.347951 -285.791637) (xy 131.324825 -285.839658) (xy 131.294801 -285.883695) (xy 131.258549 -285.922766)
			(xy 131.216878 -285.955997) (xy 131.17072 -285.982646) (xy 131.121106 -286.002118) (xy 131.069144 -286.013978)
			(xy 131.015994 -286.017962) (xy 130.962844 -286.013978) (xy 130.910882 -286.002118) (xy 130.861268 -285.982646)
			(xy 130.81511 -285.955997) (xy 130.773439 -285.922766) (xy 130.737187 -285.883695) (xy 130.707163 -285.839658)
			(xy 130.684037 -285.791637) (xy 130.668327 -285.740707) (xy 130.660384 -285.688003) (xy 130.659886 -285.661354)
			(xy 130.660273 -285.638109) (xy 130.666312 -285.592014) (xy 130.678296 -285.547096) (xy 130.68681 -285.525464)
			(xy 130.696462 -285.50235) (xy 130.523996 -285.2039) (xy 130.499358 -285.200598) (xy 130.474012 -285.196794)
			(xy 130.424706 -285.182801) (xy 130.377913 -285.161888) (xy 130.334601 -285.134484) (xy 130.295663 -285.101157)
			(xy 130.261902 -285.062593) (xy 130.234017 -285.01959) (xy 130.212581 -284.973035) (xy 130.198038 -284.923888)
			(xy 130.190688 -284.873165) (xy 130.19024 -284.847538) (xy 129.022856 -284.847538) (xy 129.02247 -284.870783)
			(xy 129.016431 -284.916878) (xy 129.004447 -284.961796) (xy 128.995932 -284.983428) (xy 128.98628 -285.006542)
			(xy 129.158746 -285.304992) (xy 129.183384 -285.308294) (xy 129.208721 -285.312151) (xy 129.258027 -285.326136)
			(xy 129.304819 -285.347042) (xy 129.348131 -285.374438) (xy 129.387071 -285.407759) (xy 129.420833 -285.446317)
			(xy 129.44872 -285.489315) (xy 129.470158 -285.535866) (xy 129.484702 -285.585009) (xy 129.492054 -285.635729)
			(xy 129.492502 -285.661354) (xy 129.492004 -285.688003) (xy 129.484061 -285.740707) (xy 129.468351 -285.791637)
			(xy 129.445225 -285.839658) (xy 129.415201 -285.883695) (xy 129.378949 -285.922766) (xy 129.337278 -285.955997)
			(xy 129.29112 -285.982646) (xy 129.241506 -286.002118) (xy 129.189544 -286.013978) (xy 129.136394 -286.017962)
			(xy 129.083244 -286.013978) (xy 129.031282 -286.002118) (xy 128.981668 -285.982646) (xy 128.93551 -285.955997)
			(xy 128.893839 -285.922766) (xy 128.857587 -285.883695) (xy 128.827563 -285.839658) (xy 128.804437 -285.791637)
			(xy 128.788727 -285.740707) (xy 128.780784 -285.688003) (xy 128.780286 -285.661354) (xy 128.780673 -285.638109)
			(xy 128.786712 -285.592014) (xy 128.798696 -285.547096) (xy 128.80721 -285.525464) (xy 128.816862 -285.50235)
			(xy 128.644396 -285.2039) (xy 128.619758 -285.200598) (xy 128.594412 -285.196794) (xy 128.545106 -285.182801)
			(xy 128.498313 -285.161888) (xy 128.455001 -285.134484) (xy 128.416063 -285.101157) (xy 128.382302 -285.062593)
			(xy 128.354417 -285.01959) (xy 128.332981 -284.973035) (xy 128.318438 -284.923888) (xy 128.311088 -284.873165)
			(xy 128.31064 -284.847538) (xy 127.143256 -284.847538) (xy 127.14287 -284.870783) (xy 127.136831 -284.916878)
			(xy 127.124847 -284.961796) (xy 127.116332 -284.983428) (xy 127.10668 -285.006542) (xy 127.279146 -285.304992)
			(xy 127.303784 -285.308294) (xy 127.329121 -285.312151) (xy 127.378427 -285.326136) (xy 127.425219 -285.347042)
			(xy 127.468531 -285.374438) (xy 127.507471 -285.407759) (xy 127.541233 -285.446317) (xy 127.56912 -285.489315)
			(xy 127.590558 -285.535866) (xy 127.605102 -285.585009) (xy 127.612454 -285.635729) (xy 127.612902 -285.661354)
			(xy 127.612404 -285.688003) (xy 127.604461 -285.740707) (xy 127.588751 -285.791637) (xy 127.565625 -285.839658)
			(xy 127.535601 -285.883695) (xy 127.499349 -285.922766) (xy 127.457678 -285.955997) (xy 127.41152 -285.982646)
			(xy 127.361906 -286.002118) (xy 127.309944 -286.013978) (xy 127.256794 -286.017962) (xy 127.203644 -286.013978)
			(xy 127.151682 -286.002118) (xy 127.102068 -285.982646) (xy 127.05591 -285.955997) (xy 127.014239 -285.922766)
			(xy 126.977987 -285.883695) (xy 126.947963 -285.839658) (xy 126.924837 -285.791637) (xy 126.909127 -285.740707)
			(xy 126.901184 -285.688003) (xy 126.900686 -285.661354) (xy 126.901073 -285.638109) (xy 126.907112 -285.592014)
			(xy 126.919096 -285.547096) (xy 126.92761 -285.525464) (xy 126.937262 -285.50235) (xy 126.764796 -285.2039)
			(xy 126.740158 -285.200598) (xy 126.714812 -285.196794) (xy 126.665506 -285.182801) (xy 126.618713 -285.161888)
			(xy 126.575401 -285.134484) (xy 126.536463 -285.101157) (xy 126.502702 -285.062593) (xy 126.474817 -285.01959)
			(xy 126.453381 -284.973035) (xy 126.438838 -284.923888) (xy 126.431488 -284.873165) (xy 126.43104 -284.847538)
			(xy 126.203456 -284.847538) (xy 126.202958 -284.874187) (xy 126.195015 -284.926891) (xy 126.179305 -284.977821)
			(xy 126.156179 -285.025842) (xy 126.126155 -285.069879) (xy 126.089903 -285.10895) (xy 126.048232 -285.142181)
			(xy 126.002074 -285.16883) (xy 125.95246 -285.188302) (xy 125.900498 -285.200162) (xy 125.847348 -285.204146)
			(xy 125.794198 -285.200162) (xy 125.742236 -285.188302) (xy 125.692622 -285.16883) (xy 125.646464 -285.142181)
			(xy 125.604793 -285.10895) (xy 125.568541 -285.069879) (xy 125.538517 -285.025842) (xy 125.515391 -284.977821)
			(xy 125.499681 -284.926891) (xy 125.491738 -284.874187) (xy 125.262824 -284.874187) (xy 125.257231 -284.916878)
			(xy 125.245247 -284.961796) (xy 125.236732 -284.983428) (xy 125.22708 -285.006542) (xy 125.399546 -285.304992)
			(xy 125.424184 -285.308294) (xy 125.449521 -285.312151) (xy 125.498827 -285.326136) (xy 125.545619 -285.347042)
			(xy 125.588931 -285.374438) (xy 125.627871 -285.407759) (xy 125.661633 -285.446317) (xy 125.68952 -285.489315)
			(xy 125.710958 -285.535866) (xy 125.725502 -285.585009) (xy 125.732854 -285.635729) (xy 125.733302 -285.661354)
			(xy 125.732804 -285.688003) (xy 125.724861 -285.740707) (xy 125.709151 -285.791637) (xy 125.686025 -285.839658)
			(xy 125.656001 -285.883695) (xy 125.619749 -285.922766) (xy 125.578078 -285.955997) (xy 125.53192 -285.982646)
			(xy 125.482306 -286.002118) (xy 125.430344 -286.013978) (xy 125.377194 -286.017962) (xy 125.324044 -286.013978)
			(xy 125.272082 -286.002118) (xy 125.222468 -285.982646) (xy 125.17631 -285.955997) (xy 125.134639 -285.922766)
			(xy 125.098387 -285.883695) (xy 125.068363 -285.839658) (xy 125.045237 -285.791637) (xy 125.029527 -285.740707)
			(xy 125.021584 -285.688003) (xy 125.021086 -285.661354) (xy 125.021473 -285.638109) (xy 125.027512 -285.592014)
			(xy 125.039496 -285.547096) (xy 125.04801 -285.525464) (xy 125.057662 -285.50235) (xy 124.885196 -285.2039)
			(xy 124.860558 -285.200598) (xy 124.835212 -285.196794) (xy 124.785906 -285.182801) (xy 124.739113 -285.161888)
			(xy 124.695801 -285.134484) (xy 124.656863 -285.101157) (xy 124.623102 -285.062593) (xy 124.595217 -285.01959)
			(xy 124.573781 -284.973035) (xy 124.559238 -284.923888) (xy 124.551888 -284.873165) (xy 124.55144 -284.847538)
			(xy 123.384056 -284.847538) (xy 123.38367 -284.870783) (xy 123.377631 -284.916878) (xy 123.365647 -284.961796)
			(xy 123.357132 -284.983428) (xy 123.34748 -285.006542) (xy 123.519946 -285.304992) (xy 123.544584 -285.308294)
			(xy 123.569921 -285.312151) (xy 123.619227 -285.326136) (xy 123.666019 -285.347042) (xy 123.709331 -285.374438)
			(xy 123.748271 -285.407759) (xy 123.782033 -285.446317) (xy 123.80992 -285.489315) (xy 123.831358 -285.535866)
			(xy 123.845902 -285.585009) (xy 123.853254 -285.635729) (xy 123.853702 -285.661354) (xy 123.853204 -285.688003)
			(xy 123.845261 -285.740707) (xy 123.829551 -285.791637) (xy 123.806425 -285.839658) (xy 123.776401 -285.883695)
			(xy 123.740149 -285.922766) (xy 123.698478 -285.955997) (xy 123.65232 -285.982646) (xy 123.602706 -286.002118)
			(xy 123.550744 -286.013978) (xy 123.497594 -286.017962) (xy 123.444444 -286.013978) (xy 123.392482 -286.002118)
			(xy 123.342868 -285.982646) (xy 123.29671 -285.955997) (xy 123.255039 -285.922766) (xy 123.218787 -285.883695)
			(xy 123.188763 -285.839658) (xy 123.165637 -285.791637) (xy 123.149927 -285.740707) (xy 123.141984 -285.688003)
			(xy 123.141486 -285.661354) (xy 123.141873 -285.638109) (xy 123.147912 -285.592014) (xy 123.159896 -285.547096)
			(xy 123.16841 -285.525464) (xy 123.178062 -285.50235) (xy 123.005596 -285.2039) (xy 122.980958 -285.200598)
			(xy 122.955612 -285.196794) (xy 122.906306 -285.182801) (xy 122.859513 -285.161888) (xy 122.816201 -285.134484)
			(xy 122.777263 -285.101157) (xy 122.743502 -285.062593) (xy 122.715617 -285.01959) (xy 122.694181 -284.973035)
			(xy 122.679638 -284.923888) (xy 122.672288 -284.873165) (xy 122.67184 -284.847538) (xy 121.504456 -284.847538)
			(xy 121.50407 -284.870783) (xy 121.498031 -284.916878) (xy 121.486047 -284.961796) (xy 121.477532 -284.983428)
			(xy 121.46788 -285.006542) (xy 121.640346 -285.304992) (xy 121.664984 -285.308294) (xy 121.690321 -285.312151)
			(xy 121.739627 -285.326136) (xy 121.786419 -285.347042) (xy 121.829731 -285.374438) (xy 121.868671 -285.407759)
			(xy 121.902433 -285.446317) (xy 121.93032 -285.489315) (xy 121.951758 -285.535866) (xy 121.966302 -285.585009)
			(xy 121.973654 -285.635729) (xy 121.974102 -285.661354) (xy 121.973604 -285.688003) (xy 121.965661 -285.740707)
			(xy 121.949951 -285.791637) (xy 121.926825 -285.839658) (xy 121.896801 -285.883695) (xy 121.860549 -285.922766)
			(xy 121.818878 -285.955997) (xy 121.77272 -285.982646) (xy 121.723106 -286.002118) (xy 121.671144 -286.013978)
			(xy 121.617994 -286.017962) (xy 121.564844 -286.013978) (xy 121.512882 -286.002118) (xy 121.463268 -285.982646)
			(xy 121.41711 -285.955997) (xy 121.375439 -285.922766) (xy 121.339187 -285.883695) (xy 121.309163 -285.839658)
			(xy 121.286037 -285.791637) (xy 121.270327 -285.740707) (xy 121.262384 -285.688003) (xy 121.261886 -285.661354)
			(xy 121.262273 -285.638109) (xy 121.268312 -285.592014) (xy 121.280296 -285.547096) (xy 121.28881 -285.525464)
			(xy 121.298462 -285.50235) (xy 121.125996 -285.2039) (xy 121.101358 -285.200598) (xy 121.076012 -285.196794)
			(xy 121.026706 -285.182801) (xy 120.979913 -285.161888) (xy 120.936601 -285.134484) (xy 120.897663 -285.101157)
			(xy 120.863902 -285.062593) (xy 120.836017 -285.01959) (xy 120.814581 -284.973035) (xy 120.800038 -284.923888)
			(xy 120.792688 -284.873165) (xy 120.79224 -284.847538) (xy 119.83466 -284.847538) (xy 119.83466 -285.316676)
			(xy 119.867172 -285.329376) (xy 119.89193 -285.339493) (xy 119.938339 -285.36607) (xy 119.980253 -285.399288)
			(xy 120.016728 -285.4384) (xy 120.046945 -285.482526) (xy 120.070223 -285.530675) (xy 120.08604 -285.581764)
			(xy 120.09404 -285.634643) (xy 120.094042 -285.688124) (xy 120.086048 -285.741004) (xy 120.070236 -285.792094)
			(xy 120.046962 -285.840245) (xy 120.016749 -285.884374) (xy 119.980277 -285.92349) (xy 119.938367 -285.956712)
			(xy 119.89196 -285.983293) (xy 119.867172 -285.993332) (xy 119.83466 -286.006032) (xy 119.83466 -286.107632)
			(xy 119.835101 -286.121687) (xy 119.842751 -286.148735) (xy 119.857489 -286.172671) (xy 119.878198 -286.191678)
			(xy 119.903306 -286.204316) (xy 119.930909 -286.209625) (xy 119.958914 -286.207202) (xy 119.985196 -286.197232)
			(xy 119.996712 -286.189166) (xy 120.02118 -286.171832) (xy 120.074665 -286.144733) (xy 120.131925 -286.12695)
			(xy 120.161558 -286.122364) (xy 120.186196 -286.119062) (xy 120.358662 -285.820358) (xy 120.34901 -285.797244)
			(xy 120.340495 -285.775612) (xy 120.328511 -285.730694) (xy 120.32247 -285.684599) (xy 120.322086 -285.661354)
			(xy 120.322584 -285.634705) (xy 120.330527 -285.582001) (xy 120.346237 -285.531071) (xy 120.369363 -285.48305)
			(xy 120.399387 -285.439013) (xy 120.435639 -285.399942) (xy 120.47731 -285.366711) (xy 120.523468 -285.340062)
			(xy 120.573082 -285.32059) (xy 120.625044 -285.30873) (xy 120.678194 -285.304747) (xy 120.731344 -285.30873)
			(xy 120.783306 -285.32059) (xy 120.83292 -285.340062) (xy 120.879078 -285.366711) (xy 120.920749 -285.399942)
			(xy 120.957001 -285.439013) (xy 120.987025 -285.48305) (xy 121.010151 -285.531071) (xy 121.025861 -285.582001)
			(xy 121.033804 -285.634705) (xy 121.034302 -285.661354) (xy 121.033853 -285.686979) (xy 121.026501 -285.737698)
			(xy 121.011955 -285.78684) (xy 120.990517 -285.83339) (xy 120.96263 -285.876387) (xy 120.928868 -285.914944)
			(xy 120.889929 -285.948264) (xy 120.846616 -285.975659) (xy 120.799825 -285.996565) (xy 120.75052 -286.010549)
			(xy 120.725184 -286.014414) (xy 120.700546 -286.017716) (xy 120.52808 -286.31642) (xy 120.537732 -286.339534)
			(xy 120.546249 -286.361166) (xy 120.558238 -286.406083) (xy 120.564282 -286.452179) (xy 120.564656 -286.475424)
			(xy 120.564158 -286.502073) (xy 120.792484 -286.502073) (xy 120.792484 -286.448775) (xy 120.800427 -286.396071)
			(xy 120.816137 -286.345141) (xy 120.839263 -286.29712) (xy 120.869287 -286.253083) (xy 120.905539 -286.214012)
			(xy 120.94721 -286.180781) (xy 120.993368 -286.154132) (xy 121.042982 -286.13466) (xy 121.094944 -286.1228)
			(xy 121.148094 -286.118817) (xy 121.201244 -286.1228) (xy 121.253206 -286.13466) (xy 121.30282 -286.154132)
			(xy 121.348978 -286.180781) (xy 121.390649 -286.214012) (xy 121.426901 -286.253083) (xy 121.456925 -286.29712)
			(xy 121.480051 -286.345141) (xy 121.495761 -286.396071) (xy 121.503704 -286.448775) (xy 121.504202 -286.475424)
			(xy 121.73204 -286.475424) (xy 121.732493 -286.449796) (xy 121.739826 -286.399067) (xy 121.754356 -286.349914)
			(xy 121.775785 -286.303352) (xy 121.803669 -286.260345) (xy 121.837433 -286.22178) (xy 121.876377 -286.188455)
			(xy 121.919697 -286.16106) (xy 121.966498 -286.140159) (xy 122.015813 -286.126185) (xy 122.041158 -286.122364)
			(xy 122.065796 -286.119062) (xy 122.238262 -285.820358) (xy 122.22861 -285.797244) (xy 122.220079 -285.775617)
			(xy 122.208098 -285.730697) (xy 122.202059 -285.6846) (xy 122.201686 -285.661354) (xy 122.202184 -285.634705)
			(xy 122.210127 -285.582001) (xy 122.225837 -285.531071) (xy 122.248963 -285.48305) (xy 122.278987 -285.439013)
			(xy 122.315239 -285.399942) (xy 122.35691 -285.366711) (xy 122.403068 -285.340062) (xy 122.452682 -285.32059)
			(xy 122.504644 -285.30873) (xy 122.557794 -285.304747) (xy 122.610944 -285.30873) (xy 122.662906 -285.32059)
			(xy 122.71252 -285.340062) (xy 122.758678 -285.366711) (xy 122.800349 -285.399942) (xy 122.836601 -285.439013)
			(xy 122.866625 -285.48305) (xy 122.889751 -285.531071) (xy 122.905461 -285.582001) (xy 122.913404 -285.634705)
			(xy 122.913902 -285.661354) (xy 122.913479 -285.686984) (xy 122.906148 -285.737716) (xy 122.891617 -285.786873)
			(xy 122.870187 -285.833438) (xy 122.8423 -285.876448) (xy 122.808532 -285.915013) (xy 122.769583 -285.948337)
			(xy 122.726258 -285.975731) (xy 122.679451 -285.996628) (xy 122.630132 -286.010596) (xy 122.604784 -286.014414)
			(xy 122.580146 -286.017716) (xy 122.40768 -286.31642) (xy 122.417332 -286.339534) (xy 122.425853 -286.361164)
			(xy 122.437839 -286.406083) (xy 122.443882 -286.452179) (xy 122.444256 -286.475424) (xy 122.443758 -286.502073)
			(xy 122.672084 -286.502073) (xy 122.672084 -286.448775) (xy 122.680027 -286.396071) (xy 122.695737 -286.345141)
			(xy 122.718863 -286.29712) (xy 122.748887 -286.253083) (xy 122.785139 -286.214012) (xy 122.82681 -286.180781)
			(xy 122.872968 -286.154132) (xy 122.922582 -286.13466) (xy 122.974544 -286.1228) (xy 123.027694 -286.118817)
			(xy 123.080844 -286.1228) (xy 123.132806 -286.13466) (xy 123.18242 -286.154132) (xy 123.228578 -286.180781)
			(xy 123.270249 -286.214012) (xy 123.306501 -286.253083) (xy 123.336525 -286.29712) (xy 123.359651 -286.345141)
			(xy 123.375361 -286.396071) (xy 123.383304 -286.448775) (xy 123.383802 -286.475424) (xy 123.61164 -286.475424)
			(xy 123.612093 -286.449796) (xy 123.619426 -286.399067) (xy 123.633956 -286.349914) (xy 123.655385 -286.303352)
			(xy 123.683269 -286.260345) (xy 123.717033 -286.22178) (xy 123.755977 -286.188455) (xy 123.799297 -286.16106)
			(xy 123.846098 -286.140159) (xy 123.895413 -286.126185) (xy 123.920758 -286.122364) (xy 123.945396 -286.119062)
			(xy 124.117862 -285.820358) (xy 124.10821 -285.797244) (xy 124.099679 -285.775617) (xy 124.087698 -285.730697)
			(xy 124.081659 -285.6846) (xy 124.081286 -285.661354) (xy 124.081784 -285.634705) (xy 124.089727 -285.582001)
			(xy 124.105437 -285.531071) (xy 124.128563 -285.48305) (xy 124.158587 -285.439013) (xy 124.194839 -285.399942)
			(xy 124.23651 -285.366711) (xy 124.282668 -285.340062) (xy 124.332282 -285.32059) (xy 124.384244 -285.30873)
			(xy 124.437394 -285.304747) (xy 124.490544 -285.30873) (xy 124.542506 -285.32059) (xy 124.59212 -285.340062)
			(xy 124.638278 -285.366711) (xy 124.679949 -285.399942) (xy 124.716201 -285.439013) (xy 124.746225 -285.48305)
			(xy 124.769351 -285.531071) (xy 124.785061 -285.582001) (xy 124.793004 -285.634705) (xy 124.793502 -285.661354)
			(xy 124.793079 -285.686984) (xy 124.785748 -285.737716) (xy 124.771217 -285.786873) (xy 124.749787 -285.833438)
			(xy 124.7219 -285.876448) (xy 124.688132 -285.915013) (xy 124.649183 -285.948337) (xy 124.605858 -285.975731)
			(xy 124.559051 -285.996628) (xy 124.509732 -286.010596) (xy 124.484384 -286.014414) (xy 124.459746 -286.017716)
			(xy 124.28728 -286.31642) (xy 124.296932 -286.339534) (xy 124.305453 -286.361164) (xy 124.317439 -286.406083)
			(xy 124.323482 -286.452179) (xy 124.323856 -286.475424) (xy 124.323358 -286.502073) (xy 124.551684 -286.502073)
			(xy 124.551684 -286.448775) (xy 124.559627 -286.396071) (xy 124.575337 -286.345141) (xy 124.598463 -286.29712)
			(xy 124.628487 -286.253083) (xy 124.664739 -286.214012) (xy 124.70641 -286.180781) (xy 124.752568 -286.154132)
			(xy 124.802182 -286.13466) (xy 124.854144 -286.1228) (xy 124.907294 -286.118817) (xy 124.960444 -286.1228)
			(xy 125.012406 -286.13466) (xy 125.06202 -286.154132) (xy 125.108178 -286.180781) (xy 125.149849 -286.214012)
			(xy 125.186101 -286.253083) (xy 125.216125 -286.29712) (xy 125.239251 -286.345141) (xy 125.254961 -286.396071)
			(xy 125.262904 -286.448775) (xy 125.263402 -286.475424) (xy 125.49124 -286.475424) (xy 125.491693 -286.449796)
			(xy 125.499026 -286.399067) (xy 125.513556 -286.349914) (xy 125.534985 -286.303352) (xy 125.562869 -286.260345)
			(xy 125.596633 -286.22178) (xy 125.635577 -286.188455) (xy 125.678897 -286.16106) (xy 125.725698 -286.140159)
			(xy 125.775013 -286.126185) (xy 125.800358 -286.122364) (xy 125.824996 -286.119062) (xy 125.997462 -285.820358)
			(xy 125.98781 -285.797244) (xy 125.979279 -285.775617) (xy 125.967298 -285.730697) (xy 125.961259 -285.6846)
			(xy 125.960886 -285.661354) (xy 125.961384 -285.634705) (xy 125.969327 -285.582001) (xy 125.985037 -285.531071)
			(xy 126.008163 -285.48305) (xy 126.038187 -285.439013) (xy 126.074439 -285.399942) (xy 126.11611 -285.366711)
			(xy 126.162268 -285.340062) (xy 126.211882 -285.32059) (xy 126.263844 -285.30873) (xy 126.316994 -285.304747)
			(xy 126.370144 -285.30873) (xy 126.422106 -285.32059) (xy 126.47172 -285.340062) (xy 126.517878 -285.366711)
			(xy 126.559549 -285.399942) (xy 126.595801 -285.439013) (xy 126.625825 -285.48305) (xy 126.648951 -285.531071)
			(xy 126.664661 -285.582001) (xy 126.672604 -285.634705) (xy 126.673102 -285.661354) (xy 126.672679 -285.686984)
			(xy 126.665348 -285.737716) (xy 126.650817 -285.786873) (xy 126.629387 -285.833438) (xy 126.6015 -285.876448)
			(xy 126.567732 -285.915013) (xy 126.528783 -285.948337) (xy 126.485458 -285.975731) (xy 126.438651 -285.996628)
			(xy 126.389332 -286.010596) (xy 126.363984 -286.014414) (xy 126.339346 -286.017716) (xy 126.16688 -286.31642)
			(xy 126.176532 -286.339534) (xy 126.185053 -286.361164) (xy 126.197039 -286.406083) (xy 126.203082 -286.452179)
			(xy 126.203456 -286.475424) (xy 126.202958 -286.502073) (xy 126.431284 -286.502073) (xy 126.431284 -286.448775)
			(xy 126.439227 -286.396071) (xy 126.454937 -286.345141) (xy 126.478063 -286.29712) (xy 126.508087 -286.253083)
			(xy 126.544339 -286.214012) (xy 126.58601 -286.180781) (xy 126.632168 -286.154132) (xy 126.681782 -286.13466)
			(xy 126.733744 -286.1228) (xy 126.786894 -286.118817) (xy 126.840044 -286.1228) (xy 126.892006 -286.13466)
			(xy 126.94162 -286.154132) (xy 126.987778 -286.180781) (xy 127.029449 -286.214012) (xy 127.065701 -286.253083)
			(xy 127.095725 -286.29712) (xy 127.118851 -286.345141) (xy 127.134561 -286.396071) (xy 127.142504 -286.448775)
			(xy 127.143002 -286.475424) (xy 127.37084 -286.475424) (xy 127.371293 -286.449796) (xy 127.378626 -286.399067)
			(xy 127.393156 -286.349914) (xy 127.414585 -286.303352) (xy 127.442469 -286.260345) (xy 127.476233 -286.22178)
			(xy 127.515177 -286.188455) (xy 127.558497 -286.16106) (xy 127.605298 -286.140159) (xy 127.654613 -286.126185)
			(xy 127.679958 -286.122364) (xy 127.704596 -286.119062) (xy 127.877062 -285.820358) (xy 127.86741 -285.797244)
			(xy 127.858879 -285.775617) (xy 127.846898 -285.730697) (xy 127.840859 -285.6846) (xy 127.840486 -285.661354)
			(xy 127.840984 -285.634705) (xy 127.848927 -285.582001) (xy 127.864637 -285.531071) (xy 127.887763 -285.48305)
			(xy 127.917787 -285.439013) (xy 127.954039 -285.399942) (xy 127.99571 -285.366711) (xy 128.041868 -285.340062)
			(xy 128.091482 -285.32059) (xy 128.143444 -285.30873) (xy 128.196594 -285.304747) (xy 128.249744 -285.30873)
			(xy 128.301706 -285.32059) (xy 128.35132 -285.340062) (xy 128.397478 -285.366711) (xy 128.439149 -285.399942)
			(xy 128.475401 -285.439013) (xy 128.505425 -285.48305) (xy 128.528551 -285.531071) (xy 128.544261 -285.582001)
			(xy 128.552204 -285.634705) (xy 128.552702 -285.661354) (xy 128.552279 -285.686984) (xy 128.544948 -285.737716)
			(xy 128.530417 -285.786873) (xy 128.508987 -285.833438) (xy 128.4811 -285.876448) (xy 128.447332 -285.915013)
			(xy 128.408383 -285.948337) (xy 128.365058 -285.975731) (xy 128.318251 -285.996628) (xy 128.268932 -286.010596)
			(xy 128.243584 -286.014414) (xy 128.218946 -286.017716) (xy 128.04648 -286.31642) (xy 128.056132 -286.339534)
			(xy 128.064653 -286.361164) (xy 128.076639 -286.406083) (xy 128.082682 -286.452179) (xy 128.083056 -286.475424)
			(xy 128.082558 -286.502073) (xy 128.310884 -286.502073) (xy 128.310884 -286.448775) (xy 128.318827 -286.396071)
			(xy 128.334537 -286.345141) (xy 128.357663 -286.29712) (xy 128.387687 -286.253083) (xy 128.423939 -286.214012)
			(xy 128.46561 -286.180781) (xy 128.511768 -286.154132) (xy 128.561382 -286.13466) (xy 128.613344 -286.1228)
			(xy 128.666494 -286.118817) (xy 128.719644 -286.1228) (xy 128.771606 -286.13466) (xy 128.82122 -286.154132)
			(xy 128.867378 -286.180781) (xy 128.909049 -286.214012) (xy 128.945301 -286.253083) (xy 128.975325 -286.29712)
			(xy 128.998451 -286.345141) (xy 129.014161 -286.396071) (xy 129.022104 -286.448775) (xy 129.022602 -286.475424)
			(xy 129.25044 -286.475424) (xy 129.250893 -286.449796) (xy 129.258226 -286.399067) (xy 129.272756 -286.349914)
			(xy 129.294185 -286.303352) (xy 129.322069 -286.260345) (xy 129.355833 -286.22178) (xy 129.394777 -286.188455)
			(xy 129.438097 -286.16106) (xy 129.484898 -286.140159) (xy 129.534213 -286.126185) (xy 129.559558 -286.122364)
			(xy 129.584196 -286.119062) (xy 129.756662 -285.820358) (xy 129.74701 -285.797244) (xy 129.738479 -285.775617)
			(xy 129.726498 -285.730697) (xy 129.720459 -285.6846) (xy 129.720086 -285.661354) (xy 129.720584 -285.634705)
			(xy 129.728527 -285.582001) (xy 129.744237 -285.531071) (xy 129.767363 -285.48305) (xy 129.797387 -285.439013)
			(xy 129.833639 -285.399942) (xy 129.87531 -285.366711) (xy 129.921468 -285.340062) (xy 129.971082 -285.32059)
			(xy 130.023044 -285.30873) (xy 130.076194 -285.304747) (xy 130.129344 -285.30873) (xy 130.181306 -285.32059)
			(xy 130.23092 -285.340062) (xy 130.277078 -285.366711) (xy 130.318749 -285.399942) (xy 130.355001 -285.439013)
			(xy 130.385025 -285.48305) (xy 130.408151 -285.531071) (xy 130.423861 -285.582001) (xy 130.431804 -285.634705)
			(xy 130.432302 -285.661354) (xy 130.431879 -285.686984) (xy 130.424548 -285.737716) (xy 130.410017 -285.786873)
			(xy 130.388587 -285.833438) (xy 130.3607 -285.876448) (xy 130.326932 -285.915013) (xy 130.287983 -285.948337)
			(xy 130.244658 -285.975731) (xy 130.197851 -285.996628) (xy 130.148532 -286.010596) (xy 130.123184 -286.014414)
			(xy 130.098546 -286.017716) (xy 129.92608 -286.31642) (xy 129.935732 -286.339534) (xy 129.944253 -286.361164)
			(xy 129.956239 -286.406083) (xy 129.962282 -286.452179) (xy 129.962656 -286.475424) (xy 129.962158 -286.502073)
			(xy 130.190484 -286.502073) (xy 130.190484 -286.448775) (xy 130.198427 -286.396071) (xy 130.214137 -286.345141)
			(xy 130.237263 -286.29712) (xy 130.267287 -286.253083) (xy 130.303539 -286.214012) (xy 130.34521 -286.180781)
			(xy 130.391368 -286.154132) (xy 130.440982 -286.13466) (xy 130.492944 -286.1228) (xy 130.546094 -286.118817)
			(xy 130.599244 -286.1228) (xy 130.651206 -286.13466) (xy 130.70082 -286.154132) (xy 130.746978 -286.180781)
			(xy 130.788649 -286.214012) (xy 130.824901 -286.253083) (xy 130.854925 -286.29712) (xy 130.878051 -286.345141)
			(xy 130.893761 -286.396071) (xy 130.901704 -286.448775) (xy 130.902202 -286.475424) (xy 131.13004 -286.475424)
			(xy 131.130493 -286.449796) (xy 131.137826 -286.399067) (xy 131.152356 -286.349914) (xy 131.173785 -286.303352)
			(xy 131.201669 -286.260345) (xy 131.235433 -286.22178) (xy 131.274377 -286.188455) (xy 131.317697 -286.16106)
			(xy 131.364498 -286.140159) (xy 131.413813 -286.126185) (xy 131.439158 -286.122364) (xy 131.463796 -286.119062)
			(xy 131.636262 -285.820358) (xy 131.62661 -285.797244) (xy 131.618079 -285.775617) (xy 131.606098 -285.730697)
			(xy 131.600059 -285.6846) (xy 131.599686 -285.661354) (xy 131.600184 -285.634705) (xy 131.608127 -285.582001)
			(xy 131.623837 -285.531071) (xy 131.646963 -285.48305) (xy 131.676987 -285.439013) (xy 131.713239 -285.399942)
			(xy 131.75491 -285.366711) (xy 131.801068 -285.340062) (xy 131.850682 -285.32059) (xy 131.902644 -285.30873)
			(xy 131.955794 -285.304747) (xy 132.008944 -285.30873) (xy 132.060906 -285.32059) (xy 132.11052 -285.340062)
			(xy 132.156678 -285.366711) (xy 132.198349 -285.399942) (xy 132.234601 -285.439013) (xy 132.264625 -285.48305)
			(xy 132.287751 -285.531071) (xy 132.303461 -285.582001) (xy 132.311404 -285.634705) (xy 132.311902 -285.661354)
			(xy 132.311479 -285.686984) (xy 132.304148 -285.737716) (xy 132.289617 -285.786873) (xy 132.268187 -285.833438)
			(xy 132.2403 -285.876448) (xy 132.206532 -285.915013) (xy 132.167583 -285.948337) (xy 132.124258 -285.975731)
			(xy 132.077451 -285.996628) (xy 132.028132 -286.010596) (xy 132.002784 -286.014414) (xy 131.978146 -286.017716)
			(xy 131.80568 -286.31642) (xy 131.815332 -286.339534) (xy 131.823853 -286.361164) (xy 131.835839 -286.406083)
			(xy 131.841882 -286.452179) (xy 131.842256 -286.475424) (xy 131.841758 -286.502073) (xy 132.070084 -286.502073)
			(xy 132.070084 -286.448775) (xy 132.078027 -286.396071) (xy 132.093737 -286.345141) (xy 132.116863 -286.29712)
			(xy 132.146887 -286.253083) (xy 132.183139 -286.214012) (xy 132.22481 -286.180781) (xy 132.270968 -286.154132)
			(xy 132.320582 -286.13466) (xy 132.372544 -286.1228) (xy 132.425694 -286.118817) (xy 132.478844 -286.1228)
			(xy 132.530806 -286.13466) (xy 132.58042 -286.154132) (xy 132.626578 -286.180781) (xy 132.668249 -286.214012)
			(xy 132.704501 -286.253083) (xy 132.734525 -286.29712) (xy 132.757651 -286.345141) (xy 132.773361 -286.396071)
			(xy 132.781304 -286.448775) (xy 132.781802 -286.475424) (xy 133.00964 -286.475424) (xy 133.010093 -286.449796)
			(xy 133.017426 -286.399067) (xy 133.031956 -286.349914) (xy 133.053385 -286.303352) (xy 133.081269 -286.260345)
			(xy 133.115033 -286.22178) (xy 133.153977 -286.188455) (xy 133.197297 -286.16106) (xy 133.244098 -286.140159)
			(xy 133.293413 -286.126185) (xy 133.318758 -286.122364) (xy 133.343396 -286.119062) (xy 133.515862 -285.820358)
			(xy 133.50621 -285.797244) (xy 133.497679 -285.775617) (xy 133.485698 -285.730697) (xy 133.479659 -285.6846)
			(xy 133.479286 -285.661354) (xy 133.479784 -285.634705) (xy 133.487727 -285.582001) (xy 133.503437 -285.531071)
			(xy 133.526563 -285.48305) (xy 133.556587 -285.439013) (xy 133.592839 -285.399942) (xy 133.63451 -285.366711)
			(xy 133.680668 -285.340062) (xy 133.730282 -285.32059) (xy 133.782244 -285.30873) (xy 133.835394 -285.304747)
			(xy 133.888544 -285.30873) (xy 133.940506 -285.32059) (xy 133.99012 -285.340062) (xy 134.036278 -285.366711)
			(xy 134.077949 -285.399942) (xy 134.114201 -285.439013) (xy 134.144225 -285.48305) (xy 134.167351 -285.531071)
			(xy 134.183061 -285.582001) (xy 134.191004 -285.634705) (xy 134.191502 -285.661354) (xy 134.191079 -285.686984)
			(xy 134.190932 -285.688003) (xy 134.419584 -285.688003) (xy 134.419584 -285.634705) (xy 134.427527 -285.582001)
			(xy 134.443237 -285.531071) (xy 134.466363 -285.48305) (xy 134.496387 -285.439013) (xy 134.532639 -285.399942)
			(xy 134.57431 -285.366711) (xy 134.620468 -285.340062) (xy 134.670082 -285.32059) (xy 134.722044 -285.30873)
			(xy 134.775194 -285.304747) (xy 134.828344 -285.30873) (xy 134.880306 -285.32059) (xy 134.92992 -285.340062)
			(xy 134.976078 -285.366711) (xy 135.017749 -285.399942) (xy 135.054001 -285.439013) (xy 135.084025 -285.48305)
			(xy 135.107151 -285.531071) (xy 135.122861 -285.582001) (xy 135.130804 -285.634705) (xy 135.131302 -285.661354)
			(xy 135.130809 -285.687749) (xy 135.359384 -285.687749) (xy 135.359384 -285.634451) (xy 135.367327 -285.581747)
			(xy 135.383037 -285.530817) (xy 135.406163 -285.482796) (xy 135.436187 -285.438759) (xy 135.472439 -285.399688)
			(xy 135.51411 -285.366457) (xy 135.560268 -285.339808) (xy 135.609882 -285.320336) (xy 135.661844 -285.308476)
			(xy 135.714994 -285.304493) (xy 135.768144 -285.308476) (xy 135.820106 -285.320336) (xy 135.86972 -285.339808)
			(xy 135.915878 -285.366457) (xy 135.957549 -285.399688) (xy 135.993801 -285.438759) (xy 136.023825 -285.482796)
			(xy 136.046951 -285.530817) (xy 136.062661 -285.581747) (xy 136.070604 -285.634451) (xy 136.071102 -285.6611)
			(xy 136.070604 -285.687749) (xy 136.070566 -285.688003) (xy 136.299184 -285.688003) (xy 136.299184 -285.634705)
			(xy 136.307127 -285.582001) (xy 136.322837 -285.531071) (xy 136.345963 -285.48305) (xy 136.375987 -285.439013)
			(xy 136.412239 -285.399942) (xy 136.45391 -285.366711) (xy 136.500068 -285.340062) (xy 136.549682 -285.32059)
			(xy 136.601644 -285.30873) (xy 136.654794 -285.304747) (xy 136.707944 -285.30873) (xy 136.759906 -285.32059)
			(xy 136.80952 -285.340062) (xy 136.855678 -285.366711) (xy 136.897349 -285.399942) (xy 136.933601 -285.439013)
			(xy 136.963625 -285.48305) (xy 136.986751 -285.531071) (xy 137.002461 -285.582001) (xy 137.010404 -285.634705)
			(xy 137.010902 -285.661354) (xy 137.010404 -285.688003) (xy 137.002461 -285.740707) (xy 136.986751 -285.791637)
			(xy 136.963625 -285.839658) (xy 136.933601 -285.883695) (xy 136.897349 -285.922766) (xy 136.855678 -285.955997)
			(xy 136.80952 -285.982646) (xy 136.759906 -286.002118) (xy 136.707944 -286.013978) (xy 136.654794 -286.017962)
			(xy 136.601644 -286.013978) (xy 136.549682 -286.002118) (xy 136.500068 -285.982646) (xy 136.45391 -285.955997)
			(xy 136.412239 -285.922766) (xy 136.375987 -285.883695) (xy 136.345963 -285.839658) (xy 136.322837 -285.791637)
			(xy 136.307127 -285.740707) (xy 136.299184 -285.688003) (xy 136.070566 -285.688003) (xy 136.062661 -285.740453)
			(xy 136.046951 -285.791383) (xy 136.023825 -285.839404) (xy 135.993801 -285.883441) (xy 135.957549 -285.922512)
			(xy 135.915878 -285.955743) (xy 135.86972 -285.982392) (xy 135.820106 -286.001864) (xy 135.768144 -286.013724)
			(xy 135.714994 -286.017708) (xy 135.661844 -286.013724) (xy 135.609882 -286.001864) (xy 135.560268 -285.982392)
			(xy 135.51411 -285.955743) (xy 135.472439 -285.922512) (xy 135.436187 -285.883441) (xy 135.406163 -285.839404)
			(xy 135.383037 -285.791383) (xy 135.367327 -285.740453) (xy 135.359384 -285.687749) (xy 135.130809 -285.687749)
			(xy 135.130804 -285.688003) (xy 135.122861 -285.740707) (xy 135.107151 -285.791637) (xy 135.084025 -285.839658)
			(xy 135.054001 -285.883695) (xy 135.017749 -285.922766) (xy 134.976078 -285.955997) (xy 134.92992 -285.982646)
			(xy 134.880306 -286.002118) (xy 134.828344 -286.013978) (xy 134.775194 -286.017962) (xy 134.722044 -286.013978)
			(xy 134.670082 -286.002118) (xy 134.620468 -285.982646) (xy 134.57431 -285.955997) (xy 134.532639 -285.922766)
			(xy 134.496387 -285.883695) (xy 134.466363 -285.839658) (xy 134.443237 -285.791637) (xy 134.427527 -285.740707)
			(xy 134.419584 -285.688003) (xy 134.190932 -285.688003) (xy 134.183748 -285.737716) (xy 134.169217 -285.786873)
			(xy 134.147787 -285.833438) (xy 134.1199 -285.876448) (xy 134.086132 -285.915013) (xy 134.047183 -285.948337)
			(xy 134.003858 -285.975731) (xy 133.957051 -285.996628) (xy 133.907732 -286.010596) (xy 133.882384 -286.014414)
			(xy 133.857746 -286.017716) (xy 133.68528 -286.31642) (xy 133.694932 -286.339534) (xy 133.703453 -286.361164)
			(xy 133.715439 -286.406083) (xy 133.721482 -286.452179) (xy 133.721856 -286.475424) (xy 133.721358 -286.502073)
			(xy 133.949684 -286.502073) (xy 133.949684 -286.448775) (xy 133.957627 -286.396071) (xy 133.973337 -286.345141)
			(xy 133.996463 -286.29712) (xy 134.026487 -286.253083) (xy 134.062739 -286.214012) (xy 134.10441 -286.180781)
			(xy 134.150568 -286.154132) (xy 134.200182 -286.13466) (xy 134.252144 -286.1228) (xy 134.305294 -286.118817)
			(xy 134.358444 -286.1228) (xy 134.410406 -286.13466) (xy 134.46002 -286.154132) (xy 134.506178 -286.180781)
			(xy 134.547849 -286.214012) (xy 134.584101 -286.253083) (xy 134.614125 -286.29712) (xy 134.637251 -286.345141)
			(xy 134.652961 -286.396071) (xy 134.660904 -286.448775) (xy 134.661402 -286.475424) (xy 134.660909 -286.501819)
			(xy 134.889484 -286.501819) (xy 134.889484 -286.448521) (xy 134.897427 -286.395817) (xy 134.913137 -286.344887)
			(xy 134.936263 -286.296866) (xy 134.966287 -286.252829) (xy 135.002539 -286.213758) (xy 135.04421 -286.180527)
			(xy 135.090368 -286.153878) (xy 135.139982 -286.134406) (xy 135.191944 -286.122546) (xy 135.245094 -286.118563)
			(xy 135.298244 -286.122546) (xy 135.350206 -286.134406) (xy 135.39982 -286.153878) (xy 135.445978 -286.180527)
			(xy 135.487649 -286.213758) (xy 135.523901 -286.252829) (xy 135.553925 -286.296866) (xy 135.577051 -286.344887)
			(xy 135.592761 -286.395817) (xy 135.600704 -286.448521) (xy 135.601202 -286.47517) (xy 135.600704 -286.501819)
			(xy 135.829284 -286.501819) (xy 135.829284 -286.448521) (xy 135.837227 -286.395817) (xy 135.852937 -286.344887)
			(xy 135.876063 -286.296866) (xy 135.906087 -286.252829) (xy 135.942339 -286.213758) (xy 135.98401 -286.180527)
			(xy 136.030168 -286.153878) (xy 136.079782 -286.134406) (xy 136.131744 -286.122546) (xy 136.184894 -286.118563)
			(xy 136.238044 -286.122546) (xy 136.290006 -286.134406) (xy 136.33962 -286.153878) (xy 136.385778 -286.180527)
			(xy 136.427449 -286.213758) (xy 136.463701 -286.252829) (xy 136.493725 -286.296866) (xy 136.516851 -286.344887)
			(xy 136.532561 -286.395817) (xy 136.540504 -286.448521) (xy 136.541002 -286.47517) (xy 136.540504 -286.501819)
			(xy 136.532561 -286.554523) (xy 136.516851 -286.605453) (xy 136.493725 -286.653474) (xy 136.463701 -286.697511)
			(xy 136.427449 -286.736582) (xy 136.385778 -286.769813) (xy 136.33962 -286.796462) (xy 136.290006 -286.815934)
			(xy 136.238044 -286.827794) (xy 136.184894 -286.831778) (xy 136.131744 -286.827794) (xy 136.079782 -286.815934)
			(xy 136.030168 -286.796462) (xy 135.98401 -286.769813) (xy 135.942339 -286.736582) (xy 135.906087 -286.697511)
			(xy 135.876063 -286.653474) (xy 135.852937 -286.605453) (xy 135.837227 -286.554523) (xy 135.829284 -286.501819)
			(xy 135.600704 -286.501819) (xy 135.592761 -286.554523) (xy 135.577051 -286.605453) (xy 135.553925 -286.653474)
			(xy 135.523901 -286.697511) (xy 135.487649 -286.736582) (xy 135.445978 -286.769813) (xy 135.39982 -286.796462)
			(xy 135.350206 -286.815934) (xy 135.298244 -286.827794) (xy 135.245094 -286.831778) (xy 135.191944 -286.827794)
			(xy 135.139982 -286.815934) (xy 135.090368 -286.796462) (xy 135.04421 -286.769813) (xy 135.002539 -286.736582)
			(xy 134.966287 -286.697511) (xy 134.936263 -286.653474) (xy 134.913137 -286.605453) (xy 134.897427 -286.554523)
			(xy 134.889484 -286.501819) (xy 134.660909 -286.501819) (xy 134.660904 -286.502073) (xy 134.652961 -286.554777)
			(xy 134.637251 -286.605707) (xy 134.614125 -286.653728) (xy 134.584101 -286.697765) (xy 134.547849 -286.736836)
			(xy 134.506178 -286.770067) (xy 134.46002 -286.796716) (xy 134.410406 -286.816188) (xy 134.358444 -286.828048)
			(xy 134.305294 -286.832032) (xy 134.252144 -286.828048) (xy 134.200182 -286.816188) (xy 134.150568 -286.796716)
			(xy 134.10441 -286.770067) (xy 134.062739 -286.736836) (xy 134.026487 -286.697765) (xy 133.996463 -286.653728)
			(xy 133.973337 -286.605707) (xy 133.957627 -286.554777) (xy 133.949684 -286.502073) (xy 133.721358 -286.502073)
			(xy 133.713415 -286.554777) (xy 133.697705 -286.605707) (xy 133.674579 -286.653728) (xy 133.644555 -286.697765)
			(xy 133.608303 -286.736836) (xy 133.566632 -286.770067) (xy 133.520474 -286.796716) (xy 133.47086 -286.816188)
			(xy 133.418898 -286.828048) (xy 133.365748 -286.832032) (xy 133.312598 -286.828048) (xy 133.260636 -286.816188)
			(xy 133.211022 -286.796716) (xy 133.164864 -286.770067) (xy 133.123193 -286.736836) (xy 133.086941 -286.697765)
			(xy 133.056917 -286.653728) (xy 133.033791 -286.605707) (xy 133.018081 -286.554777) (xy 133.010138 -286.502073)
			(xy 133.00964 -286.475424) (xy 132.781802 -286.475424) (xy 132.781304 -286.502073) (xy 132.773361 -286.554777)
			(xy 132.757651 -286.605707) (xy 132.734525 -286.653728) (xy 132.704501 -286.697765) (xy 132.668249 -286.736836)
			(xy 132.626578 -286.770067) (xy 132.58042 -286.796716) (xy 132.530806 -286.816188) (xy 132.478844 -286.828048)
			(xy 132.425694 -286.832032) (xy 132.372544 -286.828048) (xy 132.320582 -286.816188) (xy 132.270968 -286.796716)
			(xy 132.22481 -286.770067) (xy 132.183139 -286.736836) (xy 132.146887 -286.697765) (xy 132.116863 -286.653728)
			(xy 132.093737 -286.605707) (xy 132.078027 -286.554777) (xy 132.070084 -286.502073) (xy 131.841758 -286.502073)
			(xy 131.833815 -286.554777) (xy 131.818105 -286.605707) (xy 131.794979 -286.653728) (xy 131.764955 -286.697765)
			(xy 131.728703 -286.736836) (xy 131.687032 -286.770067) (xy 131.640874 -286.796716) (xy 131.59126 -286.816188)
			(xy 131.539298 -286.828048) (xy 131.486148 -286.832032) (xy 131.432998 -286.828048) (xy 131.381036 -286.816188)
			(xy 131.331422 -286.796716) (xy 131.285264 -286.770067) (xy 131.243593 -286.736836) (xy 131.207341 -286.697765)
			(xy 131.177317 -286.653728) (xy 131.154191 -286.605707) (xy 131.138481 -286.554777) (xy 131.130538 -286.502073)
			(xy 131.13004 -286.475424) (xy 130.902202 -286.475424) (xy 130.901704 -286.502073) (xy 130.893761 -286.554777)
			(xy 130.878051 -286.605707) (xy 130.854925 -286.653728) (xy 130.824901 -286.697765) (xy 130.788649 -286.736836)
			(xy 130.746978 -286.770067) (xy 130.70082 -286.796716) (xy 130.651206 -286.816188) (xy 130.599244 -286.828048)
			(xy 130.546094 -286.832032) (xy 130.492944 -286.828048) (xy 130.440982 -286.816188) (xy 130.391368 -286.796716)
			(xy 130.34521 -286.770067) (xy 130.303539 -286.736836) (xy 130.267287 -286.697765) (xy 130.237263 -286.653728)
			(xy 130.214137 -286.605707) (xy 130.198427 -286.554777) (xy 130.190484 -286.502073) (xy 129.962158 -286.502073)
			(xy 129.954215 -286.554777) (xy 129.938505 -286.605707) (xy 129.915379 -286.653728) (xy 129.885355 -286.697765)
			(xy 129.849103 -286.736836) (xy 129.807432 -286.770067) (xy 129.761274 -286.796716) (xy 129.71166 -286.816188)
			(xy 129.659698 -286.828048) (xy 129.606548 -286.832032) (xy 129.553398 -286.828048) (xy 129.501436 -286.816188)
			(xy 129.451822 -286.796716) (xy 129.405664 -286.770067) (xy 129.363993 -286.736836) (xy 129.327741 -286.697765)
			(xy 129.297717 -286.653728) (xy 129.274591 -286.605707) (xy 129.258881 -286.554777) (xy 129.250938 -286.502073)
			(xy 129.25044 -286.475424) (xy 129.022602 -286.475424) (xy 129.022104 -286.502073) (xy 129.014161 -286.554777)
			(xy 128.998451 -286.605707) (xy 128.975325 -286.653728) (xy 128.945301 -286.697765) (xy 128.909049 -286.736836)
			(xy 128.867378 -286.770067) (xy 128.82122 -286.796716) (xy 128.771606 -286.816188) (xy 128.719644 -286.828048)
			(xy 128.666494 -286.832032) (xy 128.613344 -286.828048) (xy 128.561382 -286.816188) (xy 128.511768 -286.796716)
			(xy 128.46561 -286.770067) (xy 128.423939 -286.736836) (xy 128.387687 -286.697765) (xy 128.357663 -286.653728)
			(xy 128.334537 -286.605707) (xy 128.318827 -286.554777) (xy 128.310884 -286.502073) (xy 128.082558 -286.502073)
			(xy 128.074615 -286.554777) (xy 128.058905 -286.605707) (xy 128.035779 -286.653728) (xy 128.005755 -286.697765)
			(xy 127.969503 -286.736836) (xy 127.927832 -286.770067) (xy 127.881674 -286.796716) (xy 127.83206 -286.816188)
			(xy 127.780098 -286.828048) (xy 127.726948 -286.832032) (xy 127.673798 -286.828048) (xy 127.621836 -286.816188)
			(xy 127.572222 -286.796716) (xy 127.526064 -286.770067) (xy 127.484393 -286.736836) (xy 127.448141 -286.697765)
			(xy 127.418117 -286.653728) (xy 127.394991 -286.605707) (xy 127.379281 -286.554777) (xy 127.371338 -286.502073)
			(xy 127.37084 -286.475424) (xy 127.143002 -286.475424) (xy 127.142504 -286.502073) (xy 127.134561 -286.554777)
			(xy 127.118851 -286.605707) (xy 127.095725 -286.653728) (xy 127.065701 -286.697765) (xy 127.029449 -286.736836)
			(xy 126.987778 -286.770067) (xy 126.94162 -286.796716) (xy 126.892006 -286.816188) (xy 126.840044 -286.828048)
			(xy 126.786894 -286.832032) (xy 126.733744 -286.828048) (xy 126.681782 -286.816188) (xy 126.632168 -286.796716)
			(xy 126.58601 -286.770067) (xy 126.544339 -286.736836) (xy 126.508087 -286.697765) (xy 126.478063 -286.653728)
			(xy 126.454937 -286.605707) (xy 126.439227 -286.554777) (xy 126.431284 -286.502073) (xy 126.202958 -286.502073)
			(xy 126.195015 -286.554777) (xy 126.179305 -286.605707) (xy 126.156179 -286.653728) (xy 126.126155 -286.697765)
			(xy 126.089903 -286.736836) (xy 126.048232 -286.770067) (xy 126.002074 -286.796716) (xy 125.95246 -286.816188)
			(xy 125.900498 -286.828048) (xy 125.847348 -286.832032) (xy 125.794198 -286.828048) (xy 125.742236 -286.816188)
			(xy 125.692622 -286.796716) (xy 125.646464 -286.770067) (xy 125.604793 -286.736836) (xy 125.568541 -286.697765)
			(xy 125.538517 -286.653728) (xy 125.515391 -286.605707) (xy 125.499681 -286.554777) (xy 125.491738 -286.502073)
			(xy 125.49124 -286.475424) (xy 125.263402 -286.475424) (xy 125.262904 -286.502073) (xy 125.254961 -286.554777)
			(xy 125.239251 -286.605707) (xy 125.216125 -286.653728) (xy 125.186101 -286.697765) (xy 125.149849 -286.736836)
			(xy 125.108178 -286.770067) (xy 125.06202 -286.796716) (xy 125.012406 -286.816188) (xy 124.960444 -286.828048)
			(xy 124.907294 -286.832032) (xy 124.854144 -286.828048) (xy 124.802182 -286.816188) (xy 124.752568 -286.796716)
			(xy 124.70641 -286.770067) (xy 124.664739 -286.736836) (xy 124.628487 -286.697765) (xy 124.598463 -286.653728)
			(xy 124.575337 -286.605707) (xy 124.559627 -286.554777) (xy 124.551684 -286.502073) (xy 124.323358 -286.502073)
			(xy 124.315415 -286.554777) (xy 124.299705 -286.605707) (xy 124.276579 -286.653728) (xy 124.246555 -286.697765)
			(xy 124.210303 -286.736836) (xy 124.168632 -286.770067) (xy 124.122474 -286.796716) (xy 124.07286 -286.816188)
			(xy 124.020898 -286.828048) (xy 123.967748 -286.832032) (xy 123.914598 -286.828048) (xy 123.862636 -286.816188)
			(xy 123.813022 -286.796716) (xy 123.766864 -286.770067) (xy 123.725193 -286.736836) (xy 123.688941 -286.697765)
			(xy 123.658917 -286.653728) (xy 123.635791 -286.605707) (xy 123.620081 -286.554777) (xy 123.612138 -286.502073)
			(xy 123.61164 -286.475424) (xy 123.383802 -286.475424) (xy 123.383304 -286.502073) (xy 123.375361 -286.554777)
			(xy 123.359651 -286.605707) (xy 123.336525 -286.653728) (xy 123.306501 -286.697765) (xy 123.270249 -286.736836)
			(xy 123.228578 -286.770067) (xy 123.18242 -286.796716) (xy 123.132806 -286.816188) (xy 123.080844 -286.828048)
			(xy 123.027694 -286.832032) (xy 122.974544 -286.828048) (xy 122.922582 -286.816188) (xy 122.872968 -286.796716)
			(xy 122.82681 -286.770067) (xy 122.785139 -286.736836) (xy 122.748887 -286.697765) (xy 122.718863 -286.653728)
			(xy 122.695737 -286.605707) (xy 122.680027 -286.554777) (xy 122.672084 -286.502073) (xy 122.443758 -286.502073)
			(xy 122.435815 -286.554777) (xy 122.420105 -286.605707) (xy 122.396979 -286.653728) (xy 122.366955 -286.697765)
			(xy 122.330703 -286.736836) (xy 122.289032 -286.770067) (xy 122.242874 -286.796716) (xy 122.19326 -286.816188)
			(xy 122.141298 -286.828048) (xy 122.088148 -286.832032) (xy 122.034998 -286.828048) (xy 121.983036 -286.816188)
			(xy 121.933422 -286.796716) (xy 121.887264 -286.770067) (xy 121.845593 -286.736836) (xy 121.809341 -286.697765)
			(xy 121.779317 -286.653728) (xy 121.756191 -286.605707) (xy 121.740481 -286.554777) (xy 121.732538 -286.502073)
			(xy 121.73204 -286.475424) (xy 121.504202 -286.475424) (xy 121.503704 -286.502073) (xy 121.495761 -286.554777)
			(xy 121.480051 -286.605707) (xy 121.456925 -286.653728) (xy 121.426901 -286.697765) (xy 121.390649 -286.736836)
			(xy 121.348978 -286.770067) (xy 121.30282 -286.796716) (xy 121.253206 -286.816188) (xy 121.201244 -286.828048)
			(xy 121.148094 -286.832032) (xy 121.094944 -286.828048) (xy 121.042982 -286.816188) (xy 120.993368 -286.796716)
			(xy 120.94721 -286.770067) (xy 120.905539 -286.736836) (xy 120.869287 -286.697765) (xy 120.839263 -286.653728)
			(xy 120.816137 -286.605707) (xy 120.800427 -286.554777) (xy 120.792484 -286.502073) (xy 120.564158 -286.502073)
			(xy 120.564131 -286.503544) (xy 120.555301 -286.559087) (xy 120.53785 -286.612552) (xy 120.51221 -286.662608)
			(xy 120.479021 -286.708011) (xy 120.439106 -286.747631) (xy 120.393459 -286.780485) (xy 120.343215 -286.805753)
			(xy 120.289623 -286.822809) (xy 120.261888 -286.827468) (xy 120.248031 -286.82997) (xy 120.222367 -286.841528)
			(xy 120.200836 -286.859658) (xy 120.185078 -286.882981) (xy 120.176292 -286.909722) (xy 120.175145 -286.937846)
			(xy 120.181726 -286.965213) (xy 120.195534 -286.989741) (xy 120.205246 -286.999934) (xy 120.263412 -287.0581)
			(xy 120.273514 -287.067567) (xy 120.297609 -287.081178) (xy 120.324478 -287.087801) (xy 120.352138 -287.086949)
			(xy 120.378548 -287.078684) (xy 120.401759 -287.063616) (xy 120.41124 -287.053528) (xy 120.42822 -287.034957)
			(xy 120.466508 -287.002306) (xy 120.509012 -286.975371) (xy 120.554885 -286.954689) (xy 120.603214 -286.940672)
			(xy 120.653034 -286.9336) (xy 120.678194 -286.933132) (xy 120.706179 -286.933652) (xy 120.761458 -286.942407)
			(xy 120.814688 -286.959703) (xy 120.864556 -286.985114) (xy 120.909835 -287.018013) (xy 120.949409 -287.057591)
			(xy 120.982304 -287.102873) (xy 121.00771 -287.152743) (xy 121.025001 -287.205975) (xy 121.033751 -287.261255)
			(xy 121.034302 -287.28924) (xy 121.033866 -287.3144) (xy 121.033654 -287.315889) (xy 121.262384 -287.315889)
			(xy 121.262384 -287.262591) (xy 121.270327 -287.209887) (xy 121.286037 -287.158957) (xy 121.309163 -287.110936)
			(xy 121.339187 -287.066899) (xy 121.375439 -287.027828) (xy 121.41711 -286.994597) (xy 121.463268 -286.967948)
			(xy 121.512882 -286.948476) (xy 121.564844 -286.936616) (xy 121.617994 -286.932633) (xy 121.671144 -286.936616)
			(xy 121.723106 -286.948476) (xy 121.77272 -286.967948) (xy 121.818878 -286.994597) (xy 121.860549 -287.027828)
			(xy 121.896801 -287.066899) (xy 121.926825 -287.110936) (xy 121.949951 -287.158957) (xy 121.965661 -287.209887)
			(xy 121.973604 -287.262591) (xy 121.974102 -287.28924) (xy 121.973604 -287.315889) (xy 122.202184 -287.315889)
			(xy 122.202184 -287.262591) (xy 122.210127 -287.209887) (xy 122.225837 -287.158957) (xy 122.248963 -287.110936)
			(xy 122.278987 -287.066899) (xy 122.315239 -287.027828) (xy 122.35691 -286.994597) (xy 122.403068 -286.967948)
			(xy 122.452682 -286.948476) (xy 122.504644 -286.936616) (xy 122.557794 -286.932633) (xy 122.610944 -286.936616)
			(xy 122.662906 -286.948476) (xy 122.71252 -286.967948) (xy 122.758678 -286.994597) (xy 122.800349 -287.027828)
			(xy 122.836601 -287.066899) (xy 122.866625 -287.110936) (xy 122.889751 -287.158957) (xy 122.905461 -287.209887)
			(xy 122.913404 -287.262591) (xy 122.913902 -287.28924) (xy 122.913404 -287.315889) (xy 123.141984 -287.315889)
			(xy 123.141984 -287.262591) (xy 123.149927 -287.209887) (xy 123.165637 -287.158957) (xy 123.188763 -287.110936)
			(xy 123.218787 -287.066899) (xy 123.255039 -287.027828) (xy 123.29671 -286.994597) (xy 123.342868 -286.967948)
			(xy 123.392482 -286.948476) (xy 123.444444 -286.936616) (xy 123.497594 -286.932633) (xy 123.550744 -286.936616)
			(xy 123.602706 -286.948476) (xy 123.65232 -286.967948) (xy 123.698478 -286.994597) (xy 123.740149 -287.027828)
			(xy 123.776401 -287.066899) (xy 123.806425 -287.110936) (xy 123.829551 -287.158957) (xy 123.845261 -287.209887)
			(xy 123.853204 -287.262591) (xy 123.853702 -287.28924) (xy 123.853204 -287.315889) (xy 124.081784 -287.315889)
			(xy 124.081784 -287.262591) (xy 124.089727 -287.209887) (xy 124.105437 -287.158957) (xy 124.128563 -287.110936)
			(xy 124.158587 -287.066899) (xy 124.194839 -287.027828) (xy 124.23651 -286.994597) (xy 124.282668 -286.967948)
			(xy 124.332282 -286.948476) (xy 124.384244 -286.936616) (xy 124.437394 -286.932633) (xy 124.490544 -286.936616)
			(xy 124.542506 -286.948476) (xy 124.59212 -286.967948) (xy 124.638278 -286.994597) (xy 124.679949 -287.027828)
			(xy 124.716201 -287.066899) (xy 124.746225 -287.110936) (xy 124.769351 -287.158957) (xy 124.785061 -287.209887)
			(xy 124.793004 -287.262591) (xy 124.793502 -287.28924) (xy 124.793004 -287.315889) (xy 125.021584 -287.315889)
			(xy 125.021584 -287.262591) (xy 125.029527 -287.209887) (xy 125.045237 -287.158957) (xy 125.068363 -287.110936)
			(xy 125.098387 -287.066899) (xy 125.134639 -287.027828) (xy 125.17631 -286.994597) (xy 125.222468 -286.967948)
			(xy 125.272082 -286.948476) (xy 125.324044 -286.936616) (xy 125.377194 -286.932633) (xy 125.430344 -286.936616)
			(xy 125.482306 -286.948476) (xy 125.53192 -286.967948) (xy 125.578078 -286.994597) (xy 125.619749 -287.027828)
			(xy 125.656001 -287.066899) (xy 125.686025 -287.110936) (xy 125.709151 -287.158957) (xy 125.724861 -287.209887)
			(xy 125.732804 -287.262591) (xy 125.733302 -287.28924) (xy 125.732804 -287.315889) (xy 125.961384 -287.315889)
			(xy 125.961384 -287.262591) (xy 125.969327 -287.209887) (xy 125.985037 -287.158957) (xy 126.008163 -287.110936)
			(xy 126.038187 -287.066899) (xy 126.074439 -287.027828) (xy 126.11611 -286.994597) (xy 126.162268 -286.967948)
			(xy 126.211882 -286.948476) (xy 126.263844 -286.936616) (xy 126.316994 -286.932633) (xy 126.370144 -286.936616)
			(xy 126.422106 -286.948476) (xy 126.47172 -286.967948) (xy 126.517878 -286.994597) (xy 126.559549 -287.027828)
			(xy 126.595801 -287.066899) (xy 126.625825 -287.110936) (xy 126.648951 -287.158957) (xy 126.664661 -287.209887)
			(xy 126.672604 -287.262591) (xy 126.673102 -287.28924) (xy 126.672604 -287.315889) (xy 126.901184 -287.315889)
			(xy 126.901184 -287.262591) (xy 126.909127 -287.209887) (xy 126.924837 -287.158957) (xy 126.947963 -287.110936)
			(xy 126.977987 -287.066899) (xy 127.014239 -287.027828) (xy 127.05591 -286.994597) (xy 127.102068 -286.967948)
			(xy 127.151682 -286.948476) (xy 127.203644 -286.936616) (xy 127.256794 -286.932633) (xy 127.309944 -286.936616)
			(xy 127.361906 -286.948476) (xy 127.41152 -286.967948) (xy 127.457678 -286.994597) (xy 127.499349 -287.027828)
			(xy 127.535601 -287.066899) (xy 127.565625 -287.110936) (xy 127.588751 -287.158957) (xy 127.604461 -287.209887)
			(xy 127.612404 -287.262591) (xy 127.612902 -287.28924) (xy 127.612404 -287.315889) (xy 127.840984 -287.315889)
			(xy 127.840984 -287.262591) (xy 127.848927 -287.209887) (xy 127.864637 -287.158957) (xy 127.887763 -287.110936)
			(xy 127.917787 -287.066899) (xy 127.954039 -287.027828) (xy 127.99571 -286.994597) (xy 128.041868 -286.967948)
			(xy 128.091482 -286.948476) (xy 128.143444 -286.936616) (xy 128.196594 -286.932633) (xy 128.249744 -286.936616)
			(xy 128.301706 -286.948476) (xy 128.35132 -286.967948) (xy 128.397478 -286.994597) (xy 128.439149 -287.027828)
			(xy 128.475401 -287.066899) (xy 128.505425 -287.110936) (xy 128.528551 -287.158957) (xy 128.544261 -287.209887)
			(xy 128.552204 -287.262591) (xy 128.552702 -287.28924) (xy 128.552204 -287.315889) (xy 128.780784 -287.315889)
			(xy 128.780784 -287.262591) (xy 128.788727 -287.209887) (xy 128.804437 -287.158957) (xy 128.827563 -287.110936)
			(xy 128.857587 -287.066899) (xy 128.893839 -287.027828) (xy 128.93551 -286.994597) (xy 128.981668 -286.967948)
			(xy 129.031282 -286.948476) (xy 129.083244 -286.936616) (xy 129.136394 -286.932633) (xy 129.189544 -286.936616)
			(xy 129.241506 -286.948476) (xy 129.29112 -286.967948) (xy 129.337278 -286.994597) (xy 129.378949 -287.027828)
			(xy 129.415201 -287.066899) (xy 129.445225 -287.110936) (xy 129.468351 -287.158957) (xy 129.484061 -287.209887)
			(xy 129.492004 -287.262591) (xy 129.492502 -287.28924) (xy 129.492004 -287.315889) (xy 129.720584 -287.315889)
			(xy 129.720584 -287.262591) (xy 129.728527 -287.209887) (xy 129.744237 -287.158957) (xy 129.767363 -287.110936)
			(xy 129.797387 -287.066899) (xy 129.833639 -287.027828) (xy 129.87531 -286.994597) (xy 129.921468 -286.967948)
			(xy 129.971082 -286.948476) (xy 130.023044 -286.936616) (xy 130.076194 -286.932633) (xy 130.129344 -286.936616)
			(xy 130.181306 -286.948476) (xy 130.23092 -286.967948) (xy 130.277078 -286.994597) (xy 130.318749 -287.027828)
			(xy 130.355001 -287.066899) (xy 130.385025 -287.110936) (xy 130.408151 -287.158957) (xy 130.423861 -287.209887)
			(xy 130.431804 -287.262591) (xy 130.432302 -287.28924) (xy 130.431804 -287.315889) (xy 130.660384 -287.315889)
			(xy 130.660384 -287.262591) (xy 130.668327 -287.209887) (xy 130.684037 -287.158957) (xy 130.707163 -287.110936)
			(xy 130.737187 -287.066899) (xy 130.773439 -287.027828) (xy 130.81511 -286.994597) (xy 130.861268 -286.967948)
			(xy 130.910882 -286.948476) (xy 130.962844 -286.936616) (xy 131.015994 -286.932633) (xy 131.069144 -286.936616)
			(xy 131.121106 -286.948476) (xy 131.17072 -286.967948) (xy 131.216878 -286.994597) (xy 131.258549 -287.027828)
			(xy 131.294801 -287.066899) (xy 131.324825 -287.110936) (xy 131.347951 -287.158957) (xy 131.363661 -287.209887)
			(xy 131.371604 -287.262591) (xy 131.372102 -287.28924) (xy 131.371604 -287.315889) (xy 131.600184 -287.315889)
			(xy 131.600184 -287.262591) (xy 131.608127 -287.209887) (xy 131.623837 -287.158957) (xy 131.646963 -287.110936)
			(xy 131.676987 -287.066899) (xy 131.713239 -287.027828) (xy 131.75491 -286.994597) (xy 131.801068 -286.967948)
			(xy 131.850682 -286.948476) (xy 131.902644 -286.936616) (xy 131.955794 -286.932633) (xy 132.008944 -286.936616)
			(xy 132.060906 -286.948476) (xy 132.11052 -286.967948) (xy 132.156678 -286.994597) (xy 132.198349 -287.027828)
			(xy 132.234601 -287.066899) (xy 132.264625 -287.110936) (xy 132.287751 -287.158957) (xy 132.303461 -287.209887)
			(xy 132.311404 -287.262591) (xy 132.311902 -287.28924) (xy 132.311404 -287.315889) (xy 132.539984 -287.315889)
			(xy 132.539984 -287.262591) (xy 132.547927 -287.209887) (xy 132.563637 -287.158957) (xy 132.586763 -287.110936)
			(xy 132.616787 -287.066899) (xy 132.653039 -287.027828) (xy 132.69471 -286.994597) (xy 132.740868 -286.967948)
			(xy 132.790482 -286.948476) (xy 132.842444 -286.936616) (xy 132.895594 -286.932633) (xy 132.948744 -286.936616)
			(xy 133.000706 -286.948476) (xy 133.05032 -286.967948) (xy 133.096478 -286.994597) (xy 133.138149 -287.027828)
			(xy 133.174401 -287.066899) (xy 133.204425 -287.110936) (xy 133.227551 -287.158957) (xy 133.243261 -287.209887)
			(xy 133.251204 -287.262591) (xy 133.251702 -287.28924) (xy 133.251204 -287.315889) (xy 133.480038 -287.315889)
			(xy 133.480038 -287.262591) (xy 133.487981 -287.209887) (xy 133.503691 -287.158957) (xy 133.526817 -287.110936)
			(xy 133.556841 -287.066899) (xy 133.593093 -287.027828) (xy 133.634764 -286.994597) (xy 133.680922 -286.967948)
			(xy 133.730536 -286.948476) (xy 133.782498 -286.936616) (xy 133.835648 -286.932633) (xy 133.888798 -286.936616)
			(xy 133.94076 -286.948476) (xy 133.990374 -286.967948) (xy 134.036532 -286.994597) (xy 134.078203 -287.027828)
			(xy 134.114455 -287.066899) (xy 134.144479 -287.110936) (xy 134.167605 -287.158957) (xy 134.183315 -287.209887)
			(xy 134.191258 -287.262591) (xy 134.191756 -287.28924) (xy 134.191258 -287.315889) (xy 134.419838 -287.315889)
			(xy 134.419838 -287.262591) (xy 134.427781 -287.209887) (xy 134.443491 -287.158957) (xy 134.466617 -287.110936)
			(xy 134.496641 -287.066899) (xy 134.532893 -287.027828) (xy 134.574564 -286.994597) (xy 134.620722 -286.967948)
			(xy 134.670336 -286.948476) (xy 134.722298 -286.936616) (xy 134.775448 -286.932633) (xy 134.828598 -286.936616)
			(xy 134.88056 -286.948476) (xy 134.930174 -286.967948) (xy 134.976332 -286.994597) (xy 135.018003 -287.027828)
			(xy 135.054255 -287.066899) (xy 135.084279 -287.110936) (xy 135.107405 -287.158957) (xy 135.123115 -287.209887)
			(xy 135.131058 -287.262591) (xy 135.131556 -287.28924) (xy 135.131058 -287.315889) (xy 135.359384 -287.315889)
			(xy 135.359384 -287.262591) (xy 135.367327 -287.209887) (xy 135.383037 -287.158957) (xy 135.406163 -287.110936)
			(xy 135.436187 -287.066899) (xy 135.472439 -287.027828) (xy 135.51411 -286.994597) (xy 135.560268 -286.967948)
			(xy 135.609882 -286.948476) (xy 135.661844 -286.936616) (xy 135.714994 -286.932633) (xy 135.768144 -286.936616)
			(xy 135.820106 -286.948476) (xy 135.86972 -286.967948) (xy 135.915878 -286.994597) (xy 135.957549 -287.027828)
			(xy 135.993801 -287.066899) (xy 136.023825 -287.110936) (xy 136.046951 -287.158957) (xy 136.062661 -287.209887)
			(xy 136.070604 -287.262591) (xy 136.071102 -287.28924) (xy 136.070604 -287.315889) (xy 136.062661 -287.368593)
			(xy 136.046951 -287.419523) (xy 136.023825 -287.467544) (xy 135.993801 -287.511581) (xy 135.957549 -287.550652)
			(xy 135.915878 -287.583883) (xy 135.86972 -287.610532) (xy 135.820106 -287.630004) (xy 135.768144 -287.641864)
			(xy 135.714994 -287.645848) (xy 135.661844 -287.641864) (xy 135.609882 -287.630004) (xy 135.560268 -287.610532)
			(xy 135.51411 -287.583883) (xy 135.472439 -287.550652) (xy 135.436187 -287.511581) (xy 135.406163 -287.467544)
			(xy 135.383037 -287.419523) (xy 135.367327 -287.368593) (xy 135.359384 -287.315889) (xy 135.131058 -287.315889)
			(xy 135.123115 -287.368593) (xy 135.107405 -287.419523) (xy 135.084279 -287.467544) (xy 135.054255 -287.511581)
			(xy 135.018003 -287.550652) (xy 134.976332 -287.583883) (xy 134.930174 -287.610532) (xy 134.88056 -287.630004)
			(xy 134.828598 -287.641864) (xy 134.775448 -287.645848) (xy 134.722298 -287.641864) (xy 134.670336 -287.630004)
			(xy 134.620722 -287.610532) (xy 134.574564 -287.583883) (xy 134.532893 -287.550652) (xy 134.496641 -287.511581)
			(xy 134.466617 -287.467544) (xy 134.443491 -287.419523) (xy 134.427781 -287.368593) (xy 134.419838 -287.315889)
			(xy 134.191258 -287.315889) (xy 134.183315 -287.368593) (xy 134.167605 -287.419523) (xy 134.144479 -287.467544)
			(xy 134.114455 -287.511581) (xy 134.078203 -287.550652) (xy 134.036532 -287.583883) (xy 133.990374 -287.610532)
			(xy 133.94076 -287.630004) (xy 133.888798 -287.641864) (xy 133.835648 -287.645848) (xy 133.782498 -287.641864)
			(xy 133.730536 -287.630004) (xy 133.680922 -287.610532) (xy 133.634764 -287.583883) (xy 133.593093 -287.550652)
			(xy 133.556841 -287.511581) (xy 133.526817 -287.467544) (xy 133.503691 -287.419523) (xy 133.487981 -287.368593)
			(xy 133.480038 -287.315889) (xy 133.251204 -287.315889) (xy 133.243261 -287.368593) (xy 133.227551 -287.419523)
			(xy 133.204425 -287.467544) (xy 133.174401 -287.511581) (xy 133.138149 -287.550652) (xy 133.096478 -287.583883)
			(xy 133.05032 -287.610532) (xy 133.000706 -287.630004) (xy 132.948744 -287.641864) (xy 132.895594 -287.645848)
			(xy 132.842444 -287.641864) (xy 132.790482 -287.630004) (xy 132.740868 -287.610532) (xy 132.69471 -287.583883)
			(xy 132.653039 -287.550652) (xy 132.616787 -287.511581) (xy 132.586763 -287.467544) (xy 132.563637 -287.419523)
			(xy 132.547927 -287.368593) (xy 132.539984 -287.315889) (xy 132.311404 -287.315889) (xy 132.303461 -287.368593)
			(xy 132.287751 -287.419523) (xy 132.264625 -287.467544) (xy 132.234601 -287.511581) (xy 132.198349 -287.550652)
			(xy 132.156678 -287.583883) (xy 132.11052 -287.610532) (xy 132.060906 -287.630004) (xy 132.008944 -287.641864)
			(xy 131.955794 -287.645848) (xy 131.902644 -287.641864) (xy 131.850682 -287.630004) (xy 131.801068 -287.610532)
			(xy 131.75491 -287.583883) (xy 131.713239 -287.550652) (xy 131.676987 -287.511581) (xy 131.646963 -287.467544)
			(xy 131.623837 -287.419523) (xy 131.608127 -287.368593) (xy 131.600184 -287.315889) (xy 131.371604 -287.315889)
			(xy 131.363661 -287.368593) (xy 131.347951 -287.419523) (xy 131.324825 -287.467544) (xy 131.294801 -287.511581)
			(xy 131.258549 -287.550652) (xy 131.216878 -287.583883) (xy 131.17072 -287.610532) (xy 131.121106 -287.630004)
			(xy 131.069144 -287.641864) (xy 131.015994 -287.645848) (xy 130.962844 -287.641864) (xy 130.910882 -287.630004)
			(xy 130.861268 -287.610532) (xy 130.81511 -287.583883) (xy 130.773439 -287.550652) (xy 130.737187 -287.511581)
			(xy 130.707163 -287.467544) (xy 130.684037 -287.419523) (xy 130.668327 -287.368593) (xy 130.660384 -287.315889)
			(xy 130.431804 -287.315889) (xy 130.423861 -287.368593) (xy 130.408151 -287.419523) (xy 130.385025 -287.467544)
			(xy 130.355001 -287.511581) (xy 130.318749 -287.550652) (xy 130.277078 -287.583883) (xy 130.23092 -287.610532)
			(xy 130.181306 -287.630004) (xy 130.129344 -287.641864) (xy 130.076194 -287.645848) (xy 130.023044 -287.641864)
			(xy 129.971082 -287.630004) (xy 129.921468 -287.610532) (xy 129.87531 -287.583883) (xy 129.833639 -287.550652)
			(xy 129.797387 -287.511581) (xy 129.767363 -287.467544) (xy 129.744237 -287.419523) (xy 129.728527 -287.368593)
			(xy 129.720584 -287.315889) (xy 129.492004 -287.315889) (xy 129.484061 -287.368593) (xy 129.468351 -287.419523)
			(xy 129.445225 -287.467544) (xy 129.415201 -287.511581) (xy 129.378949 -287.550652) (xy 129.337278 -287.583883)
			(xy 129.29112 -287.610532) (xy 129.241506 -287.630004) (xy 129.189544 -287.641864) (xy 129.136394 -287.645848)
			(xy 129.083244 -287.641864) (xy 129.031282 -287.630004) (xy 128.981668 -287.610532) (xy 128.93551 -287.583883)
			(xy 128.893839 -287.550652) (xy 128.857587 -287.511581) (xy 128.827563 -287.467544) (xy 128.804437 -287.419523)
			(xy 128.788727 -287.368593) (xy 128.780784 -287.315889) (xy 128.552204 -287.315889) (xy 128.544261 -287.368593)
			(xy 128.528551 -287.419523) (xy 128.505425 -287.467544) (xy 128.475401 -287.511581) (xy 128.439149 -287.550652)
			(xy 128.397478 -287.583883) (xy 128.35132 -287.610532) (xy 128.301706 -287.630004) (xy 128.249744 -287.641864)
			(xy 128.196594 -287.645848) (xy 128.143444 -287.641864) (xy 128.091482 -287.630004) (xy 128.041868 -287.610532)
			(xy 127.99571 -287.583883) (xy 127.954039 -287.550652) (xy 127.917787 -287.511581) (xy 127.887763 -287.467544)
			(xy 127.864637 -287.419523) (xy 127.848927 -287.368593) (xy 127.840984 -287.315889) (xy 127.612404 -287.315889)
			(xy 127.604461 -287.368593) (xy 127.588751 -287.419523) (xy 127.565625 -287.467544) (xy 127.535601 -287.511581)
			(xy 127.499349 -287.550652) (xy 127.457678 -287.583883) (xy 127.41152 -287.610532) (xy 127.361906 -287.630004)
			(xy 127.309944 -287.641864) (xy 127.256794 -287.645848) (xy 127.203644 -287.641864) (xy 127.151682 -287.630004)
			(xy 127.102068 -287.610532) (xy 127.05591 -287.583883) (xy 127.014239 -287.550652) (xy 126.977987 -287.511581)
			(xy 126.947963 -287.467544) (xy 126.924837 -287.419523) (xy 126.909127 -287.368593) (xy 126.901184 -287.315889)
			(xy 126.672604 -287.315889) (xy 126.664661 -287.368593) (xy 126.648951 -287.419523) (xy 126.625825 -287.467544)
			(xy 126.595801 -287.511581) (xy 126.559549 -287.550652) (xy 126.517878 -287.583883) (xy 126.47172 -287.610532)
			(xy 126.422106 -287.630004) (xy 126.370144 -287.641864) (xy 126.316994 -287.645848) (xy 126.263844 -287.641864)
			(xy 126.211882 -287.630004) (xy 126.162268 -287.610532) (xy 126.11611 -287.583883) (xy 126.074439 -287.550652)
			(xy 126.038187 -287.511581) (xy 126.008163 -287.467544) (xy 125.985037 -287.419523) (xy 125.969327 -287.368593)
			(xy 125.961384 -287.315889) (xy 125.732804 -287.315889) (xy 125.724861 -287.368593) (xy 125.709151 -287.419523)
			(xy 125.686025 -287.467544) (xy 125.656001 -287.511581) (xy 125.619749 -287.550652) (xy 125.578078 -287.583883)
			(xy 125.53192 -287.610532) (xy 125.482306 -287.630004) (xy 125.430344 -287.641864) (xy 125.377194 -287.645848)
			(xy 125.324044 -287.641864) (xy 125.272082 -287.630004) (xy 125.222468 -287.610532) (xy 125.17631 -287.583883)
			(xy 125.134639 -287.550652) (xy 125.098387 -287.511581) (xy 125.068363 -287.467544) (xy 125.045237 -287.419523)
			(xy 125.029527 -287.368593) (xy 125.021584 -287.315889) (xy 124.793004 -287.315889) (xy 124.785061 -287.368593)
			(xy 124.769351 -287.419523) (xy 124.746225 -287.467544) (xy 124.716201 -287.511581) (xy 124.679949 -287.550652)
			(xy 124.638278 -287.583883) (xy 124.59212 -287.610532) (xy 124.542506 -287.630004) (xy 124.490544 -287.641864)
			(xy 124.437394 -287.645848) (xy 124.384244 -287.641864) (xy 124.332282 -287.630004) (xy 124.282668 -287.610532)
			(xy 124.23651 -287.583883) (xy 124.194839 -287.550652) (xy 124.158587 -287.511581) (xy 124.128563 -287.467544)
			(xy 124.105437 -287.419523) (xy 124.089727 -287.368593) (xy 124.081784 -287.315889) (xy 123.853204 -287.315889)
			(xy 123.845261 -287.368593) (xy 123.829551 -287.419523) (xy 123.806425 -287.467544) (xy 123.776401 -287.511581)
			(xy 123.740149 -287.550652) (xy 123.698478 -287.583883) (xy 123.65232 -287.610532) (xy 123.602706 -287.630004)
			(xy 123.550744 -287.641864) (xy 123.497594 -287.645848) (xy 123.444444 -287.641864) (xy 123.392482 -287.630004)
			(xy 123.342868 -287.610532) (xy 123.29671 -287.583883) (xy 123.255039 -287.550652) (xy 123.218787 -287.511581)
			(xy 123.188763 -287.467544) (xy 123.165637 -287.419523) (xy 123.149927 -287.368593) (xy 123.141984 -287.315889)
			(xy 122.913404 -287.315889) (xy 122.905461 -287.368593) (xy 122.889751 -287.419523) (xy 122.866625 -287.467544)
			(xy 122.836601 -287.511581) (xy 122.800349 -287.550652) (xy 122.758678 -287.583883) (xy 122.71252 -287.610532)
			(xy 122.662906 -287.630004) (xy 122.610944 -287.641864) (xy 122.557794 -287.645848) (xy 122.504644 -287.641864)
			(xy 122.452682 -287.630004) (xy 122.403068 -287.610532) (xy 122.35691 -287.583883) (xy 122.315239 -287.550652)
			(xy 122.278987 -287.511581) (xy 122.248963 -287.467544) (xy 122.225837 -287.419523) (xy 122.210127 -287.368593)
			(xy 122.202184 -287.315889) (xy 121.973604 -287.315889) (xy 121.965661 -287.368593) (xy 121.949951 -287.419523)
			(xy 121.926825 -287.467544) (xy 121.896801 -287.511581) (xy 121.860549 -287.550652) (xy 121.818878 -287.583883)
			(xy 121.77272 -287.610532) (xy 121.723106 -287.630004) (xy 121.671144 -287.641864) (xy 121.617994 -287.645848)
			(xy 121.564844 -287.641864) (xy 121.512882 -287.630004) (xy 121.463268 -287.610532) (xy 121.41711 -287.583883)
			(xy 121.375439 -287.550652) (xy 121.339187 -287.511581) (xy 121.309163 -287.467544) (xy 121.286037 -287.419523)
			(xy 121.270327 -287.368593) (xy 121.262384 -287.315889) (xy 121.033654 -287.315889) (xy 121.026778 -287.364219)
			(xy 121.01275 -287.412544) (xy 120.99206 -287.458414) (xy 120.96512 -287.500916) (xy 120.932468 -287.539203)
			(xy 120.913906 -287.556194) (xy 120.903877 -287.565717) (xy 120.888879 -287.58894) (xy 120.88065 -287.615331)
			(xy 120.879789 -287.642962) (xy 120.886361 -287.669814) (xy 120.899885 -287.693925) (xy 120.909334 -287.704022)
			(xy 120.988328 -287.783016) (xy 121.019316 -287.771078) (xy 121.050375 -287.759809) (xy 121.115315 -287.74767)
			(xy 121.148348 -287.746948) (xy 121.17633 -287.747501) (xy 121.231604 -287.756261) (xy 121.284827 -287.773559)
			(xy 121.33469 -287.798969) (xy 121.379965 -287.831866) (xy 121.419537 -287.871438) (xy 121.452433 -287.916713)
			(xy 121.477842 -287.966576) (xy 121.49514 -288.0198) (xy 121.5039 -288.075074) (xy 121.504456 -288.103056)
			(xy 121.50376 -288.136091) (xy 121.491617 -288.201034) (xy 121.480326 -288.232088) (xy 121.468388 -288.263076)
			(xy 121.96318 -288.757868)
		)
		(stroke
			(width 0)
			(type solid)
		)
		(fill yes)
		(layer "In15.Cu")
		(net "PVCCFA_EHV_FIVRA_CPU1")
	)
	(gr_poly
		(pts
			(xy 347.55836 -371.25275) (xy 347.573153 -371.252239) (xy 347.601496 -371.243749) (xy 347.62622 -371.227498)
			(xy 347.645254 -371.204847) (xy 347.657004 -371.177694) (xy 347.660486 -371.148313) (xy 347.655408 -371.119165)
			(xy 347.649292 -371.105684) (xy 347.636563 -371.079051) (xy 347.618574 -371.022832) (xy 347.609479 -370.96451)
			(xy 347.608906 -370.934996) (xy 347.609397 -370.906931) (xy 347.617612 -370.851405) (xy 347.633879 -370.797684)
			(xy 347.657846 -370.746928) (xy 347.688994 -370.700234) (xy 347.726652 -370.658611) (xy 347.770006 -370.622959)
			(xy 347.793818 -370.608098) (xy 347.799406 -370.604796) (xy 347.86951 -370.534438) (xy 347.814138 -370.478812)
			(xy 347.791219 -370.48426) (xy 347.744475 -370.49012) (xy 347.72092 -370.490496) (xy 347.693667 -370.490034)
			(xy 347.639714 -370.482279) (xy 347.587415 -370.466925) (xy 347.537833 -370.444283) (xy 347.491978 -370.414816)
			(xy 347.450784 -370.379122) (xy 347.415089 -370.337929) (xy 347.38562 -370.292074) (xy 347.362978 -370.242493)
			(xy 347.347622 -370.190194) (xy 347.339867 -370.136241) (xy 347.339412 -370.108988) (xy 347.339904 -370.080923)
			(xy 347.34812 -370.025398) (xy 347.364388 -369.971678) (xy 347.388355 -369.920923) (xy 347.419505 -369.87423)
			(xy 347.457163 -369.832609) (xy 347.500517 -369.796958) (xy 347.524324 -369.78209) (xy 347.529912 -369.778788)
			(xy 348.840552 -368.467894) (xy 348.840552 -363.129322) (xy 347.183202 -361.471718) (xy 347.163102 -361.450858)
			(xy 347.129051 -361.403995) (xy 347.102751 -361.352382) (xy 347.084848 -361.297291) (xy 347.075784 -361.240078)
			(xy 347.075252 -361.211114) (xy 347.075252 -360.583988) (xy 347.073728 -360.577892) (xy 347.068408 -360.555213)
			(xy 347.062682 -360.508982) (xy 347.062298 -360.48569) (xy 347.062784 -360.458439) (xy 347.070542 -360.404493)
			(xy 347.085898 -360.3522) (xy 347.10854 -360.302624) (xy 347.138007 -360.256776) (xy 347.173698 -360.215587)
			(xy 347.214888 -360.179897) (xy 347.260738 -360.150432) (xy 347.310315 -360.127793) (xy 347.362609 -360.112439)
			(xy 347.416555 -360.104683) (xy 347.443806 -360.104182) (xy 347.471057 -360.104668) (xy 347.525005 -360.112425)
			(xy 347.577299 -360.127781) (xy 347.626877 -360.150422) (xy 347.672727 -360.179889) (xy 347.713917 -360.21558)
			(xy 347.742623 -360.248708) (xy 352.035362 -360.248708) (xy 352.039433 -360.193086) (xy 352.051559 -360.138649)
			(xy 352.071482 -360.086558) (xy 352.098778 -360.037923) (xy 352.132864 -359.99378) (xy 352.173013 -359.955071)
			(xy 352.218371 -359.92262) (xy 352.267971 -359.897119) (xy 352.320755 -359.879112) (xy 352.375598 -359.868982)
			(xy 352.431332 -359.866945) (xy 352.486769 -359.873045) (xy 352.540726 -359.887151) (xy 352.592055 -359.908963)
			(xy 352.639661 -359.938017) (xy 352.682529 -359.973692) (xy 352.719746 -360.015229) (xy 352.750519 -360.061742)
			(xy 352.774191 -360.112239) (xy 352.786745 -360.153966) (xy 366.16843 -360.153966) (xy 366.172501 -360.098344)
			(xy 366.184627 -360.043907) (xy 366.20455 -359.991816) (xy 366.231846 -359.943181) (xy 366.265932 -359.899038)
			(xy 366.306081 -359.860329) (xy 366.351439 -359.827878) (xy 366.401039 -359.802377) (xy 366.453823 -359.78437)
			(xy 366.508666 -359.77424) (xy 366.5644 -359.772203) (xy 366.619837 -359.778303) (xy 366.673794 -359.792409)
			(xy 366.725123 -359.814221) (xy 366.772729 -359.843275) (xy 366.815597 -359.87895) (xy 366.852814 -359.920487)
			(xy 366.883587 -359.967) (xy 366.907259 -360.017497) (xy 366.923327 -360.070904) (xy 366.931447 -360.12608)
			(xy 366.931956 -360.153966) (xy 366.931447 -360.181852) (xy 366.923327 -360.237028) (xy 366.907259 -360.290435)
			(xy 366.883587 -360.340932) (xy 366.852814 -360.387445) (xy 366.815597 -360.428982) (xy 366.772729 -360.464657)
			(xy 366.725123 -360.493711) (xy 366.673794 -360.515523) (xy 366.619837 -360.529629) (xy 366.5644 -360.535729)
			(xy 366.508666 -360.533692) (xy 366.453823 -360.523562) (xy 366.401039 -360.505555) (xy 366.351439 -360.480054)
			(xy 366.306081 -360.447603) (xy 366.265932 -360.408894) (xy 366.231846 -360.364751) (xy 366.20455 -360.316116)
			(xy 366.184627 -360.264025) (xy 366.172501 -360.209588) (xy 366.16843 -360.153966) (xy 352.786745 -360.153966)
			(xy 352.790259 -360.165646) (xy 352.798379 -360.220822) (xy 352.798888 -360.248708) (xy 352.798379 -360.276594)
			(xy 352.790259 -360.33177) (xy 352.774191 -360.385177) (xy 352.750519 -360.435674) (xy 352.719746 -360.482187)
			(xy 352.682529 -360.523724) (xy 352.639661 -360.559399) (xy 352.592055 -360.588453) (xy 352.540726 -360.610265)
			(xy 352.536308 -360.61142) (xy 360.771438 -360.61142) (xy 360.775509 -360.555798) (xy 360.787635 -360.501361)
			(xy 360.807558 -360.44927) (xy 360.834854 -360.400635) (xy 360.86894 -360.356492) (xy 360.909089 -360.317783)
			(xy 360.954447 -360.285332) (xy 361.004047 -360.259831) (xy 361.056831 -360.241824) (xy 361.111674 -360.231694)
			(xy 361.167408 -360.229657) (xy 361.222845 -360.235757) (xy 361.276802 -360.249863) (xy 361.328131 -360.271675)
			(xy 361.375737 -360.300729) (xy 361.418605 -360.336404) (xy 361.455822 -360.377941) (xy 361.486595 -360.424454)
			(xy 361.510267 -360.474951) (xy 361.526335 -360.528358) (xy 361.534455 -360.583534) (xy 361.534964 -360.61142)
			(xy 361.534455 -360.639306) (xy 361.528391 -360.680508) (xy 376.90628 -360.680508) (xy 376.910351 -360.624886)
			(xy 376.922477 -360.570449) (xy 376.9424 -360.518358) (xy 376.969696 -360.469723) (xy 377.003782 -360.42558)
			(xy 377.043931 -360.386871) (xy 377.089289 -360.35442) (xy 377.138889 -360.328919) (xy 377.191673 -360.310912)
			(xy 377.246516 -360.300782) (xy 377.30225 -360.298745) (xy 377.357687 -360.304845) (xy 377.411644 -360.318951)
			(xy 377.462973 -360.340763) (xy 377.510579 -360.369817) (xy 377.553447 -360.405492) (xy 377.590664 -360.447029)
			(xy 377.621437 -360.493542) (xy 377.645109 -360.544039) (xy 377.661177 -360.597446) (xy 377.669297 -360.652622)
			(xy 377.669806 -360.680508) (xy 377.669297 -360.708394) (xy 377.661177 -360.76357) (xy 377.645109 -360.816977)
			(xy 377.621437 -360.867474) (xy 377.590664 -360.913987) (xy 377.553447 -360.955524) (xy 377.510579 -360.991199)
			(xy 377.462973 -361.020253) (xy 377.411644 -361.042065) (xy 377.357687 -361.056171) (xy 377.30225 -361.062271)
			(xy 377.246516 -361.060234) (xy 377.191673 -361.050104) (xy 377.138889 -361.032097) (xy 377.089289 -361.006596)
			(xy 377.043931 -360.974145) (xy 377.003782 -360.935436) (xy 376.969696 -360.891293) (xy 376.9424 -360.842658)
			(xy 376.922477 -360.790567) (xy 376.910351 -360.73613) (xy 376.90628 -360.680508) (xy 361.528391 -360.680508)
			(xy 361.526335 -360.694482) (xy 361.510267 -360.747889) (xy 361.486595 -360.798386) (xy 361.455822 -360.844899)
			(xy 361.418605 -360.886436) (xy 361.375737 -360.922111) (xy 361.328131 -360.951165) (xy 361.276802 -360.972977)
			(xy 361.222845 -360.987083) (xy 361.167408 -360.993183) (xy 361.111674 -360.991146) (xy 361.056831 -360.981016)
			(xy 361.004047 -360.963009) (xy 360.954447 -360.937508) (xy 360.909089 -360.905057) (xy 360.86894 -360.866348)
			(xy 360.834854 -360.822205) (xy 360.807558 -360.77357) (xy 360.787635 -360.721479) (xy 360.775509 -360.667042)
			(xy 360.771438 -360.61142) (xy 352.536308 -360.61142) (xy 352.486769 -360.624371) (xy 352.431332 -360.630471)
			(xy 352.375598 -360.628434) (xy 352.320755 -360.618304) (xy 352.267971 -360.600297) (xy 352.218371 -360.574796)
			(xy 352.173013 -360.542345) (xy 352.132864 -360.503636) (xy 352.098778 -360.459493) (xy 352.071482 -360.410858)
			(xy 352.051559 -360.358767) (xy 352.039433 -360.30433) (xy 352.035362 -360.248708) (xy 347.742623 -360.248708)
			(xy 347.749609 -360.25677) (xy 347.779076 -360.30262) (xy 347.801718 -360.352197) (xy 347.817074 -360.404491)
			(xy 347.824832 -360.458439) (xy 347.825314 -360.48569) (xy 347.824937 -360.508982) (xy 347.819211 -360.555214)
			(xy 347.813884 -360.577892) (xy 347.81236 -360.583988) (xy 347.81236 -360.728514) (xy 347.812857 -360.743247)
			(xy 347.821274 -360.771484) (xy 347.837404 -360.796142) (xy 347.859902 -360.815169) (xy 347.886897 -360.826979)
			(xy 347.91614 -360.830589) (xy 347.945197 -360.825699) (xy 347.958664 -360.8197) (xy 347.984901 -360.807469)
			(xy 348.040144 -360.790179) (xy 348.097362 -360.781411) (xy 348.126304 -360.780838) (xy 348.126558 -360.780838)
			(xy 348.153812 -360.781299) (xy 348.207765 -360.789051) (xy 348.260065 -360.804404) (xy 348.309647 -360.827044)
			(xy 348.355502 -360.856512) (xy 348.396696 -360.892206) (xy 348.43239 -360.933401) (xy 348.461857 -360.979256)
			(xy 348.484498 -361.028839) (xy 348.49985 -361.081139) (xy 348.507321 -361.133136) (xy 369.3861 -361.133136)
			(xy 369.390189 -361.077254) (xy 369.402372 -361.022564) (xy 369.422388 -360.97023) (xy 369.449811 -360.921368)
			(xy 369.484056 -360.87702) (xy 369.524392 -360.83813) (xy 369.569962 -360.805528) (xy 369.619793 -360.779909)
			(xy 369.672823 -360.761817) (xy 369.727921 -360.75164) (xy 369.783915 -360.749594) (xy 369.83961 -360.755722)
			(xy 369.893819 -360.769894) (xy 369.945387 -360.791808) (xy 369.993215 -360.820997) (xy 370.036283 -360.856838)
			(xy 370.073673 -360.898568) (xy 370.104589 -360.945298) (xy 370.128372 -360.996031) (xy 370.144514 -361.049687)
			(xy 370.152673 -361.105121) (xy 370.153184 -361.133136) (xy 370.152673 -361.161151) (xy 370.144514 -361.216585)
			(xy 370.128372 -361.270241) (xy 370.104589 -361.320974) (xy 370.073673 -361.367704) (xy 370.036283 -361.409434)
			(xy 369.993215 -361.445275) (xy 369.945387 -361.474464) (xy 369.893819 -361.496378) (xy 369.83961 -361.51055)
			(xy 369.783915 -361.516678) (xy 369.727921 -361.514632) (xy 369.672823 -361.504455) (xy 369.619793 -361.486363)
			(xy 369.569962 -361.460744) (xy 369.524392 -361.428142) (xy 369.484056 -361.389252) (xy 369.449811 -361.344904)
			(xy 369.422388 -361.296042) (xy 369.402372 -361.243708) (xy 369.390189 -361.189018) (xy 369.3861 -361.133136)
			(xy 348.507321 -361.133136) (xy 348.507602 -361.135092) (xy 348.508066 -361.162346) (xy 348.507571 -361.190418)
			(xy 348.499348 -361.245957) (xy 348.48307 -361.29969) (xy 348.45909 -361.350456) (xy 348.427926 -361.397157)
			(xy 348.390252 -361.438785) (xy 348.368874 -361.456986) (xy 348.358242 -361.466334) (xy 348.342161 -361.489621)
			(xy 348.333082 -361.516425) (xy 348.3317 -361.544691) (xy 348.338122 -361.572252) (xy 348.351856 -361.596996)
			(xy 348.361508 -361.607354) (xy 349.235014 -362.48086) (xy 349.245996 -362.491093) (xy 349.272454 -362.505239)
			(xy 349.301879 -362.511094) (xy 349.331736 -362.508155) (xy 349.359454 -362.496673) (xy 349.382645 -362.477638)
			(xy 349.39931 -362.452691) (xy 349.408014 -362.423979) (xy 349.408496 -362.408978) (xy 349.408496 -362.051854)
			(xy 349.406972 -362.045758) (xy 349.401649 -362.023079) (xy 349.395916 -361.976848) (xy 349.395542 -361.953556)
			(xy 349.396008 -361.926306) (xy 349.403771 -361.872363) (xy 349.419131 -361.820073) (xy 349.441777 -361.770502)
			(xy 349.471247 -361.724658) (xy 349.506941 -361.683475) (xy 349.548133 -361.64779) (xy 349.593984 -361.618332)
			(xy 349.643561 -361.595698) (xy 349.695855 -361.580351) (xy 349.7498 -361.572602) (xy 349.77705 -361.572048)
			(xy 349.804306 -361.572507) (xy 349.858265 -361.580258) (xy 349.910572 -361.59561) (xy 349.960161 -361.618249)
			(xy 350.006023 -361.647715) (xy 350.047226 -361.683408) (xy 350.082929 -361.724601) (xy 350.112406 -361.770457)
			(xy 350.135057 -361.82004) (xy 350.150422 -361.872343) (xy 350.158186 -361.9263) (xy 350.158544 -361.95254)
			(xy 350.409256 -361.95254) (xy 350.409256 -361.952032) (xy 350.409742 -361.924781) (xy 350.417498 -361.870833)
			(xy 350.432853 -361.818538) (xy 350.455495 -361.768961) (xy 350.484961 -361.723111) (xy 350.520652 -361.68192)
			(xy 350.561843 -361.646229) (xy 350.607693 -361.616763) (xy 350.65727 -361.594121) (xy 350.709565 -361.578766)
			(xy 350.763513 -361.57101) (xy 350.818015 -361.57101) (xy 350.871963 -361.578766) (xy 350.924258 -361.594121)
			(xy 350.973835 -361.616763) (xy 351.019685 -361.646229) (xy 351.060124 -361.681268) (xy 352.721162 -361.681268)
			(xy 352.725233 -361.625646) (xy 352.737359 -361.571209) (xy 352.757282 -361.519118) (xy 352.784578 -361.470483)
			(xy 352.818664 -361.42634) (xy 352.858813 -361.387631) (xy 352.904171 -361.35518) (xy 352.953771 -361.329679)
			(xy 353.006555 -361.311672) (xy 353.061398 -361.301542) (xy 353.117132 -361.299505) (xy 353.172569 -361.305605)
			(xy 353.226526 -361.319711) (xy 353.277855 -361.341523) (xy 353.325461 -361.370577) (xy 353.368329 -361.406252)
			(xy 353.405546 -361.447789) (xy 353.436319 -361.494302) (xy 353.459905 -361.544616) (xy 360.295696 -361.544616)
			(xy 360.299767 -361.488994) (xy 360.311893 -361.434557) (xy 360.331816 -361.382466) (xy 360.359112 -361.333831)
			(xy 360.393198 -361.289688) (xy 360.433347 -361.250979) (xy 360.478705 -361.218528) (xy 360.528305 -361.193027)
			(xy 360.581089 -361.17502) (xy 360.635932 -361.16489) (xy 360.691666 -361.162853) (xy 360.747103 -361.168953)
			(xy 360.80106 -361.183059) (xy 360.852389 -361.204871) (xy 360.899995 -361.233925) (xy 360.942863 -361.2696)
			(xy 360.98008 -361.311137) (xy 361.010853 -361.35765) (xy 361.034525 -361.408147) (xy 361.050593 -361.461554)
			(xy 361.058713 -361.51673) (xy 361.059222 -361.544616) (xy 361.058713 -361.572502) (xy 361.050593 -361.627678)
			(xy 361.034525 -361.681085) (xy 361.010853 -361.731582) (xy 360.98008 -361.778095) (xy 360.942863 -361.819632)
			(xy 360.899995 -361.855307) (xy 360.852389 -361.884361) (xy 360.80106 -361.906173) (xy 360.747103 -361.920279)
			(xy 360.691666 -361.926379) (xy 360.635932 -361.924342) (xy 360.581089 -361.914212) (xy 360.528305 -361.896205)
			(xy 360.478705 -361.870704) (xy 360.433347 -361.838253) (xy 360.393198 -361.799544) (xy 360.359112 -361.755401)
			(xy 360.331816 -361.706766) (xy 360.311893 -361.654675) (xy 360.299767 -361.600238) (xy 360.295696 -361.544616)
			(xy 353.459905 -361.544616) (xy 353.459991 -361.544799) (xy 353.476059 -361.598206) (xy 353.484179 -361.653382)
			(xy 353.484688 -361.681268) (xy 353.484179 -361.709154) (xy 353.476059 -361.76433) (xy 353.459991 -361.817737)
			(xy 353.436319 -361.868234) (xy 353.405546 -361.914747) (xy 353.368329 -361.956284) (xy 353.325461 -361.991959)
			(xy 353.277855 -362.021013) (xy 353.226526 -362.042825) (xy 353.172569 -362.056931) (xy 353.117132 -362.063031)
			(xy 353.061398 -362.060994) (xy 353.006555 -362.050864) (xy 352.953771 -362.032857) (xy 352.904171 -362.007356)
			(xy 352.858813 -361.974905) (xy 352.818664 -361.936196) (xy 352.784578 -361.892053) (xy 352.757282 -361.843418)
			(xy 352.737359 -361.791327) (xy 352.725233 -361.73689) (xy 352.721162 -361.681268) (xy 351.060124 -361.681268)
			(xy 351.060876 -361.68192) (xy 351.096567 -361.723111) (xy 351.126033 -361.768961) (xy 351.148675 -361.818538)
			(xy 351.16403 -361.870833) (xy 351.171786 -361.924781) (xy 351.172272 -361.952032) (xy 351.171834 -361.978171)
			(xy 351.164617 -362.029949) (xy 351.150393 -362.080256) (xy 351.129427 -362.128147) (xy 351.116138 -362.15066)
			(xy 351.108772 -362.162852) (xy 351.108772 -362.25861) (xy 351.185734 -362.301028) (xy 351.210118 -362.28782)
			(xy 351.238077 -362.273455) (xy 351.297542 -362.253097) (xy 351.35954 -362.242759) (xy 351.390966 -362.2421)
			(xy 351.418221 -362.242545) (xy 351.472177 -362.250298) (xy 351.52448 -362.265652) (xy 351.574065 -362.288293)
			(xy 351.619924 -362.31776) (xy 351.65338 -362.346748) (xy 353.600002 -362.346748) (xy 353.604073 -362.291126)
			(xy 353.616199 -362.236689) (xy 353.636122 -362.184598) (xy 353.663418 -362.135963) (xy 353.697504 -362.09182)
			(xy 353.737653 -362.053111) (xy 353.783011 -362.02066) (xy 353.832611 -361.995159) (xy 353.885395 -361.977152)
			(xy 353.940238 -361.967022) (xy 353.995972 -361.964985) (xy 354.051409 -361.971085) (xy 354.105366 -361.985191)
			(xy 354.156695 -362.007003) (xy 354.204301 -362.036057) (xy 354.247169 -362.071732) (xy 354.284386 -362.113269)
			(xy 354.315159 -362.159782) (xy 354.338831 -362.210279) (xy 354.354899 -362.263686) (xy 354.363019 -362.318862)
			(xy 354.363528 -362.346748) (xy 354.363019 -362.374634) (xy 354.354899 -362.42981) (xy 354.354824 -362.43006)
			(xy 358.973626 -362.43006) (xy 358.977697 -362.374438) (xy 358.989823 -362.320001) (xy 359.009746 -362.26791)
			(xy 359.037042 -362.219275) (xy 359.071128 -362.175132) (xy 359.111277 -362.136423) (xy 359.156635 -362.103972)
			(xy 359.206235 -362.078471) (xy 359.259019 -362.060464) (xy 359.313862 -362.050334) (xy 359.369596 -362.048297)
			(xy 359.425033 -362.054397) (xy 359.47899 -362.068503) (xy 359.530319 -362.090315) (xy 359.541381 -362.097066)
			(xy 376.025154 -362.097066) (xy 376.029225 -362.041444) (xy 376.041351 -361.987007) (xy 376.061274 -361.934916)
			(xy 376.08857 -361.886281) (xy 376.122656 -361.842138) (xy 376.162805 -361.803429) (xy 376.208163 -361.770978)
			(xy 376.257763 -361.745477) (xy 376.310547 -361.72747) (xy 376.36539 -361.71734) (xy 376.421124 -361.715303)
			(xy 376.476561 -361.721403) (xy 376.52724 -361.734652) (xy 382.553685 -361.734652) (xy 382.553685 -361.680148)
			(xy 382.561442 -361.6262) (xy 382.576798 -361.573905) (xy 382.59944 -361.524328) (xy 382.628907 -361.478477)
			(xy 382.6646 -361.437287) (xy 382.705792 -361.401596) (xy 382.751643 -361.372131) (xy 382.801222 -361.349492)
			(xy 382.853518 -361.334138) (xy 382.907466 -361.326384) (xy 382.934718 -361.325922) (xy 382.96148 -361.326343)
			(xy 383.014474 -361.333852) (xy 383.0659 -361.348693) (xy 383.114747 -361.370573) (xy 383.160058 -361.399065)
			(xy 383.200943 -361.433608) (xy 383.2366 -361.473525) (xy 383.26633 -361.518033) (xy 383.289549 -361.566259)
			(xy 383.305801 -361.617256) (xy 383.314768 -361.670023) (xy 383.315972 -361.696762) (xy 383.316841 -361.712162)
			(xy 383.3268 -361.741345) (xy 383.345005 -361.766232) (xy 383.369801 -361.784562) (xy 383.398933 -361.794667)
			(xy 383.429753 -361.79563) (xy 383.44475 -361.792012) (xy 383.469775 -361.785504) (xy 383.521005 -361.778492)
			(xy 383.546858 -361.778042) (xy 383.574112 -361.778495) (xy 383.628066 -361.786247) (xy 383.680367 -361.8016)
			(xy 383.72995 -361.824242) (xy 383.775806 -361.85371) (xy 383.817001 -361.889405) (xy 383.852695 -361.9306)
			(xy 383.882162 -361.976457) (xy 383.904802 -362.02604) (xy 383.920155 -362.078342) (xy 383.927906 -362.132296)
			(xy 383.928366 -362.15955) (xy 383.928112 -362.176568) (xy 383.927909 -362.191398) (xy 383.935129 -362.220154)
			(xy 383.950314 -362.245619) (xy 383.97218 -362.265641) (xy 383.998881 -362.278529) (xy 384.02816 -362.283195)
			(xy 384.04292 -362.281724) (xy 384.055371 -362.280175) (xy 384.080411 -362.278523) (xy 384.092958 -362.278422)
			(xy 384.120211 -362.278894) (xy 384.174163 -362.286646) (xy 384.226463 -362.301999) (xy 384.276045 -362.324639)
			(xy 384.3219 -362.354105) (xy 384.363094 -362.389798) (xy 384.398788 -362.430991) (xy 384.428256 -362.476845)
			(xy 384.450897 -362.526426) (xy 384.466251 -362.578725) (xy 384.474005 -362.632677) (xy 384.474466 -362.65993)
			(xy 384.474274 -362.676528) (xy 384.471345 -362.709595) (xy 384.468624 -362.72597) (xy 384.466495 -362.741477)
			(xy 384.470727 -362.772475) (xy 384.484126 -362.800745) (xy 384.505442 -362.823645) (xy 384.532681 -362.839034)
			(xy 384.547872 -362.84281) (xy 384.576032 -362.849306) (xy 384.630114 -362.869669) (xy 384.680507 -362.897954)
			(xy 384.726059 -362.933515) (xy 384.765729 -362.975538) (xy 384.798607 -363.023062) (xy 384.823944 -363.075)
			(xy 384.84116 -363.130165) (xy 384.84986 -363.187295) (xy 384.850386 -363.21619) (xy 384.850207 -363.233753)
			(xy 384.84703 -363.268734) (xy 384.844036 -363.28604) (xy 384.841779 -363.301008) (xy 384.845177 -363.331074)
			(xy 384.857239 -363.358822) (xy 384.876904 -363.381817) (xy 384.902446 -363.398037) (xy 384.93162 -363.406059)
			(xy 384.961864 -363.405177) (xy 384.97637 -363.400848) (xy 385.005916 -363.391507) (xy 385.067055 -363.381427)
			(xy 385.098036 -363.380782) (xy 385.098798 -363.380782) (xy 385.126051 -363.381253) (xy 385.180003 -363.38901)
			(xy 385.232301 -363.404366) (xy 385.281882 -363.427009) (xy 385.327736 -363.456477) (xy 385.368929 -363.492171)
			(xy 385.404623 -363.533364) (xy 385.434091 -363.579218) (xy 385.456734 -363.628799) (xy 385.47209 -363.681097)
			(xy 385.479847 -363.735049) (xy 385.479847 -363.789555) (xy 385.472089 -363.843507) (xy 385.456733 -363.895805)
			(xy 385.434089 -363.945386) (xy 385.404621 -363.991239) (xy 385.368926 -364.032432) (xy 385.327733 -364.068125)
			(xy 385.281879 -364.097593) (xy 385.232298 -364.120235) (xy 385.179999 -364.135591) (xy 385.126047 -364.143347)
			(xy 385.071541 -364.143346) (xy 385.017589 -364.135588) (xy 384.965291 -364.120231) (xy 384.915711 -364.097587)
			(xy 384.869858 -364.068118) (xy 384.828665 -364.032423) (xy 384.792972 -363.991229) (xy 384.763505 -363.945375)
			(xy 384.740863 -363.895794) (xy 384.725508 -363.843495) (xy 384.717753 -363.789543) (xy 384.71729 -363.76229)
			(xy 384.717465 -363.744727) (xy 384.720645 -363.709746) (xy 384.72364 -363.69244) (xy 384.725817 -363.677466)
			(xy 384.722415 -363.647418) (xy 384.71036 -363.619686) (xy 384.690709 -363.596702) (xy 384.665187 -363.580483)
			(xy 384.636034 -363.572453) (xy 384.605807 -363.573315) (xy 384.591306 -363.577632) (xy 384.561761 -363.586978)
			(xy 384.500621 -363.597055) (xy 384.46964 -363.597698) (xy 384.468878 -363.597698) (xy 384.441626 -363.597243)
			(xy 384.387676 -363.589483) (xy 384.33538 -363.574124) (xy 384.285803 -363.55148) (xy 384.239952 -363.522011)
			(xy 384.198762 -363.486316) (xy 384.16307 -363.445123) (xy 384.133605 -363.399269) (xy 384.110964 -363.349689)
			(xy 384.09561 -363.297392) (xy 384.087855 -363.243442) (xy 384.08737 -363.21619) (xy 384.087564 -363.199592)
			(xy 384.090491 -363.166525) (xy 384.093212 -363.15015) (xy 384.095292 -363.134639) (xy 384.091067 -363.103649)
			(xy 384.077678 -363.075384) (xy 384.056375 -363.052484) (xy 384.029149 -363.037091) (xy 384.013964 -363.03331)
			(xy 383.985798 -363.026841) (xy 383.931718 -363.00647) (xy 383.881327 -362.978179) (xy 383.835777 -362.942614)
			(xy 383.79611 -362.900588) (xy 383.763232 -362.853061) (xy 383.737895 -362.801122) (xy 383.720679 -362.745956)
			(xy 383.711977 -362.688825) (xy 383.71145 -362.65993) (xy 383.711704 -362.642912) (xy 383.711907 -362.628082)
			(xy 383.704683 -362.599329) (xy 383.689497 -362.573866) (xy 383.667631 -362.553845) (xy 383.640933 -362.540956)
			(xy 383.611655 -362.536288) (xy 383.596896 -362.537756) (xy 383.584444 -362.539304) (xy 383.559405 -362.540956)
			(xy 383.546858 -362.541058) (xy 383.520097 -362.540586) (xy 383.467103 -362.533086) (xy 383.415678 -362.518254)
			(xy 383.36683 -362.496381) (xy 383.321518 -362.467896) (xy 383.280631 -362.433357) (xy 383.244973 -362.393444)
			(xy 383.215243 -362.348939) (xy 383.192024 -362.300716) (xy 383.175772 -362.249721) (xy 383.166806 -362.196956)
			(xy 383.165604 -362.170218) (xy 383.164656 -362.154828) (xy 383.154702 -362.125661) (xy 383.13651 -362.100785)
			(xy 383.111733 -362.082457) (xy 383.08262 -362.072344) (xy 383.051817 -362.071363) (xy 383.036826 -362.074968)
			(xy 383.011802 -362.08148) (xy 382.960572 -362.08849) (xy 382.934718 -362.088938) (xy 382.907466 -362.088416)
			(xy 382.853518 -362.080662) (xy 382.801222 -362.065308) (xy 382.751643 -362.042669) (xy 382.705792 -362.013204)
			(xy 382.6646 -361.977513) (xy 382.628907 -361.936323) (xy 382.59944 -361.890472) (xy 382.576798 -361.840895)
			(xy 382.561442 -361.7886) (xy 382.553685 -361.734652) (xy 376.52724 -361.734652) (xy 376.530518 -361.735509)
			(xy 376.581847 -361.757321) (xy 376.629453 -361.786375) (xy 376.672321 -361.82205) (xy 376.709538 -361.863587)
			(xy 376.740311 -361.9101) (xy 376.763983 -361.960597) (xy 376.780051 -362.014004) (xy 376.788171 -362.06918)
			(xy 376.78868 -362.097066) (xy 376.788171 -362.124952) (xy 376.780051 -362.180128) (xy 376.763983 -362.233535)
			(xy 376.740311 -362.284032) (xy 376.709538 -362.330545) (xy 376.672321 -362.372082) (xy 376.629453 -362.407757)
			(xy 376.581847 -362.436811) (xy 376.530518 -362.458623) (xy 376.476561 -362.472729) (xy 376.421124 -362.478829)
			(xy 376.36539 -362.476792) (xy 376.310547 -362.466662) (xy 376.257763 -362.448655) (xy 376.208163 -362.423154)
			(xy 376.162805 -362.390703) (xy 376.122656 -362.351994) (xy 376.08857 -362.307851) (xy 376.061274 -362.259216)
			(xy 376.041351 -362.207125) (xy 376.029225 -362.152688) (xy 376.025154 -362.097066) (xy 359.541381 -362.097066)
			(xy 359.577925 -362.119369) (xy 359.620793 -362.155044) (xy 359.65801 -362.196581) (xy 359.688783 -362.243094)
			(xy 359.712455 -362.293591) (xy 359.728523 -362.346998) (xy 359.736643 -362.402174) (xy 359.737152 -362.43006)
			(xy 359.736643 -362.457946) (xy 359.728523 -362.513122) (xy 359.712455 -362.566529) (xy 359.688783 -362.617026)
			(xy 359.65801 -362.663539) (xy 359.620793 -362.705076) (xy 359.577925 -362.740751) (xy 359.530319 -362.769805)
			(xy 359.47899 -362.791617) (xy 359.425033 -362.805723) (xy 359.369596 -362.811823) (xy 359.313862 -362.809786)
			(xy 359.259019 -362.799656) (xy 359.206235 -362.781649) (xy 359.156635 -362.756148) (xy 359.111277 -362.723697)
			(xy 359.071128 -362.684988) (xy 359.037042 -362.640845) (xy 359.009746 -362.59221) (xy 358.989823 -362.540119)
			(xy 358.977697 -362.485682) (xy 358.973626 -362.43006) (xy 354.354824 -362.43006) (xy 354.338831 -362.483217)
			(xy 354.315159 -362.533714) (xy 354.284386 -362.580227) (xy 354.247169 -362.621764) (xy 354.204301 -362.657439)
			(xy 354.156695 -362.686493) (xy 354.105366 -362.708305) (xy 354.051409 -362.722411) (xy 353.995972 -362.728511)
			(xy 353.940238 -362.726474) (xy 353.885395 -362.716344) (xy 353.832611 -362.698337) (xy 353.783011 -362.672836)
			(xy 353.737653 -362.640385) (xy 353.697504 -362.601676) (xy 353.663418 -362.557533) (xy 353.636122 -362.508898)
			(xy 353.616199 -362.456807) (xy 353.604073 -362.40237) (xy 353.600002 -362.346748) (xy 351.65338 -362.346748)
			(xy 351.661121 -362.353455) (xy 351.696819 -362.394649) (xy 351.726291 -362.440505) (xy 351.748936 -362.490088)
			(xy 351.764295 -362.54239) (xy 351.772053 -362.596345) (xy 351.772053 -362.650855) (xy 351.764295 -362.70481)
			(xy 351.748936 -362.757112) (xy 351.726291 -362.806695) (xy 351.696819 -362.852551) (xy 351.661121 -362.893745)
			(xy 351.619924 -362.92944) (xy 351.574065 -362.958907) (xy 351.52448 -362.981548) (xy 351.472177 -362.996902)
			(xy 351.418221 -363.004655) (xy 351.390966 -363.005116) (xy 351.366574 -363.004726) (xy 351.318187 -362.998517)
			(xy 351.270985 -362.986192) (xy 351.248218 -362.97743) (xy 351.234875 -362.972553) (xy 351.20663 -362.969616)
			(xy 351.178669 -362.974576) (xy 351.153158 -362.987048) (xy 351.132071 -363.006068) (xy 351.117042 -363.030162)
			(xy 351.109234 -363.057465) (xy 351.108772 -363.071664) (xy 351.108772 -363.354366) (xy 351.392236 -363.63783)
			(xy 352.31146 -363.63783) (xy 352.315531 -363.582208) (xy 352.327657 -363.527771) (xy 352.34758 -363.47568)
			(xy 352.374876 -363.427045) (xy 352.408962 -363.382902) (xy 352.449111 -363.344193) (xy 352.494469 -363.311742)
			(xy 352.544069 -363.286241) (xy 352.596853 -363.268234) (xy 352.651696 -363.258104) (xy 352.70743 -363.256067)
			(xy 352.762867 -363.262167) (xy 352.816824 -363.276273) (xy 352.820083 -363.277658) (xy 354.17836 -363.277658)
			(xy 354.182431 -363.222036) (xy 354.194557 -363.167599) (xy 354.21448 -363.115508) (xy 354.241776 -363.066873)
			(xy 354.275862 -363.02273) (xy 354.316011 -362.984021) (xy 354.361369 -362.95157) (xy 354.410969 -362.926069)
			(xy 354.463753 -362.908062) (xy 354.518596 -362.897932) (xy 354.57433 -362.895895) (xy 354.629767 -362.901995)
			(xy 354.683724 -362.916101) (xy 354.735053 -362.937913) (xy 354.782659 -362.966967) (xy 354.825527 -363.002642)
			(xy 354.862744 -363.044179) (xy 354.893517 -363.090692) (xy 354.917189 -363.141189) (xy 354.933257 -363.194596)
			(xy 354.941377 -363.249772) (xy 354.941886 -363.277658) (xy 354.941377 -363.305544) (xy 354.933257 -363.36072)
			(xy 354.92875 -363.375702) (xy 357.676702 -363.375702) (xy 357.680773 -363.32008) (xy 357.692899 -363.265643)
			(xy 357.712822 -363.213552) (xy 357.740118 -363.164917) (xy 357.774204 -363.120774) (xy 357.814353 -363.082065)
			(xy 357.859711 -363.049614) (xy 357.909311 -363.024113) (xy 357.962095 -363.006106) (xy 358.016938 -362.995976)
			(xy 358.072672 -362.993939) (xy 358.128109 -363.000039) (xy 358.182066 -363.014145) (xy 358.233395 -363.035957)
			(xy 358.281001 -363.065011) (xy 358.323869 -363.100686) (xy 358.361086 -363.142223) (xy 358.391859 -363.188736)
			(xy 358.415531 -363.239233) (xy 358.431599 -363.29264) (xy 358.436422 -363.32541) (xy 360.662218 -363.32541)
			(xy 360.666291 -363.269751) (xy 360.678426 -363.215278) (xy 360.698362 -363.163152) (xy 360.725676 -363.114484)
			(xy 360.759784 -363.070312) (xy 360.799961 -363.031577) (xy 360.845349 -362.999105) (xy 360.894981 -362.973587)
			(xy 360.947801 -362.955568) (xy 361.00268 -362.945431) (xy 361.058451 -362.943393) (xy 361.113925 -362.949496)
			(xy 361.167918 -362.963612) (xy 361.219281 -362.985439) (xy 361.266919 -363.014512) (xy 361.27211 -363.018832)
			(xy 363.790482 -363.018832) (xy 363.794553 -362.96321) (xy 363.806679 -362.908773) (xy 363.826602 -362.856682)
			(xy 363.853898 -362.808047) (xy 363.887984 -362.763904) (xy 363.928133 -362.725195) (xy 363.973491 -362.692744)
			(xy 364.023091 -362.667243) (xy 364.075875 -362.649236) (xy 364.130718 -362.639106) (xy 364.186452 -362.637069)
			(xy 364.241889 -362.643169) (xy 364.295846 -362.657275) (xy 364.347175 -362.679087) (xy 364.394781 -362.708141)
			(xy 364.437649 -362.743816) (xy 364.474866 -362.785353) (xy 364.505639 -362.831866) (xy 364.529311 -362.882363)
			(xy 364.545379 -362.93577) (xy 364.553499 -362.990946) (xy 364.554008 -363.018832) (xy 364.553499 -363.046718)
			(xy 364.545379 -363.101894) (xy 364.529311 -363.155301) (xy 364.505639 -363.205798) (xy 364.474866 -363.252311)
			(xy 364.437649 -363.293848) (xy 364.394781 -363.329523) (xy 364.347175 -363.358577) (xy 364.295846 -363.380389)
			(xy 364.241889 -363.394495) (xy 364.186452 -363.400595) (xy 364.130718 -363.398558) (xy 364.075875 -363.388428)
			(xy 364.023091 -363.370421) (xy 363.973491 -363.34492) (xy 363.928133 -363.312469) (xy 363.887984 -363.27376)
			(xy 363.853898 -363.229617) (xy 363.826602 -363.180982) (xy 363.806679 -363.128891) (xy 363.794553 -363.074454)
			(xy 363.790482 -363.018832) (xy 361.27211 -363.018832) (xy 361.309815 -363.050211) (xy 361.347057 -363.091775)
			(xy 361.377851 -363.138319) (xy 361.401539 -363.18885) (xy 361.417617 -363.242292) (xy 361.425743 -363.297506)
			(xy 361.426252 -363.32541) (xy 361.425743 -363.353314) (xy 361.417617 -363.408528) (xy 361.401539 -363.46197)
			(xy 361.377851 -363.512501) (xy 361.347057 -363.559045) (xy 361.309815 -363.600609) (xy 361.266919 -363.636308)
			(xy 361.219281 -363.665381) (xy 361.167918 -363.687208) (xy 361.113925 -363.701324) (xy 361.058451 -363.707427)
			(xy 361.00268 -363.705389) (xy 360.947801 -363.695252) (xy 360.894981 -363.677233) (xy 360.845349 -363.651715)
			(xy 360.799961 -363.619243) (xy 360.759784 -363.580508) (xy 360.725676 -363.536336) (xy 360.698362 -363.487668)
			(xy 360.678426 -363.435542) (xy 360.666291 -363.381069) (xy 360.662218 -363.32541) (xy 358.436422 -363.32541)
			(xy 358.439719 -363.347816) (xy 358.440228 -363.375702) (xy 358.439719 -363.403588) (xy 358.431599 -363.458764)
			(xy 358.415531 -363.512171) (xy 358.391859 -363.562668) (xy 358.361086 -363.609181) (xy 358.323869 -363.650718)
			(xy 358.281001 -363.686393) (xy 358.233395 -363.715447) (xy 358.182066 -363.737259) (xy 358.128109 -363.751365)
			(xy 358.072672 -363.757465) (xy 358.016938 -363.755428) (xy 357.962095 -363.745298) (xy 357.909311 -363.727291)
			(xy 357.859711 -363.70179) (xy 357.814353 -363.669339) (xy 357.774204 -363.63063) (xy 357.740118 -363.586487)
			(xy 357.712822 -363.537852) (xy 357.692899 -363.485761) (xy 357.680773 -363.431324) (xy 357.676702 -363.375702)
			(xy 354.92875 -363.375702) (xy 354.917189 -363.414127) (xy 354.893517 -363.464624) (xy 354.862744 -363.511137)
			(xy 354.825527 -363.552674) (xy 354.782659 -363.588349) (xy 354.735053 -363.617403) (xy 354.683724 -363.639215)
			(xy 354.629767 -363.653321) (xy 354.57433 -363.659421) (xy 354.518596 -363.657384) (xy 354.463753 -363.647254)
			(xy 354.410969 -363.629247) (xy 354.361369 -363.603746) (xy 354.316011 -363.571295) (xy 354.275862 -363.532586)
			(xy 354.241776 -363.488443) (xy 354.21448 -363.439808) (xy 354.194557 -363.387717) (xy 354.182431 -363.33328)
			(xy 354.17836 -363.277658) (xy 352.820083 -363.277658) (xy 352.868153 -363.298085) (xy 352.915759 -363.327139)
			(xy 352.958627 -363.362814) (xy 352.995844 -363.404351) (xy 353.026617 -363.450864) (xy 353.050289 -363.501361)
			(xy 353.066357 -363.554768) (xy 353.074477 -363.609944) (xy 353.074986 -363.63783) (xy 353.074477 -363.665716)
			(xy 353.066357 -363.720892) (xy 353.050289 -363.774299) (xy 353.026617 -363.824796) (xy 352.995844 -363.871309)
			(xy 352.958627 -363.912846) (xy 352.915759 -363.948521) (xy 352.868153 -363.977575) (xy 352.816824 -363.999387)
			(xy 352.762867 -364.013493) (xy 352.70743 -364.019593) (xy 352.651696 -364.017556) (xy 352.596853 -364.007426)
			(xy 352.544069 -363.989419) (xy 352.494469 -363.963918) (xy 352.449111 -363.931467) (xy 352.408962 -363.892758)
			(xy 352.374876 -363.848615) (xy 352.34758 -363.79998) (xy 352.327657 -363.747889) (xy 352.315531 -363.693452)
			(xy 352.31146 -363.63783) (xy 351.392236 -363.63783) (xy 352.168206 -364.4138) (xy 354.060504 -364.4138)
			(xy 354.064575 -364.358178) (xy 354.076701 -364.303741) (xy 354.096624 -364.25165) (xy 354.12392 -364.203015)
			(xy 354.158006 -364.158872) (xy 354.198155 -364.120163) (xy 354.243513 -364.087712) (xy 354.293113 -364.062211)
			(xy 354.345897 -364.044204) (xy 354.40074 -364.034074) (xy 354.456474 -364.032037) (xy 354.511911 -364.038137)
			(xy 354.565868 -364.052243) (xy 354.617197 -364.074055) (xy 354.664803 -364.103109) (xy 354.707671 -364.138784)
			(xy 354.744888 -364.180321) (xy 354.775661 -364.226834) (xy 354.799333 -364.277331) (xy 354.815401 -364.330738)
			(xy 354.823521 -364.385914) (xy 354.823529 -364.386368) (xy 355.566216 -364.386368) (xy 355.570287 -364.330746)
			(xy 355.582413 -364.276309) (xy 355.602336 -364.224218) (xy 355.629632 -364.175583) (xy 355.663718 -364.13144)
			(xy 355.703867 -364.092731) (xy 355.749225 -364.06028) (xy 355.798825 -364.034779) (xy 355.851609 -364.016772)
			(xy 355.906452 -364.006642) (xy 355.962186 -364.004605) (xy 356.017623 -364.010705) (xy 356.07158 -364.024811)
			(xy 356.122909 -364.046623) (xy 356.170515 -364.075677) (xy 356.213383 -364.111352) (xy 356.2506 -364.152889)
			(xy 356.281373 -364.199402) (xy 356.305045 -364.249899) (xy 356.321113 -364.303306) (xy 356.329233 -364.358482)
			(xy 356.329742 -364.386368) (xy 356.32938 -364.40618) (xy 357.767634 -364.40618) (xy 357.771705 -364.350558)
			(xy 357.783831 -364.296121) (xy 357.803754 -364.24403) (xy 357.83105 -364.195395) (xy 357.865136 -364.151252)
			(xy 357.905285 -364.112543) (xy 357.950643 -364.080092) (xy 358.000243 -364.054591) (xy 358.053027 -364.036584)
			(xy 358.10787 -364.026454) (xy 358.163604 -364.024417) (xy 358.219041 -364.030517) (xy 358.272998 -364.044623)
			(xy 358.324327 -364.066435) (xy 358.371933 -364.095489) (xy 358.414801 -364.131164) (xy 358.452018 -364.172701)
			(xy 358.482791 -364.219214) (xy 358.484587 -364.223046) (xy 359.35107 -364.223046) (xy 359.355141 -364.167424)
			(xy 359.367267 -364.112987) (xy 359.38719 -364.060896) (xy 359.414486 -364.012261) (xy 359.448572 -363.968118)
			(xy 359.488721 -363.929409) (xy 359.534079 -363.896958) (xy 359.583679 -363.871457) (xy 359.636463 -363.85345)
			(xy 359.691306 -363.84332) (xy 359.74704 -363.841283) (xy 359.802477 -363.847383) (xy 359.856434 -363.861489)
			(xy 359.907763 -363.883301) (xy 359.955369 -363.912355) (xy 359.998237 -363.94803) (xy 360.035454 -363.989567)
			(xy 360.066227 -364.03608) (xy 360.089899 -364.086577) (xy 360.105967 -364.139984) (xy 360.114087 -364.19516)
			(xy 360.114596 -364.223046) (xy 360.114087 -364.250932) (xy 360.105967 -364.306108) (xy 360.089899 -364.359515)
			(xy 360.066227 -364.410012) (xy 360.035454 -364.456525) (xy 359.998237 -364.498062) (xy 359.955369 -364.533737)
			(xy 359.907763 -364.562791) (xy 359.856434 -364.584603) (xy 359.802477 -364.598709) (xy 359.74704 -364.604809)
			(xy 359.691306 -364.602772) (xy 359.636463 -364.592642) (xy 359.583679 -364.574635) (xy 359.534079 -364.549134)
			(xy 359.488721 -364.516683) (xy 359.448572 -364.477974) (xy 359.414486 -364.433831) (xy 359.38719 -364.385196)
			(xy 359.367267 -364.333105) (xy 359.355141 -364.278668) (xy 359.35107 -364.223046) (xy 358.484587 -364.223046)
			(xy 358.506463 -364.269711) (xy 358.522531 -364.323118) (xy 358.530651 -364.378294) (xy 358.53116 -364.40618)
			(xy 358.530651 -364.434066) (xy 358.522531 -364.489242) (xy 358.506463 -364.542649) (xy 358.482791 -364.593146)
			(xy 358.452018 -364.639659) (xy 358.414801 -364.681196) (xy 358.371933 -364.716871) (xy 358.324327 -364.745925)
			(xy 358.272998 -364.767737) (xy 358.219041 -364.781843) (xy 358.163604 -364.787943) (xy 358.10787 -364.785906)
			(xy 358.053027 -364.775776) (xy 358.000243 -364.757769) (xy 357.950643 -364.732268) (xy 357.905285 -364.699817)
			(xy 357.865136 -364.661108) (xy 357.83105 -364.616965) (xy 357.803754 -364.56833) (xy 357.783831 -364.516239)
			(xy 357.771705 -364.461802) (xy 357.767634 -364.40618) (xy 356.32938 -364.40618) (xy 356.329233 -364.414254)
			(xy 356.321113 -364.46943) (xy 356.305045 -364.522837) (xy 356.281373 -364.573334) (xy 356.2506 -364.619847)
			(xy 356.213383 -364.661384) (xy 356.170515 -364.697059) (xy 356.122909 -364.726113) (xy 356.07158 -364.747925)
			(xy 356.017623 -364.762031) (xy 355.962186 -364.768131) (xy 355.906452 -364.766094) (xy 355.851609 -364.755964)
			(xy 355.798825 -364.737957) (xy 355.749225 -364.712456) (xy 355.703867 -364.680005) (xy 355.663718 -364.641296)
			(xy 355.629632 -364.597153) (xy 355.602336 -364.548518) (xy 355.582413 -364.496427) (xy 355.570287 -364.44199)
			(xy 355.566216 -364.386368) (xy 354.823529 -364.386368) (xy 354.82403 -364.4138) (xy 354.823521 -364.441686)
			(xy 354.815401 -364.496862) (xy 354.799333 -364.550269) (xy 354.775661 -364.600766) (xy 354.744888 -364.647279)
			(xy 354.707671 -364.688816) (xy 354.664803 -364.724491) (xy 354.617197 -364.753545) (xy 354.565868 -364.775357)
			(xy 354.511911 -364.789463) (xy 354.456474 -364.795563) (xy 354.40074 -364.793526) (xy 354.345897 -364.783396)
			(xy 354.293113 -364.765389) (xy 354.243513 -364.739888) (xy 354.198155 -364.707437) (xy 354.158006 -364.668728)
			(xy 354.12392 -364.624585) (xy 354.096624 -364.57595) (xy 354.076701 -364.523859) (xy 354.064575 -364.469422)
			(xy 354.060504 -364.4138) (xy 352.168206 -364.4138) (xy 352.970846 -365.21644) (xy 354.854508 -365.21644)
			(xy 354.858579 -365.160818) (xy 354.870705 -365.106381) (xy 354.890628 -365.05429) (xy 354.917924 -365.005655)
			(xy 354.95201 -364.961512) (xy 354.992159 -364.922803) (xy 355.037517 -364.890352) (xy 355.087117 -364.864851)
			(xy 355.139901 -364.846844) (xy 355.194744 -364.836714) (xy 355.250478 -364.834677) (xy 355.305915 -364.840777)
			(xy 355.359872 -364.854883) (xy 355.411201 -364.876695) (xy 355.458807 -364.905749) (xy 355.50068 -364.940596)
			(xy 358.631742 -364.940596) (xy 358.635813 -364.884974) (xy 358.647939 -364.830537) (xy 358.667862 -364.778446)
			(xy 358.695158 -364.729811) (xy 358.729244 -364.685668) (xy 358.769393 -364.646959) (xy 358.814751 -364.614508)
			(xy 358.864351 -364.589007) (xy 358.917135 -364.571) (xy 358.971978 -364.56087) (xy 359.027712 -364.558833)
			(xy 359.083149 -364.564933) (xy 359.137106 -364.579039) (xy 359.188435 -364.600851) (xy 359.236041 -364.629905)
			(xy 359.278909 -364.66558) (xy 359.316126 -364.707117) (xy 359.329101 -364.726728) (xy 360.233466 -364.726728)
			(xy 360.237537 -364.671106) (xy 360.249663 -364.616669) (xy 360.269586 -364.564578) (xy 360.296882 -364.515943)
			(xy 360.330968 -364.4718) (xy 360.371117 -364.433091) (xy 360.416475 -364.40064) (xy 360.466075 -364.375139)
			(xy 360.518859 -364.357132) (xy 360.573702 -364.347002) (xy 360.629436 -364.344965) (xy 360.684873 -364.351065)
			(xy 360.73883 -364.365171) (xy 360.790159 -364.386983) (xy 360.837765 -364.416037) (xy 360.880633 -364.451712)
			(xy 360.91785 -364.493249) (xy 360.948623 -364.539762) (xy 360.972295 -364.590259) (xy 360.988363 -364.643666)
			(xy 360.996483 -364.698842) (xy 360.996992 -364.726728) (xy 360.996483 -364.754614) (xy 360.988363 -364.80979)
			(xy 360.972295 -364.863197) (xy 360.948623 -364.913694) (xy 360.91785 -364.960207) (xy 360.880633 -365.001744)
			(xy 360.837765 -365.037419) (xy 360.790159 -365.066473) (xy 360.73883 -365.088285) (xy 360.684873 -365.102391)
			(xy 360.629436 -365.108491) (xy 360.573702 -365.106454) (xy 360.518859 -365.096324) (xy 360.466075 -365.078317)
			(xy 360.416475 -365.052816) (xy 360.371117 -365.020365) (xy 360.330968 -364.981656) (xy 360.296882 -364.937513)
			(xy 360.269586 -364.888878) (xy 360.249663 -364.836787) (xy 360.237537 -364.78235) (xy 360.233466 -364.726728)
			(xy 359.329101 -364.726728) (xy 359.346899 -364.75363) (xy 359.370571 -364.804127) (xy 359.386639 -364.857534)
			(xy 359.394759 -364.91271) (xy 359.395268 -364.940596) (xy 359.394759 -364.968482) (xy 359.386639 -365.023658)
			(xy 359.370571 -365.077065) (xy 359.346899 -365.127562) (xy 359.316126 -365.174075) (xy 359.278909 -365.215612)
			(xy 359.236041 -365.251287) (xy 359.188435 -365.280341) (xy 359.137106 -365.302153) (xy 359.083149 -365.316259)
			(xy 359.027712 -365.322359) (xy 358.971978 -365.320322) (xy 358.917135 -365.310192) (xy 358.864351 -365.292185)
			(xy 358.814751 -365.266684) (xy 358.769393 -365.234233) (xy 358.729244 -365.195524) (xy 358.695158 -365.151381)
			(xy 358.667862 -365.102746) (xy 358.647939 -365.050655) (xy 358.635813 -364.996218) (xy 358.631742 -364.940596)
			(xy 355.50068 -364.940596) (xy 355.501675 -364.941424) (xy 355.538892 -364.982961) (xy 355.569665 -365.029474)
			(xy 355.593337 -365.079971) (xy 355.609405 -365.133378) (xy 355.617525 -365.188554) (xy 355.618034 -365.21644)
			(xy 355.617525 -365.244326) (xy 355.609405 -365.299502) (xy 355.593337 -365.352909) (xy 355.569665 -365.403406)
			(xy 355.538892 -365.449919) (xy 355.501675 -365.491456) (xy 355.458807 -365.527131) (xy 355.411201 -365.556185)
			(xy 355.359872 -365.577997) (xy 355.305915 -365.592103) (xy 355.250478 -365.598203) (xy 355.194744 -365.596166)
			(xy 355.139901 -365.586036) (xy 355.087117 -365.568029) (xy 355.037517 -365.542528) (xy 354.992159 -365.510077)
			(xy 354.95201 -365.471368) (xy 354.917924 -365.427225) (xy 354.890628 -365.37859) (xy 354.870705 -365.326499)
			(xy 354.858579 -365.272062) (xy 354.854508 -365.21644) (xy 352.970846 -365.21644) (xy 353.544124 -365.789718)
			(xy 357.87914 -365.789718) (xy 357.883211 -365.734096) (xy 357.895337 -365.679659) (xy 357.91526 -365.627568)
			(xy 357.942556 -365.578933) (xy 357.976642 -365.53479) (xy 358.016791 -365.496081) (xy 358.062149 -365.46363)
			(xy 358.111749 -365.438129) (xy 358.164533 -365.420122) (xy 358.219376 -365.409992) (xy 358.27511 -365.407955)
			(xy 358.330547 -365.414055) (xy 358.384504 -365.428161) (xy 358.435833 -365.449973) (xy 358.483439 -365.479027)
			(xy 358.526307 -365.514702) (xy 358.563524 -365.556239) (xy 358.594297 -365.602752) (xy 358.617969 -365.653249)
			(xy 358.634037 -365.706656) (xy 358.642157 -365.761832) (xy 358.642666 -365.789718) (xy 358.642157 -365.817604)
			(xy 358.634037 -365.87278) (xy 358.617969 -365.926187) (xy 358.594297 -365.976684) (xy 358.563524 -366.023197)
			(xy 358.526307 -366.064734) (xy 358.483439 -366.100409) (xy 358.435833 -366.129463) (xy 358.384504 -366.151275)
			(xy 358.330547 -366.165381) (xy 358.27511 -366.171481) (xy 358.219376 -366.169444) (xy 358.164533 -366.159314)
			(xy 358.111749 -366.141307) (xy 358.062149 -366.115806) (xy 358.016791 -366.083355) (xy 357.976642 -366.044646)
			(xy 357.942556 -366.000503) (xy 357.91526 -365.951868) (xy 357.895337 -365.899777) (xy 357.883211 -365.84534)
			(xy 357.87914 -365.789718) (xy 353.544124 -365.789718) (xy 355.144578 -367.390172) (xy 355.322124 -367.390172)
			(xy 355.336902 -367.389645) (xy 355.365196 -367.381093) (xy 355.389857 -367.364799) (xy 355.408823 -367.342127)
			(xy 355.420504 -367.314975) (xy 355.423923 -367.285615) (xy 355.418795 -367.256505) (xy 355.405548 -367.230082)
			(xy 355.395784 -367.218976) (xy 355.376299 -367.197602) (xy 355.343331 -367.150085) (xy 355.317921 -367.098132)
			(xy 355.300653 -367.042936) (xy 355.291922 -366.985765) (xy 355.29139 -366.956848) (xy 355.29139 -366.956594)
			(xy 355.291872 -366.929343) (xy 355.299629 -366.875395) (xy 355.314985 -366.8231) (xy 355.337627 -366.773523)
			(xy 355.367094 -366.727673) (xy 355.402786 -366.686483) (xy 355.443976 -366.650791) (xy 355.489827 -366.621325)
			(xy 355.539404 -366.598684) (xy 355.591699 -366.583329) (xy 355.645647 -366.575572) (xy 355.672898 -366.575086)
			(xy 355.699276 -366.575567) (xy 355.751532 -366.582819) (xy 355.802291 -366.597199) (xy 355.850585 -366.618432)
			(xy 355.895495 -366.646115) (xy 355.936164 -366.679719) (xy 355.971818 -366.718604) (xy 356.001776 -366.762029)
			(xy 356.01402 -366.785398) (xy 356.020722 -366.797757) (xy 356.039697 -366.818485) (xy 356.063611 -366.833247)
			(xy 356.090647 -366.840919) (xy 356.118749 -366.840919) (xy 356.145785 -366.833247) (xy 356.169699 -366.818485)
			(xy 356.188674 -366.797757) (xy 356.195376 -366.785398) (xy 356.207619 -366.762028) (xy 356.23758 -366.718604)
			(xy 356.273235 -366.679718) (xy 356.313905 -366.646112) (xy 356.358813 -366.618425) (xy 356.407106 -366.597184)
			(xy 356.457864 -366.582795) (xy 356.510119 -366.575531) (xy 356.536498 -366.575086) (xy 356.563749 -366.57558)
			(xy 356.617696 -366.583336) (xy 356.66999 -366.59869) (xy 356.719567 -366.621331) (xy 356.765417 -366.650796)
			(xy 356.806607 -366.686487) (xy 356.842299 -366.727676) (xy 356.871765 -366.773526) (xy 356.894407 -366.823102)
			(xy 356.909763 -366.875396) (xy 356.91752 -366.929343) (xy 356.918006 -366.956594) (xy 356.918006 -366.956848)
			(xy 356.917457 -366.985762) (xy 356.908701 -367.042925) (xy 356.891427 -367.098114) (xy 356.86603 -367.150068)
			(xy 356.83309 -367.197599) (xy 356.813612 -367.218976) (xy 356.803802 -367.230048) (xy 356.790536 -367.256478)
			(xy 356.785398 -367.285601) (xy 356.788818 -367.314974) (xy 356.800509 -367.342138) (xy 356.819491 -367.364814)
			(xy 356.844173 -367.381102) (xy 356.872487 -367.389636) (xy 356.887272 -367.390172) (xy 359.42905 -367.390172)
			(xy 360.981752 -365.837724) (xy 361.32516 -365.494316) (xy 361.32516 -364.355634) (xy 361.55757 -364.123224)
			(xy 361.560872 -364.109254) (xy 361.567962 -364.08179) (xy 361.58915 -364.029177) (xy 361.617889 -363.980278)
			(xy 361.653547 -363.936169) (xy 361.695338 -363.897821) (xy 361.742344 -363.866078) (xy 361.793528 -363.84164)
			(xy 361.847765 -363.825044) (xy 361.90386 -363.816655) (xy 361.93222 -363.816138) (xy 361.95949 -363.816606)
			(xy 362.013474 -363.82437) (xy 362.065804 -363.839738) (xy 362.115414 -363.862397) (xy 362.15291 -363.886496)
			(xy 366.311686 -363.886496) (xy 366.315757 -363.830874) (xy 366.327883 -363.776437) (xy 366.347806 -363.724346)
			(xy 366.375102 -363.675711) (xy 366.409188 -363.631568) (xy 366.449337 -363.592859) (xy 366.494695 -363.560408)
			(xy 366.544295 -363.534907) (xy 366.597079 -363.5169) (xy 366.651922 -363.50677) (xy 366.707656 -363.504733)
			(xy 366.763093 -363.510833) (xy 366.81705 -363.524939) (xy 366.868379 -363.546751) (xy 366.915985 -363.575805)
			(xy 366.958853 -363.61148) (xy 366.99607 -363.653017) (xy 367.026843 -363.69953) (xy 367.050515 -363.750027)
			(xy 367.066583 -363.803434) (xy 367.074703 -363.85861) (xy 367.075212 -363.886496) (xy 367.074703 -363.914382)
			(xy 367.066583 -363.969558) (xy 367.050515 -364.022965) (xy 367.026843 -364.073462) (xy 366.99607 -364.119975)
			(xy 366.958853 -364.161512) (xy 366.915985 -364.197187) (xy 366.868379 -364.226241) (xy 366.81705 -364.248053)
			(xy 366.763093 -364.262159) (xy 366.707656 -364.268259) (xy 366.651922 -364.266222) (xy 366.597079 -364.256092)
			(xy 366.544295 -364.238085) (xy 366.494695 -364.212584) (xy 366.449337 -364.180133) (xy 366.409188 -364.141424)
			(xy 366.375102 -364.097281) (xy 366.347806 -364.048646) (xy 366.327883 -363.996555) (xy 366.315757 -363.942118)
			(xy 366.311686 -363.886496) (xy 362.15291 -363.886496) (xy 362.161295 -363.891885) (xy 362.202512 -363.927602)
			(xy 362.238227 -363.968821) (xy 362.267713 -364.014703) (xy 362.290369 -364.064315) (xy 362.305734 -364.116645)
			(xy 362.313496 -364.17063) (xy 362.313982 -364.1979) (xy 362.313469 -364.22626) (xy 362.305077 -364.282355)
			(xy 362.288479 -364.336591) (xy 362.26404 -364.387775) (xy 362.232297 -364.434779) (xy 362.19395 -364.476571)
			(xy 362.149841 -364.512229) (xy 362.100942 -364.540969) (xy 362.04833 -364.562158) (xy 362.020866 -364.569248)
			(xy 362.006896 -364.57255) (xy 361.960668 -364.618778) (xy 361.960668 -364.978696) (xy 365.31245 -364.978696)
			(xy 365.316521 -364.923074) (xy 365.328647 -364.868637) (xy 365.34857 -364.816546) (xy 365.375866 -364.767911)
			(xy 365.409952 -364.723768) (xy 365.450101 -364.685059) (xy 365.495459 -364.652608) (xy 365.545059 -364.627107)
			(xy 365.597843 -364.6091) (xy 365.652686 -364.59897) (xy 365.70842 -364.596933) (xy 365.763857 -364.603033)
			(xy 365.817814 -364.617139) (xy 365.869143 -364.638951) (xy 365.916749 -364.668005) (xy 365.959617 -364.70368)
			(xy 365.996834 -364.745217) (xy 366.027607 -364.79173) (xy 366.051279 -364.842227) (xy 366.067347 -364.895634)
			(xy 366.075467 -364.95081) (xy 366.075976 -364.978696) (xy 366.075467 -365.006582) (xy 366.067347 -365.061758)
			(xy 366.051279 -365.115165) (xy 366.027607 -365.165662) (xy 365.996834 -365.212175) (xy 365.959617 -365.253712)
			(xy 365.916749 -365.289387) (xy 365.869143 -365.318441) (xy 365.817814 -365.340253) (xy 365.763857 -365.354359)
			(xy 365.70842 -365.360459) (xy 365.652686 -365.358422) (xy 365.597843 -365.348292) (xy 365.545059 -365.330285)
			(xy 365.495459 -365.304784) (xy 365.450101 -365.272333) (xy 365.409952 -365.233624) (xy 365.375866 -365.189481)
			(xy 365.34857 -365.140846) (xy 365.328647 -365.088755) (xy 365.316521 -365.034318) (xy 365.31245 -364.978696)
			(xy 361.960668 -364.978696) (xy 361.960668 -365.64062) (xy 380.886211 -365.64062) (xy 380.890247 -365.557173)
			(xy 380.902319 -365.474505) (xy 380.922312 -365.393388) (xy 380.950041 -365.314579) (xy 380.985247 -365.238814)
			(xy 381.027601 -365.166801) (xy 381.076707 -365.099212) (xy 381.132108 -365.036678) (xy 381.193285 -364.979783)
			(xy 381.259668 -364.929057) (xy 381.330636 -364.884976) (xy 381.405528 -364.84795) (xy 381.483644 -364.818324)
			(xy 381.564254 -364.796376) (xy 381.646606 -364.782311) (xy 381.729932 -364.776259) (xy 381.813452 -364.778278)
			(xy 381.896388 -364.788348) (xy 381.977964 -364.806376) (xy 382.05742 -364.832193) (xy 382.134013 -364.865558)
			(xy 382.207029 -364.906159) (xy 382.275785 -364.953618) (xy 382.339639 -365.007491) (xy 382.397996 -365.067276)
			(xy 382.450311 -365.132413) (xy 382.496094 -365.202296) (xy 382.534919 -365.276271) (xy 382.566424 -365.353648)
			(xy 382.590313 -365.433705) (xy 382.606364 -365.515693) (xy 382.614427 -365.598848) (xy 382.614932 -365.64062)
			(xy 382.614427 -365.682392) (xy 382.606364 -365.765547) (xy 382.590313 -365.847535) (xy 382.566424 -365.927592)
			(xy 382.534919 -366.004969) (xy 382.496094 -366.078944) (xy 382.450311 -366.148827) (xy 382.397996 -366.213964)
			(xy 382.339639 -366.273749) (xy 382.275785 -366.327622) (xy 382.207029 -366.375081) (xy 382.134013 -366.415682)
			(xy 382.05742 -366.449047) (xy 381.977964 -366.474864) (xy 381.896388 -366.492892) (xy 381.813452 -366.502962)
			(xy 381.729932 -366.504981) (xy 381.646606 -366.498929) (xy 381.564254 -366.484864) (xy 381.483644 -366.462916)
			(xy 381.405528 -366.43329) (xy 381.330636 -366.396264) (xy 381.259668 -366.352183) (xy 381.193285 -366.301457)
			(xy 381.132108 -366.244562) (xy 381.076707 -366.182028) (xy 381.027601 -366.114439) (xy 380.985247 -366.042426)
			(xy 380.950041 -365.966661) (xy 380.922312 -365.887852) (xy 380.902319 -365.806735) (xy 380.890247 -365.724067)
			(xy 380.886211 -365.64062) (xy 361.960668 -365.64062) (xy 361.960668 -365.75746) (xy 361.874308 -365.84382)
			(xy 361.867704 -365.850678) (xy 359.94213 -367.776252) (xy 369.189506 -367.776252) (xy 369.193577 -367.72063)
			(xy 369.205703 -367.666193) (xy 369.225626 -367.614102) (xy 369.252922 -367.565467) (xy 369.287008 -367.521324)
			(xy 369.327157 -367.482615) (xy 369.372515 -367.450164) (xy 369.422115 -367.424663) (xy 369.474899 -367.406656)
			(xy 369.529742 -367.396526) (xy 369.585476 -367.394489) (xy 369.640913 -367.400589) (xy 369.69487 -367.414695)
			(xy 369.746199 -367.436507) (xy 369.793805 -367.465561) (xy 369.836673 -367.501236) (xy 369.87389 -367.542773)
			(xy 369.904663 -367.589286) (xy 369.928335 -367.639783) (xy 369.944403 -367.69319) (xy 369.952523 -367.748366)
			(xy 369.953032 -367.776252) (xy 369.952523 -367.804138) (xy 369.944403 -367.859314) (xy 369.928335 -367.912721)
			(xy 369.905269 -367.961926) (xy 370.232686 -367.961926) (xy 370.23319 -367.933008) (xy 370.241918 -367.875835)
			(xy 370.259176 -367.820634) (xy 370.28457 -367.768672) (xy 370.317518 -367.721139) (xy 370.357264 -367.679124)
			(xy 370.379752 -367.660936) (xy 370.391535 -367.651012) (xy 370.409059 -367.625697) (xy 370.418241 -367.59631)
			(xy 370.418245 -367.565522) (xy 370.409073 -367.536131) (xy 370.391557 -367.510811) (xy 370.379752 -367.500916)
			(xy 370.357266 -367.482728) (xy 370.317533 -367.440706) (xy 370.284596 -367.39317) (xy 370.259208 -367.341209)
			(xy 370.241952 -367.286011) (xy 370.233222 -367.228842) (xy 370.232686 -367.199926) (xy 370.233172 -367.172675)
			(xy 370.240928 -367.118727) (xy 370.256283 -367.066432) (xy 370.278925 -367.016855) (xy 370.308391 -366.971005)
			(xy 370.344082 -366.929814) (xy 370.385273 -366.894123) (xy 370.431123 -366.864657) (xy 370.4807 -366.842015)
			(xy 370.532995 -366.82666) (xy 370.586943 -366.818904) (xy 370.641445 -366.818904) (xy 370.695393 -366.82666)
			(xy 370.747688 -366.842015) (xy 370.797265 -366.864657) (xy 370.843115 -366.894123) (xy 370.884306 -366.929814)
			(xy 370.919997 -366.971005) (xy 370.949463 -367.016855) (xy 370.972105 -367.066432) (xy 370.98746 -367.118727)
			(xy 370.995216 -367.172675) (xy 370.995702 -367.199926) (xy 370.99513 -367.228841) (xy 370.986412 -367.28601)
			(xy 370.969165 -367.341207) (xy 370.943783 -367.393169) (xy 370.910849 -367.440705) (xy 370.871117 -367.482724)
			(xy 370.848636 -367.500916) (xy 370.836802 -367.510784) (xy 370.819281 -367.536114) (xy 370.810106 -367.565516)
			(xy 370.810111 -367.596316) (xy 370.819295 -367.625715) (xy 370.836825 -367.65104) (xy 370.848636 -367.660936)
			(xy 370.871144 -367.679098) (xy 370.910876 -367.721125) (xy 370.943811 -367.768666) (xy 370.969195 -367.820633)
			(xy 370.986446 -367.875835) (xy 370.99517 -367.933008) (xy 370.995702 -367.961926) (xy 372.38051 -367.961926)
			(xy 372.381043 -367.93301) (xy 372.389769 -367.875839) (xy 372.407023 -367.82064) (xy 372.432412 -367.768678)
			(xy 372.465353 -367.721144) (xy 372.505092 -367.679127) (xy 372.527576 -367.660936) (xy 372.539356 -367.651011)
			(xy 372.556876 -367.625695) (xy 372.566056 -367.596309) (xy 372.56606 -367.565523) (xy 372.55689 -367.536134)
			(xy 372.539378 -367.510813) (xy 372.527576 -367.500916) (xy 372.505095 -367.482722) (xy 372.465361 -367.440702)
			(xy 372.432422 -367.393168) (xy 372.407034 -367.341207) (xy 372.389777 -367.28601) (xy 372.381046 -367.228842)
			(xy 372.38051 -367.199926) (xy 372.380996 -367.172675) (xy 372.388752 -367.118727) (xy 372.404107 -367.066432)
			(xy 372.426749 -367.016855) (xy 372.456215 -366.971005) (xy 372.491906 -366.929814) (xy 372.533097 -366.894123)
			(xy 372.578947 -366.864657) (xy 372.628524 -366.842015) (xy 372.680819 -366.82666) (xy 372.734767 -366.818904)
			(xy 372.789269 -366.818904) (xy 372.843217 -366.82666) (xy 372.895512 -366.842015) (xy 372.945089 -366.864657)
			(xy 372.990939 -366.894123) (xy 373.03213 -366.929814) (xy 373.067821 -366.971005) (xy 373.097287 -367.016855)
			(xy 373.119929 -367.066432) (xy 373.135284 -367.118727) (xy 373.14304 -367.172675) (xy 373.143526 -367.199926)
			(xy 373.142982 -367.228842) (xy 373.134263 -367.286014) (xy 373.117011 -367.341213) (xy 373.091625 -367.393176)
			(xy 373.058684 -367.44071) (xy 373.018945 -367.482726) (xy 372.99646 -367.500916) (xy 372.984624 -367.510783)
			(xy 372.967099 -367.536112) (xy 372.957922 -367.565515) (xy 372.957926 -367.596317) (xy 372.967113 -367.625716)
			(xy 372.984647 -367.651041) (xy 372.99646 -367.660936) (xy 373.018952 -367.679117) (xy 373.058689 -367.721137)
			(xy 373.091628 -367.768674) (xy 373.117015 -367.820638) (xy 373.134269 -367.875838) (xy 373.142994 -367.933009)
			(xy 373.143526 -367.961926) (xy 374.51411 -367.961926) (xy 374.514643 -367.93301) (xy 374.523369 -367.875839)
			(xy 374.540623 -367.82064) (xy 374.566012 -367.768678) (xy 374.598953 -367.721144) (xy 374.638692 -367.679127)
			(xy 374.661176 -367.660936) (xy 374.672956 -367.651011) (xy 374.690476 -367.625695) (xy 374.699656 -367.596309)
			(xy 374.69966 -367.565523) (xy 374.69049 -367.536134) (xy 374.672978 -367.510813) (xy 374.661176 -367.500916)
			(xy 374.638695 -367.482722) (xy 374.598961 -367.440702) (xy 374.566022 -367.393168) (xy 374.540634 -367.341207)
			(xy 374.523377 -367.28601) (xy 374.514646 -367.228842) (xy 374.51411 -367.199926) (xy 374.514596 -367.172675)
			(xy 374.522352 -367.118727) (xy 374.537707 -367.066432) (xy 374.560349 -367.016855) (xy 374.589815 -366.971005)
			(xy 374.625506 -366.929814) (xy 374.666697 -366.894123) (xy 374.712547 -366.864657) (xy 374.762124 -366.842015)
			(xy 374.814419 -366.82666) (xy 374.868367 -366.818904) (xy 374.922869 -366.818904) (xy 374.976817 -366.82666)
			(xy 375.029112 -366.842015) (xy 375.078689 -366.864657) (xy 375.124539 -366.894123) (xy 375.16573 -366.929814)
			(xy 375.201421 -366.971005) (xy 375.230887 -367.016855) (xy 375.253529 -367.066432) (xy 375.268884 -367.118727)
			(xy 375.27664 -367.172675) (xy 375.277126 -367.199926) (xy 375.276582 -367.228842) (xy 375.267863 -367.286014)
			(xy 375.250611 -367.341213) (xy 375.225225 -367.393176) (xy 375.192284 -367.44071) (xy 375.152545 -367.482726)
			(xy 375.13006 -367.500916) (xy 375.118224 -367.510783) (xy 375.100699 -367.536112) (xy 375.091522 -367.565515)
			(xy 375.091526 -367.596317) (xy 375.100713 -367.625716) (xy 375.118247 -367.651041) (xy 375.13006 -367.660936)
			(xy 375.152552 -367.679117) (xy 375.192289 -367.721137) (xy 375.225228 -367.768674) (xy 375.250615 -367.820638)
			(xy 375.267869 -367.875838) (xy 375.276594 -367.933009) (xy 375.276603 -367.933478) (xy 376.66676 -367.933478)
			(xy 376.667312 -367.904562) (xy 376.676031 -367.847391) (xy 376.693281 -367.792192) (xy 376.718666 -367.74023)
			(xy 376.751605 -367.692695) (xy 376.791342 -367.650678) (xy 376.813826 -367.632488) (xy 376.825649 -367.622612)
			(xy 376.84316 -367.597281) (xy 376.852329 -367.567884) (xy 376.852325 -367.537089) (xy 376.843148 -367.507694)
			(xy 376.825631 -367.482368) (xy 376.813826 -367.472468) (xy 376.791333 -367.454288) (xy 376.751597 -367.412267)
			(xy 376.718658 -367.36473) (xy 376.693271 -367.312766) (xy 376.676018 -367.257566) (xy 376.667293 -367.200395)
			(xy 376.66676 -367.171478) (xy 376.667246 -367.144227) (xy 376.675002 -367.090279) (xy 376.690357 -367.037984)
			(xy 376.712999 -366.988407) (xy 376.742465 -366.942557) (xy 376.778156 -366.901366) (xy 376.819347 -366.865675)
			(xy 376.865197 -366.836209) (xy 376.914774 -366.813567) (xy 376.967069 -366.798212) (xy 377.021017 -366.790456)
			(xy 377.075519 -366.790456) (xy 377.129467 -366.798212) (xy 377.181762 -366.813567) (xy 377.231339 -366.836209)
			(xy 377.277189 -366.865675) (xy 377.31838 -366.901366) (xy 377.354071 -366.942557) (xy 377.383537 -366.988407)
			(xy 377.406179 -367.037984) (xy 377.421534 -367.090279) (xy 377.42929 -367.144227) (xy 377.429776 -367.171478)
			(xy 377.429251 -367.200395) (xy 377.420525 -367.257566) (xy 377.403269 -367.312765) (xy 377.377878 -367.364727)
			(xy 377.344935 -367.412261) (xy 377.305195 -367.454278) (xy 377.28271 -367.472468) (xy 377.270927 -367.48239)
			(xy 377.25341 -367.507707) (xy 377.244232 -367.537093) (xy 377.244228 -367.56788) (xy 377.253398 -367.597269)
			(xy 377.270909 -367.62259) (xy 377.28271 -367.632488) (xy 377.30519 -367.650683) (xy 377.344925 -367.692702)
			(xy 377.377864 -367.740237) (xy 377.403253 -367.792197) (xy 377.42051 -367.847394) (xy 377.42924 -367.904562)
			(xy 377.429776 -367.933478) (xy 377.42929 -367.960729) (xy 377.421534 -368.014677) (xy 377.406179 -368.066972)
			(xy 377.383537 -368.116549) (xy 377.354071 -368.162399) (xy 377.336143 -368.18309) (xy 380.86182 -368.18309)
			(xy 380.86182 -368.098394) (xy 380.869871 -368.01408) (xy 380.8859 -367.930914) (xy 380.909761 -367.849647)
			(xy 380.94124 -367.771017) (xy 380.980051 -367.695736) (xy 381.025841 -367.624484) (xy 381.078197 -367.557908)
			(xy 381.136645 -367.49661) (xy 381.200655 -367.441145) (xy 381.269647 -367.392016) (xy 381.342997 -367.349667)
			(xy 381.42004 -367.314483) (xy 381.500079 -367.286781) (xy 381.582388 -367.266813) (xy 381.666223 -367.25476)
			(xy 381.750824 -367.25073) (xy 381.835425 -367.25476) (xy 381.91926 -367.266813) (xy 382.001569 -367.286781)
			(xy 382.081608 -367.314483) (xy 382.158651 -367.349667) (xy 382.232001 -367.392016) (xy 382.300993 -367.441145)
			(xy 382.365003 -367.49661) (xy 382.423451 -367.557908) (xy 382.475807 -367.624484) (xy 382.521597 -367.695736)
			(xy 382.560408 -367.771017) (xy 382.591887 -367.849647) (xy 382.615748 -367.930914) (xy 382.631777 -368.01408)
			(xy 382.639828 -368.098394) (xy 382.640332 -368.140742) (xy 382.639828 -368.18309) (xy 382.631777 -368.267404)
			(xy 382.615748 -368.35057) (xy 382.591887 -368.431837) (xy 382.560408 -368.510467) (xy 382.521597 -368.585748)
			(xy 382.475807 -368.657) (xy 382.423451 -368.723576) (xy 382.365003 -368.784874) (xy 382.300993 -368.840339)
			(xy 382.232001 -368.889468) (xy 382.158651 -368.931817) (xy 382.081608 -368.967001) (xy 382.001569 -368.994703)
			(xy 381.91926 -369.014671) (xy 381.835425 -369.026724) (xy 381.750824 -369.030755) (xy 381.666223 -369.026724)
			(xy 381.582388 -369.014671) (xy 381.500079 -368.994703) (xy 381.42004 -368.967001) (xy 381.342997 -368.931817)
			(xy 381.269647 -368.889468) (xy 381.200655 -368.840339) (xy 381.136645 -368.784874) (xy 381.078197 -368.723576)
			(xy 381.025841 -368.657) (xy 380.980051 -368.585748) (xy 380.94124 -368.510467) (xy 380.909761 -368.431837)
			(xy 380.8859 -368.35057) (xy 380.869871 -368.267404) (xy 380.86182 -368.18309) (xy 377.336143 -368.18309)
			(xy 377.31838 -368.20359) (xy 377.277189 -368.239281) (xy 377.231339 -368.268747) (xy 377.181762 -368.291389)
			(xy 377.129467 -368.306744) (xy 377.075519 -368.3145) (xy 377.021017 -368.3145) (xy 376.967069 -368.306744)
			(xy 376.914774 -368.291389) (xy 376.865197 -368.268747) (xy 376.819347 -368.239281) (xy 376.778156 -368.20359)
			(xy 376.742465 -368.162399) (xy 376.712999 -368.116549) (xy 376.690357 -368.066972) (xy 376.675002 -368.014677)
			(xy 376.667246 -367.960729) (xy 376.66676 -367.933478) (xy 375.276603 -367.933478) (xy 375.277126 -367.961926)
			(xy 375.27664 -367.989177) (xy 375.268884 -368.043125) (xy 375.253529 -368.09542) (xy 375.230887 -368.144997)
			(xy 375.201421 -368.190847) (xy 375.16573 -368.232038) (xy 375.124539 -368.267729) (xy 375.078689 -368.297195)
			(xy 375.029112 -368.319837) (xy 374.976817 -368.335192) (xy 374.922869 -368.342948) (xy 374.868367 -368.342948)
			(xy 374.814419 -368.335192) (xy 374.762124 -368.319837) (xy 374.712547 -368.297195) (xy 374.666697 -368.267729)
			(xy 374.625506 -368.232038) (xy 374.589815 -368.190847) (xy 374.560349 -368.144997) (xy 374.537707 -368.09542)
			(xy 374.522352 -368.043125) (xy 374.514596 -367.989177) (xy 374.51411 -367.961926) (xy 373.143526 -367.961926)
			(xy 373.14304 -367.989177) (xy 373.135284 -368.043125) (xy 373.119929 -368.09542) (xy 373.097287 -368.144997)
			(xy 373.067821 -368.190847) (xy 373.03213 -368.232038) (xy 372.990939 -368.267729) (xy 372.945089 -368.297195)
			(xy 372.895512 -368.319837) (xy 372.843217 -368.335192) (xy 372.789269 -368.342948) (xy 372.734767 -368.342948)
			(xy 372.680819 -368.335192) (xy 372.628524 -368.319837) (xy 372.578947 -368.297195) (xy 372.533097 -368.267729)
			(xy 372.491906 -368.232038) (xy 372.456215 -368.190847) (xy 372.426749 -368.144997) (xy 372.404107 -368.09542)
			(xy 372.388752 -368.043125) (xy 372.380996 -367.989177) (xy 372.38051 -367.961926) (xy 370.995702 -367.961926)
			(xy 370.995216 -367.989177) (xy 370.98746 -368.043125) (xy 370.972105 -368.09542) (xy 370.949463 -368.144997)
			(xy 370.919997 -368.190847) (xy 370.884306 -368.232038) (xy 370.843115 -368.267729) (xy 370.797265 -368.297195)
			(xy 370.747688 -368.319837) (xy 370.695393 -368.335192) (xy 370.641445 -368.342948) (xy 370.586943 -368.342948)
			(xy 370.532995 -368.335192) (xy 370.4807 -368.319837) (xy 370.431123 -368.297195) (xy 370.385273 -368.267729)
			(xy 370.344082 -368.232038) (xy 370.308391 -368.190847) (xy 370.278925 -368.144997) (xy 370.256283 -368.09542)
			(xy 370.240928 -368.043125) (xy 370.233172 -367.989177) (xy 370.232686 -367.961926) (xy 369.905269 -367.961926)
			(xy 369.904663 -367.963218) (xy 369.87389 -368.009731) (xy 369.836673 -368.051268) (xy 369.793805 -368.086943)
			(xy 369.746199 -368.115997) (xy 369.69487 -368.137809) (xy 369.640913 -368.151915) (xy 369.585476 -368.158015)
			(xy 369.529742 -368.155978) (xy 369.474899 -368.145848) (xy 369.422115 -368.127841) (xy 369.372515 -368.10234)
			(xy 369.327157 -368.069889) (xy 369.287008 -368.03118) (xy 369.252922 -367.987037) (xy 369.225626 -367.938402)
			(xy 369.205703 -367.886311) (xy 369.193577 -367.831874) (xy 369.189506 -367.776252) (xy 359.94213 -367.776252)
			(xy 359.785412 -367.93297) (xy 359.778808 -367.93932) (xy 359.692194 -368.025934) (xy 359.572306 -368.025934)
			(xy 359.57129 -368.025934) (xy 359.560622 -368.026188) (xy 355.013006 -368.026188) (xy 355.002338 -368.025934)
			(xy 355.001322 -368.025934) (xy 354.881434 -368.025934) (xy 354.79482 -367.93932) (xy 354.788216 -367.93297)
			(xy 354.371656 -367.516156) (xy 354.277676 -367.422176) (xy 354.266907 -367.412578) (xy 354.241279 -367.399357)
			(xy 354.212979 -367.393821) (xy 354.184258 -367.396409) (xy 354.157403 -367.406915) (xy 354.134551 -367.424504)
			(xy 354.117522 -367.447776) (xy 354.107669 -367.474877) (xy 354.106226 -367.489232) (xy 354.103748 -367.517838)
			(xy 354.091369 -367.573903) (xy 354.070731 -367.627481) (xy 354.042301 -367.677363) (xy 354.006719 -367.722423)
			(xy 353.964788 -367.761645) (xy 353.917455 -367.794143) (xy 353.865788 -367.819184) (xy 353.810953 -367.836203)
			(xy 353.754188 -367.844816) (xy 353.72548 -367.84534) (xy 353.699102 -367.844863) (xy 353.646847 -367.837609)
			(xy 353.596089 -367.823227) (xy 353.547795 -367.801992) (xy 353.502885 -367.774309) (xy 353.462216 -367.740705)
			(xy 353.426562 -367.70182) (xy 353.396603 -367.658396) (xy 353.384358 -367.635028) (xy 353.377656 -367.622669)
			(xy 353.358681 -367.601941) (xy 353.334767 -367.587179) (xy 353.307731 -367.579507) (xy 353.279629 -367.579507)
			(xy 353.252593 -367.587179) (xy 353.228679 -367.601941) (xy 353.209704 -367.622669) (xy 353.203002 -367.635028)
			(xy 353.190787 -367.658413) (xy 353.160821 -367.701837) (xy 353.125161 -367.740721) (xy 353.084488 -367.774326)
			(xy 353.039575 -367.802011) (xy 352.991278 -367.823249) (xy 352.940518 -367.837635) (xy 352.88826 -367.844896)
			(xy 352.86188 -367.84534) (xy 352.834632 -367.844788) (xy 352.780691 -367.83703) (xy 352.728403 -367.821675)
			(xy 352.678833 -367.799034) (xy 352.632989 -367.76957) (xy 352.591804 -367.733882) (xy 352.556118 -367.692695)
			(xy 352.526656 -367.64685) (xy 352.504018 -367.597278) (xy 352.488665 -367.544989) (xy 352.48091 -367.491048)
			(xy 352.48091 -367.436552) (xy 352.488665 -367.382611) (xy 352.504018 -367.330322) (xy 352.526656 -367.28075)
			(xy 352.556118 -367.234905) (xy 352.591804 -367.193718) (xy 352.632989 -367.15803) (xy 352.678833 -367.128566)
			(xy 352.728403 -367.105925) (xy 352.780691 -367.09057) (xy 352.834632 -367.082812) (xy 352.86188 -367.082324)
			(xy 352.888261 -367.082716) (xy 352.940522 -367.08998) (xy 352.991284 -367.104372) (xy 353.03958 -367.125618)
			(xy 353.084489 -367.153313) (xy 353.125157 -367.18693) (xy 353.160807 -367.225826) (xy 353.190761 -367.269262)
			(xy 353.203002 -367.292636) (xy 353.209704 -367.304995) (xy 353.228679 -367.325723) (xy 353.252593 -367.340485)
			(xy 353.279629 -367.348157) (xy 353.307731 -367.348157) (xy 353.334767 -367.340485) (xy 353.358681 -367.325723)
			(xy 353.377656 -367.304995) (xy 353.384358 -367.292636) (xy 353.397567 -367.267563) (xy 353.430214 -367.221243)
			(xy 353.469348 -367.180256) (xy 353.51411 -367.145503) (xy 353.563516 -367.117746) (xy 353.616481 -367.097596)
			(xy 353.671843 -367.085494) (xy 353.70008 -367.083086) (xy 353.714442 -367.081642) (xy 353.741567 -367.071822)
			(xy 353.764863 -367.054805) (xy 353.782468 -367.031951) (xy 353.792978 -367.005085) (xy 353.795552 -366.976351)
			(xy 353.789985 -366.948045) (xy 353.776723 -366.922426) (xy 353.767136 -366.911636) (xy 350.565974 -363.710728)
			(xy 350.559624 -363.704124) (xy 350.47301 -363.61751) (xy 350.47301 -363.497622) (xy 350.47301 -363.496606)
			(xy 350.472756 -363.485938) (xy 350.472756 -362.163106) (xy 350.457782 -362.139561) (xy 350.434068 -362.089054)
			(xy 350.417956 -362.035634) (xy 350.409789 -361.980438) (xy 350.409256 -361.95254) (xy 350.158544 -361.95254)
			(xy 350.158558 -361.953556) (xy 350.158177 -361.976848) (xy 350.152444 -362.023078) (xy 350.147128 -362.045758)
			(xy 350.145604 -362.051854) (xy 350.145604 -369.14836) (xy 350.145068 -369.177324) (xy 350.136011 -369.23454)
			(xy 350.118113 -369.289635) (xy 350.091816 -369.34125) (xy 350.057767 -369.388115) (xy 350.037654 -369.408964)
			(xy 349.911689 -369.534948) (xy 364.036862 -369.534948) (xy 364.040933 -369.479326) (xy 364.053059 -369.424889)
			(xy 364.072982 -369.372798) (xy 364.100278 -369.324163) (xy 364.134364 -369.28002) (xy 364.174513 -369.241311)
			(xy 364.219871 -369.20886) (xy 364.269471 -369.183359) (xy 364.322255 -369.165352) (xy 364.377098 -369.155222)
			(xy 364.432832 -369.153185) (xy 364.488269 -369.159285) (xy 364.542226 -369.173391) (xy 364.593555 -369.195203)
			(xy 364.641161 -369.224257) (xy 364.684029 -369.259932) (xy 364.721246 -369.301469) (xy 364.752019 -369.347982)
			(xy 364.775691 -369.398479) (xy 364.791759 -369.451886) (xy 364.799879 -369.507062) (xy 364.800388 -369.534948)
			(xy 364.800249 -369.542568) (xy 365.489742 -369.542568) (xy 365.493813 -369.486946) (xy 365.505939 -369.432509)
			(xy 365.525862 -369.380418) (xy 365.553158 -369.331783) (xy 365.587244 -369.28764) (xy 365.627393 -369.248931)
			(xy 365.672751 -369.21648) (xy 365.722351 -369.190979) (xy 365.775135 -369.172972) (xy 365.829978 -369.162842)
			(xy 365.885712 -369.160805) (xy 365.941149 -369.166905) (xy 365.995106 -369.181011) (xy 366.046435 -369.202823)
			(xy 366.094041 -369.231877) (xy 366.136909 -369.267552) (xy 366.174126 -369.309089) (xy 366.204899 -369.355602)
			(xy 366.228571 -369.406099) (xy 366.244639 -369.459506) (xy 366.252759 -369.514682) (xy 366.253268 -369.542568)
			(xy 366.252759 -369.570454) (xy 366.244639 -369.62563) (xy 366.228571 -369.679037) (xy 366.204899 -369.729534)
			(xy 366.174126 -369.776047) (xy 366.136909 -369.817584) (xy 366.094041 -369.853259) (xy 366.046435 -369.882313)
			(xy 365.995106 -369.904125) (xy 365.941149 -369.918231) (xy 365.885712 -369.924331) (xy 365.829978 -369.922294)
			(xy 365.775135 -369.912164) (xy 365.722351 -369.894157) (xy 365.672751 -369.868656) (xy 365.627393 -369.836205)
			(xy 365.587244 -369.797496) (xy 365.553158 -369.753353) (xy 365.525862 -369.704718) (xy 365.505939 -369.652627)
			(xy 365.493813 -369.59819) (xy 365.489742 -369.542568) (xy 364.800249 -369.542568) (xy 364.799879 -369.562834)
			(xy 364.791759 -369.61801) (xy 364.775691 -369.671417) (xy 364.752019 -369.721914) (xy 364.721246 -369.768427)
			(xy 364.684029 -369.809964) (xy 364.641161 -369.845639) (xy 364.593555 -369.874693) (xy 364.542226 -369.896505)
			(xy 364.488269 -369.910611) (xy 364.432832 -369.916711) (xy 364.377098 -369.914674) (xy 364.322255 -369.904544)
			(xy 364.269471 -369.886537) (xy 364.219871 -369.861036) (xy 364.174513 -369.828585) (xy 364.134364 -369.789876)
			(xy 364.100278 -369.745733) (xy 364.072982 -369.697098) (xy 364.053059 -369.645007) (xy 364.040933 -369.59057)
			(xy 364.036862 -369.534948) (xy 349.911689 -369.534948) (xy 348.320614 -371.126258) (xy 348.317312 -371.131592)
			(xy 348.31401 -371.136672) (xy 348.295214 -371.164612) (xy 348.290388 -371.170962) (xy 348.276672 -371.210078)
			(xy 348.307152 -371.25275) (xy 381.173736 -371.25275) (xy 386.239004 -366.187482) (xy 389.146796 -355.133148)
			(xy 389.497316 -353.648518) (xy 390.515348 -349.635826) (xy 390.931654 -347.083888) (xy 390.931654 -334.330294)
			(xy 388.58444 -331.98308) (xy 382.212596 -331.98308) (xy 380.065534 -329.836018) (xy 380.065534 -329.766676)
			(xy 379.927104 -329.628246) (xy 375.21769 -329.628246) (xy 371.754654 -326.16521) (xy 343.774014 -326.16521)
			(xy 340.103206 -329.836018) (xy 335.393538 -329.836018) (xy 331.238098 -333.991458) (xy 320.987674 -333.991458)
			(xy 319.802764 -335.176368) (xy 340.981284 -335.176368) (xy 340.981711 -335.148996) (xy 340.989535 -335.094815)
			(xy 341.005032 -335.04231) (xy 341.027883 -334.992564) (xy 341.057618 -334.9466) (xy 341.075264 -334.92567)
			(xy 341.084535 -334.914367) (xy 341.096713 -334.887801) (xy 341.100881 -334.858876) (xy 341.096699 -334.829952)
			(xy 341.084508 -334.803392) (xy 341.075264 -334.792066) (xy 341.057637 -334.771124) (xy 341.027924 -334.725154)
			(xy 341.005087 -334.675409) (xy 340.989593 -334.62291) (xy 340.98176 -334.568736) (xy 340.981284 -334.541368)
			(xy 340.98177 -334.514117) (xy 340.989526 -334.460169) (xy 341.004881 -334.407874) (xy 341.027523 -334.358297)
			(xy 341.056989 -334.312447) (xy 341.09268 -334.271256) (xy 341.133871 -334.235565) (xy 341.179721 -334.206099)
			(xy 341.229298 -334.183457) (xy 341.281593 -334.168102) (xy 341.335541 -334.160346) (xy 341.390043 -334.160346)
			(xy 341.443991 -334.168102) (xy 341.496286 -334.183457) (xy 341.545863 -334.206099) (xy 341.591713 -334.235565)
			(xy 341.632904 -334.271256) (xy 341.668595 -334.312447) (xy 341.698061 -334.358297) (xy 341.720703 -334.407874)
			(xy 341.736058 -334.460169) (xy 341.743814 -334.514117) (xy 341.7443 -334.541368) (xy 341.743815 -334.568738)
			(xy 341.736002 -334.622916) (xy 341.720517 -334.675419) (xy 341.69768 -334.725166) (xy 341.667959 -334.771134)
			(xy 341.65032 -334.792066) (xy 341.641113 -334.803416) (xy 341.628929 -334.829965) (xy 341.62475 -334.858876)
			(xy 341.628916 -334.887788) (xy 341.641086 -334.914343) (xy 341.65032 -334.92567) (xy 341.667962 -334.9466)
			(xy 341.697672 -334.992574) (xy 341.720508 -335.042322) (xy 341.735998 -335.094823) (xy 341.743826 -335.148999)
			(xy 341.7443 -335.176368) (xy 341.743814 -335.203619) (xy 341.736058 -335.257567) (xy 341.720703 -335.309862)
			(xy 341.698061 -335.359439) (xy 341.668595 -335.405289) (xy 341.632904 -335.44648) (xy 341.591713 -335.482171)
			(xy 341.545863 -335.511637) (xy 341.496286 -335.534279) (xy 341.443991 -335.549634) (xy 341.390043 -335.55739)
			(xy 341.335541 -335.55739) (xy 341.281593 -335.549634) (xy 341.229298 -335.534279) (xy 341.179721 -335.511637)
			(xy 341.133871 -335.482171) (xy 341.09268 -335.44648) (xy 341.056989 -335.405289) (xy 341.027523 -335.359439)
			(xy 341.004881 -335.309862) (xy 340.989526 -335.257567) (xy 340.98177 -335.203619) (xy 340.981284 -335.176368)
			(xy 319.802764 -335.176368) (xy 319.223632 -335.7555) (xy 345.217421 -335.7555) (xy 345.22159 -335.699879)
			(xy 345.234002 -335.6455) (xy 345.254381 -335.593578) (xy 345.28227 -335.545274) (xy 345.317048 -335.501666)
			(xy 345.357937 -335.463729) (xy 345.404023 -335.432311) (xy 345.454278 -335.408112) (xy 345.507578 -335.391674)
			(xy 345.562733 -335.383363) (xy 345.590622 -335.38287) (xy 345.590876 -335.38287) (xy 345.618412 -335.383381)
			(xy 345.672883 -335.391499) (xy 345.725561 -335.40756) (xy 345.750642 -335.418938) (xy 345.763019 -335.424383)
			(xy 345.789613 -335.429217) (xy 345.816543 -335.426897) (xy 345.841919 -335.417588) (xy 345.86396 -335.401941)
			(xy 345.881119 -335.381056) (xy 345.88704 -335.3689) (xy 345.898378 -335.344653) (xy 345.927062 -335.299459)
			(xy 345.96192 -335.258838) (xy 346.002233 -335.223624) (xy 346.047173 -335.194544) (xy 346.095812 -335.172197)
			(xy 346.14715 -335.157042) (xy 346.200128 -335.149393) (xy 346.226892 -335.148936) (xy 346.253364 -335.149401)
			(xy 346.305773 -335.156901) (xy 346.356596 -335.171737) (xy 346.404809 -335.193611) (xy 346.449445 -335.222083)
			(xy 346.489606 -335.256582) (xy 346.524485 -335.296413) (xy 346.55338 -335.340776) (xy 346.564966 -335.364582)
			(xy 346.571667 -335.377804) (xy 346.5913 -335.399992) (xy 346.616473 -335.415614) (xy 346.64507 -335.423359)
			(xy 346.674687 -335.422574) (xy 346.688918 -335.41843) (xy 346.717263 -335.409661) (xy 346.775839 -335.400225)
			(xy 346.805504 -335.399634) (xy 346.833361 -335.40015) (xy 346.888456 -335.40844) (xy 346.915232 -335.416144)
			(xy 346.929563 -335.419986) (xy 346.959217 -335.420195) (xy 346.987682 -335.411879) (xy 347.01256 -335.395739)
			(xy 347.031755 -335.373135) (xy 347.038168 -335.359756) (xy 347.049483 -335.335288) (xy 347.078037 -335.289568)
			(xy 347.112884 -335.248442) (xy 347.153294 -335.212767) (xy 347.198425 -335.18329) (xy 347.247333 -335.160625)
			(xy 347.298997 -335.145247) (xy 347.352338 -335.137476) (xy 347.37929 -335.136998) (xy 347.407178 -335.13746)
			(xy 347.462333 -335.145772) (xy 347.515632 -335.162211) (xy 347.54503 -335.176368) (xy 349.141796 -335.176368)
			(xy 349.142244 -335.148997) (xy 349.150067 -335.094817) (xy 349.16556 -335.042314) (xy 349.188405 -334.992568)
			(xy 349.218133 -334.946601) (xy 349.235776 -334.92567) (xy 349.245046 -334.914367) (xy 349.257222 -334.887801)
			(xy 349.26139 -334.858876) (xy 349.257208 -334.829953) (xy 349.245019 -334.803393) (xy 349.235776 -334.792066)
			(xy 349.218151 -334.771123) (xy 349.188438 -334.725153) (xy 349.165599 -334.675408) (xy 349.150105 -334.62291)
			(xy 349.142273 -334.568736) (xy 349.141796 -334.541368) (xy 349.142282 -334.514117) (xy 349.150038 -334.460169)
			(xy 349.165393 -334.407874) (xy 349.188035 -334.358297) (xy 349.217501 -334.312447) (xy 349.253192 -334.271256)
			(xy 349.294383 -334.235565) (xy 349.340233 -334.206099) (xy 349.38981 -334.183457) (xy 349.442105 -334.168102)
			(xy 349.496053 -334.160346) (xy 349.550555 -334.160346) (xy 349.604503 -334.168102) (xy 349.656798 -334.183457)
			(xy 349.706375 -334.206099) (xy 349.752225 -334.235565) (xy 349.793416 -334.271256) (xy 349.829107 -334.312447)
			(xy 349.858573 -334.358297) (xy 349.881215 -334.407874) (xy 349.89657 -334.460169) (xy 349.904326 -334.514117)
			(xy 349.904812 -334.541368) (xy 349.904324 -334.568737) (xy 349.896511 -334.622915) (xy 349.881027 -334.675418)
			(xy 349.85819 -334.725165) (xy 349.828471 -334.771133) (xy 349.810832 -334.792066) (xy 349.801624 -334.803415)
			(xy 349.789439 -334.829965) (xy 349.785259 -334.858876) (xy 349.789425 -334.887789) (xy 349.801598 -334.914344)
			(xy 349.810832 -334.92567) (xy 349.828475 -334.946598) (xy 349.858186 -334.992573) (xy 349.88102 -335.042321)
			(xy 349.89651 -335.094823) (xy 349.904338 -335.148999) (xy 349.904812 -335.176368) (xy 357.302308 -335.176368)
			(xy 357.302753 -335.148997) (xy 357.310576 -335.094817) (xy 357.32607 -335.042314) (xy 357.348916 -334.992567)
			(xy 357.378645 -334.946601) (xy 357.396288 -334.92567) (xy 357.405557 -334.914366) (xy 357.417732 -334.8878)
			(xy 357.421899 -334.858876) (xy 357.417718 -334.829953) (xy 357.40553 -334.803393) (xy 357.396288 -334.792066)
			(xy 357.378665 -334.771121) (xy 357.348951 -334.725152) (xy 357.326112 -334.675408) (xy 357.310617 -334.62291)
			(xy 357.302785 -334.568736) (xy 357.302308 -334.541368) (xy 357.302794 -334.514117) (xy 357.31055 -334.460169)
			(xy 357.325905 -334.407874) (xy 357.348547 -334.358297) (xy 357.378013 -334.312447) (xy 357.413704 -334.271256)
			(xy 357.454895 -334.235565) (xy 357.500745 -334.206099) (xy 357.550322 -334.183457) (xy 357.602617 -334.168102)
			(xy 357.656565 -334.160346) (xy 357.711067 -334.160346) (xy 357.765015 -334.168102) (xy 357.81731 -334.183457)
			(xy 357.866887 -334.206099) (xy 357.912737 -334.235565) (xy 357.953928 -334.271256) (xy 357.989619 -334.312447)
			(xy 358.019085 -334.358297) (xy 358.041727 -334.407874) (xy 358.057082 -334.460169) (xy 358.064838 -334.514117)
			(xy 358.065324 -334.541368) (xy 358.064858 -334.568738) (xy 358.057043 -334.622918) (xy 358.041555 -334.675422)
			(xy 358.018713 -334.725169) (xy 357.988986 -334.771135) (xy 357.971344 -334.792066) (xy 357.962142 -334.803418)
			(xy 357.949968 -334.829968) (xy 357.945792 -334.858876) (xy 357.949954 -334.887786) (xy 357.962116 -334.914341)
			(xy 357.971344 -334.92567) (xy 357.98899 -334.946597) (xy 358.018699 -334.992572) (xy 358.041533 -335.042321)
			(xy 358.057023 -335.094822) (xy 358.064851 -335.148999) (xy 358.065324 -335.176368) (xy 365.46282 -335.176368)
			(xy 365.463262 -335.148997) (xy 365.471085 -335.094817) (xy 365.48658 -335.042313) (xy 365.509427 -334.992567)
			(xy 365.539156 -334.946601) (xy 365.5568 -334.92567) (xy 365.566068 -334.914366) (xy 365.578241 -334.8878)
			(xy 365.582408 -334.858876) (xy 365.578228 -334.829954) (xy 365.566041 -334.803393) (xy 365.5568 -334.792066)
			(xy 365.539178 -334.77112) (xy 365.509464 -334.725151) (xy 365.486625 -334.675407) (xy 365.471129 -334.622909)
			(xy 365.463297 -334.568736) (xy 365.46282 -334.541368) (xy 365.463306 -334.514117) (xy 365.471062 -334.460169)
			(xy 365.486417 -334.407874) (xy 365.509059 -334.358297) (xy 365.538525 -334.312447) (xy 365.574216 -334.271256)
			(xy 365.615407 -334.235565) (xy 365.661257 -334.206099) (xy 365.710834 -334.183457) (xy 365.763129 -334.168102)
			(xy 365.817077 -334.160346) (xy 365.871579 -334.160346) (xy 365.925527 -334.168102) (xy 365.977822 -334.183457)
			(xy 366.027399 -334.206099) (xy 366.073249 -334.235565) (xy 366.11444 -334.271256) (xy 366.150131 -334.312447)
			(xy 366.179597 -334.358297) (xy 366.202239 -334.407874) (xy 366.217594 -334.460169) (xy 366.22535 -334.514117)
			(xy 366.225836 -334.541368) (xy 366.225367 -334.568738) (xy 366.217552 -334.622918) (xy 366.202065 -334.675422)
			(xy 366.179223 -334.725169) (xy 366.149498 -334.771135) (xy 366.131856 -334.792066) (xy 366.122653 -334.803418)
			(xy 366.110478 -334.829967) (xy 366.106301 -334.858876) (xy 366.110464 -334.887786) (xy 366.122627 -334.914341)
			(xy 366.131856 -334.92567) (xy 366.149488 -334.946608) (xy 366.179202 -334.992579) (xy 366.20204 -335.042324)
			(xy 366.217533 -335.094824) (xy 366.225362 -335.148999) (xy 366.225836 -335.176368) (xy 366.22535 -335.203619)
			(xy 366.217594 -335.257567) (xy 366.202239 -335.309862) (xy 366.179597 -335.359439) (xy 366.150131 -335.405289)
			(xy 366.11444 -335.44648) (xy 366.073249 -335.482171) (xy 366.027399 -335.511637) (xy 365.977822 -335.534279)
			(xy 365.925527 -335.549634) (xy 365.871579 -335.55739) (xy 365.817077 -335.55739) (xy 365.763129 -335.549634)
			(xy 365.710834 -335.534279) (xy 365.661257 -335.511637) (xy 365.615407 -335.482171) (xy 365.574216 -335.44648)
			(xy 365.538525 -335.405289) (xy 365.509059 -335.359439) (xy 365.486417 -335.309862) (xy 365.471062 -335.257567)
			(xy 365.463306 -335.203619) (xy 365.46282 -335.176368) (xy 358.065324 -335.176368) (xy 358.064838 -335.203619)
			(xy 358.057082 -335.257567) (xy 358.041727 -335.309862) (xy 358.019085 -335.359439) (xy 357.989619 -335.405289)
			(xy 357.953928 -335.44648) (xy 357.912737 -335.482171) (xy 357.866887 -335.511637) (xy 357.81731 -335.534279)
			(xy 357.765015 -335.549634) (xy 357.711067 -335.55739) (xy 357.656565 -335.55739) (xy 357.602617 -335.549634)
			(xy 357.550322 -335.534279) (xy 357.500745 -335.511637) (xy 357.454895 -335.482171) (xy 357.413704 -335.44648)
			(xy 357.378013 -335.405289) (xy 357.348547 -335.359439) (xy 357.325905 -335.309862) (xy 357.31055 -335.257567)
			(xy 357.302794 -335.203619) (xy 357.302308 -335.176368) (xy 349.904812 -335.176368) (xy 349.904326 -335.203619)
			(xy 349.89657 -335.257567) (xy 349.881215 -335.309862) (xy 349.858573 -335.359439) (xy 349.829107 -335.405289)
			(xy 349.793416 -335.44648) (xy 349.752225 -335.482171) (xy 349.706375 -335.511637) (xy 349.656798 -335.534279)
			(xy 349.604503 -335.549634) (xy 349.550555 -335.55739) (xy 349.496053 -335.55739) (xy 349.442105 -335.549634)
			(xy 349.38981 -335.534279) (xy 349.340233 -335.511637) (xy 349.294383 -335.482171) (xy 349.253192 -335.44648)
			(xy 349.217501 -335.405289) (xy 349.188035 -335.359439) (xy 349.165393 -335.309862) (xy 349.150038 -335.257567)
			(xy 349.142282 -335.203619) (xy 349.141796 -335.176368) (xy 347.54503 -335.176368) (xy 347.565885 -335.186411)
			(xy 347.611971 -335.217831) (xy 347.652859 -335.255768) (xy 347.687636 -335.299376) (xy 347.715525 -335.34768)
			(xy 347.735902 -335.399601) (xy 347.748314 -335.453979) (xy 347.752483 -335.5096) (xy 347.748314 -335.565221)
			(xy 347.735902 -335.619599) (xy 347.715525 -335.67152) (xy 347.687636 -335.719824) (xy 347.652859 -335.763432)
			(xy 347.611971 -335.801369) (xy 347.565885 -335.832789) (xy 347.515632 -335.856989) (xy 347.462333 -335.873428)
			(xy 347.407178 -335.88174) (xy 347.37929 -335.882234) (xy 347.351433 -335.88172) (xy 347.296338 -335.873428)
			(xy 347.269562 -335.865724) (xy 347.255229 -335.861894) (xy 347.225578 -335.861687) (xy 347.197116 -335.870002)
			(xy 347.172239 -335.886138) (xy 347.153041 -335.908736) (xy 347.146626 -335.922112) (xy 347.135349 -335.946598)
			(xy 347.106786 -335.992315) (xy 347.071933 -336.033439) (xy 347.031516 -336.069111) (xy 346.986381 -336.098585)
			(xy 346.937469 -336.121247) (xy 346.885801 -336.136624) (xy 346.832457 -336.144393) (xy 346.805504 -336.14487)
			(xy 346.779032 -336.144405) (xy 346.726623 -336.136904) (xy 346.675801 -336.122068) (xy 346.627587 -336.100194)
			(xy 346.582951 -336.071722) (xy 346.54279 -336.037224) (xy 346.507912 -335.997393) (xy 346.479016 -335.95303)
			(xy 346.46743 -335.929224) (xy 346.46073 -335.916001) (xy 346.441097 -335.893812) (xy 346.415924 -335.878189)
			(xy 346.387326 -335.870445) (xy 346.357709 -335.871231) (xy 346.343478 -335.875376) (xy 346.315133 -335.884146)
			(xy 346.256557 -335.893581) (xy 346.226892 -335.894172) (xy 346.226638 -335.894172) (xy 346.199102 -335.893661)
			(xy 346.144631 -335.885544) (xy 346.091952 -335.869482) (xy 346.066872 -335.858104) (xy 346.054496 -335.852654)
			(xy 346.027901 -335.847814) (xy 346.000968 -335.850131) (xy 345.97559 -335.859442) (xy 345.953548 -335.875092)
			(xy 345.936392 -335.895983) (xy 345.930474 -335.908142) (xy 345.919098 -335.93237) (xy 345.890422 -335.977566)
			(xy 345.855571 -336.01819) (xy 345.815263 -336.053406) (xy 345.770329 -336.082489) (xy 345.721693 -336.104839)
			(xy 345.67036 -336.119996) (xy 345.617385 -336.127648) (xy 345.590622 -336.128106) (xy 345.562733 -336.127637)
			(xy 345.507578 -336.119326) (xy 345.454278 -336.102888) (xy 345.404023 -336.078689) (xy 345.357937 -336.047271)
			(xy 345.317048 -336.009334) (xy 345.28227 -335.965726) (xy 345.254381 -335.917422) (xy 345.234002 -335.8655)
			(xy 345.22159 -335.811121) (xy 345.217421 -335.7555) (xy 319.223632 -335.7555) (xy 318.840612 -336.13852)
			(xy 318.840612 -336.63128) (xy 341.85682 -336.63128) (xy 341.860891 -336.575658) (xy 341.873017 -336.521221)
			(xy 341.89294 -336.46913) (xy 341.920236 -336.420495) (xy 341.954322 -336.376352) (xy 341.994471 -336.337643)
			(xy 342.039829 -336.305192) (xy 342.089429 -336.279691) (xy 342.142213 -336.261684) (xy 342.197056 -336.251554)
			(xy 342.25279 -336.249517) (xy 342.308227 -336.255617) (xy 342.362184 -336.269723) (xy 342.413513 -336.291535)
			(xy 342.461119 -336.320589) (xy 342.503987 -336.356264) (xy 342.541204 -336.397801) (xy 342.571977 -336.444314)
			(xy 342.595649 -336.494811) (xy 342.611717 -336.548218) (xy 342.619837 -336.603394) (xy 342.620346 -336.63128)
			(xy 342.619837 -336.659166) (xy 342.611717 -336.714342) (xy 342.595649 -336.767749) (xy 342.571977 -336.818246)
			(xy 342.541204 -336.864759) (xy 342.503987 -336.906296) (xy 342.461119 -336.941971) (xy 342.413513 -336.971025)
			(xy 342.362184 -336.992837) (xy 342.308227 -337.006943) (xy 342.25279 -337.013043) (xy 342.197056 -337.011006)
			(xy 342.142213 -337.000876) (xy 342.089429 -336.982869) (xy 342.039829 -336.957368) (xy 341.994471 -336.924917)
			(xy 341.954322 -336.886208) (xy 341.920236 -336.842065) (xy 341.89294 -336.79343) (xy 341.873017 -336.741339)
			(xy 341.860891 -336.686902) (xy 341.85682 -336.63128) (xy 318.840612 -336.63128) (xy 318.840612 -337.352894)
			(xy 341.12911 -337.352894) (xy 341.133181 -337.297272) (xy 341.145307 -337.242835) (xy 341.16523 -337.190744)
			(xy 341.192526 -337.142109) (xy 341.226612 -337.097966) (xy 341.266761 -337.059257) (xy 341.312119 -337.026806)
			(xy 341.361719 -337.001305) (xy 341.414503 -336.983298) (xy 341.469346 -336.973168) (xy 341.52508 -336.971131)
			(xy 341.580517 -336.977231) (xy 341.634474 -336.991337) (xy 341.685803 -337.013149) (xy 341.733409 -337.042203)
			(xy 341.776277 -337.077878) (xy 341.813494 -337.119415) (xy 341.844267 -337.165928) (xy 341.867939 -337.216425)
			(xy 341.884007 -337.269832) (xy 341.892127 -337.325008) (xy 341.892636 -337.352894) (xy 341.892127 -337.38078)
			(xy 341.884007 -337.435956) (xy 341.867939 -337.489363) (xy 341.844267 -337.53986) (xy 341.813494 -337.586373)
			(xy 341.776277 -337.62791) (xy 341.733409 -337.663585) (xy 341.685803 -337.692639) (xy 341.634474 -337.714451)
			(xy 341.580517 -337.728557) (xy 341.52508 -337.734657) (xy 341.469346 -337.73262) (xy 341.414503 -337.72249)
			(xy 341.361719 -337.704483) (xy 341.312119 -337.678982) (xy 341.266761 -337.646531) (xy 341.226612 -337.607822)
			(xy 341.192526 -337.563679) (xy 341.16523 -337.515044) (xy 341.145307 -337.462953) (xy 341.133181 -337.408516)
			(xy 341.12911 -337.352894) (xy 318.840612 -337.352894) (xy 318.840612 -338.586572) (xy 332.820772 -338.586572)
			(xy 332.821204 -338.5592) (xy 332.829027 -338.505019) (xy 332.844523 -338.452515) (xy 332.867373 -338.402769)
			(xy 332.897106 -338.356804) (xy 332.914752 -338.335874) (xy 332.924012 -338.324565) (xy 332.93618 -338.298)
			(xy 332.940345 -338.269079) (xy 332.936168 -338.240159) (xy 332.923989 -338.213599) (xy 332.914752 -338.20227)
			(xy 332.89714 -338.181316) (xy 332.867423 -338.13535) (xy 332.844581 -338.085608) (xy 332.829083 -338.033112)
			(xy 332.821249 -337.97894) (xy 332.820772 -337.951572) (xy 332.821258 -337.924321) (xy 332.829014 -337.870373)
			(xy 332.844369 -337.818078) (xy 332.867011 -337.768501) (xy 332.896477 -337.722651) (xy 332.932168 -337.68146)
			(xy 332.973359 -337.645769) (xy 333.019209 -337.616303) (xy 333.068786 -337.593661) (xy 333.121081 -337.578306)
			(xy 333.175029 -337.57055) (xy 333.229531 -337.57055) (xy 333.283479 -337.578306) (xy 333.335774 -337.593661)
			(xy 333.385351 -337.616303) (xy 333.431201 -337.645769) (xy 333.472392 -337.68146) (xy 333.508083 -337.722651)
			(xy 333.537549 -337.768501) (xy 333.560191 -337.818078) (xy 333.575546 -337.870373) (xy 333.583302 -337.924321)
			(xy 333.583788 -337.951572) (xy 333.583308 -337.978942) (xy 333.575494 -338.03312) (xy 333.560009 -338.085623)
			(xy 333.53717 -338.135371) (xy 333.507448 -338.181338) (xy 333.489808 -338.20227) (xy 333.480597 -338.213617)
			(xy 333.469256 -338.238338) (xy 342.578944 -338.238338) (xy 342.579509 -338.20865) (xy 342.588703 -338.149991)
			(xy 342.606875 -338.093464) (xy 342.633587 -338.040436) (xy 342.668192 -337.992187) (xy 342.709855 -337.949883)
			(xy 342.733376 -337.93176) (xy 342.74396 -337.923305) (xy 342.760672 -337.902001) (xy 342.771195 -337.877053)
			(xy 342.77479 -337.850216) (xy 342.771204 -337.823377) (xy 342.760688 -337.798426) (xy 342.743982 -337.777116)
			(xy 342.733376 -337.768692) (xy 342.709857 -337.750567) (xy 342.668198 -337.70826) (xy 342.633595 -337.660011)
			(xy 342.606884 -337.606984) (xy 342.588709 -337.550459) (xy 342.57951 -337.491801) (xy 342.578944 -337.462114)
			(xy 342.57943 -337.434863) (xy 342.587186 -337.380915) (xy 342.602541 -337.32862) (xy 342.625183 -337.279043)
			(xy 342.654649 -337.233193) (xy 342.69034 -337.192002) (xy 342.731531 -337.156311) (xy 342.777381 -337.126845)
			(xy 342.826958 -337.104203) (xy 342.879253 -337.088848) (xy 342.933201 -337.081092) (xy 342.987703 -337.081092)
			(xy 343.041651 -337.088848) (xy 343.093946 -337.104203) (xy 343.143523 -337.126845) (xy 343.189373 -337.156311)
			(xy 343.230564 -337.192002) (xy 343.266255 -337.233193) (xy 343.295721 -337.279043) (xy 343.318363 -337.32862)
			(xy 343.333718 -337.380915) (xy 343.341474 -337.434863) (xy 343.34196 -337.462114) (xy 343.341431 -337.491803)
			(xy 343.332229 -337.550464) (xy 343.31405 -337.606991) (xy 343.287332 -337.660019) (xy 343.275257 -337.676851)
			(xy 343.595444 -337.676851) (xy 343.595444 -337.622349) (xy 343.6032 -337.5684) (xy 343.618554 -337.516105)
			(xy 343.641193 -337.466526) (xy 343.670658 -337.420674) (xy 343.706347 -337.379481) (xy 343.747536 -337.343787)
			(xy 343.793384 -337.314316) (xy 343.84296 -337.291671) (xy 343.895253 -337.27631) (xy 343.949201 -337.268547)
			(xy 343.976452 -337.268058) (xy 343.976706 -337.268058) (xy 344.00191 -337.268452) (xy 344.051878 -337.275093)
			(xy 344.100533 -337.288271) (xy 344.147022 -337.307756) (xy 344.168984 -337.320128) (xy 344.181966 -337.327134)
			(xy 344.210596 -337.334177) (xy 344.240045 -337.33274) (xy 344.267854 -337.322944) (xy 344.291702 -337.305606)
			(xy 344.309598 -337.282175) (xy 344.315288 -337.268566) (xy 344.325959 -337.241779) (xy 344.354252 -337.191538)
			(xy 344.389785 -337.146129) (xy 344.431751 -337.106587) (xy 344.479192 -337.073815) (xy 344.531026 -337.048559)
			(xy 344.586072 -337.031395) (xy 344.643074 -337.022715) (xy 344.671904 -337.022186) (xy 344.699155 -337.022674)
			(xy 344.753102 -337.030431) (xy 344.805397 -337.045786) (xy 344.854974 -337.068427) (xy 344.900824 -337.097894)
			(xy 344.942014 -337.133585) (xy 344.977705 -337.174775) (xy 345.007172 -337.220625) (xy 345.016538 -337.241134)
			(xy 347.15958 -337.241134) (xy 347.160076 -337.213561) (xy 347.168023 -337.158989) (xy 347.183743 -337.10613)
			(xy 347.206907 -337.056085) (xy 347.237034 -337.009894) (xy 347.273496 -336.968521) (xy 347.2942 -336.950304)
			(xy 347.305063 -336.940371) (xy 347.321136 -336.91573) (xy 347.329523 -336.887532) (xy 347.32953 -336.858112)
			(xy 347.321155 -336.82991) (xy 347.305092 -336.805263) (xy 347.2942 -336.795364) (xy 347.273468 -336.777175)
			(xy 347.237 -336.735802) (xy 347.20687 -336.689607) (xy 347.183708 -336.639555) (xy 347.167996 -336.586688)
			(xy 347.160062 -336.53211) (xy 347.15958 -336.504534) (xy 347.160087 -336.477283) (xy 347.167839 -336.423334)
			(xy 347.18319 -336.371037) (xy 347.205828 -336.321458) (xy 347.235291 -336.275606) (xy 347.27098 -336.234413)
			(xy 347.312169 -336.198719) (xy 347.358018 -336.16925) (xy 347.407594 -336.146606) (xy 347.459889 -336.131249)
			(xy 347.513837 -336.12349) (xy 347.541088 -336.123026) (xy 347.541596 -336.123026) (xy 347.575378 -336.12455)
			(xy 347.588737 -336.125329) (xy 347.615099 -336.120819) (xy 347.639377 -336.109598) (xy 347.659895 -336.092442)
			(xy 347.675237 -336.070533) (xy 347.684343 -336.045386) (xy 347.685868 -336.032094) (xy 347.688871 -336.003927)
			(xy 347.702039 -335.948837) (xy 347.723211 -335.896301) (xy 347.751922 -335.847475) (xy 347.78754 -335.803434)
			(xy 347.829282 -335.765146) (xy 347.876228 -335.733455) (xy 347.927346 -335.709058) (xy 347.981511 -335.692491)
			(xy 348.037531 -335.684119) (xy 348.065852 -335.683606) (xy 348.083871 -335.683823) (xy 348.119746 -335.68726)
			(xy 348.13748 -335.690464) (xy 348.152691 -335.692778) (xy 348.183241 -335.689255) (xy 348.211358 -335.6768)
			(xy 348.234494 -335.65654) (xy 348.250551 -335.630313) (xy 348.254828 -335.615534) (xy 348.262201 -335.588483)
			(xy 348.283834 -335.536756) (xy 348.312802 -335.48875) (xy 348.348481 -335.445499) (xy 348.390103 -335.407933)
			(xy 348.436774 -335.37686) (xy 348.487488 -335.352948) (xy 348.541154 -335.336713) (xy 348.596618 -335.328504)
			(xy 348.624652 -335.328006) (xy 348.651904 -335.3285) (xy 348.705855 -335.336251) (xy 348.758153 -335.351601)
			(xy 348.807734 -335.374239) (xy 348.853588 -335.403704) (xy 348.894782 -335.439394) (xy 348.930476 -335.480585)
			(xy 348.959944 -335.526436) (xy 348.982587 -335.576015) (xy 348.983463 -335.579) (xy 353.390417 -335.579)
			(xy 353.394585 -335.523382) (xy 353.406996 -335.469006) (xy 353.427372 -335.417087) (xy 353.455258 -335.368785)
			(xy 353.490031 -335.325178) (xy 353.530916 -335.287241) (xy 353.576997 -335.255821) (xy 353.627247 -335.23162)
			(xy 353.680542 -335.215178) (xy 353.735693 -335.206862) (xy 353.76358 -335.20634) (xy 353.790913 -335.206792)
			(xy 353.844993 -335.214765) (xy 353.897328 -335.230556) (xy 353.946793 -335.253827) (xy 353.992325 -335.284078)
			(xy 354.032946 -335.320659) (xy 354.067785 -335.362784) (xy 354.08235 -335.385918) (xy 354.090244 -335.398163)
			(xy 354.111724 -335.417832) (xy 354.137885 -335.430633) (xy 354.166597 -335.435523) (xy 354.195521 -335.432104)
			(xy 354.209096 -335.426812) (xy 354.23231 -335.417332) (xy 354.280641 -335.403977) (xy 354.330329 -335.397245)
			(xy 354.3554 -335.39684) (xy 354.380469 -335.397275) (xy 354.430152 -335.40402) (xy 354.478486 -335.417348)
			(xy 354.501704 -335.426812) (xy 354.515304 -335.431992) (xy 354.544193 -335.435371) (xy 354.572863 -335.430475)
			(xy 354.598994 -335.417702) (xy 354.620468 -335.398086) (xy 354.62845 -335.385918) (xy 354.643019 -335.362787)
			(xy 354.677862 -335.320666) (xy 354.718485 -335.284087) (xy 354.764016 -335.253836) (xy 354.813478 -335.23056)
			(xy 354.865809 -335.21476) (xy 354.919888 -335.206774) (xy 354.974552 -335.206774) (xy 355.028631 -335.21476)
			(xy 355.080962 -335.23056) (xy 355.130424 -335.253836) (xy 355.175955 -335.284087) (xy 355.216578 -335.320666)
			(xy 355.251421 -335.362787) (xy 355.26599 -335.385918) (xy 355.273941 -335.398122) (xy 355.295405 -335.417791)
			(xy 355.321551 -335.430597) (xy 355.350249 -335.435498) (xy 355.379163 -335.432094) (xy 355.392736 -335.426812)
			(xy 355.415945 -335.41732) (xy 355.464278 -335.403969) (xy 355.513968 -335.397243) (xy 355.53904 -335.39684)
			(xy 355.56588 -335.397387) (xy 355.619004 -335.405082) (xy 355.670475 -335.420321) (xy 355.719225 -335.442789)
			(xy 355.764247 -335.472021) (xy 355.804608 -335.507411) (xy 355.839472 -335.548227) (xy 355.868118 -335.593623)
			(xy 355.889952 -335.642661) (xy 355.897688 -335.668366) (xy 355.902375 -335.682854) (xy 355.91889 -335.708414)
			(xy 355.9422 -335.727978) (xy 355.970239 -335.739808) (xy 356.000517 -335.742857) (xy 356.030351 -335.736853)
			(xy 356.043992 -335.730088) (xy 356.072132 -335.715442) (xy 356.132086 -335.694719) (xy 356.194647 -335.684226)
			(xy 356.226364 -335.683606) (xy 356.244384 -335.683822) (xy 356.280258 -335.687259) (xy 356.297992 -335.690464)
			(xy 356.313202 -335.69279) (xy 356.343753 -335.689265) (xy 356.371871 -335.676806) (xy 356.395007 -335.656544)
			(xy 356.411064 -335.630314) (xy 356.41534 -335.615534) (xy 356.422702 -335.588479) (xy 356.444336 -335.536752)
			(xy 356.473305 -335.488746) (xy 356.508985 -335.445495) (xy 356.550609 -335.407928) (xy 356.597281 -335.376856)
			(xy 356.647996 -335.352945) (xy 356.701664 -335.336711) (xy 356.757129 -335.328503) (xy 356.785164 -335.328006)
			(xy 356.812417 -335.328489) (xy 356.866368 -335.336241) (xy 356.918666 -335.351593) (xy 356.968247 -335.374233)
			(xy 357.014101 -335.403698) (xy 357.055294 -335.43939) (xy 357.090988 -335.480582) (xy 357.120457 -335.526434)
			(xy 357.143099 -335.576013) (xy 357.143976 -335.579) (xy 361.550917 -335.579) (xy 361.555086 -335.523381)
			(xy 361.567497 -335.469004) (xy 361.587873 -335.417084) (xy 361.61576 -335.368781) (xy 361.650535 -335.325174)
			(xy 361.691421 -335.287237) (xy 361.737504 -335.255817) (xy 361.787755 -335.231616) (xy 361.841052 -335.215175)
			(xy 361.896204 -335.206862) (xy 361.924092 -335.20634) (xy 361.951425 -335.206783) (xy 362.005506 -335.214757)
			(xy 362.057841 -335.23055) (xy 362.107306 -335.253822) (xy 362.152838 -335.284075) (xy 362.193459 -335.320657)
			(xy 362.228297 -335.362784) (xy 362.242862 -335.385918) (xy 362.250744 -335.398171) (xy 362.272228 -335.417841)
			(xy 362.298392 -335.43064) (xy 362.327106 -335.435528) (xy 362.356032 -335.432105) (xy 362.369608 -335.426812)
			(xy 362.39282 -335.417328) (xy 362.441152 -335.403975) (xy 362.490841 -335.397244) (xy 362.515912 -335.39684)
			(xy 362.540981 -335.397271) (xy 362.590664 -335.404017) (xy 362.638998 -335.417347) (xy 362.662216 -335.426812)
			(xy 362.675812 -335.432005) (xy 362.704703 -335.435381) (xy 362.733375 -335.430482) (xy 362.759506 -335.417706)
			(xy 362.78098 -335.398087) (xy 362.788962 -335.385918) (xy 362.803531 -335.362787) (xy 362.838374 -335.320666)
			(xy 362.878997 -335.284087) (xy 362.924528 -335.253836) (xy 362.97399 -335.23056) (xy 363.026321 -335.21476)
			(xy 363.0804 -335.206774) (xy 363.135064 -335.206774) (xy 363.189143 -335.21476) (xy 363.241474 -335.23056)
			(xy 363.290936 -335.253836) (xy 363.336467 -335.284087) (xy 363.37709 -335.320666) (xy 363.411933 -335.362787)
			(xy 363.426502 -335.385918) (xy 363.434441 -335.39813) (xy 363.455909 -335.417799) (xy 363.482058 -335.430604)
			(xy 363.510759 -335.435503) (xy 363.539675 -335.432096) (xy 363.553248 -335.426812) (xy 363.576455 -335.417316)
			(xy 363.624789 -335.403967) (xy 363.67448 -335.397242) (xy 363.699552 -335.39684) (xy 363.726392 -335.397376)
			(xy 363.779517 -335.405073) (xy 363.830988 -335.420314) (xy 363.879739 -335.442783) (xy 363.92476 -335.472016)
			(xy 363.965121 -335.507407) (xy 363.999985 -335.548224) (xy 364.02863 -335.593622) (xy 364.050464 -335.642661)
			(xy 364.0582 -335.668366) (xy 364.062871 -335.68286) (xy 364.079389 -335.708422) (xy 364.102703 -335.727986)
			(xy 364.130744 -335.739816) (xy 364.161026 -335.742862) (xy 364.190862 -335.736855) (xy 364.204504 -335.730088)
			(xy 364.232659 -335.715474) (xy 364.292606 -335.69474) (xy 364.35516 -335.684233) (xy 364.386876 -335.683606)
			(xy 364.404896 -335.68382) (xy 364.44077 -335.687259) (xy 364.458504 -335.690464) (xy 364.473713 -335.692802)
			(xy 364.504265 -335.689273) (xy 364.532384 -335.676812) (xy 364.555519 -335.656547) (xy 364.571576 -335.630315)
			(xy 364.575852 -335.615534) (xy 364.583203 -335.588476) (xy 364.604838 -335.536748) (xy 364.633808 -335.488742)
			(xy 364.66949 -335.44549) (xy 364.711115 -335.407924) (xy 364.757788 -335.376851) (xy 364.808505 -335.352942)
			(xy 364.862174 -335.336709) (xy 364.917641 -335.328502) (xy 364.945676 -335.328006) (xy 364.972929 -335.328478)
			(xy 365.02688 -335.336232) (xy 365.079179 -335.351585) (xy 365.12876 -335.374226) (xy 365.174614 -335.403693)
			(xy 365.215807 -335.439386) (xy 365.251501 -335.480578) (xy 365.280969 -335.526431) (xy 365.303611 -335.576012)
			(xy 365.304488 -335.579) (xy 369.711391 -335.579) (xy 369.71556 -335.523376) (xy 369.727972 -335.468994)
			(xy 369.748351 -335.41707) (xy 369.776242 -335.368763) (xy 369.81102 -335.325152) (xy 369.85191 -335.287212)
			(xy 369.897998 -335.255791) (xy 369.948254 -335.231589) (xy 370.001557 -335.215148) (xy 370.056714 -335.206835)
			(xy 370.084604 -335.20634) (xy 370.111937 -335.206773) (xy 370.166019 -335.214749) (xy 370.218354 -335.230543)
			(xy 370.267819 -335.253818) (xy 370.313351 -335.284071) (xy 370.353972 -335.320655) (xy 370.38881 -335.362783)
			(xy 370.403374 -335.385918) (xy 370.41134 -335.398111) (xy 370.4328 -335.41778) (xy 370.458942 -335.430588)
			(xy 370.487637 -335.435491) (xy 370.516548 -335.432092) (xy 370.53012 -335.426812) (xy 370.553331 -335.417325)
			(xy 370.601663 -335.403973) (xy 370.651352 -335.397244) (xy 370.676424 -335.39684) (xy 370.701493 -335.397267)
			(xy 370.751176 -335.404015) (xy 370.799511 -335.417346) (xy 370.822728 -335.426812) (xy 370.836319 -335.432017)
			(xy 370.865212 -335.435391) (xy 370.893886 -335.430489) (xy 370.920018 -335.41771) (xy 370.941493 -335.398088)
			(xy 370.949474 -335.385918) (xy 370.964043 -335.362787) (xy 370.998886 -335.320666) (xy 371.039509 -335.284087)
			(xy 371.08504 -335.253836) (xy 371.134502 -335.23056) (xy 371.186833 -335.21476) (xy 371.240912 -335.206774)
			(xy 371.295576 -335.206774) (xy 371.349655 -335.21476) (xy 371.401986 -335.23056) (xy 371.451448 -335.253836)
			(xy 371.496979 -335.284087) (xy 371.537602 -335.320666) (xy 371.572445 -335.362787) (xy 371.587014 -335.385918)
			(xy 371.594942 -335.398139) (xy 371.616413 -335.417808) (xy 371.642565 -335.430612) (xy 371.671268 -335.435508)
			(xy 371.700186 -335.432098) (xy 371.71376 -335.426812) (xy 371.736966 -335.417312) (xy 371.785301 -335.403965)
			(xy 371.834992 -335.397241) (xy 371.860064 -335.39684) (xy 371.887949 -335.397417) (xy 371.943098 -335.405724)
			(xy 371.996392 -335.422159) (xy 372.046641 -335.446353) (xy 372.092723 -335.477767) (xy 372.133608 -335.515699)
			(xy 372.168382 -335.5593) (xy 372.196269 -335.607598) (xy 372.216645 -335.659513) (xy 372.229056 -335.713885)
			(xy 372.233224 -335.7695) (xy 372.229056 -335.825115) (xy 372.216645 -335.879487) (xy 372.196269 -335.931402)
			(xy 372.168382 -335.9797) (xy 372.133608 -336.023301) (xy 372.092723 -336.061233) (xy 372.046641 -336.092647)
			(xy 371.996392 -336.116841) (xy 371.943098 -336.133276) (xy 371.887949 -336.141583) (xy 371.860064 -336.142076)
			(xy 371.832733 -336.141582) (xy 371.778654 -336.133616) (xy 371.726321 -336.117831) (xy 371.676857 -336.094567)
			(xy 371.631324 -336.064323) (xy 371.590701 -336.027748) (xy 371.55586 -335.985629) (xy 371.541294 -335.962498)
			(xy 371.533355 -335.950285) (xy 371.511888 -335.930614) (xy 371.485739 -335.917808) (xy 371.457037 -335.91291)
			(xy 371.428121 -335.916318) (xy 371.414548 -335.921604) (xy 371.391341 -335.931102) (xy 371.343007 -335.94445)
			(xy 371.293316 -335.951174) (xy 371.268244 -335.951576) (xy 371.243174 -335.951158) (xy 371.193491 -335.944406)
			(xy 371.145157 -335.931071) (xy 371.12194 -335.921604) (xy 371.108362 -335.916358) (xy 371.079462 -335.912991)
			(xy 371.050783 -335.917901) (xy 371.024648 -335.93069) (xy 371.003174 -335.950323) (xy 370.995194 -335.962498)
			(xy 370.980625 -335.985629) (xy 370.945782 -336.02775) (xy 370.905159 -336.064329) (xy 370.859628 -336.09458)
			(xy 370.810166 -336.117856) (xy 370.757835 -336.133656) (xy 370.703756 -336.141642) (xy 370.649092 -336.141642)
			(xy 370.595013 -336.133656) (xy 370.542682 -336.117856) (xy 370.49322 -336.09458) (xy 370.447689 -336.064329)
			(xy 370.407066 -336.02775) (xy 370.372223 -335.985629) (xy 370.357654 -335.962498) (xy 370.349753 -335.950258)
			(xy 370.328276 -335.930587) (xy 370.302116 -335.917784) (xy 370.273406 -335.912893) (xy 370.244483 -335.916312)
			(xy 370.230908 -335.921604) (xy 370.207694 -335.931084) (xy 370.159363 -335.944438) (xy 370.109675 -335.95117)
			(xy 370.084604 -335.951576) (xy 370.056714 -335.951165) (xy 370.001557 -335.942852) (xy 369.948254 -335.926411)
			(xy 369.897998 -335.902209) (xy 369.85191 -335.870788) (xy 369.81102 -335.832848) (xy 369.776242 -335.789237)
			(xy 369.748351 -335.74093) (xy 369.727972 -335.689006) (xy 369.71556 -335.634624) (xy 369.711391 -335.579)
			(xy 365.304488 -335.579) (xy 365.318966 -335.62831) (xy 365.326722 -335.682261) (xy 365.327184 -335.709514)
			(xy 365.326665 -335.737087) (xy 365.318724 -335.791657) (xy 365.30301 -335.844517) (xy 365.27985 -335.894563)
			(xy 365.249727 -335.940754) (xy 365.213267 -335.982127) (xy 365.192564 -336.000344) (xy 365.181647 -336.010225)
			(xy 365.165566 -336.034878) (xy 365.157178 -336.063092) (xy 365.157181 -336.092526) (xy 365.165573 -336.120739)
			(xy 365.181659 -336.145388) (xy 365.192564 -336.155284) (xy 365.213285 -336.173484) (xy 365.249752 -336.214856)
			(xy 365.279881 -336.261047) (xy 365.303045 -336.311096) (xy 365.318761 -336.363959) (xy 365.326701 -336.418534)
			(xy 365.326699 -336.473684) (xy 365.318757 -336.528258) (xy 365.303039 -336.581121) (xy 365.279872 -336.631168)
			(xy 365.249741 -336.677359) (xy 365.213272 -336.718729) (xy 365.192564 -336.736944) (xy 365.181647 -336.746825)
			(xy 365.165566 -336.771478) (xy 365.157178 -336.799692) (xy 365.157181 -336.829126) (xy 365.165573 -336.857339)
			(xy 365.181659 -336.881988) (xy 365.192564 -336.891884) (xy 365.213263 -336.910108) (xy 365.249736 -336.951473)
			(xy 365.279871 -336.99766) (xy 365.303039 -337.047706) (xy 365.318757 -337.100566) (xy 365.326698 -337.15514)
			(xy 365.327184 -337.182714) (xy 365.326758 -337.209968) (xy 365.318999 -337.263922) (xy 365.312332 -337.286625)
			(xy 365.717275 -337.286625) (xy 365.717279 -337.232123) (xy 365.725039 -337.178175) (xy 365.740398 -337.125881)
			(xy 365.763043 -337.076305) (xy 365.792513 -337.030457) (xy 365.828207 -336.989269) (xy 365.8694 -336.95358)
			(xy 365.915253 -336.924117) (xy 365.964832 -336.901479) (xy 366.017128 -336.886128) (xy 366.071077 -336.878375)
			(xy 366.098328 -336.877914) (xy 366.113057 -336.878063) (xy 366.142427 -336.880351) (xy 366.157002 -336.882486)
			(xy 366.171557 -336.88423) (xy 366.200601 -336.880377) (xy 366.227353 -336.86843) (xy 366.249607 -336.849374)
			(xy 366.265529 -336.82478) (xy 366.273806 -336.796675) (xy 366.273755 -336.767376) (xy 366.270032 -336.7532)
			(xy 366.262676 -336.726691) (xy 366.254769 -336.672249) (xy 366.254284 -336.644742) (xy 366.25471 -336.617485)
			(xy 366.262462 -336.563526) (xy 366.277815 -336.511219) (xy 366.300456 -336.46163) (xy 366.329924 -336.415768)
			(xy 366.365619 -336.374566) (xy 366.406814 -336.338864) (xy 366.452671 -336.309388) (xy 366.502256 -336.286739)
			(xy 366.55456 -336.271377) (xy 366.608518 -336.263615) (xy 366.663031 -336.263611) (xy 366.71699 -336.271366)
			(xy 366.769296 -336.286721) (xy 366.818885 -336.309364) (xy 366.864745 -336.338834) (xy 366.905946 -336.37453)
			(xy 366.941646 -336.415727) (xy 366.97112 -336.461586) (xy 366.993767 -336.511172) (xy 367.009127 -336.563476)
			(xy 367.016886 -336.617435) (xy 367.016888 -336.671948) (xy 367.009131 -336.725907) (xy 366.993773 -336.778212)
			(xy 366.971128 -336.827799) (xy 366.941656 -336.873659) (xy 366.905958 -336.914857) (xy 366.864759 -336.950556)
			(xy 366.8189 -336.980028) (xy 366.769313 -337.002673) (xy 366.717007 -337.01803) (xy 366.663049 -337.025788)
			(xy 366.635792 -337.02625) (xy 366.621063 -337.026099) (xy 366.591693 -337.023813) (xy 366.577118 -337.021678)
			(xy 366.562577 -337.019774) (xy 366.533512 -337.023648) (xy 366.506747 -337.03562) (xy 366.484486 -337.054704)
			(xy 366.468564 -337.079326) (xy 366.460293 -337.107457) (xy 366.460356 -337.136778) (xy 366.464088 -337.150964)
			(xy 366.471458 -337.17747) (xy 366.479357 -337.231915) (xy 366.479836 -337.259422) (xy 366.479321 -337.286673)
			(xy 366.471561 -337.340621) (xy 366.456203 -337.392915) (xy 366.433559 -337.442491) (xy 366.40409 -337.48834)
			(xy 366.368396 -337.529528) (xy 366.327203 -337.565217) (xy 366.281351 -337.594681) (xy 366.231772 -337.617319)
			(xy 366.179476 -337.632671) (xy 366.125527 -337.640424) (xy 366.071025 -337.640421) (xy 366.017077 -337.632661)
			(xy 365.964783 -337.617302) (xy 365.915207 -337.594658) (xy 365.869358 -337.565189) (xy 365.82817 -337.529494)
			(xy 365.792481 -337.488301) (xy 365.763018 -337.442449) (xy 365.74038 -337.39287) (xy 365.725028 -337.340574)
			(xy 365.717275 -337.286625) (xy 365.312332 -337.286625) (xy 365.30364 -337.316222) (xy 365.280994 -337.365804)
			(xy 365.251522 -337.411658) (xy 365.215824 -337.452851) (xy 365.174628 -337.488545) (xy 365.12877 -337.518012)
			(xy 365.079186 -337.540653) (xy 365.026885 -337.556007) (xy 364.97293 -337.563761) (xy 364.945676 -337.564222)
			(xy 364.917821 -337.563704) (xy 364.862706 -337.555578) (xy 364.809356 -337.53953) (xy 364.758904 -337.515902)
			(xy 364.71242 -337.485194) (xy 364.670891 -337.448059) (xy 364.635198 -337.405284) (xy 364.606098 -337.357777)
			(xy 364.584209 -337.306547) (xy 364.576614 -337.279742) (xy 364.572272 -337.26565) (xy 364.556899 -337.240508)
			(xy 364.534998 -337.22079) (xy 364.508385 -337.208132) (xy 364.479268 -337.203584) (xy 364.4646 -337.205066)
			(xy 364.451647 -337.206728) (xy 364.425589 -337.208508) (xy 364.41253 -337.208622) (xy 364.412276 -337.208622)
			(xy 364.398127 -337.208531) (xy 364.369904 -337.206495) (xy 364.355888 -337.204558) (xy 364.342533 -337.203057)
			(xy 364.315853 -337.206144) (xy 364.290907 -337.216099) (xy 364.26943 -337.232227) (xy 364.252916 -337.253409)
			(xy 364.242512 -337.278171) (xy 364.240318 -337.291426) (xy 364.236214 -337.318577) (xy 364.221244 -337.371407)
			(xy 364.198855 -337.421545) (xy 364.169509 -337.467956) (xy 364.133814 -337.509681) (xy 364.092506 -337.545858)
			(xy 364.046438 -337.57574) (xy 363.996563 -337.598709) (xy 363.94391 -337.614291) (xy 363.889567 -337.622164)
			(xy 363.862112 -337.622642) (xy 363.834863 -337.622111) (xy 363.780918 -337.614357) (xy 363.728627 -337.599005)
			(xy 363.679052 -337.576368) (xy 363.633203 -337.546906) (xy 363.592014 -337.511219) (xy 363.556322 -337.470034)
			(xy 363.526855 -337.424189) (xy 363.504211 -337.374617) (xy 363.488853 -337.322327) (xy 363.481093 -337.268383)
			(xy 363.480604 -337.241134) (xy 363.481092 -337.21356) (xy 363.48904 -337.158988) (xy 363.50476 -337.106129)
			(xy 363.527926 -337.056083) (xy 363.558055 -337.009893) (xy 363.594519 -336.96852) (xy 363.615224 -336.950304)
			(xy 363.626084 -336.940369) (xy 363.642154 -336.915728) (xy 363.650539 -336.887531) (xy 363.650546 -336.858113)
			(xy 363.642173 -336.829912) (xy 363.626114 -336.805264) (xy 363.615224 -336.795364) (xy 363.594497 -336.77717)
			(xy 363.558027 -336.735798) (xy 363.527896 -336.689605) (xy 363.504733 -336.639553) (xy 363.48902 -336.586688)
			(xy 363.481086 -336.53211) (xy 363.480604 -336.504534) (xy 363.481038 -336.478032) (xy 363.488387 -336.42554)
			(xy 363.502936 -336.374572) (xy 363.524404 -336.32611) (xy 363.552377 -336.281088) (xy 363.568996 -336.26044)
			(xy 363.578467 -336.248313) (xy 363.590263 -336.219907) (xy 363.593087 -336.189278) (xy 363.586685 -336.159193)
			(xy 363.571635 -336.132369) (xy 363.549295 -336.111226) (xy 363.535722 -336.103976) (xy 363.512025 -336.091888)
			(xy 363.468045 -336.061961) (xy 363.428765 -336.026086) (xy 363.394984 -335.984992) (xy 363.380782 -335.962498)
			(xy 363.372854 -335.950277) (xy 363.351384 -335.930606) (xy 363.325232 -335.917801) (xy 363.296528 -335.912905)
			(xy 363.26761 -335.916317) (xy 363.254036 -335.921604) (xy 363.230819 -335.931075) (xy 363.18249 -335.944433)
			(xy 363.132803 -335.951169) (xy 363.107732 -335.951576) (xy 363.082662 -335.951162) (xy 363.032979 -335.944408)
			(xy 362.984645 -335.931072) (xy 362.961428 -335.921604) (xy 362.947855 -335.916345) (xy 362.918952 -335.912981)
			(xy 362.890271 -335.917894) (xy 362.864136 -335.930686) (xy 362.842662 -335.950321) (xy 362.834682 -335.962498)
			(xy 362.820113 -335.985629) (xy 362.78527 -336.02775) (xy 362.744647 -336.064329) (xy 362.699116 -336.09458)
			(xy 362.649654 -336.117856) (xy 362.597323 -336.133656) (xy 362.543244 -336.141642) (xy 362.48858 -336.141642)
			(xy 362.434501 -336.133656) (xy 362.38217 -336.117856) (xy 362.332708 -336.09458) (xy 362.287177 -336.064329)
			(xy 362.246554 -336.02775) (xy 362.211711 -335.985629) (xy 362.197142 -335.962498) (xy 362.189252 -335.95025)
			(xy 362.167772 -335.930579) (xy 362.141609 -335.917777) (xy 362.112896 -335.912888) (xy 362.083971 -335.916311)
			(xy 362.070396 -335.921604) (xy 362.047184 -335.931087) (xy 361.998852 -335.944441) (xy 361.949163 -335.951171)
			(xy 361.924092 -335.951576) (xy 361.896204 -335.951138) (xy 361.841052 -335.942825) (xy 361.787755 -335.926384)
			(xy 361.737504 -335.902183) (xy 361.691421 -335.870763) (xy 361.650535 -335.832826) (xy 361.61576 -335.789219)
			(xy 361.587873 -335.740916) (xy 361.567497 -335.688996) (xy 361.555086 -335.634619) (xy 361.550917 -335.579)
			(xy 357.143976 -335.579) (xy 357.158454 -335.628311) (xy 357.16621 -335.682261) (xy 357.166672 -335.709514)
			(xy 357.166157 -335.737087) (xy 357.158216 -335.791658) (xy 357.142501 -335.844517) (xy 357.119341 -335.894564)
			(xy 357.089216 -335.940755) (xy 357.052756 -335.982127) (xy 357.032052 -336.000344) (xy 357.021136 -336.010226)
			(xy 357.005057 -336.034879) (xy 356.99667 -336.063092) (xy 356.996673 -336.092526) (xy 357.005064 -336.120738)
			(xy 357.021148 -336.145388) (xy 357.032052 -336.155284) (xy 357.052774 -336.173483) (xy 357.089241 -336.214855)
			(xy 357.119372 -336.261047) (xy 357.142536 -336.311096) (xy 357.158253 -336.363959) (xy 357.166193 -336.418534)
			(xy 357.166192 -336.473684) (xy 357.158249 -336.528259) (xy 357.14253 -336.581121) (xy 357.119363 -336.631169)
			(xy 357.08923 -336.67736) (xy 357.052761 -336.718729) (xy 357.032052 -336.736944) (xy 357.021136 -336.746826)
			(xy 357.005057 -336.771479) (xy 356.99667 -336.799692) (xy 356.996673 -336.829126) (xy 357.005064 -336.857338)
			(xy 357.021148 -336.881988) (xy 357.032052 -336.891884) (xy 357.052749 -336.910111) (xy 357.089222 -336.951475)
			(xy 357.119358 -336.997661) (xy 357.142526 -337.047706) (xy 357.158245 -337.100567) (xy 357.166186 -337.15514)
			(xy 357.166672 -337.182714) (xy 357.166258 -337.209969) (xy 357.160641 -337.249022) (xy 357.497106 -337.249022)
			(xy 357.49711 -337.194524) (xy 357.50487 -337.140581) (xy 357.520227 -337.088292) (xy 357.54287 -337.03872)
			(xy 357.572337 -336.992875) (xy 357.608029 -336.951691) (xy 357.649218 -336.916005) (xy 357.695067 -336.886545)
			(xy 357.744642 -336.863909) (xy 357.796933 -336.848559) (xy 357.850877 -336.840806) (xy 357.878126 -336.840322)
			(xy 357.903517 -336.840764) (xy 357.953848 -336.847513) (xy 357.978456 -336.853784) (xy 357.993101 -336.857224)
			(xy 358.023156 -336.856294) (xy 358.051639 -336.846659) (xy 358.076088 -336.829153) (xy 358.094384 -336.805291)
			(xy 358.104946 -336.777137) (xy 358.106859 -336.747129) (xy 358.103932 -336.732372) (xy 358.099173 -336.710842)
			(xy 358.094083 -336.667043) (xy 358.093772 -336.644996) (xy 358.093772 -336.644742) (xy 358.09421 -336.617485)
			(xy 358.101962 -336.563526) (xy 358.117315 -336.511219) (xy 358.139957 -336.461629) (xy 358.169425 -336.415767)
			(xy 358.20512 -336.374565) (xy 358.246316 -336.338863) (xy 358.292173 -336.309387) (xy 358.341759 -336.286738)
			(xy 358.394064 -336.271376) (xy 358.448022 -336.263615) (xy 358.502536 -336.263611) (xy 358.556495 -336.271367)
			(xy 358.608801 -336.286723) (xy 358.658389 -336.309366) (xy 358.70425 -336.338837) (xy 358.74545 -336.374535)
			(xy 358.78115 -336.415732) (xy 358.810623 -336.461592) (xy 358.83327 -336.511179) (xy 358.848628 -336.563484)
			(xy 358.856387 -336.617443) (xy 358.856387 -336.671956) (xy 358.848629 -336.725915) (xy 358.83327 -336.77822)
			(xy 358.810624 -336.827807) (xy 358.781151 -336.873667) (xy 358.745451 -336.914864) (xy 358.704251 -336.950562)
			(xy 358.65839 -336.980033) (xy 358.608802 -337.002677) (xy 358.556496 -337.018033) (xy 358.502537 -337.025788)
			(xy 358.47528 -337.02625) (xy 358.449889 -337.025807) (xy 358.399558 -337.019059) (xy 358.37495 -337.012788)
			(xy 358.360298 -337.009388) (xy 358.330251 -337.010317) (xy 358.301774 -337.019948) (xy 358.27733 -337.037447)
			(xy 358.259034 -337.061301) (xy 358.24847 -337.089446) (xy 358.246551 -337.119446) (xy 358.249474 -337.1342)
			(xy 358.254228 -337.155731) (xy 358.259321 -337.199529) (xy 358.259634 -337.221576) (xy 358.259634 -337.22183)
			(xy 358.25909 -337.249079) (xy 358.25133 -337.303022) (xy 358.235972 -337.355311) (xy 358.213328 -337.404882)
			(xy 358.183861 -337.450727) (xy 358.148169 -337.491911) (xy 358.10698 -337.527596) (xy 358.061131 -337.557057)
			(xy 358.011556 -337.579692) (xy 357.959264 -337.595042) (xy 357.90532 -337.602794) (xy 357.850822 -337.60279)
			(xy 357.79688 -337.59503) (xy 357.74459 -337.579672) (xy 357.695019 -337.557029) (xy 357.649174 -337.527562)
			(xy 357.60799 -337.49187) (xy 357.572305 -337.450681) (xy 357.542844 -337.404832) (xy 357.520208 -337.355257)
			(xy 357.504858 -337.302966) (xy 357.497106 -337.249022) (xy 357.160641 -337.249022) (xy 357.158498 -337.263923)
			(xy 357.143139 -337.316225) (xy 357.120492 -337.365807) (xy 357.091019 -337.411662) (xy 357.05532 -337.452855)
			(xy 357.014122 -337.488549) (xy 356.968263 -337.518016) (xy 356.918678 -337.540656) (xy 356.866375 -337.556009)
			(xy 356.812419 -337.563762) (xy 356.785164 -337.564222) (xy 356.757309 -337.563715) (xy 356.702193 -337.555587)
			(xy 356.648843 -337.539538) (xy 356.598391 -337.515908) (xy 356.551907 -337.485199) (xy 356.510378 -337.448062)
			(xy 356.474685 -337.405286) (xy 356.445586 -337.357779) (xy 356.423697 -337.306547) (xy 356.416102 -337.279742)
			(xy 356.411772 -337.265645) (xy 356.396397 -337.240502) (xy 356.374492 -337.220784) (xy 356.347876 -337.208128)
			(xy 356.318757 -337.203582) (xy 356.304088 -337.205066) (xy 356.291135 -337.206729) (xy 356.265077 -337.208508)
			(xy 356.252018 -337.208622) (xy 356.251764 -337.208622) (xy 356.237615 -337.208532) (xy 356.209392 -337.206495)
			(xy 356.195376 -337.204558) (xy 356.182023 -337.203045) (xy 356.155341 -337.206135) (xy 356.130394 -337.216092)
			(xy 356.108917 -337.232223) (xy 356.092403 -337.253406) (xy 356.082 -337.27817) (xy 356.079806 -337.291426)
			(xy 356.075714 -337.318579) (xy 356.060743 -337.37141) (xy 356.038353 -337.421549) (xy 356.009006 -337.46796)
			(xy 355.973309 -337.509686) (xy 355.932 -337.545862) (xy 355.885931 -337.575744) (xy 355.836054 -337.598712)
			(xy 355.7834 -337.614293) (xy 355.729056 -337.622165) (xy 355.7016 -337.622642) (xy 355.67435 -337.622122)
			(xy 355.620406 -337.614367) (xy 355.568114 -337.599013) (xy 355.518539 -337.576375) (xy 355.47269 -337.546911)
			(xy 355.4315 -337.511224) (xy 355.395809 -337.470037) (xy 355.366342 -337.424191) (xy 355.343699 -337.374618)
			(xy 355.328341 -337.322328) (xy 355.32058 -337.268384) (xy 355.320092 -337.241134) (xy 355.320584 -337.21356)
			(xy 355.328531 -337.158989) (xy 355.344252 -337.10613) (xy 355.367417 -337.056084) (xy 355.397544 -337.009893)
			(xy 355.434007 -336.968521) (xy 355.454712 -336.950304) (xy 355.465574 -336.94037) (xy 355.481645 -336.915729)
			(xy 355.490031 -336.887531) (xy 355.490038 -336.858113) (xy 355.481664 -336.829911) (xy 355.465603 -336.805263)
			(xy 355.454712 -336.795364) (xy 355.433983 -336.777173) (xy 355.397513 -336.7358) (xy 355.367383 -336.689606)
			(xy 355.34422 -336.639554) (xy 355.328508 -336.586688) (xy 355.320574 -336.53211) (xy 355.320092 -336.504534)
			(xy 355.320528 -336.478032) (xy 355.327878 -336.425541) (xy 355.342426 -336.374573) (xy 355.363893 -336.326111)
			(xy 355.391865 -336.281089) (xy 355.408484 -336.26044) (xy 355.417925 -336.248295) (xy 355.429707 -336.219894)
			(xy 355.432526 -336.189276) (xy 355.42613 -336.159201) (xy 355.411094 -336.13238) (xy 355.388774 -336.111232)
			(xy 355.37521 -336.103976) (xy 355.351511 -336.091892) (xy 355.307531 -336.061963) (xy 355.268253 -336.026087)
			(xy 355.234472 -335.984992) (xy 355.22027 -335.962498) (xy 355.212354 -335.950269) (xy 355.19088 -335.930598)
			(xy 355.164725 -335.917794) (xy 355.136018 -335.9129) (xy 355.107098 -335.916315) (xy 355.093524 -335.921604)
			(xy 355.070308 -335.931079) (xy 355.021978 -335.944435) (xy 354.972291 -335.951169) (xy 354.94722 -335.951576)
			(xy 354.922151 -335.951133) (xy 354.872469 -335.944392) (xy 354.824134 -335.931066) (xy 354.800916 -335.921604)
			(xy 354.787324 -335.916389) (xy 354.758423 -335.913003) (xy 354.729739 -335.917897) (xy 354.703596 -335.930674)
			(xy 354.682112 -335.950299) (xy 354.67417 -335.962498) (xy 354.659601 -335.985629) (xy 354.624758 -336.02775)
			(xy 354.584135 -336.064329) (xy 354.538604 -336.09458) (xy 354.489142 -336.117856) (xy 354.436811 -336.133656)
			(xy 354.382732 -336.141642) (xy 354.328068 -336.141642) (xy 354.273989 -336.133656) (xy 354.221658 -336.117856)
			(xy 354.172196 -336.09458) (xy 354.126665 -336.064329) (xy 354.086042 -336.02775) (xy 354.051199 -335.985629)
			(xy 354.03663 -335.962498) (xy 354.028751 -335.950242) (xy 354.007268 -335.93057) (xy 353.981103 -335.91777)
			(xy 353.952387 -335.912884) (xy 353.92346 -335.916309) (xy 353.909884 -335.921604) (xy 353.886673 -335.931091)
			(xy 353.838341 -335.944443) (xy 353.788652 -335.951172) (xy 353.76358 -335.951576) (xy 353.735693 -335.951138)
			(xy 353.680542 -335.942822) (xy 353.627247 -335.92638) (xy 353.576997 -335.902179) (xy 353.530916 -335.870759)
			(xy 353.490031 -335.832822) (xy 353.455258 -335.789215) (xy 353.427372 -335.740913) (xy 353.406996 -335.688994)
			(xy 353.394585 -335.634618) (xy 353.390417 -335.579) (xy 348.983463 -335.579) (xy 348.997942 -335.628312)
			(xy 349.005698 -335.682262) (xy 349.00616 -335.709514) (xy 349.005649 -335.737087) (xy 348.997708 -335.791659)
			(xy 348.981993 -335.844518) (xy 348.958831 -335.894565) (xy 348.928706 -335.940755) (xy 348.892245 -335.982128)
			(xy 348.87154 -336.000344) (xy 348.860626 -336.010227) (xy 348.844548 -336.03488) (xy 348.836162 -336.063093)
			(xy 348.836165 -336.092525) (xy 348.844555 -336.120737) (xy 348.860638 -336.145387) (xy 348.87154 -336.155284)
			(xy 348.892262 -336.173483) (xy 348.928731 -336.214854) (xy 348.958862 -336.261046) (xy 348.982028 -336.311095)
			(xy 348.997745 -336.363958) (xy 349.005685 -336.418534) (xy 349.005684 -336.473684) (xy 348.997741 -336.52826)
			(xy 348.982021 -336.581122) (xy 348.958854 -336.63117) (xy 348.92872 -336.67736) (xy 348.892249 -336.71873)
			(xy 348.87154 -336.736944) (xy 348.860626 -336.746827) (xy 348.844548 -336.77148) (xy 348.836162 -336.799693)
			(xy 348.836165 -336.829125) (xy 348.844555 -336.857337) (xy 348.860638 -336.881987) (xy 348.87154 -336.891884)
			(xy 348.892255 -336.910091) (xy 348.928723 -336.951462) (xy 348.958854 -336.997653) (xy 348.982018 -337.047701)
			(xy 348.997735 -337.100564) (xy 349.005674 -337.155139) (xy 349.00616 -337.182714) (xy 349.005758 -337.209969)
			(xy 349.00376 -337.223862) (xy 349.430848 -337.223862) (xy 349.431342 -337.196612) (xy 349.439103 -337.142667)
			(xy 349.454461 -337.090375) (xy 349.477103 -337.0408) (xy 349.506569 -336.994952) (xy 349.542259 -336.953764)
			(xy 349.583447 -336.918073) (xy 349.629295 -336.888606) (xy 349.678869 -336.865963) (xy 349.731161 -336.850604)
			(xy 349.785106 -336.842843) (xy 349.812356 -336.842354) (xy 349.83547 -336.843116) (xy 349.848795 -336.843542)
			(xy 349.874897 -336.838144) (xy 349.898719 -336.826187) (xy 349.918644 -336.808483) (xy 349.933321 -336.786233)
			(xy 349.941752 -336.760947) (xy 349.943367 -336.734342) (xy 349.941134 -336.721196) (xy 349.937481 -336.702293)
			(xy 349.933539 -336.663993) (xy 349.93326 -336.644742) (xy 349.933794 -336.617492) (xy 349.941545 -336.563545)
			(xy 349.956894 -336.51125) (xy 349.979529 -336.461672) (xy 350.00899 -336.415821) (xy 350.044676 -336.374628)
			(xy 350.085861 -336.338934) (xy 350.131707 -336.309465) (xy 350.181281 -336.28682) (xy 350.233573 -336.27146)
			(xy 350.287518 -336.2637) (xy 350.314768 -336.263234) (xy 350.342022 -336.263685) (xy 350.395976 -336.271439)
			(xy 350.448276 -336.286793) (xy 350.497859 -336.309435) (xy 350.543714 -336.338903) (xy 350.584908 -336.374599)
			(xy 350.620603 -336.415794) (xy 350.65007 -336.46165) (xy 350.67271 -336.511233) (xy 350.688063 -336.563534)
			(xy 350.695816 -336.617488) (xy 350.696276 -336.644742) (xy 350.695861 -336.671996) (xy 350.688098 -336.725948)
			(xy 350.672736 -336.778246) (xy 350.650088 -336.827825) (xy 350.620614 -336.873677) (xy 350.584915 -336.914868)
			(xy 350.543718 -336.950558) (xy 350.49786 -336.980023) (xy 350.448276 -337.002662) (xy 350.395975 -337.018014)
			(xy 350.342022 -337.025766) (xy 350.314768 -337.02625) (xy 350.291654 -337.025488) (xy 350.278329 -337.025079)
			(xy 350.252227 -337.030472) (xy 350.228404 -337.042425) (xy 350.208478 -337.060126) (xy 350.193801 -337.082374)
			(xy 350.18537 -337.107659) (xy 350.183757 -337.134263) (xy 350.18599 -337.147408) (xy 350.189644 -337.166311)
			(xy 350.193585 -337.204611) (xy 350.193864 -337.223862) (xy 350.193409 -337.251116) (xy 350.185656 -337.305069)
			(xy 350.170303 -337.35737) (xy 350.147662 -337.406953) (xy 350.118193 -337.452809) (xy 350.082499 -337.494003)
			(xy 350.041304 -337.529697) (xy 349.995448 -337.559164) (xy 349.945865 -337.581805) (xy 349.893564 -337.597158)
			(xy 349.83961 -337.60491) (xy 349.812356 -337.60537) (xy 349.785102 -337.604963) (xy 349.731149 -337.5972)
			(xy 349.678851 -337.581837) (xy 349.629271 -337.559188) (xy 349.583419 -337.529713) (xy 349.542228 -337.494014)
			(xy 349.506537 -337.452815) (xy 349.477073 -337.406957) (xy 349.454434 -337.357372) (xy 349.439083 -337.30507)
			(xy 349.431331 -337.251116) (xy 349.430848 -337.223862) (xy 349.00376 -337.223862) (xy 348.997998 -337.263925)
			(xy 348.982638 -337.316227) (xy 348.95999 -337.365811) (xy 348.930516 -337.411666) (xy 348.894816 -337.45286)
			(xy 348.853616 -337.488553) (xy 348.807756 -337.51802) (xy 348.758169 -337.540659) (xy 348.705864 -337.556011)
			(xy 348.651907 -337.563762) (xy 348.624652 -337.564222) (xy 348.596796 -337.563726) (xy 348.54168 -337.555596)
			(xy 348.48833 -337.539545) (xy 348.437878 -337.515914) (xy 348.391394 -337.485204) (xy 348.349865 -337.448066)
			(xy 348.314173 -337.405289) (xy 348.285073 -337.35778) (xy 348.263185 -337.306548) (xy 348.25559 -337.279742)
			(xy 348.251272 -337.265641) (xy 348.235894 -337.240497) (xy 348.213987 -337.220779) (xy 348.187368 -337.208124)
			(xy 348.158246 -337.203581) (xy 348.143576 -337.205066) (xy 348.130623 -337.20673) (xy 348.104565 -337.208509)
			(xy 348.091506 -337.208622) (xy 348.091252 -337.208622) (xy 348.077103 -337.208522) (xy 348.04888 -337.206492)
			(xy 348.034864 -337.204558) (xy 348.021512 -337.203033) (xy 347.994829 -337.206126) (xy 347.969882 -337.216085)
			(xy 347.948405 -337.232218) (xy 347.931891 -337.253404) (xy 347.921488 -337.278169) (xy 347.919294 -337.291426)
			(xy 347.915213 -337.318581) (xy 347.900242 -337.371413) (xy 347.877851 -337.421553) (xy 347.848503 -337.467965)
			(xy 347.812805 -337.50969) (xy 347.771494 -337.545867) (xy 347.725423 -337.575748) (xy 347.675545 -337.598715)
			(xy 347.622889 -337.614295) (xy 347.568544 -337.622166) (xy 347.541088 -337.622642) (xy 347.513838 -337.622133)
			(xy 347.459893 -337.614376) (xy 347.407601 -337.599021) (xy 347.358026 -337.576381) (xy 347.312177 -337.546917)
			(xy 347.270988 -337.511228) (xy 347.235296 -337.470041) (xy 347.205829 -337.424194) (xy 347.183186 -337.37462)
			(xy 347.167828 -337.322329) (xy 347.160068 -337.268384) (xy 347.15958 -337.241134) (xy 345.016538 -337.241134)
			(xy 345.029813 -337.270201) (xy 345.045169 -337.322496) (xy 345.052926 -337.376443) (xy 345.053412 -337.403694)
			(xy 345.053412 -337.403948) (xy 345.05284 -337.433787) (xy 345.043522 -337.492733) (xy 345.03487 -337.521296)
			(xy 345.030926 -337.535227) (xy 345.030004 -337.564145) (xy 345.037252 -337.592155) (xy 345.052087 -337.616995)
			(xy 345.073309 -337.63666) (xy 345.099206 -337.649562) (xy 345.113356 -337.652614) (xy 345.139432 -337.657766)
			(xy 345.189936 -337.674341) (xy 345.237648 -337.697767) (xy 345.281646 -337.727591) (xy 345.321075 -337.763236)
			(xy 345.355174 -337.804011) (xy 345.38328 -337.849126) (xy 345.404849 -337.897706) (xy 345.419464 -337.94881)
			(xy 345.426841 -338.001449) (xy 345.4273 -338.028026) (xy 345.426814 -338.055277) (xy 345.419058 -338.109225)
			(xy 345.403703 -338.16152) (xy 345.381061 -338.211097) (xy 345.363554 -338.238338) (xy 350.739456 -338.238338)
			(xy 350.740016 -338.20865) (xy 350.749211 -338.14999) (xy 350.767383 -338.093463) (xy 350.794096 -338.040435)
			(xy 350.828702 -337.992186) (xy 350.870366 -337.949883) (xy 350.893888 -337.93176) (xy 350.904471 -337.923305)
			(xy 350.921181 -337.902) (xy 350.931703 -337.877052) (xy 350.935297 -337.850216) (xy 350.931711 -337.823378)
			(xy 350.921197 -337.798427) (xy 350.904493 -337.777117) (xy 350.893888 -337.768692) (xy 350.870371 -337.750564)
			(xy 350.828712 -337.708258) (xy 350.794108 -337.66001) (xy 350.767397 -337.606983) (xy 350.749222 -337.550459)
			(xy 350.740022 -337.491801) (xy 350.739456 -337.462114) (xy 350.739942 -337.434863) (xy 350.747698 -337.380915)
			(xy 350.763053 -337.32862) (xy 350.785695 -337.279043) (xy 350.815161 -337.233193) (xy 350.850852 -337.192002)
			(xy 350.892043 -337.156311) (xy 350.937893 -337.126845) (xy 350.98747 -337.104203) (xy 351.039765 -337.088848)
			(xy 351.093713 -337.081092) (xy 351.148215 -337.081092) (xy 351.202163 -337.088848) (xy 351.254458 -337.104203)
			(xy 351.304035 -337.126845) (xy 351.349885 -337.156311) (xy 351.391076 -337.192002) (xy 351.426767 -337.233193)
			(xy 351.456233 -337.279043) (xy 351.478875 -337.32862) (xy 351.49423 -337.380915) (xy 351.501986 -337.434863)
			(xy 351.502472 -337.462114) (xy 351.501938 -337.491803) (xy 351.492737 -337.550464) (xy 351.474558 -337.60699)
			(xy 351.447841 -337.660018) (xy 351.435765 -337.676852) (xy 351.755944 -337.676852) (xy 351.755944 -337.622348)
			(xy 351.7637 -337.568399) (xy 351.779055 -337.516102) (xy 351.801695 -337.466523) (xy 351.831161 -337.42067)
			(xy 351.866852 -337.379477) (xy 351.908041 -337.343782) (xy 351.953891 -337.314313) (xy 352.003468 -337.291667)
			(xy 352.055763 -337.276308) (xy 352.109712 -337.268546) (xy 352.136964 -337.268058) (xy 352.137218 -337.268058)
			(xy 352.162422 -337.268447) (xy 352.21239 -337.27509) (xy 352.261045 -337.288269) (xy 352.307534 -337.307755)
			(xy 352.329496 -337.320128) (xy 352.342471 -337.327148) (xy 352.371104 -337.334189) (xy 352.400555 -337.332749)
			(xy 352.428366 -337.322951) (xy 352.452214 -337.30561) (xy 352.47011 -337.282176) (xy 352.4758 -337.268566)
			(xy 352.486461 -337.241775) (xy 352.514755 -337.191533) (xy 352.55029 -337.146124) (xy 352.592257 -337.106583)
			(xy 352.639699 -337.073811) (xy 352.691535 -337.048556) (xy 352.746582 -337.031393) (xy 352.803586 -337.022714)
			(xy 352.832416 -337.022186) (xy 352.859667 -337.022663) (xy 352.913615 -337.030421) (xy 352.96591 -337.045778)
			(xy 353.015487 -337.068421) (xy 353.061337 -337.097888) (xy 353.102526 -337.133581) (xy 353.138218 -337.174771)
			(xy 353.167684 -337.220622) (xy 353.190325 -337.2702) (xy 353.205681 -337.322495) (xy 353.213438 -337.376443)
			(xy 353.213924 -337.403694) (xy 353.213924 -337.403948) (xy 353.213352 -337.433787) (xy 353.204034 -337.492733)
			(xy 353.195382 -337.521296) (xy 353.191429 -337.535225) (xy 353.190506 -337.564145) (xy 353.197755 -337.592157)
			(xy 353.212592 -337.616998) (xy 353.233817 -337.636663) (xy 353.259717 -337.649563) (xy 353.273868 -337.652614)
			(xy 353.299946 -337.657757) (xy 353.350449 -337.674333) (xy 353.398162 -337.697761) (xy 353.442159 -337.727587)
			(xy 353.481589 -337.763233) (xy 353.515687 -337.804008) (xy 353.543792 -337.849124) (xy 353.565362 -337.897704)
			(xy 353.579976 -337.94881) (xy 353.587353 -338.001449) (xy 353.587812 -338.028026) (xy 353.587326 -338.055277)
			(xy 353.57957 -338.109225) (xy 353.564215 -338.16152) (xy 353.541573 -338.211097) (xy 353.524066 -338.238338)
			(xy 358.899968 -338.238338) (xy 358.900524 -338.20865) (xy 358.909719 -338.149989) (xy 358.927892 -338.093462)
			(xy 358.954605 -338.040434) (xy 358.989212 -337.992186) (xy 359.030878 -337.949883) (xy 359.0544 -337.93176)
			(xy 359.064982 -337.923304) (xy 359.08169 -337.901999) (xy 359.092211 -337.877051) (xy 359.095804 -337.850216)
			(xy 359.092219 -337.823379) (xy 359.081706 -337.798428) (xy 359.065004 -337.777118) (xy 359.0544 -337.768692)
			(xy 359.030886 -337.750561) (xy 358.989225 -337.708256) (xy 358.954621 -337.660008) (xy 358.927909 -337.606982)
			(xy 358.909734 -337.550458) (xy 358.900534 -337.491801) (xy 358.899968 -337.462114) (xy 358.900454 -337.434863)
			(xy 358.90821 -337.380915) (xy 358.923565 -337.32862) (xy 358.946207 -337.279043) (xy 358.975673 -337.233193)
			(xy 359.011364 -337.192002) (xy 359.052555 -337.156311) (xy 359.098405 -337.126845) (xy 359.147982 -337.104203)
			(xy 359.200277 -337.088848) (xy 359.254225 -337.081092) (xy 359.308727 -337.081092) (xy 359.362675 -337.088848)
			(xy 359.41497 -337.104203) (xy 359.464547 -337.126845) (xy 359.510397 -337.156311) (xy 359.551588 -337.192002)
			(xy 359.587279 -337.233193) (xy 359.616745 -337.279043) (xy 359.639387 -337.32862) (xy 359.654742 -337.380915)
			(xy 359.662498 -337.434863) (xy 359.662984 -337.462114) (xy 359.662446 -337.491803) (xy 359.653244 -337.550463)
			(xy 359.635066 -337.606989) (xy 359.60835 -337.660017) (xy 359.596273 -337.676853) (xy 359.916444 -337.676853)
			(xy 359.916444 -337.622347) (xy 359.9242 -337.568397) (xy 359.939556 -337.516099) (xy 359.962197 -337.466519)
			(xy 359.991664 -337.420666) (xy 360.027356 -337.379473) (xy 360.068547 -337.343778) (xy 360.114398 -337.314309)
			(xy 360.163977 -337.291664) (xy 360.216274 -337.276305) (xy 360.270223 -337.268546) (xy 360.297476 -337.268058)
			(xy 360.29773 -337.268058) (xy 360.322934 -337.268442) (xy 360.372903 -337.275086) (xy 360.421557 -337.288267)
			(xy 360.468047 -337.307754) (xy 360.490008 -337.320128) (xy 360.502976 -337.327162) (xy 360.531612 -337.334201)
			(xy 360.561065 -337.332759) (xy 360.588877 -337.322957) (xy 360.612726 -337.305614) (xy 360.630622 -337.282177)
			(xy 360.636312 -337.268566) (xy 360.646963 -337.241771) (xy 360.675258 -337.191528) (xy 360.710794 -337.146119)
			(xy 360.752763 -337.106578) (xy 360.800207 -337.073806) (xy 360.852044 -337.048552) (xy 360.907092 -337.03139)
			(xy 360.964097 -337.022713) (xy 360.992928 -337.022186) (xy 361.02018 -337.022652) (xy 361.074128 -337.030412)
			(xy 361.126423 -337.04577) (xy 361.175999 -337.068414) (xy 361.221849 -337.097883) (xy 361.263039 -337.133576)
			(xy 361.29873 -337.174768) (xy 361.328196 -337.22062) (xy 361.350837 -337.270198) (xy 361.366193 -337.322494)
			(xy 361.37395 -337.376442) (xy 361.374436 -337.403694) (xy 361.374436 -337.403948) (xy 361.373863 -337.433787)
			(xy 361.364546 -337.492733) (xy 361.355894 -337.521296) (xy 361.351931 -337.535223) (xy 361.351008 -337.564145)
			(xy 361.358258 -337.592159) (xy 361.373097 -337.617001) (xy 361.394325 -337.636666) (xy 361.420227 -337.649564)
			(xy 361.43438 -337.652614) (xy 361.460445 -337.657823) (xy 361.510948 -337.674387) (xy 361.558661 -337.697804)
			(xy 361.60266 -337.727621) (xy 361.642092 -337.763259) (xy 361.676192 -337.804028) (xy 361.704301 -337.849138)
			(xy 361.725872 -337.897714) (xy 361.740488 -337.948815) (xy 361.747865 -338.001451) (xy 361.748324 -338.028026)
			(xy 361.747838 -338.055277) (xy 361.740082 -338.109225) (xy 361.724727 -338.16152) (xy 361.702085 -338.211097)
			(xy 361.684578 -338.238338) (xy 367.06048 -338.238338) (xy 367.061071 -338.208651) (xy 367.070263 -338.149994)
			(xy 367.088432 -338.09347) (xy 367.115138 -338.040442) (xy 367.149738 -337.992192) (xy 367.191394 -337.949885)
			(xy 367.214912 -337.93176) (xy 367.225493 -337.923304) (xy 367.242199 -337.901998) (xy 367.252719 -337.877051)
			(xy 367.256312 -337.850216) (xy 367.252727 -337.82338) (xy 367.242215 -337.798429) (xy 367.225516 -337.777118)
			(xy 367.214912 -337.768692) (xy 367.1914 -337.750558) (xy 367.149739 -337.708254) (xy 367.115135 -337.660007)
			(xy 367.088422 -337.606981) (xy 367.070246 -337.550458) (xy 367.061046 -337.491801) (xy 367.06048 -337.462114)
			(xy 367.060966 -337.434863) (xy 367.068722 -337.380915) (xy 367.084077 -337.32862) (xy 367.106719 -337.279043)
			(xy 367.136185 -337.233193) (xy 367.171876 -337.192002) (xy 367.213067 -337.156311) (xy 367.258917 -337.126845)
			(xy 367.308494 -337.104203) (xy 367.360789 -337.088848) (xy 367.414737 -337.081092) (xy 367.469239 -337.081092)
			(xy 367.523187 -337.088848) (xy 367.575482 -337.104203) (xy 367.625059 -337.126845) (xy 367.670909 -337.156311)
			(xy 367.7121 -337.192002) (xy 367.747791 -337.233193) (xy 367.777257 -337.279043) (xy 367.799899 -337.32862)
			(xy 367.815254 -337.380915) (xy 367.82301 -337.434863) (xy 367.823496 -337.462114) (xy 367.822953 -337.491802)
			(xy 367.813752 -337.550462) (xy 367.795574 -337.606988) (xy 367.768859 -337.660016) (xy 367.756782 -337.676853)
			(xy 368.076944 -337.676853) (xy 368.076944 -337.622347) (xy 368.084701 -337.568395) (xy 368.100057 -337.516097)
			(xy 368.122699 -337.466516) (xy 368.152167 -337.420662) (xy 368.18786 -337.379469) (xy 368.229053 -337.343774)
			(xy 368.274906 -337.314305) (xy 368.324486 -337.291661) (xy 368.376784 -337.276303) (xy 368.430735 -337.268545)
			(xy 368.457988 -337.268058) (xy 368.458242 -337.268058) (xy 368.483446 -337.268437) (xy 368.533415 -337.275082)
			(xy 368.58207 -337.288265) (xy 368.628559 -337.307753) (xy 368.65052 -337.320128) (xy 368.66348 -337.327177)
			(xy 368.692119 -337.334213) (xy 368.721575 -337.332769) (xy 368.749388 -337.322964) (xy 368.773238 -337.305619)
			(xy 368.791135 -337.282179) (xy 368.796824 -337.268566) (xy 368.807549 -337.241802) (xy 368.835835 -337.191563)
			(xy 368.871361 -337.146155) (xy 368.913319 -337.106613) (xy 368.960752 -337.073838) (xy 369.012578 -337.048578)
			(xy 369.067617 -337.031408) (xy 369.124613 -337.022719) (xy 369.15344 -337.022186) (xy 369.180692 -337.022641)
			(xy 369.23464 -337.030402) (xy 369.286935 -337.045762) (xy 369.336512 -337.068408) (xy 369.382362 -337.097878)
			(xy 369.423552 -337.133572) (xy 369.459243 -337.174765) (xy 369.488709 -337.220617) (xy 369.51135 -337.270196)
			(xy 369.526705 -337.322493) (xy 369.534462 -337.376442) (xy 369.534948 -337.403694) (xy 369.534948 -337.403948)
			(xy 369.534375 -337.433787) (xy 369.526646 -337.482688) (xy 371.647212 -337.482688) (xy 371.647734 -337.455115)
			(xy 371.655675 -337.400545) (xy 371.671388 -337.347686) (xy 371.694547 -337.29764) (xy 371.72467 -337.251449)
			(xy 371.761129 -337.210075) (xy 371.781832 -337.191858) (xy 371.792738 -337.18197) (xy 371.808804 -337.157315)
			(xy 371.817183 -337.129106) (xy 371.817181 -337.099679) (xy 371.808798 -337.071471) (xy 371.792728 -337.046819)
			(xy 371.781832 -337.036918) (xy 371.761133 -337.018694) (xy 371.72466 -336.977329) (xy 371.694526 -336.931142)
			(xy 371.671358 -336.881096) (xy 371.655639 -336.828235) (xy 371.647698 -336.773662) (xy 371.647212 -336.746088)
			(xy 371.647644 -336.718834) (xy 371.655403 -336.664881) (xy 371.670761 -336.612581) (xy 371.693407 -336.562999)
			(xy 371.722878 -336.517145) (xy 371.758575 -336.475952) (xy 371.799771 -336.440259) (xy 371.845628 -336.410791)
			(xy 371.895211 -336.38815) (xy 371.947512 -336.372796) (xy 372.001466 -336.365041) (xy 372.02872 -336.36458)
			(xy 372.029482 -336.36458) (xy 372.041453 -336.364696) (xy 372.065346 -336.366219) (xy 372.077234 -336.367628)
			(xy 372.090996 -336.368863) (xy 372.118323 -336.364892) (xy 372.143589 -336.353747) (xy 372.164947 -336.336242)
			(xy 372.180837 -336.313657) (xy 372.190098 -336.287642) (xy 372.191534 -336.273902) (xy 372.194089 -336.24537)
			(xy 372.206571 -336.189465) (xy 372.227274 -336.136055) (xy 372.255732 -336.086344) (xy 372.291306 -336.041447)
			(xy 372.333195 -336.002377) (xy 372.380457 -335.970012) (xy 372.432028 -335.945079) (xy 372.486747 -335.92814)
			(xy 372.543385 -335.919577) (xy 372.572026 -335.919064) (xy 372.590045 -335.919286) (xy 372.62592 -335.922719)
			(xy 372.643654 -335.925922) (xy 372.658866 -335.928241) (xy 372.689419 -335.924725) (xy 372.71754 -335.91227)
			(xy 372.740676 -335.892007) (xy 372.756729 -335.865774) (xy 372.761002 -335.850992) (xy 372.768437 -335.823959)
			(xy 372.790061 -335.772233) (xy 372.819019 -335.724227) (xy 372.854689 -335.680974) (xy 372.896304 -335.643406)
			(xy 372.942967 -335.61233) (xy 372.993675 -335.588415) (xy 373.047335 -335.572177) (xy 373.102794 -335.563964)
			(xy 373.130826 -335.563464) (xy 373.158077 -335.563954) (xy 373.212023 -335.571713) (xy 373.264316 -335.58707)
			(xy 373.313891 -335.609712) (xy 373.35974 -335.639178) (xy 373.400929 -335.674869) (xy 373.43662 -335.716058)
			(xy 373.466087 -335.761907) (xy 373.488729 -335.811482) (xy 373.504087 -335.863775) (xy 373.511846 -335.917721)
			(xy 373.512334 -335.944972) (xy 373.511872 -335.972547) (xy 373.503922 -336.027121) (xy 373.488198 -336.079982)
			(xy 373.465027 -336.130028) (xy 373.434893 -336.176218) (xy 373.398423 -336.217587) (xy 373.377714 -336.235802)
			(xy 373.366844 -336.245729) (xy 373.350769 -336.27037) (xy 373.342381 -336.298571) (xy 373.342376 -336.327993)
			(xy 373.350753 -336.356197) (xy 373.36682 -336.380844) (xy 373.377714 -336.390742) (xy 373.398391 -336.408989)
			(xy 373.434853 -336.450357) (xy 373.464979 -336.496543) (xy 373.488141 -336.546586) (xy 373.503857 -336.599442)
			(xy 373.511799 -336.65401) (xy 373.511802 -336.709154) (xy 373.503865 -336.763723) (xy 373.488154 -336.81658)
			(xy 373.464997 -336.866625) (xy 373.434875 -336.912815) (xy 373.398417 -336.954186) (xy 373.377714 -336.972402)
			(xy 373.366844 -336.982329) (xy 373.350769 -337.00697) (xy 373.342381 -337.035171) (xy 373.342376 -337.064593)
			(xy 373.350753 -337.092797) (xy 373.36682 -337.117444) (xy 373.377714 -337.127342) (xy 373.398403 -337.145577)
			(xy 373.434875 -337.186941) (xy 373.465009 -337.233126) (xy 373.488179 -337.283169) (xy 373.5039 -337.336028)
			(xy 373.511845 -337.390599) (xy 373.512334 -337.418172) (xy 373.511819 -337.445423) (xy 373.504066 -337.499371)
			(xy 373.488715 -337.551666) (xy 373.466078 -337.601244) (xy 373.436615 -337.647096) (xy 373.400927 -337.688289)
			(xy 373.35974 -337.723983) (xy 373.313892 -337.753452) (xy 373.264317 -337.776096) (xy 373.212024 -337.791455)
			(xy 373.158077 -337.799215) (xy 373.130826 -337.79968) (xy 373.102971 -337.799148) (xy 373.047855 -337.791028)
			(xy 372.994504 -337.774985) (xy 372.944051 -337.75136) (xy 372.897566 -337.720654) (xy 372.856036 -337.683519)
			(xy 372.820343 -337.640744) (xy 372.791244 -337.593237) (xy 372.769358 -337.542005) (xy 372.761764 -337.5152)
			(xy 372.757496 -337.501082) (xy 372.742104 -337.475937) (xy 372.720184 -337.456222) (xy 372.693554 -337.443572)
			(xy 372.664424 -337.439035) (xy 372.64975 -337.440524) (xy 372.636923 -337.442176) (xy 372.61112 -337.443953)
			(xy 372.598188 -337.44408) (xy 372.597426 -337.44408) (xy 372.579795 -337.443842) (xy 372.544687 -337.440537)
			(xy 372.527322 -337.437476) (xy 372.513546 -337.435268) (xy 372.485761 -337.437711) (xy 372.459678 -337.447592)
			(xy 372.437249 -337.464172) (xy 372.420152 -337.48621) (xy 372.409666 -337.512056) (xy 372.407688 -337.525868)
			(xy 372.404033 -337.553442) (xy 372.389802 -337.607212) (xy 372.36791 -337.658344) (xy 372.338821 -337.705752)
			(xy 372.303152 -337.748431) (xy 372.261661 -337.785475) (xy 372.215229 -337.816097) (xy 372.16484 -337.839648)
			(xy 372.111563 -337.855628) (xy 372.056531 -337.863698) (xy 372.02872 -337.864196) (xy 372.001467 -337.863726)
			(xy 371.947516 -337.855971) (xy 371.895217 -337.840617) (xy 371.845636 -337.817976) (xy 371.799783 -337.788509)
			(xy 371.758589 -337.752816) (xy 371.722896 -337.711624) (xy 371.693428 -337.665771) (xy 371.670785 -337.61619)
			(xy 371.65543 -337.563892) (xy 371.647675 -337.509941) (xy 371.647212 -337.482688) (xy 369.526646 -337.482688)
			(xy 369.525058 -337.492733) (xy 369.516406 -337.521296) (xy 369.512434 -337.535221) (xy 369.51151 -337.564145)
			(xy 369.518761 -337.59216) (xy 369.533602 -337.617004) (xy 369.554832 -337.636669) (xy 369.580738 -337.649566)
			(xy 369.594892 -337.652614) (xy 369.620959 -337.657814) (xy 369.671462 -337.67438) (xy 369.719175 -337.697798)
			(xy 369.763174 -337.727617) (xy 369.802605 -337.763256) (xy 369.836705 -337.804026) (xy 369.864813 -337.849136)
			(xy 369.886384 -337.897713) (xy 369.901 -337.948814) (xy 369.908377 -338.001451) (xy 369.908836 -338.028026)
			(xy 369.90835 -338.055277) (xy 369.900594 -338.109225) (xy 369.885239 -338.16152) (xy 369.862597 -338.211097)
			(xy 369.833131 -338.256947) (xy 369.79744 -338.298138) (xy 369.756249 -338.333829) (xy 369.710399 -338.363295)
			(xy 369.660822 -338.385937) (xy 369.608527 -338.401292) (xy 369.554579 -338.409048) (xy 369.500077 -338.409048)
			(xy 369.446129 -338.401292) (xy 369.393834 -338.385937) (xy 369.344257 -338.363295) (xy 369.298407 -338.333829)
			(xy 369.257216 -338.298138) (xy 369.221525 -338.256947) (xy 369.192059 -338.211097) (xy 369.169417 -338.16152)
			(xy 369.154062 -338.109225) (xy 369.146306 -338.055277) (xy 369.14582 -338.028026) (xy 369.14582 -338.027772)
			(xy 369.146395 -337.997933) (xy 369.15571 -337.938987) (xy 369.164362 -337.910424) (xy 369.168449 -337.896528)
			(xy 369.169356 -337.867586) (xy 369.162084 -337.839558) (xy 369.147221 -337.814708) (xy 369.125967 -337.795042)
			(xy 369.10004 -337.78215) (xy 369.085876 -337.779106) (xy 369.053035 -337.77253) (xy 368.990184 -337.749402)
			(xy 368.960908 -337.733132) (xy 368.947922 -337.726137) (xy 368.919294 -337.719101) (xy 368.889849 -337.720539)
			(xy 368.862044 -337.730333) (xy 368.838197 -337.747665) (xy 368.820298 -337.771089) (xy 368.814604 -337.784694)
			(xy 368.803918 -337.811475) (xy 368.77563 -337.861718) (xy 368.740099 -337.907128) (xy 368.698136 -337.946671)
			(xy 368.650697 -337.979445) (xy 368.598864 -338.004702) (xy 368.543819 -338.021866) (xy 368.486817 -338.030546)
			(xy 368.457988 -338.031074) (xy 368.430735 -338.030655) (xy 368.376784 -338.022897) (xy 368.324486 -338.007539)
			(xy 368.274906 -337.984895) (xy 368.229053 -337.955426) (xy 368.18786 -337.919731) (xy 368.152167 -337.878538)
			(xy 368.122699 -337.832684) (xy 368.100057 -337.783103) (xy 368.084701 -337.730805) (xy 368.076944 -337.676853)
			(xy 367.756782 -337.676853) (xy 367.734251 -337.708264) (xy 367.692586 -337.750569) (xy 367.669064 -337.768692)
			(xy 367.658433 -337.77709) (xy 367.641731 -337.79841) (xy 367.631218 -337.82337) (xy 367.627632 -337.850216)
			(xy 367.631226 -337.87706) (xy 367.641747 -337.902017) (xy 367.658456 -337.923332) (xy 367.669064 -337.93176)
			(xy 367.692595 -337.94987) (xy 367.734256 -337.992178) (xy 367.76886 -338.04043) (xy 367.795569 -338.09346)
			(xy 367.81374 -338.149989) (xy 367.822934 -338.208649) (xy 367.823496 -338.238338) (xy 367.82301 -338.265589)
			(xy 367.815254 -338.319537) (xy 367.799899 -338.371832) (xy 367.777257 -338.421409) (xy 367.747791 -338.467259)
			(xy 367.7121 -338.50845) (xy 367.670909 -338.544141) (xy 367.625059 -338.573607) (xy 367.582767 -338.592922)
			(xy 373.623332 -338.592922) (xy 373.623332 -338.592668) (xy 373.623867 -338.564654) (xy 373.632086 -338.509233)
			(xy 373.648313 -338.455606) (xy 373.672201 -338.404926) (xy 373.703237 -338.358279) (xy 373.72163 -338.337144)
			(xy 373.731299 -338.325722) (xy 373.74407 -338.298671) (xy 373.748448 -338.269079) (xy 373.744057 -338.239489)
			(xy 373.731275 -338.212444) (xy 373.72163 -338.201) (xy 373.703193 -338.179896) (xy 373.672127 -338.133257)
			(xy 373.648227 -338.082572) (xy 373.632007 -338.028932) (xy 373.623818 -337.973495) (xy 373.623332 -337.945476)
			(xy 373.623332 -337.945222) (xy 373.623818 -337.917971) (xy 373.631574 -337.864023) (xy 373.646929 -337.811728)
			(xy 373.669571 -337.762151) (xy 373.699037 -337.716301) (xy 373.734728 -337.67511) (xy 373.775919 -337.639419)
			(xy 373.821769 -337.609953) (xy 373.871346 -337.587311) (xy 373.923641 -337.571956) (xy 373.977589 -337.5642)
			(xy 374.032091 -337.5642) (xy 374.086039 -337.571956) (xy 374.138334 -337.587311) (xy 374.187911 -337.609953)
			(xy 374.233761 -337.639419) (xy 374.274952 -337.67511) (xy 374.310643 -337.716301) (xy 374.340109 -337.762151)
			(xy 374.362751 -337.811728) (xy 374.378106 -337.864023) (xy 374.385862 -337.917971) (xy 374.386348 -337.945222)
			(xy 374.386348 -337.945476) (xy 374.385845 -337.973491) (xy 374.377619 -338.028914) (xy 374.361384 -338.082541)
			(xy 374.337489 -338.133221) (xy 374.306447 -338.179866) (xy 374.28805 -338.201) (xy 374.27843 -338.212462)
			(xy 374.265642 -338.239497) (xy 374.261249 -338.269079) (xy 374.26563 -338.298663) (xy 374.278406 -338.325704)
			(xy 374.28805 -338.337144) (xy 374.306457 -338.358273) (xy 374.337528 -338.404905) (xy 374.361434 -338.455584)
			(xy 374.37766 -338.509218) (xy 374.385857 -338.56465) (xy 374.386348 -338.592668) (xy 374.386348 -338.592922)
			(xy 374.385862 -338.620173) (xy 374.378106 -338.674121) (xy 374.362751 -338.726416) (xy 374.340109 -338.775993)
			(xy 374.310643 -338.821843) (xy 374.274952 -338.863034) (xy 374.233761 -338.898725) (xy 374.187911 -338.928191)
			(xy 374.138334 -338.950833) (xy 374.086039 -338.966188) (xy 374.032091 -338.973944) (xy 373.977589 -338.973944)
			(xy 373.923641 -338.966188) (xy 373.871346 -338.950833) (xy 373.821769 -338.928191) (xy 373.775919 -338.898725)
			(xy 373.734728 -338.863034) (xy 373.699037 -338.821843) (xy 373.669571 -338.775993) (xy 373.646929 -338.726416)
			(xy 373.631574 -338.674121) (xy 373.623818 -338.620173) (xy 373.623332 -338.592922) (xy 367.582767 -338.592922)
			(xy 367.575482 -338.596249) (xy 367.523187 -338.611604) (xy 367.469239 -338.61936) (xy 367.414737 -338.61936)
			(xy 367.360789 -338.611604) (xy 367.308494 -338.596249) (xy 367.258917 -338.573607) (xy 367.213067 -338.544141)
			(xy 367.171876 -338.50845) (xy 367.136185 -338.467259) (xy 367.106719 -338.421409) (xy 367.084077 -338.371832)
			(xy 367.068722 -338.319537) (xy 367.060966 -338.265589) (xy 367.06048 -338.238338) (xy 361.684578 -338.238338)
			(xy 361.672619 -338.256947) (xy 361.636928 -338.298138) (xy 361.595737 -338.333829) (xy 361.549887 -338.363295)
			(xy 361.50031 -338.385937) (xy 361.448015 -338.401292) (xy 361.394067 -338.409048) (xy 361.339565 -338.409048)
			(xy 361.285617 -338.401292) (xy 361.233322 -338.385937) (xy 361.183745 -338.363295) (xy 361.137895 -338.333829)
			(xy 361.096704 -338.298138) (xy 361.061013 -338.256947) (xy 361.031547 -338.211097) (xy 361.008905 -338.16152)
			(xy 360.99355 -338.109225) (xy 360.985794 -338.055277) (xy 360.985308 -338.028026) (xy 360.985308 -338.027772)
			(xy 360.985883 -337.997933) (xy 360.995199 -337.938987) (xy 361.00385 -337.910424) (xy 361.007868 -337.896513)
			(xy 361.008772 -337.867586) (xy 361.001506 -337.839571) (xy 360.986658 -337.814728) (xy 360.965424 -337.795062)
			(xy 360.939518 -337.782159) (xy 360.925364 -337.779106) (xy 360.892528 -337.772509) (xy 360.829674 -337.749396)
			(xy 360.800396 -337.733132) (xy 360.787417 -337.726123) (xy 360.758786 -337.719088) (xy 360.729339 -337.720529)
			(xy 360.701532 -337.730326) (xy 360.677684 -337.74766) (xy 360.659785 -337.771087) (xy 360.654092 -337.784694)
			(xy 360.643416 -337.811479) (xy 360.615127 -337.861723) (xy 360.579595 -337.907133) (xy 360.53763 -337.946676)
			(xy 360.49019 -337.979449) (xy 360.438355 -338.004705) (xy 360.383309 -338.021868) (xy 360.326306 -338.030547)
			(xy 360.297476 -338.031074) (xy 360.270223 -338.030654) (xy 360.216274 -338.022895) (xy 360.163977 -338.007536)
			(xy 360.114398 -337.984891) (xy 360.068547 -337.955422) (xy 360.027356 -337.919727) (xy 359.991664 -337.878534)
			(xy 359.962197 -337.832681) (xy 359.939556 -337.783101) (xy 359.9242 -337.730803) (xy 359.916444 -337.676853)
			(xy 359.596273 -337.676853) (xy 359.57374 -337.708265) (xy 359.532074 -337.750569) (xy 359.508552 -337.768692)
			(xy 359.497922 -337.77709) (xy 359.481222 -337.798411) (xy 359.47071 -337.823371) (xy 359.467125 -337.850216)
			(xy 359.470718 -337.877059) (xy 359.481238 -337.902016) (xy 359.497945 -337.923332) (xy 359.508552 -337.93176)
			(xy 359.532102 -337.949846) (xy 359.573758 -337.992162) (xy 359.608356 -338.04042) (xy 359.635062 -338.093454)
			(xy 359.65323 -338.149985) (xy 359.662422 -338.208649) (xy 359.662984 -338.238338) (xy 359.662498 -338.265589)
			(xy 359.654742 -338.319537) (xy 359.639387 -338.371832) (xy 359.616745 -338.421409) (xy 359.587279 -338.467259)
			(xy 359.551588 -338.50845) (xy 359.510397 -338.544141) (xy 359.464547 -338.573607) (xy 359.41497 -338.596249)
			(xy 359.362675 -338.611604) (xy 359.308727 -338.61936) (xy 359.254225 -338.61936) (xy 359.200277 -338.611604)
			(xy 359.147982 -338.596249) (xy 359.098405 -338.573607) (xy 359.052555 -338.544141) (xy 359.011364 -338.50845)
			(xy 358.975673 -338.467259) (xy 358.946207 -338.421409) (xy 358.923565 -338.371832) (xy 358.90821 -338.319537)
			(xy 358.900454 -338.265589) (xy 358.899968 -338.238338) (xy 353.524066 -338.238338) (xy 353.512107 -338.256947)
			(xy 353.476416 -338.298138) (xy 353.435225 -338.333829) (xy 353.389375 -338.363295) (xy 353.339798 -338.385937)
			(xy 353.287503 -338.401292) (xy 353.233555 -338.409048) (xy 353.179053 -338.409048) (xy 353.125105 -338.401292)
			(xy 353.07281 -338.385937) (xy 353.023233 -338.363295) (xy 352.977383 -338.333829) (xy 352.936192 -338.298138)
			(xy 352.900501 -338.256947) (xy 352.871035 -338.211097) (xy 352.848393 -338.16152) (xy 352.833038 -338.109225)
			(xy 352.825282 -338.055277) (xy 352.824796 -338.028026) (xy 352.824796 -338.027772) (xy 352.825372 -337.997933)
			(xy 352.834687 -337.938987) (xy 352.843338 -337.910424) (xy 352.847365 -337.896515) (xy 352.848269 -337.867586)
			(xy 352.841003 -337.839569) (xy 352.826153 -337.814726) (xy 352.804916 -337.79506) (xy 352.779007 -337.782158)
			(xy 352.764852 -337.779106) (xy 352.732015 -337.772512) (xy 352.669162 -337.749397) (xy 352.639884 -337.733132)
			(xy 352.626912 -337.726109) (xy 352.598279 -337.719076) (xy 352.568829 -337.72052) (xy 352.541021 -337.730319)
			(xy 352.517172 -337.747656) (xy 352.499273 -337.771086) (xy 352.49358 -337.784694) (xy 352.482914 -337.811483)
			(xy 352.454624 -337.861727) (xy 352.41909 -337.907138) (xy 352.377124 -337.946681) (xy 352.329682 -337.979454)
			(xy 352.277846 -338.004709) (xy 352.222799 -338.021871) (xy 352.165794 -338.030548) (xy 352.136964 -338.031074)
			(xy 352.109712 -338.030654) (xy 352.055763 -338.022892) (xy 352.003468 -338.007533) (xy 351.953891 -337.984887)
			(xy 351.908041 -337.955418) (xy 351.866852 -337.919723) (xy 351.831161 -337.87853) (xy 351.801695 -337.832677)
			(xy 351.779055 -337.783098) (xy 351.7637 -337.730801) (xy 351.755944 -337.676852) (xy 351.435765 -337.676852)
			(xy 351.41323 -337.708266) (xy 351.371563 -337.750569) (xy 351.34804 -337.768692) (xy 351.337403 -337.777085)
			(xy 351.320688 -337.798403) (xy 351.310166 -337.823365) (xy 351.306577 -337.850216) (xy 351.310174 -337.877065)
			(xy 351.320704 -337.902024) (xy 351.337425 -337.923336) (xy 351.34804 -337.93176) (xy 351.371587 -337.94985)
			(xy 351.413244 -337.992164) (xy 351.447843 -338.040421) (xy 351.474549 -338.093455) (xy 351.492718 -338.149986)
			(xy 351.50191 -338.208649) (xy 351.502472 -338.238338) (xy 351.501986 -338.265589) (xy 351.49423 -338.319537)
			(xy 351.478875 -338.371832) (xy 351.456233 -338.421409) (xy 351.426767 -338.467259) (xy 351.391076 -338.50845)
			(xy 351.349885 -338.544141) (xy 351.304035 -338.573607) (xy 351.254458 -338.596249) (xy 351.202163 -338.611604)
			(xy 351.148215 -338.61936) (xy 351.093713 -338.61936) (xy 351.039765 -338.611604) (xy 350.98747 -338.596249)
			(xy 350.937893 -338.573607) (xy 350.892043 -338.544141) (xy 350.850852 -338.50845) (xy 350.815161 -338.467259)
			(xy 350.785695 -338.421409) (xy 350.763053 -338.371832) (xy 350.747698 -338.319537) (xy 350.739942 -338.265589)
			(xy 350.739456 -338.238338) (xy 345.363554 -338.238338) (xy 345.351595 -338.256947) (xy 345.315904 -338.298138)
			(xy 345.274713 -338.333829) (xy 345.228863 -338.363295) (xy 345.179286 -338.385937) (xy 345.126991 -338.401292)
			(xy 345.073043 -338.409048) (xy 345.018541 -338.409048) (xy 344.964593 -338.401292) (xy 344.912298 -338.385937)
			(xy 344.862721 -338.363295) (xy 344.816871 -338.333829) (xy 344.77568 -338.298138) (xy 344.739989 -338.256947)
			(xy 344.710523 -338.211097) (xy 344.687881 -338.16152) (xy 344.672526 -338.109225) (xy 344.66477 -338.055277)
			(xy 344.664284 -338.028026) (xy 344.664284 -338.027772) (xy 344.66486 -337.997933) (xy 344.674175 -337.938987)
			(xy 344.682826 -337.910424) (xy 344.686863 -337.896517) (xy 344.687767 -337.867586) (xy 344.6805 -337.839567)
			(xy 344.665647 -337.814723) (xy 344.644409 -337.795057) (xy 344.618497 -337.782157) (xy 344.60434 -337.779106)
			(xy 344.571503 -337.772515) (xy 344.508649 -337.749398) (xy 344.479372 -337.733132) (xy 344.466407 -337.726095)
			(xy 344.437771 -337.719064) (xy 344.40832 -337.72051) (xy 344.38051 -337.730312) (xy 344.35666 -337.747652)
			(xy 344.338761 -337.771085) (xy 344.333068 -337.784694) (xy 344.322329 -337.811452) (xy 344.294047 -337.861692)
			(xy 344.258523 -337.907102) (xy 344.216568 -337.946646) (xy 344.169137 -337.979422) (xy 344.117312 -338.004683)
			(xy 344.062274 -338.021853) (xy 344.005279 -338.030541) (xy 343.976452 -338.031074) (xy 343.949201 -338.030653)
			(xy 343.895253 -338.02289) (xy 343.84296 -338.007529) (xy 343.793384 -337.984884) (xy 343.747536 -337.955413)
			(xy 343.706347 -337.919719) (xy 343.670658 -337.878526) (xy 343.641193 -337.832674) (xy 343.618554 -337.783095)
			(xy 343.6032 -337.7308) (xy 343.595444 -337.676851) (xy 343.275257 -337.676851) (xy 343.25272 -337.708267)
			(xy 343.211052 -337.75057) (xy 343.187528 -337.768692) (xy 343.176892 -337.777086) (xy 343.160179 -337.798404)
			(xy 343.149658 -337.823366) (xy 343.14607 -337.850216) (xy 343.149666 -337.877064) (xy 343.160195 -337.902023)
			(xy 343.176914 -337.923336) (xy 343.187528 -337.93176) (xy 343.211073 -337.949853) (xy 343.25273 -337.992167)
			(xy 343.28733 -338.040423) (xy 343.314037 -338.093456) (xy 343.332205 -338.149986) (xy 343.341398 -338.208649)
			(xy 343.34196 -338.238338) (xy 343.341474 -338.265589) (xy 343.333718 -338.319537) (xy 343.318363 -338.371832)
			(xy 343.295721 -338.421409) (xy 343.266255 -338.467259) (xy 343.230564 -338.50845) (xy 343.189373 -338.544141)
			(xy 343.143523 -338.573607) (xy 343.093946 -338.596249) (xy 343.041651 -338.611604) (xy 342.987703 -338.61936)
			(xy 342.933201 -338.61936) (xy 342.879253 -338.611604) (xy 342.826958 -338.596249) (xy 342.777381 -338.573607)
			(xy 342.731531 -338.544141) (xy 342.69034 -338.50845) (xy 342.654649 -338.467259) (xy 342.625183 -338.421409)
			(xy 342.602541 -338.371832) (xy 342.587186 -338.319537) (xy 342.57943 -338.265589) (xy 342.578944 -338.238338)
			(xy 333.469256 -338.238338) (xy 333.468416 -338.240168) (xy 333.464238 -338.269079) (xy 333.468404 -338.297992)
			(xy 333.480574 -338.324547) (xy 333.489808 -338.335874) (xy 333.50745 -338.356804) (xy 333.537161 -338.402778)
			(xy 333.559996 -338.452526) (xy 333.575487 -338.505027) (xy 333.583314 -338.559203) (xy 333.583788 -338.586572)
			(xy 333.583302 -338.613823) (xy 333.575546 -338.667771) (xy 333.560191 -338.720066) (xy 333.537549 -338.769643)
			(xy 333.508083 -338.815493) (xy 333.472392 -338.856684) (xy 333.431201 -338.892375) (xy 333.385351 -338.921841)
			(xy 333.335774 -338.944483) (xy 333.283479 -338.959838) (xy 333.229531 -338.967594) (xy 333.175029 -338.967594)
			(xy 333.121081 -338.959838) (xy 333.068786 -338.944483) (xy 333.019209 -338.921841) (xy 332.973359 -338.892375)
			(xy 332.932168 -338.856684) (xy 332.896477 -338.815493) (xy 332.867011 -338.769643) (xy 332.844369 -338.720066)
			(xy 332.829014 -338.667771) (xy 332.821258 -338.613823) (xy 332.820772 -338.586572) (xy 318.840612 -338.586572)
			(xy 318.840612 -338.9892) (xy 337.069421 -338.9892) (xy 337.073589 -338.933585) (xy 337.085998 -338.879212)
			(xy 337.106372 -338.827295) (xy 337.134256 -338.778995) (xy 337.169027 -338.73539) (xy 337.209907 -338.697453)
			(xy 337.255985 -338.666033) (xy 337.306231 -338.64183) (xy 337.359523 -338.625386) (xy 337.41467 -338.617068)
			(xy 337.442556 -338.616544) (xy 337.469888 -338.617013) (xy 337.523968 -338.624982) (xy 337.576303 -338.64077)
			(xy 337.625767 -338.664039) (xy 337.6713 -338.694287) (xy 337.711922 -338.730866) (xy 337.746761 -338.772989)
			(xy 337.761326 -338.796122) (xy 337.769241 -338.808351) (xy 337.790716 -338.82802) (xy 337.816871 -338.840823)
			(xy 337.845578 -338.845717) (xy 337.874498 -338.842304) (xy 337.888072 -338.837016) (xy 337.911288 -338.827544)
			(xy 337.959618 -338.814186) (xy 338.009305 -338.807451) (xy 338.034376 -338.807044) (xy 338.059446 -338.807454)
			(xy 338.109129 -338.814209) (xy 338.157463 -338.827547) (xy 338.18068 -338.837016) (xy 338.194253 -338.842275)
			(xy 338.223156 -338.845636) (xy 338.251835 -338.840723) (xy 338.27797 -338.827931) (xy 338.299445 -338.808297)
			(xy 338.307426 -338.796122) (xy 338.321995 -338.772991) (xy 338.356838 -338.73087) (xy 338.397461 -338.694291)
			(xy 338.442992 -338.66404) (xy 338.492454 -338.640764) (xy 338.544785 -338.624964) (xy 338.598864 -338.616978)
			(xy 338.653528 -338.616978) (xy 338.707607 -338.624964) (xy 338.759938 -338.640764) (xy 338.8094 -338.66404)
			(xy 338.854931 -338.694291) (xy 338.895554 -338.73087) (xy 338.930397 -338.772991) (xy 338.944966 -338.796122)
			(xy 338.952843 -338.808379) (xy 338.974328 -338.828047) (xy 339.000494 -338.840846) (xy 339.029209 -338.845733)
			(xy 339.058136 -338.84231) (xy 339.071712 -338.837016) (xy 339.094924 -338.827531) (xy 339.143256 -338.814178)
			(xy 339.192945 -338.807448) (xy 339.218016 -338.807044) (xy 339.245655 -338.807541) (xy 339.300322 -338.815736)
			(xy 339.35318 -338.831914) (xy 339.40307 -338.85572) (xy 339.448896 -338.886633) (xy 339.489656 -338.923974)
			(xy 339.524454 -338.966925) (xy 339.552528 -339.014544) (xy 339.573262 -339.065786) (xy 339.58022 -339.09254)
			(xy 339.583825 -339.105648) (xy 339.596965 -339.129436) (xy 339.615914 -339.148918) (xy 339.639329 -339.162712)
			(xy 339.665554 -339.169842) (xy 339.69273 -339.169804) (xy 339.718934 -339.1626) (xy 339.730842 -339.15604)
			(xy 339.752965 -339.143433) (xy 339.799854 -339.123576) (xy 339.84897 -339.110142) (xy 339.899438 -339.103372)
			(xy 339.924898 -339.102954) (xy 339.93201 -339.102954) (xy 339.947094 -339.102679) (xy 339.976082 -339.094373)
			(xy 340.001392 -339.07798) (xy 340.020827 -339.054924) (xy 340.032701 -339.027205) (xy 340.03488 -339.012276)
			(xy 340.038284 -338.984522) (xy 340.052283 -338.930385) (xy 340.07403 -338.878869) (xy 340.103059 -338.831077)
			(xy 340.13875 -338.788031) (xy 340.180338 -338.750652) (xy 340.226935 -338.71974) (xy 340.277543 -338.695956)
			(xy 340.331079 -338.67981) (xy 340.386397 -338.671646) (xy 340.414356 -338.671154) (xy 340.441606 -338.671696)
			(xy 340.495552 -338.679446) (xy 340.547846 -338.694795) (xy 340.597424 -338.717429) (xy 340.643275 -338.746889)
			(xy 340.684467 -338.782575) (xy 340.720162 -338.823759) (xy 340.749631 -338.869604) (xy 340.772277 -338.919177)
			(xy 340.787636 -338.971468) (xy 340.790187 -338.9892) (xy 377.871895 -338.9892) (xy 377.876064 -338.933575)
			(xy 377.888477 -338.879193) (xy 377.908856 -338.827269) (xy 377.936747 -338.778961) (xy 377.971527 -338.735351)
			(xy 378.012418 -338.697411) (xy 378.058507 -338.66599) (xy 378.108764 -338.641789) (xy 378.162068 -338.625349)
			(xy 378.217226 -338.617038) (xy 378.245116 -338.616544) (xy 378.27245 -338.616965) (xy 378.326532 -338.624943)
			(xy 378.378868 -338.64074) (xy 378.428332 -338.664016) (xy 378.473864 -338.694271) (xy 378.514485 -338.730857)
			(xy 378.549322 -338.772986) (xy 378.563886 -338.796122) (xy 378.571839 -338.808324) (xy 378.593304 -338.827993)
			(xy 378.619449 -338.840799) (xy 378.648146 -338.8457) (xy 378.677059 -338.842298) (xy 378.690632 -338.837016)
			(xy 378.713841 -338.827525) (xy 378.762174 -338.814174) (xy 378.811864 -338.807447) (xy 378.836936 -338.807044)
			(xy 378.862005 -338.807467) (xy 378.911688 -338.814217) (xy 378.960023 -338.82755) (xy 378.98324 -338.837016)
			(xy 378.996827 -338.842232) (xy 379.025723 -338.845603) (xy 379.054397 -338.840699) (xy 379.08053 -338.827917)
			(xy 379.102005 -338.808293) (xy 379.109986 -338.796122) (xy 379.124555 -338.772991) (xy 379.159398 -338.73087)
			(xy 379.200021 -338.694291) (xy 379.245552 -338.66404) (xy 379.295014 -338.640764) (xy 379.347345 -338.624964)
			(xy 379.401424 -338.616978) (xy 379.456088 -338.616978) (xy 379.510167 -338.624964) (xy 379.562498 -338.640764)
			(xy 379.61196 -338.66404) (xy 379.657491 -338.694291) (xy 379.698114 -338.73087) (xy 379.732957 -338.772991)
			(xy 379.747526 -338.796122) (xy 379.755441 -338.808351) (xy 379.776916 -338.82802) (xy 379.803071 -338.840823)
			(xy 379.831778 -338.845717) (xy 379.860698 -338.842304) (xy 379.874272 -338.837016) (xy 379.897488 -338.827544)
			(xy 379.945818 -338.814186) (xy 379.995505 -338.807451) (xy 380.020576 -338.807044) (xy 380.045517 -338.807416)
			(xy 380.094955 -338.814065) (xy 380.143064 -338.827247) (xy 380.188986 -338.846727) (xy 380.231899 -338.872158)
			(xy 380.251716 -338.887308) (xy 380.26328 -338.895793) (xy 380.289788 -338.906699) (xy 380.318285 -338.909788)
			(xy 380.346513 -338.904813) (xy 380.372238 -338.89217) (xy 380.393421 -338.872859) (xy 380.401322 -338.860892)
			(xy 380.416313 -338.837415) (xy 380.451977 -338.794632) (xy 380.493486 -338.757491) (xy 380.539956 -338.726784)
			(xy 380.590398 -338.703162) (xy 380.64374 -338.68713) (xy 380.698846 -338.679027) (xy 380.726696 -338.67852)
			(xy 380.754851 -338.678952) (xy 380.810552 -338.687216) (xy 380.864433 -338.703578) (xy 380.915323 -338.727684)
			(xy 380.962116 -338.75901) (xy 381.003795 -338.796875) (xy 381.039454 -338.840456) (xy 381.068319 -338.888806)
			(xy 381.089761 -338.940874) (xy 381.097028 -338.96808) (xy 381.101361 -338.983027) (xy 381.117615 -339.009543)
			(xy 381.141093 -339.029942) (xy 381.169619 -339.042335) (xy 381.200552 -339.045572) (xy 381.2159 -339.04301)
			(xy 381.234621 -339.039456) (xy 381.272538 -339.035641) (xy 381.291592 -339.03539) (xy 381.291846 -339.03539)
			(xy 381.319095 -339.035883) (xy 381.373037 -339.043645) (xy 381.425326 -339.059004) (xy 381.474898 -339.081647)
			(xy 381.520742 -339.111115) (xy 381.561926 -339.146806) (xy 381.597613 -339.187995) (xy 381.627075 -339.233843)
			(xy 381.649712 -339.283417) (xy 381.665065 -339.335708) (xy 381.67282 -339.389651) (xy 381.67282 -339.444149)
			(xy 381.665065 -339.498092) (xy 381.649712 -339.550383) (xy 381.627075 -339.599957) (xy 381.597613 -339.645805)
			(xy 381.561926 -339.686994) (xy 381.520742 -339.722685) (xy 381.474898 -339.752153) (xy 381.425326 -339.774796)
			(xy 381.373037 -339.790155) (xy 381.319095 -339.797917) (xy 381.291846 -339.798406) (xy 381.263693 -339.797916)
			(xy 381.207995 -339.789659) (xy 381.154117 -339.773304) (xy 381.103229 -339.749205) (xy 381.056436 -339.717886)
			(xy 381.014757 -339.680028) (xy 380.979096 -339.636454) (xy 380.950229 -339.588111) (xy 380.928783 -339.536049)
			(xy 380.921514 -339.508846) (xy 380.917228 -339.493882) (xy 380.900967 -339.467358) (xy 380.877478 -339.446956)
			(xy 380.848939 -339.434569) (xy 380.817994 -339.431344) (xy 380.802642 -339.433916) (xy 380.783858 -339.437482)
			(xy 380.745814 -339.4413) (xy 380.726696 -339.441536) (xy 380.726442 -339.441536) (xy 380.700302 -339.441074)
			(xy 380.648512 -339.433943) (xy 380.598183 -339.419797) (xy 380.550262 -339.3989) (xy 380.505649 -339.371646)
			(xy 380.485142 -339.35543) (xy 380.473724 -339.346722) (xy 380.44736 -339.335384) (xy 380.41888 -339.33185)
			(xy 380.390544 -339.3364) (xy 380.364601 -339.348673) (xy 380.343112 -339.367694) (xy 380.335028 -339.37956)
			(xy 380.3293 -339.388435) (xy 380.316971 -339.405588) (xy 380.31039 -339.41385) (xy 380.301159 -339.426158)
			(xy 380.289769 -339.454718) (xy 380.287381 -339.485373) (xy 380.29421 -339.515353) (xy 380.30964 -339.541948)
			(xy 380.332277 -339.562757) (xy 380.34595 -339.569806) (xy 380.369084 -339.581162) (xy 380.412323 -339.609201)
			(xy 380.451386 -339.642814) (xy 380.485561 -339.681387) (xy 380.514222 -339.724216) (xy 380.536847 -339.770519)
			(xy 380.54534 -339.79485) (xy 380.550438 -339.808602) (xy 380.567205 -339.832649) (xy 380.590102 -339.850956)
			(xy 380.61725 -339.862021) (xy 380.64642 -339.864934) (xy 380.66091 -339.862668) (xy 380.678646 -339.859483)
			(xy 380.71452 -339.856046) (xy 380.732538 -339.85581) (xy 380.7333 -339.85581) (xy 380.760554 -339.856255)
			(xy 380.814506 -339.864013) (xy 380.866805 -339.87937) (xy 380.916387 -339.902014) (xy 380.962241 -339.931483)
			(xy 381.003434 -339.967179) (xy 381.039128 -340.008374) (xy 381.068595 -340.054229) (xy 381.091237 -340.103811)
			(xy 381.106591 -340.156111) (xy 381.114346 -340.210064) (xy 381.114808 -340.237318) (xy 381.114554 -340.247732)
			(xy 381.114676 -340.262099) (xy 381.12194 -340.289884) (xy 381.136646 -340.31455) (xy 381.157635 -340.334151)
			(xy 381.183249 -340.347138) (xy 381.211465 -340.352486) (xy 381.225806 -340.351618) (xy 381.262382 -340.34984)
			(xy 381.289639 -340.350206) (xy 381.343599 -340.357962) (xy 381.395906 -340.373318) (xy 381.445494 -340.395962)
			(xy 381.491355 -340.425434) (xy 381.532555 -340.461132) (xy 381.568256 -340.50233) (xy 381.597729 -340.54819)
			(xy 381.620376 -340.597778) (xy 381.635735 -340.650084) (xy 381.643493 -340.704043) (xy 381.643493 -340.758557)
			(xy 381.635735 -340.812516) (xy 381.620376 -340.864822) (xy 381.597729 -340.91441) (xy 381.568256 -340.96027)
			(xy 381.532555 -341.001468) (xy 381.491355 -341.037166) (xy 381.445494 -341.066638) (xy 381.395906 -341.089282)
			(xy 381.343599 -341.104638) (xy 381.289639 -341.112394) (xy 381.262382 -341.112856) (xy 381.251371 -341.112781)
			(xy 381.229386 -341.111508) (xy 381.21844 -341.110316) (xy 381.203582 -341.109091) (xy 381.174247 -341.11434)
			(xy 381.14768 -341.12784) (xy 381.126144 -341.148439) (xy 381.111478 -341.17438) (xy 381.107696 -341.188802)
			(xy 381.100847 -341.216546) (xy 381.07999 -341.269747) (xy 381.051435 -341.319245) (xy 381.015821 -341.363933)
			(xy 380.973944 -341.402814) (xy 380.926739 -341.435018) (xy 380.875262 -341.459826) (xy 380.820661 -341.476683)
			(xy 380.764158 -341.485214) (xy 380.735586 -341.485728) (xy 380.706599 -341.485189) (xy 380.649292 -341.476416)
			(xy 380.593972 -341.459074) (xy 380.541912 -341.433561) (xy 380.494312 -341.400467) (xy 380.452267 -341.360551)
			(xy 380.416744 -341.314734) (xy 380.388562 -341.26407) (xy 380.36837 -341.209726) (xy 380.356632 -341.152952)
			(xy 380.354586 -341.124032) (xy 380.353411 -341.109958) (xy 380.34432 -341.083231) (xy 380.328247 -341.060024)
			(xy 380.306424 -341.042115) (xy 380.280526 -341.030879) (xy 380.252539 -341.027179) (xy 380.238508 -341.028782)
			(xy 380.224743 -341.030678) (xy 380.19703 -341.032711) (xy 380.183136 -341.032846) (xy 380.155887 -341.032288)
			(xy 380.101944 -341.024538) (xy 380.049653 -341.009189) (xy 380.000079 -340.986555) (xy 379.95423 -340.957096)
			(xy 379.91304 -340.921412) (xy 379.877348 -340.880229) (xy 379.847881 -340.834386) (xy 379.825237 -340.784816)
			(xy 379.809878 -340.732528) (xy 379.802117 -340.678587) (xy 379.801628 -340.651338) (xy 379.80211 -340.623764)
			(xy 379.810058 -340.569191) (xy 379.825779 -340.516331) (xy 379.848946 -340.466285) (xy 379.879076 -340.420095)
			(xy 379.915542 -340.378724) (xy 379.936248 -340.360508) (xy 379.947111 -340.350573) (xy 379.963193 -340.325935)
			(xy 379.971585 -340.297735) (xy 379.971592 -340.268314) (xy 379.963214 -340.24011) (xy 379.947144 -340.215464)
			(xy 379.936248 -340.205568) (xy 379.915528 -340.187366) (xy 379.879056 -340.145997) (xy 379.848924 -340.099805)
			(xy 379.825759 -340.049755) (xy 379.810046 -339.99689) (xy 379.80211 -339.942313) (xy 379.801628 -339.914738)
			(xy 379.802058 -339.888236) (xy 379.809408 -339.835744) (xy 379.823958 -339.784775) (xy 379.845426 -339.736313)
			(xy 379.8734 -339.691292) (xy 379.89002 -339.670644) (xy 379.899478 -339.658509) (xy 379.911271 -339.630105)
			(xy 379.914094 -339.59948) (xy 379.907695 -339.569399) (xy 379.892649 -339.542576) (xy 379.870316 -339.521432)
			(xy 379.856746 -339.51418) (xy 379.833054 -339.502083) (xy 379.789072 -339.472159) (xy 379.749792 -339.436287)
			(xy 379.716009 -339.395195) (xy 379.701806 -339.372702) (xy 379.693854 -339.360498) (xy 379.672391 -339.340827)
			(xy 379.646245 -339.328019) (xy 379.617547 -339.323119) (xy 379.588632 -339.326524) (xy 379.57506 -339.331808)
			(xy 379.551852 -339.341303) (xy 379.503518 -339.354652) (xy 379.453828 -339.361378) (xy 379.428756 -339.36178)
			(xy 379.403687 -339.361358) (xy 379.354004 -339.354608) (xy 379.305669 -339.341274) (xy 379.282452 -339.331808)
			(xy 379.26887 -339.326573) (xy 379.239972 -339.323203) (xy 379.211294 -339.32811) (xy 379.18516 -339.340897)
			(xy 379.163686 -339.360528) (xy 379.155706 -339.372702) (xy 379.141137 -339.395833) (xy 379.106294 -339.437954)
			(xy 379.065671 -339.474533) (xy 379.02014 -339.504784) (xy 378.970678 -339.52806) (xy 378.918347 -339.54386)
			(xy 378.864268 -339.551846) (xy 378.809604 -339.551846) (xy 378.755525 -339.54386) (xy 378.703194 -339.52806)
			(xy 378.653732 -339.504784) (xy 378.608201 -339.474533) (xy 378.567578 -339.437954) (xy 378.532735 -339.395833)
			(xy 378.518166 -339.372702) (xy 378.510252 -339.360471) (xy 378.488779 -339.340799) (xy 378.462623 -339.327995)
			(xy 378.433915 -339.323102) (xy 378.404994 -339.326518) (xy 378.39142 -339.331808) (xy 378.368205 -339.341284)
			(xy 378.319875 -339.35464) (xy 378.270187 -339.361374) (xy 378.245116 -339.36178) (xy 378.217226 -339.361362)
			(xy 378.162068 -339.353051) (xy 378.108764 -339.336611) (xy 378.058507 -339.31241) (xy 378.012418 -339.280989)
			(xy 377.971527 -339.243049) (xy 377.936747 -339.199439) (xy 377.908856 -339.151131) (xy 377.888477 -339.099207)
			(xy 377.876064 -339.044825) (xy 377.871895 -338.9892) (xy 340.790187 -338.9892) (xy 340.795398 -339.025412)
			(xy 340.795864 -339.052662) (xy 340.795316 -339.082032) (xy 340.786317 -339.14008) (xy 340.768526 -339.196061)
			(xy 340.742363 -339.248654) (xy 340.708447 -339.296614) (xy 340.66758 -339.338808) (xy 340.64448 -339.356954)
			(xy 340.633399 -339.366027) (xy 340.616251 -339.388944) (xy 340.606145 -339.415722) (xy 340.603874 -339.444253)
			(xy 340.609619 -339.472293) (xy 340.622926 -339.497633) (xy 340.642749 -339.518279) (xy 340.654894 -339.525864)
			(xy 340.679326 -339.540649) (xy 340.723967 -339.576255) (xy 340.762805 -339.618116) (xy 340.794972 -339.665295)
			(xy 340.819752 -339.716741) (xy 340.836589 -339.771304) (xy 340.845109 -339.827767) (xy 340.845648 -339.856318)
			(xy 340.845255 -339.882212) (xy 340.838252 -339.933526) (xy 340.824365 -339.983418) (xy 340.803849 -340.03097)
			(xy 340.777082 -340.075305) (xy 340.744557 -340.115607) (xy 340.726014 -340.133686) (xy 340.715911 -340.143825)
			(xy 340.701296 -340.168419) (xy 340.694088 -340.196105) (xy 340.694855 -340.224704) (xy 340.703535 -340.251965)
			(xy 340.719447 -340.275741) (xy 340.730078 -340.285324) (xy 340.750901 -340.30352) (xy 340.787573 -340.344907)
			(xy 340.817878 -340.39116) (xy 340.841179 -340.441307) (xy 340.856987 -340.494296) (xy 340.864971 -340.549014)
			(xy 340.86546 -340.576662) (xy 340.865009 -340.603916) (xy 340.861078 -340.631272) (xy 374.003316 -340.631272)
			(xy 374.003769 -340.603734) (xy 374.011666 -340.549227) (xy 374.027321 -340.496423) (xy 374.050409 -340.44642)
			(xy 374.080448 -340.400257) (xy 374.116816 -340.358896) (xy 374.158754 -340.323195) (xy 374.205391 -340.293897)
			(xy 374.255757 -340.271613) (xy 374.308805 -340.256804) (xy 374.336056 -340.252812) (xy 374.349853 -340.250659)
			(xy 374.375538 -340.239719) (xy 374.397306 -340.222238) (xy 374.413534 -340.199522) (xy 374.423013 -340.173262)
			(xy 374.425036 -340.145418) (xy 374.42267 -340.131654) (xy 374.419017 -340.112687) (xy 374.415068 -340.07426)
			(xy 374.414796 -340.054946) (xy 374.415298 -340.027694) (xy 374.423049 -339.973744) (xy 374.438399 -339.921447)
			(xy 374.461037 -339.871867) (xy 374.4905 -339.826013) (xy 374.52619 -339.78482) (xy 374.56738 -339.749126)
			(xy 374.61323 -339.719657) (xy 374.662808 -339.697014) (xy 374.715103 -339.681658) (xy 374.769052 -339.673901)
			(xy 374.796304 -339.673438) (xy 374.823559 -339.673852) (xy 374.877514 -339.68161) (xy 374.929816 -339.696969)
			(xy 374.979399 -339.719616) (xy 375.025254 -339.749088) (xy 375.066448 -339.784787) (xy 375.102142 -339.825986)
			(xy 375.131608 -339.871845) (xy 375.154248 -339.921431) (xy 375.1696 -339.973735) (xy 375.177352 -340.027691)
			(xy 375.177812 -340.054946) (xy 375.177351 -340.082484) (xy 375.169452 -340.136989) (xy 375.153796 -340.189791)
			(xy 375.130709 -340.239793) (xy 375.10067 -340.285954) (xy 375.064304 -340.327316) (xy 375.022367 -340.363016)
			(xy 374.975732 -340.392315) (xy 374.925368 -340.414601) (xy 374.872322 -340.429412) (xy 374.845072 -340.433406)
			(xy 374.831299 -340.435672) (xy 374.805626 -340.446595) (xy 374.783863 -340.464053) (xy 374.767632 -340.486746)
			(xy 374.758143 -340.512982) (xy 374.756103 -340.540807) (xy 374.758458 -340.554564) (xy 374.762114 -340.573531)
			(xy 374.766061 -340.611958) (xy 374.766332 -340.631272) (xy 374.765819 -340.658523) (xy 374.758066 -340.712471)
			(xy 374.742715 -340.764766) (xy 374.720077 -340.814345) (xy 374.690615 -340.860197) (xy 374.654926 -340.901389)
			(xy 374.613739 -340.937083) (xy 374.567891 -340.966552) (xy 374.518315 -340.989197) (xy 374.466022 -341.004555)
			(xy 374.412075 -341.012315) (xy 374.384824 -341.01278) (xy 374.35757 -341.012322) (xy 374.303618 -341.004568)
			(xy 374.251318 -340.989213) (xy 374.201736 -340.966572) (xy 374.155882 -340.937104) (xy 374.114688 -340.901409)
			(xy 374.078994 -340.860215) (xy 374.049526 -340.81436) (xy 374.026885 -340.764778) (xy 374.011531 -340.712478)
			(xy 374.003777 -340.658526) (xy 374.003316 -340.631272) (xy 340.861078 -340.631272) (xy 340.857256 -340.65787)
			(xy 340.841903 -340.710171) (xy 340.819261 -340.759754) (xy 340.789792 -340.80561) (xy 340.754097 -340.846804)
			(xy 340.712902 -340.882498) (xy 340.667045 -340.911966) (xy 340.617462 -340.934606) (xy 340.56516 -340.949958)
			(xy 340.511206 -340.95771) (xy 340.483952 -340.95817) (xy 340.454875 -340.957639) (xy 340.397395 -340.948821)
			(xy 340.341918 -340.93138) (xy 340.289732 -340.905722) (xy 340.242044 -340.872441) (xy 340.19996 -340.832307)
			(xy 340.164454 -340.786251) (xy 340.136351 -340.735339) (xy 340.125812 -340.708234) (xy 340.120356 -340.694656)
			(xy 340.102875 -340.671198) (xy 340.07946 -340.653661) (xy 340.052032 -340.643485) (xy 340.022844 -340.641505)
			(xy 340.008464 -340.644226) (xy 339.988029 -340.648495) (xy 339.946534 -340.653076) (xy 339.92566 -340.65337)
			(xy 339.925152 -340.65337) (xy 339.910936 -340.653208) (xy 339.882586 -340.65105) (xy 339.86851 -340.649052)
			(xy 339.853186 -340.647282) (xy 339.822729 -340.652112) (xy 339.795094 -340.665797) (xy 339.772792 -340.687094)
			(xy 339.757848 -340.714069) (xy 339.75421 -340.729062) (xy 339.747713 -340.757293) (xy 339.727473 -340.811567)
			(xy 339.699262 -340.862158) (xy 339.663727 -340.907903) (xy 339.621687 -340.947751) (xy 339.574106 -340.980787)
			(xy 339.522078 -341.006251) (xy 339.466799 -341.023558) (xy 339.409539 -341.03231) (xy 339.380576 -341.032846)
			(xy 339.353326 -341.032345) (xy 339.299381 -341.024586) (xy 339.247089 -341.00923) (xy 339.197514 -340.986588)
			(xy 339.151665 -340.957123) (xy 339.110476 -340.921434) (xy 339.074785 -340.880246) (xy 339.045318 -340.834399)
			(xy 339.022675 -340.784825) (xy 339.007317 -340.732533) (xy 338.999556 -340.678588) (xy 338.999068 -340.651338)
			(xy 338.999571 -340.623765) (xy 339.007517 -340.569194) (xy 339.023236 -340.516336) (xy 339.046399 -340.46629)
			(xy 339.076524 -340.420099) (xy 339.112984 -340.378726) (xy 339.133688 -340.360508) (xy 339.144548 -340.350571)
			(xy 339.160623 -340.325932) (xy 339.169012 -340.297734) (xy 339.169019 -340.268315) (xy 339.160644 -340.240113)
			(xy 339.14458 -340.215466) (xy 339.133688 -340.205568) (xy 339.112956 -340.18738) (xy 339.076488 -340.146006)
			(xy 339.046358 -340.099811) (xy 339.023196 -340.049759) (xy 339.007484 -339.996892) (xy 338.99955 -339.942314)
			(xy 338.999068 -339.914738) (xy 338.999512 -339.888237) (xy 339.006861 -339.835745) (xy 339.021408 -339.784778)
			(xy 339.042873 -339.736316) (xy 339.070842 -339.691293) (xy 339.08746 -339.670644) (xy 339.096904 -339.6585)
			(xy 339.10869 -339.630099) (xy 339.111512 -339.599479) (xy 339.105115 -339.569402) (xy 339.090076 -339.542581)
			(xy 339.067752 -339.521435) (xy 339.054186 -339.51418) (xy 339.0305 -339.502071) (xy 338.986517 -339.472151)
			(xy 338.947235 -339.436283) (xy 338.91345 -339.395194) (xy 338.899246 -339.372702) (xy 338.891351 -339.360457)
			(xy 338.869873 -339.340786) (xy 338.843711 -339.327983) (xy 338.814999 -339.323094) (xy 338.786075 -339.326515)
			(xy 338.7725 -339.331808) (xy 338.749287 -339.34129) (xy 338.700956 -339.354644) (xy 338.651267 -339.361375)
			(xy 338.626196 -339.36178) (xy 338.601127 -339.361345) (xy 338.551444 -339.3546) (xy 338.50311 -339.341272)
			(xy 338.479892 -339.331808) (xy 338.466296 -339.326615) (xy 338.437405 -339.323236) (xy 338.408732 -339.328134)
			(xy 338.3826 -339.340911) (xy 338.361126 -339.360532) (xy 338.353146 -339.372702) (xy 338.338577 -339.395833)
			(xy 338.303734 -339.437954) (xy 338.263111 -339.474533) (xy 338.21758 -339.504784) (xy 338.168118 -339.52806)
			(xy 338.115787 -339.54386) (xy 338.061708 -339.551846) (xy 338.007044 -339.551846) (xy 337.952965 -339.54386)
			(xy 337.900634 -339.52806) (xy 337.851172 -339.504784) (xy 337.805641 -339.474533) (xy 337.765018 -339.437954)
			(xy 337.730175 -339.395833) (xy 337.715606 -339.372702) (xy 337.707654 -339.360498) (xy 337.686191 -339.340827)
			(xy 337.660045 -339.328019) (xy 337.631347 -339.323119) (xy 337.602432 -339.326524) (xy 337.58886 -339.331808)
			(xy 337.565652 -339.341303) (xy 337.517318 -339.354652) (xy 337.467628 -339.361378) (xy 337.442556 -339.36178)
			(xy 337.41467 -339.361332) (xy 337.359523 -339.353014) (xy 337.306231 -339.33657) (xy 337.255985 -339.312367)
			(xy 337.209907 -339.280947) (xy 337.169027 -339.24301) (xy 337.134256 -339.199405) (xy 337.106372 -339.151105)
			(xy 337.085998 -339.099188) (xy 337.073589 -339.044815) (xy 337.069421 -338.9892) (xy 318.840612 -338.9892)
			(xy 318.840612 -340.054946) (xy 333.611726 -340.054946) (xy 333.615797 -339.999324) (xy 333.627923 -339.944887)
			(xy 333.647846 -339.892796) (xy 333.675142 -339.844161) (xy 333.709228 -339.800018) (xy 333.749377 -339.761309)
			(xy 333.794735 -339.728858) (xy 333.844335 -339.703357) (xy 333.897119 -339.68535) (xy 333.951962 -339.67522)
			(xy 334.007696 -339.673183) (xy 334.063133 -339.679283) (xy 334.11709 -339.693389) (xy 334.168419 -339.715201)
			(xy 334.216025 -339.744255) (xy 334.258893 -339.77993) (xy 334.29611 -339.821467) (xy 334.326883 -339.86798)
			(xy 334.350555 -339.918477) (xy 334.366623 -339.971884) (xy 334.374743 -340.02706) (xy 334.375252 -340.054946)
			(xy 334.374743 -340.082832) (xy 334.366623 -340.138008) (xy 334.350555 -340.191415) (xy 334.326883 -340.241912)
			(xy 334.29611 -340.288425) (xy 334.258893 -340.329962) (xy 334.216025 -340.365637) (xy 334.168419 -340.394691)
			(xy 334.11709 -340.416503) (xy 334.063133 -340.430609) (xy 334.007696 -340.436709) (xy 333.951962 -340.434672)
			(xy 333.897119 -340.424542) (xy 333.844335 -340.406535) (xy 333.794735 -340.381034) (xy 333.749377 -340.348583)
			(xy 333.709228 -340.309874) (xy 333.675142 -340.265731) (xy 333.647846 -340.217096) (xy 333.627923 -340.165005)
			(xy 333.615797 -340.110568) (xy 333.611726 -340.054946) (xy 318.840612 -340.054946) (xy 318.840612 -341.013288)
			(xy 333.031082 -341.013288) (xy 333.035153 -340.957666) (xy 333.047279 -340.903229) (xy 333.067202 -340.851138)
			(xy 333.094498 -340.802503) (xy 333.128584 -340.75836) (xy 333.168733 -340.719651) (xy 333.214091 -340.6872)
			(xy 333.263691 -340.661699) (xy 333.316475 -340.643692) (xy 333.371318 -340.633562) (xy 333.427052 -340.631525)
			(xy 333.482489 -340.637625) (xy 333.536446 -340.651731) (xy 333.587775 -340.673543) (xy 333.635381 -340.702597)
			(xy 333.678249 -340.738272) (xy 333.715466 -340.779809) (xy 333.746239 -340.826322) (xy 333.769911 -340.876819)
			(xy 333.785979 -340.930226) (xy 333.794099 -340.985402) (xy 333.794608 -341.013288) (xy 333.794099 -341.041174)
			(xy 333.785979 -341.09635) (xy 333.769911 -341.149757) (xy 333.746239 -341.200254) (xy 333.715466 -341.246767)
			(xy 333.678249 -341.288304) (xy 333.635381 -341.323979) (xy 333.587775 -341.353033) (xy 333.536446 -341.374845)
			(xy 333.482489 -341.388951) (xy 333.427052 -341.395051) (xy 333.371318 -341.393014) (xy 333.316475 -341.382884)
			(xy 333.263691 -341.364877) (xy 333.214091 -341.339376) (xy 333.168733 -341.306925) (xy 333.128584 -341.268216)
			(xy 333.094498 -341.224073) (xy 333.067202 -341.175438) (xy 333.047279 -341.123347) (xy 333.035153 -341.06891)
			(xy 333.031082 -341.013288) (xy 318.840612 -341.013288) (xy 318.840612 -342.603074) (xy 318.919606 -342.957912)
			(xy 318.923074 -342.971316) (xy 318.936139 -342.995711) (xy 318.95528 -343.015698) (xy 318.979089 -343.029804)
			(xy 319.005814 -343.036991) (xy 319.033487 -343.036731) (xy 319.060071 -343.029043) (xy 319.083611 -343.014491)
			(xy 319.102373 -342.994148) (xy 319.10909 -342.982042) (xy 319.121411 -342.958939) (xy 319.151432 -342.916043)
			(xy 319.187039 -342.877657) (xy 319.227563 -342.844504) (xy 319.272241 -342.817206) (xy 319.320235 -342.796277)
			(xy 319.37064 -342.78211) (xy 319.422509 -342.774973) (xy 319.448688 -342.774524) (xy 319.475939 -342.774986)
			(xy 319.529887 -342.782741) (xy 319.582182 -342.798095) (xy 319.631759 -342.820735) (xy 319.67761 -342.8502)
			(xy 319.718801 -342.885891) (xy 319.754493 -342.92708) (xy 319.783959 -342.97293) (xy 319.806601 -343.022507)
			(xy 319.821956 -343.074801) (xy 319.829713 -343.128749) (xy 319.829713 -343.183251) (xy 319.821956 -343.237199)
			(xy 319.806601 -343.289493) (xy 319.783959 -343.33907) (xy 319.754493 -343.38492) (xy 319.718801 -343.426109)
			(xy 319.67761 -343.4618) (xy 319.631759 -343.491265) (xy 319.582182 -343.513905) (xy 319.529887 -343.529259)
			(xy 319.475939 -343.537014) (xy 319.448688 -343.53754) (xy 319.423492 -343.537116) (xy 319.373542 -343.53045)
			(xy 319.324903 -343.517275) (xy 319.278417 -343.49782) (xy 319.234893 -343.472422) (xy 319.214754 -343.457276)
			(xy 319.203519 -343.449167) (xy 319.177869 -343.438718) (xy 319.150356 -343.435541) (xy 319.123 -343.43987)
			(xy 319.097811 -343.451386) (xy 319.07664 -343.469243) (xy 319.061043 -343.49213) (xy 319.052165 -343.518364)
			(xy 319.050658 -343.54602) (xy 319.05321 -343.559638) (xy 319.250384 -344.446606) (xy 324.569328 -344.446606)
			(xy 324.569934 -344.416953) (xy 324.579123 -344.358362) (xy 324.597265 -344.301898) (xy 324.623923 -344.24892)
			(xy 324.658456 -344.200704) (xy 324.700032 -344.15841) (xy 324.723506 -344.140282) (xy 324.735339 -344.13073)
			(xy 324.753323 -344.106233) (xy 324.763305 -344.077529) (xy 324.764401 -344.047159) (xy 324.756515 -344.017811)
			(xy 324.748906 -344.004646) (xy 324.735111 -343.981796) (xy 324.713366 -343.933051) (xy 324.698629 -343.88175)
			(xy 324.691187 -343.828896) (xy 324.69074 -343.802208) (xy 324.691226 -343.774957) (xy 324.698982 -343.721009)
			(xy 324.714337 -343.668714) (xy 324.736979 -343.619137) (xy 324.766445 -343.573287) (xy 324.802136 -343.532096)
			(xy 324.843327 -343.496405) (xy 324.889177 -343.466939) (xy 324.938754 -343.444297) (xy 324.991049 -343.428942)
			(xy 325.044997 -343.421186) (xy 325.099499 -343.421186) (xy 325.153447 -343.428942) (xy 325.205742 -343.444297)
			(xy 325.255319 -343.466939) (xy 325.301169 -343.496405) (xy 325.34236 -343.532096) (xy 325.378051 -343.573287)
			(xy 325.407517 -343.619137) (xy 325.430159 -343.668714) (xy 325.445514 -343.721009) (xy 325.45327 -343.774957)
			(xy 325.453756 -343.802208) (xy 325.453167 -343.831862) (xy 325.443975 -343.890454) (xy 325.42583 -343.946919)
			(xy 325.399169 -343.999897) (xy 325.364633 -344.048112) (xy 325.323054 -344.090405) (xy 325.299578 -344.108532)
			(xy 325.287732 -344.118069) (xy 325.26975 -344.142571) (xy 325.259772 -344.171279) (xy 325.258678 -344.201652)
			(xy 325.266567 -344.231003) (xy 325.274178 -344.244168) (xy 325.287977 -344.267016) (xy 325.309721 -344.315762)
			(xy 325.324457 -344.367063) (xy 325.331898 -344.419918) (xy 325.332344 -344.446606) (xy 325.331858 -344.473857)
			(xy 325.324102 -344.527805) (xy 325.308747 -344.5801) (xy 325.286105 -344.629677) (xy 325.256639 -344.675527)
			(xy 325.220948 -344.716718) (xy 325.179757 -344.752409) (xy 325.133907 -344.781875) (xy 325.08433 -344.804517)
			(xy 325.032035 -344.819872) (xy 324.978087 -344.827628) (xy 324.923585 -344.827628) (xy 324.869637 -344.819872)
			(xy 324.817342 -344.804517) (xy 324.767765 -344.781875) (xy 324.721915 -344.752409) (xy 324.680724 -344.716718)
			(xy 324.645033 -344.675527) (xy 324.615567 -344.629677) (xy 324.592925 -344.5801) (xy 324.57757 -344.527805)
			(xy 324.569814 -344.473857) (xy 324.569328 -344.446606) (xy 319.250384 -344.446606) (xy 319.362748 -344.952066)
			(xy 322.703442 -344.952066) (xy 322.707513 -344.896444) (xy 322.719639 -344.842007) (xy 322.739562 -344.789916)
			(xy 322.766858 -344.741281) (xy 322.800944 -344.697138) (xy 322.841093 -344.658429) (xy 322.886451 -344.625978)
			(xy 322.936051 -344.600477) (xy 322.988835 -344.58247) (xy 323.043678 -344.57234) (xy 323.099412 -344.570303)
			(xy 323.154849 -344.576403) (xy 323.208806 -344.590509) (xy 323.260135 -344.612321) (xy 323.307741 -344.641375)
			(xy 323.350609 -344.67705) (xy 323.387826 -344.718587) (xy 323.418599 -344.7651) (xy 323.442271 -344.815597)
			(xy 323.458339 -344.869004) (xy 323.466459 -344.92418) (xy 323.466968 -344.952066) (xy 323.46688 -344.956892)
			(xy 323.685406 -344.956892) (xy 323.689477 -344.90127) (xy 323.701603 -344.846833) (xy 323.721526 -344.794742)
			(xy 323.748822 -344.746107) (xy 323.782908 -344.701964) (xy 323.823057 -344.663255) (xy 323.868415 -344.630804)
			(xy 323.918015 -344.605303) (xy 323.970799 -344.587296) (xy 324.025642 -344.577166) (xy 324.081376 -344.575129)
			(xy 324.136813 -344.581229) (xy 324.19077 -344.595335) (xy 324.242099 -344.617147) (xy 324.289705 -344.646201)
			(xy 324.332573 -344.681876) (xy 324.36979 -344.723413) (xy 324.400563 -344.769926) (xy 324.424235 -344.820423)
			(xy 324.430065 -344.8398) (xy 328.939331 -344.8398) (xy 328.9435 -344.78418) (xy 328.955912 -344.729802)
			(xy 328.97629 -344.677882) (xy 329.004179 -344.629579) (xy 329.038956 -344.585973) (xy 329.079844 -344.548037)
			(xy 329.12593 -344.516619) (xy 329.176183 -344.492421) (xy 329.229482 -344.475983) (xy 329.284636 -344.467673)
			(xy 329.312524 -344.46718) (xy 329.339854 -344.467705) (xy 329.39393 -344.475668) (xy 329.446262 -344.491448)
			(xy 329.495725 -344.514708) (xy 329.541258 -344.544947) (xy 329.581882 -344.581516) (xy 329.616726 -344.62363)
			(xy 329.631294 -344.646758) (xy 329.639256 -344.658956) (xy 329.660714 -344.678632) (xy 329.686857 -344.691442)
			(xy 329.715555 -344.696344) (xy 329.744468 -344.692937) (xy 329.75804 -344.687652) (xy 329.781247 -344.678155)
			(xy 329.829581 -344.664808) (xy 329.879272 -344.658082) (xy 329.904344 -344.65768) (xy 329.929413 -344.658105)
			(xy 329.979096 -344.664855) (xy 330.02743 -344.678187) (xy 330.050648 -344.687652) (xy 330.064237 -344.692861)
			(xy 330.09313 -344.696228) (xy 330.121802 -344.691324) (xy 330.147934 -344.678545) (xy 330.16941 -344.658926)
			(xy 330.177394 -344.646758) (xy 330.191963 -344.623627) (xy 330.226806 -344.581506) (xy 330.267429 -344.544927)
			(xy 330.31296 -344.514676) (xy 330.362422 -344.4914) (xy 330.414753 -344.4756) (xy 330.468832 -344.467614)
			(xy 330.523496 -344.467614) (xy 330.577575 -344.4756) (xy 330.629906 -344.4914) (xy 330.679368 -344.514676)
			(xy 330.724899 -344.544927) (xy 330.765522 -344.581506) (xy 330.800365 -344.623627) (xy 330.814934 -344.646758)
			(xy 330.822858 -344.658983) (xy 330.844326 -344.678659) (xy 330.87048 -344.691467) (xy 330.899187 -344.696361)
			(xy 330.928107 -344.692944) (xy 330.94168 -344.687652) (xy 330.964894 -344.678174) (xy 331.013225 -344.664819)
			(xy 331.062913 -344.658086) (xy 331.087984 -344.65768) (xy 331.114841 -344.658135) (xy 331.167998 -344.665853)
			(xy 331.219498 -344.681117) (xy 331.268276 -344.703613) (xy 331.313321 -344.732873) (xy 331.353703 -344.768293)
			(xy 331.388585 -344.80914) (xy 331.417247 -344.854569) (xy 331.428598 -344.878914) (xy 331.434622 -344.891386)
			(xy 331.452244 -344.912739) (xy 331.474963 -344.92856) (xy 331.501102 -344.937683) (xy 331.528733 -344.939433)
			(xy 331.555814 -344.933682) (xy 331.568298 -344.927682) (xy 331.595667 -344.914076) (xy 331.653678 -344.894838)
			(xy 331.714015 -344.885101) (xy 331.744574 -344.884502) (xy 331.744828 -344.884502) (xy 331.767947 -344.884832)
			(xy 331.813848 -344.890401) (xy 331.858736 -344.90149) (xy 331.880464 -344.909394) (xy 331.894243 -344.914198)
			(xy 331.923328 -344.916452) (xy 331.951865 -344.910395) (xy 331.977527 -344.896521) (xy 331.998222 -344.87596)
			(xy 332.012263 -344.850389) (xy 332.015846 -344.836242) (xy 332.022456 -344.808278) (xy 332.043051 -344.754635)
			(xy 332.071459 -344.704687) (xy 332.107036 -344.659565) (xy 332.148979 -344.620289) (xy 332.196338 -344.587748)
			(xy 332.248042 -344.562678) (xy 332.302921 -344.545646) (xy 332.359733 -344.537038) (xy 332.388464 -344.536522)
			(xy 332.415717 -344.536989) (xy 332.46967 -344.544742) (xy 332.521969 -344.560095) (xy 332.571551 -344.582735)
			(xy 332.617406 -344.612202) (xy 332.6586 -344.647896) (xy 332.694294 -344.689089) (xy 332.723762 -344.734943)
			(xy 332.746403 -344.784525) (xy 332.761757 -344.836824) (xy 332.769511 -344.890777) (xy 332.769972 -344.91803)
			(xy 332.76953 -344.945401) (xy 332.761708 -344.999582) (xy 332.746213 -345.052085) (xy 332.723366 -345.101832)
			(xy 332.693636 -345.147797) (xy 332.675992 -345.168728) (xy 332.666727 -345.180034) (xy 332.654554 -345.2066)
			(xy 332.650387 -345.235523) (xy 332.654567 -345.264444) (xy 332.666752 -345.291004) (xy 332.675992 -345.302332)
			(xy 332.693611 -345.32328) (xy 332.723326 -345.369248) (xy 332.746166 -345.418992) (xy 332.761662 -345.471489)
			(xy 332.769495 -345.525662) (xy 332.769972 -345.55303) (xy 332.769468 -345.580603) (xy 332.761525 -345.635175)
			(xy 332.745808 -345.688034) (xy 332.722645 -345.738081) (xy 332.692519 -345.784271) (xy 332.656057 -345.825644)
			(xy 332.635352 -345.84386) (xy 332.62442 -345.853726) (xy 332.608341 -345.878383) (xy 332.599957 -345.906601)
			(xy 332.599962 -345.936038) (xy 332.608358 -345.964252) (xy 332.624446 -345.988904) (xy 332.635352 -345.9988)
			(xy 332.656057 -346.017018) (xy 332.69253 -346.058384) (xy 332.722664 -346.104572) (xy 332.745831 -346.154619)
			(xy 332.761548 -346.207481) (xy 332.769487 -346.262055) (xy 332.769972 -346.28963) (xy 332.769573 -346.316885)
			(xy 332.761811 -346.37084) (xy 332.746449 -346.423142) (xy 332.723801 -346.472724) (xy 332.694326 -346.518579)
			(xy 332.658626 -346.559772) (xy 332.617426 -346.595466) (xy 332.571566 -346.624932) (xy 332.52198 -346.647572)
			(xy 332.469676 -346.662925) (xy 332.415719 -346.670678) (xy 332.388464 -346.671138) (xy 332.360591 -346.670614)
			(xy 332.305439 -346.662496) (xy 332.252055 -346.646438) (xy 332.201576 -346.622782) (xy 332.155078 -346.592032)
			(xy 332.11355 -346.554842) (xy 332.077876 -346.512004) (xy 332.048817 -346.464431) (xy 332.037436 -346.438982)
			(xy 332.030807 -346.424806) (xy 332.01038 -346.401115) (xy 331.983751 -346.384701) (xy 331.953407 -346.377099)
			(xy 331.922185 -346.379018) (xy 331.907388 -346.384118) (xy 331.885475 -346.392177) (xy 331.840171 -346.403477)
			(xy 331.793828 -346.409168) (xy 331.770482 -346.409518) (xy 331.770228 -346.409518) (xy 331.756079 -346.409421)
			(xy 331.727856 -346.407389) (xy 331.71384 -346.405454) (xy 331.700495 -346.403821) (xy 331.673795 -346.406923)
			(xy 331.648836 -346.416899) (xy 331.627353 -346.433054) (xy 331.610843 -346.454264) (xy 331.600453 -346.479054)
			(xy 331.59827 -346.492322) (xy 331.594113 -346.519464) (xy 331.579146 -346.57229) (xy 331.556761 -346.622425)
			(xy 331.527421 -346.668834) (xy 331.491731 -346.710557) (xy 331.45043 -346.746735) (xy 331.404369 -346.776618)
			(xy 331.3545 -346.79959) (xy 331.301854 -346.815177) (xy 331.247517 -346.823056) (xy 331.220064 -346.823538)
			(xy 331.192813 -346.823056) (xy 331.138867 -346.815295) (xy 331.086574 -346.799937) (xy 331.036999 -346.777294)
			(xy 330.99115 -346.747827) (xy 330.949961 -346.712135) (xy 330.91427 -346.670945) (xy 330.884803 -346.625096)
			(xy 330.862161 -346.57552) (xy 330.846804 -346.523227) (xy 330.839044 -346.469281) (xy 330.838556 -346.44203)
			(xy 330.839023 -346.414455) (xy 330.846972 -346.359882) (xy 330.862696 -346.307021) (xy 330.885866 -346.256974)
			(xy 330.915999 -346.210785) (xy 330.952468 -346.169415) (xy 330.973176 -346.1512) (xy 330.984045 -346.141272)
			(xy 331.000122 -346.116631) (xy 331.008511 -346.08843) (xy 331.008517 -346.059008) (xy 331.000138 -346.030805)
			(xy 330.984071 -346.006157) (xy 330.973176 -345.99626) (xy 330.952486 -345.978026) (xy 330.916015 -345.936662)
			(xy 330.885881 -345.890476) (xy 330.862712 -345.840433) (xy 330.84699 -345.787575) (xy 330.839045 -345.733003)
			(xy 330.838556 -345.70543) (xy 330.838556 -345.704922) (xy 330.8391 -345.675514) (xy 330.848181 -345.617403)
			(xy 330.866068 -345.561372) (xy 330.89234 -345.508749) (xy 330.908914 -345.48445) (xy 330.91637 -345.473083)
			(xy 330.925686 -345.44756) (xy 330.927945 -345.420484) (xy 330.922989 -345.39377) (xy 330.911167 -345.369307)
			(xy 330.893316 -345.348824) (xy 330.882244 -345.34094) (xy 330.859621 -345.325432) (xy 330.818807 -345.288794)
			(xy 330.783827 -345.246549) (xy 330.769214 -345.223338) (xy 330.761245 -345.211145) (xy 330.739789 -345.19147)
			(xy 330.713648 -345.178659) (xy 330.684951 -345.173756) (xy 330.656039 -345.17716) (xy 330.642468 -345.182444)
			(xy 330.61926 -345.191938) (xy 330.570926 -345.205287) (xy 330.521236 -345.212013) (xy 330.496164 -345.212416)
			(xy 330.471095 -345.211988) (xy 330.421412 -345.20524) (xy 330.373078 -345.191909) (xy 330.34986 -345.182444)
			(xy 330.336267 -345.177245) (xy 330.307376 -345.173876) (xy 330.278705 -345.178779) (xy 330.252575 -345.191555)
			(xy 330.231098 -345.211171) (xy 330.223114 -345.223338) (xy 330.208545 -345.246469) (xy 330.173702 -345.28859)
			(xy 330.133079 -345.325169) (xy 330.087548 -345.35542) (xy 330.038086 -345.378696) (xy 329.985755 -345.394496)
			(xy 329.931676 -345.402482) (xy 329.877012 -345.402482) (xy 329.822933 -345.394496) (xy 329.770602 -345.378696)
			(xy 329.72114 -345.35542) (xy 329.675609 -345.325169) (xy 329.634986 -345.28859) (xy 329.600143 -345.246469)
			(xy 329.585574 -345.223338) (xy 329.577644 -345.211118) (xy 329.556177 -345.191442) (xy 329.530025 -345.178634)
			(xy 329.50132 -345.173738) (xy 329.472401 -345.177154) (xy 329.458828 -345.182444) (xy 329.435613 -345.191919)
			(xy 329.387282 -345.205275) (xy 329.337595 -345.212009) (xy 329.312524 -345.212416) (xy 329.284636 -345.211927)
			(xy 329.229482 -345.203617) (xy 329.176183 -345.187179) (xy 329.12593 -345.162981) (xy 329.079844 -345.131563)
			(xy 329.038956 -345.093627) (xy 329.004179 -345.050021) (xy 328.97629 -345.001718) (xy 328.955912 -344.949798)
			(xy 328.9435 -344.89542) (xy 328.939331 -344.8398) (xy 324.430065 -344.8398) (xy 324.440303 -344.87383)
			(xy 324.448423 -344.929006) (xy 324.448932 -344.956892) (xy 324.448423 -344.984778) (xy 324.440303 -345.039954)
			(xy 324.424235 -345.093361) (xy 324.400563 -345.143858) (xy 324.36979 -345.190371) (xy 324.332573 -345.231908)
			(xy 324.289705 -345.267583) (xy 324.242099 -345.296637) (xy 324.19077 -345.318449) (xy 324.136813 -345.332555)
			(xy 324.081376 -345.338655) (xy 324.025642 -345.336618) (xy 323.970799 -345.326488) (xy 323.918015 -345.308481)
			(xy 323.868415 -345.28298) (xy 323.823057 -345.250529) (xy 323.782908 -345.21182) (xy 323.748822 -345.167677)
			(xy 323.721526 -345.119042) (xy 323.701603 -345.066951) (xy 323.689477 -345.012514) (xy 323.685406 -344.956892)
			(xy 323.46688 -344.956892) (xy 323.466459 -344.979952) (xy 323.458339 -345.035128) (xy 323.442271 -345.088535)
			(xy 323.418599 -345.139032) (xy 323.387826 -345.185545) (xy 323.350609 -345.227082) (xy 323.307741 -345.262757)
			(xy 323.260135 -345.291811) (xy 323.208806 -345.313623) (xy 323.154849 -345.327729) (xy 323.099412 -345.333829)
			(xy 323.043678 -345.331792) (xy 322.988835 -345.321662) (xy 322.936051 -345.303655) (xy 322.886451 -345.278154)
			(xy 322.841093 -345.245703) (xy 322.800944 -345.206994) (xy 322.766858 -345.162851) (xy 322.739562 -345.114216)
			(xy 322.719639 -345.062125) (xy 322.707513 -345.007688) (xy 322.703442 -344.952066) (xy 319.362748 -344.952066)
			(xy 319.634454 -346.174314) (xy 323.948296 -346.174314) (xy 323.952367 -346.118692) (xy 323.964493 -346.064255)
			(xy 323.984416 -346.012164) (xy 324.011712 -345.963529) (xy 324.045798 -345.919386) (xy 324.085947 -345.880677)
			(xy 324.131305 -345.848226) (xy 324.180905 -345.822725) (xy 324.233689 -345.804718) (xy 324.288532 -345.794588)
			(xy 324.344266 -345.792551) (xy 324.399703 -345.798651) (xy 324.45366 -345.812757) (xy 324.504989 -345.834569)
			(xy 324.552595 -345.863623) (xy 324.595463 -345.899298) (xy 324.601093 -345.905582) (xy 325.481694 -345.905582)
			(xy 325.485765 -345.84996) (xy 325.497891 -345.795523) (xy 325.517814 -345.743432) (xy 325.54511 -345.694797)
			(xy 325.579196 -345.650654) (xy 325.619345 -345.611945) (xy 325.664703 -345.579494) (xy 325.714303 -345.553993)
			(xy 325.767087 -345.535986) (xy 325.82193 -345.525856) (xy 325.877664 -345.523819) (xy 325.933101 -345.529919)
			(xy 325.987058 -345.544025) (xy 326.038387 -345.565837) (xy 326.085993 -345.594891) (xy 326.128861 -345.630566)
			(xy 326.166078 -345.672103) (xy 326.196851 -345.718616) (xy 326.220523 -345.769113) (xy 326.236591 -345.82252)
			(xy 326.244711 -345.877696) (xy 326.24522 -345.905582) (xy 326.244711 -345.933468) (xy 326.236591 -345.988644)
			(xy 326.220523 -346.042051) (xy 326.196851 -346.092548) (xy 326.166078 -346.139061) (xy 326.128861 -346.180598)
			(xy 326.085993 -346.216273) (xy 326.038387 -346.245327) (xy 325.987058 -346.267139) (xy 325.933101 -346.281245)
			(xy 325.877664 -346.287345) (xy 325.82193 -346.285308) (xy 325.767087 -346.275178) (xy 325.714303 -346.257171)
			(xy 325.664703 -346.23167) (xy 325.619345 -346.199219) (xy 325.579196 -346.16051) (xy 325.54511 -346.116367)
			(xy 325.517814 -346.067732) (xy 325.497891 -346.015641) (xy 325.485765 -345.961204) (xy 325.481694 -345.905582)
			(xy 324.601093 -345.905582) (xy 324.63268 -345.940835) (xy 324.663453 -345.987348) (xy 324.687125 -346.037845)
			(xy 324.703193 -346.091252) (xy 324.711313 -346.146428) (xy 324.711822 -346.174314) (xy 324.711313 -346.2022)
			(xy 324.703193 -346.257376) (xy 324.687125 -346.310783) (xy 324.663453 -346.36128) (xy 324.63268 -346.407793)
			(xy 324.595463 -346.44933) (xy 324.552595 -346.485005) (xy 324.504989 -346.514059) (xy 324.45366 -346.535871)
			(xy 324.399703 -346.549977) (xy 324.344266 -346.556077) (xy 324.288532 -346.55404) (xy 324.233689 -346.54391)
			(xy 324.180905 -346.525903) (xy 324.131305 -346.500402) (xy 324.085947 -346.467951) (xy 324.045798 -346.429242)
			(xy 324.011712 -346.385099) (xy 323.984416 -346.336464) (xy 323.964493 -346.284373) (xy 323.952367 -346.229936)
			(xy 323.948296 -346.174314) (xy 319.634454 -346.174314) (xy 320.131453 -348.410022) (xy 321.94754 -348.410022)
			(xy 321.947925 -348.38364) (xy 321.955189 -348.331379) (xy 321.969582 -348.280617) (xy 321.990828 -348.23232)
			(xy 322.018525 -348.18741) (xy 322.052142 -348.146743) (xy 322.09104 -348.111093) (xy 322.134478 -348.081141)
			(xy 322.157852 -348.0689) (xy 322.170193 -348.062167) (xy 322.190922 -348.043198) (xy 322.205685 -348.01929)
			(xy 322.213359 -347.992259) (xy 322.213362 -347.96416) (xy 322.205693 -347.937128) (xy 322.190935 -347.913217)
			(xy 322.170209 -347.894244) (xy 322.157852 -347.887544) (xy 322.13448 -347.875306) (xy 322.091058 -347.845342)
			(xy 322.052174 -347.809685) (xy 322.018569 -347.769015) (xy 321.990883 -347.724105) (xy 321.969642 -347.675813)
			(xy 321.955252 -347.625056) (xy 321.947987 -347.572801) (xy 321.94754 -347.546422) (xy 321.948026 -347.519171)
			(xy 321.955782 -347.465223) (xy 321.971137 -347.412928) (xy 321.993779 -347.363351) (xy 322.023245 -347.317501)
			(xy 322.058936 -347.27631) (xy 322.100127 -347.240619) (xy 322.145977 -347.211153) (xy 322.195554 -347.188511)
			(xy 322.247849 -347.173156) (xy 322.301797 -347.1654) (xy 322.356299 -347.1654) (xy 322.410247 -347.173156)
			(xy 322.462542 -347.188511) (xy 322.512119 -347.211153) (xy 322.557969 -347.240619) (xy 322.59916 -347.27631)
			(xy 322.634851 -347.317501) (xy 322.664317 -347.363351) (xy 322.686959 -347.412928) (xy 322.702314 -347.465223)
			(xy 322.707196 -347.499178) (xy 326.2884 -347.499178) (xy 326.288939 -347.469489) (xy 326.298141 -347.410829)
			(xy 326.31632 -347.354303) (xy 326.343036 -347.301276) (xy 326.377645 -347.253028) (xy 326.41931 -347.210723)
			(xy 326.442832 -347.1926) (xy 326.453471 -347.184212) (xy 326.470174 -347.162889) (xy 326.480687 -347.137927)
			(xy 326.484272 -347.11108) (xy 326.480677 -347.084233) (xy 326.470153 -347.059275) (xy 326.453442 -347.03796)
			(xy 326.442832 -347.029532) (xy 326.419344 -347.011369) (xy 326.37768 -346.969072) (xy 326.343072 -346.920831)
			(xy 326.316356 -346.867811) (xy 326.298175 -346.811292) (xy 326.288969 -346.752639) (xy 326.2884 -346.722954)
			(xy 326.288886 -346.695703) (xy 326.296642 -346.641755) (xy 326.311997 -346.58946) (xy 326.334639 -346.539883)
			(xy 326.364105 -346.494033) (xy 326.399796 -346.452842) (xy 326.440987 -346.417151) (xy 326.486837 -346.387685)
			(xy 326.536414 -346.365043) (xy 326.588709 -346.349688) (xy 326.642657 -346.341932) (xy 326.697159 -346.341932)
			(xy 326.751107 -346.349688) (xy 326.803402 -346.365043) (xy 326.852979 -346.387685) (xy 326.898829 -346.417151)
			(xy 326.94002 -346.452842) (xy 326.975711 -346.494033) (xy 327.005177 -346.539883) (xy 327.027819 -346.58946)
			(xy 327.043174 -346.641755) (xy 327.05093 -346.695703) (xy 327.051416 -346.722954) (xy 327.050821 -346.75264)
			(xy 327.04163 -346.811297) (xy 327.023462 -346.867822) (xy 326.996756 -346.92085) (xy 326.984707 -346.937653)
			(xy 327.304861 -346.937653) (xy 327.304861 -346.883147) (xy 327.312618 -346.829196) (xy 327.327975 -346.776899)
			(xy 327.350617 -346.727319) (xy 327.380086 -346.681466) (xy 327.41578 -346.640274) (xy 327.456973 -346.604581)
			(xy 327.502826 -346.575113) (xy 327.552406 -346.552472) (xy 327.604704 -346.537117) (xy 327.658655 -346.529361)
			(xy 327.685908 -346.528898) (xy 327.686162 -346.528898) (xy 327.711365 -346.529306) (xy 327.761333 -346.535942)
			(xy 327.809988 -346.549116) (xy 327.856478 -346.568597) (xy 327.87844 -346.580968) (xy 327.891398 -346.58802)
			(xy 327.920037 -346.595048) (xy 327.94949 -346.593599) (xy 327.977302 -346.583795) (xy 328.001152 -346.566452)
			(xy 328.019051 -346.543016) (xy 328.024744 -346.529406) (xy 328.035473 -346.502644) (xy 328.063756 -346.452403)
			(xy 328.099281 -346.406993) (xy 328.141238 -346.367449) (xy 328.188671 -346.334674) (xy 328.240497 -346.309414)
			(xy 328.295536 -346.292244) (xy 328.352533 -346.283558) (xy 328.38136 -346.283026) (xy 328.408613 -346.283493)
			(xy 328.462566 -346.291245) (xy 328.514866 -346.306598) (xy 328.564448 -346.329238) (xy 328.610303 -346.358705)
			(xy 328.651497 -346.394399) (xy 328.687191 -346.435592) (xy 328.716659 -346.481447) (xy 328.7393 -346.531028)
			(xy 328.754654 -346.583328) (xy 328.762407 -346.637281) (xy 328.762868 -346.664534) (xy 328.762868 -346.664788)
			(xy 328.762281 -346.694626) (xy 328.752973 -346.753572) (xy 328.744326 -346.782136) (xy 328.740293 -346.796046)
			(xy 328.739378 -346.824979) (xy 328.74664 -346.853002) (xy 328.761492 -346.877849) (xy 328.782735 -346.897514)
			(xy 328.808653 -346.910408) (xy 328.822812 -346.913454) (xy 328.84889 -346.918601) (xy 328.899396 -346.935172)
			(xy 328.947111 -346.958596) (xy 328.991111 -346.98842) (xy 329.030542 -347.024066) (xy 329.064641 -347.064842)
			(xy 329.092747 -347.109958) (xy 329.114315 -347.158541) (xy 329.128927 -347.209648) (xy 329.1363 -347.262289)
			(xy 329.136756 -347.288866) (xy 329.13627 -347.316117) (xy 329.128514 -347.370065) (xy 329.113159 -347.42236)
			(xy 329.090517 -347.471937) (xy 329.061051 -347.517787) (xy 329.02536 -347.558978) (xy 328.984169 -347.594669)
			(xy 328.938319 -347.624135) (xy 328.888742 -347.646777) (xy 328.836447 -347.662132) (xy 328.782499 -347.669888)
			(xy 328.727997 -347.669888) (xy 328.674049 -347.662132) (xy 328.621754 -347.646777) (xy 328.572177 -347.624135)
			(xy 328.526327 -347.594669) (xy 328.485136 -347.558978) (xy 328.449445 -347.517787) (xy 328.419979 -347.471937)
			(xy 328.397337 -347.42236) (xy 328.381982 -347.370065) (xy 328.374226 -347.316117) (xy 328.37374 -347.288866)
			(xy 328.37374 -347.288612) (xy 328.374328 -347.258774) (xy 328.383635 -347.199828) (xy 328.392282 -347.171264)
			(xy 328.396308 -347.157353) (xy 328.397223 -347.128421) (xy 328.389962 -347.1004) (xy 328.375111 -347.075553)
			(xy 328.35387 -347.055888) (xy 328.327954 -347.042993) (xy 328.313796 -347.039946) (xy 328.280955 -347.033371)
			(xy 328.218103 -347.010243) (xy 328.188828 -346.993972) (xy 328.175839 -346.98698) (xy 328.147211 -346.979935)
			(xy 328.117765 -346.98137) (xy 328.089957 -346.991163) (xy 328.06611 -347.008498) (xy 328.048214 -347.031927)
			(xy 328.042524 -347.045534) (xy 328.031843 -347.072316) (xy 328.003552 -347.122557) (xy 327.968019 -347.167966)
			(xy 327.926055 -347.207508) (xy 327.878616 -347.24028) (xy 327.826783 -347.265537) (xy 327.771739 -347.282702)
			(xy 327.714737 -347.291385) (xy 327.685908 -347.291914) (xy 327.658655 -347.291439) (xy 327.604704 -347.283683)
			(xy 327.552406 -347.268328) (xy 327.502826 -347.245687) (xy 327.456973 -347.216219) (xy 327.41578 -347.180526)
			(xy 327.380086 -347.139334) (xy 327.350617 -347.093481) (xy 327.327975 -347.043901) (xy 327.312618 -346.991604)
			(xy 327.304861 -346.937653) (xy 326.984707 -346.937653) (xy 326.962158 -346.9691) (xy 326.920501 -347.011407)
			(xy 326.896984 -347.029532) (xy 326.886411 -347.037998) (xy 326.869706 -347.059302) (xy 326.859187 -347.084247)
			(xy 326.855592 -347.11108) (xy 326.859176 -347.137914) (xy 326.869685 -347.162863) (xy 326.886382 -347.184173)
			(xy 326.896984 -347.1926) (xy 326.920523 -347.210768) (xy 326.962235 -347.25314) (xy 326.996868 -347.30147)
			(xy 327.023584 -347.354587) (xy 327.041737 -347.411207) (xy 327.050886 -347.469956) (xy 327.051416 -347.499686)
			(xy 327.051416 -347.521022) (xy 328.694288 -349.16364) (xy 331.49667 -349.16364) (xy 334.545432 -346.114878)
			(xy 334.545432 -341.932768) (xy 334.525833 -341.914581) (xy 334.491373 -341.873701) (xy 334.462957 -341.828411)
			(xy 334.441141 -341.779598) (xy 334.426354 -341.728217) (xy 334.418884 -341.675275) (xy 334.418432 -341.648542)
			(xy 334.419005 -341.618854) (xy 334.428198 -341.560196) (xy 334.446369 -341.50367) (xy 334.473079 -341.450642)
			(xy 334.507682 -341.402392) (xy 334.549344 -341.360088) (xy 334.572864 -341.341964) (xy 334.583445 -341.333505)
			(xy 334.600159 -341.312203) (xy 334.610684 -341.287255) (xy 334.61428 -341.260418) (xy 334.610693 -341.23358)
			(xy 334.600177 -341.208628) (xy 334.583471 -341.18732) (xy 334.572864 -341.178896) (xy 334.549344 -341.160772)
			(xy 334.507686 -341.118465) (xy 334.473083 -341.070215) (xy 334.446373 -341.017188) (xy 334.428198 -340.960663)
			(xy 334.418998 -340.902005) (xy 334.418432 -340.872318) (xy 334.418918 -340.845067) (xy 334.426674 -340.791119)
			(xy 334.442029 -340.738824) (xy 334.464671 -340.689247) (xy 334.494137 -340.643397) (xy 334.529828 -340.602206)
			(xy 334.571019 -340.566515) (xy 334.616869 -340.537049) (xy 334.666446 -340.514407) (xy 334.718741 -340.499052)
			(xy 334.772689 -340.491296) (xy 334.827191 -340.491296) (xy 334.881139 -340.499052) (xy 334.933434 -340.514407)
			(xy 334.983011 -340.537049) (xy 335.028861 -340.566515) (xy 335.070052 -340.602206) (xy 335.105743 -340.643397)
			(xy 335.135209 -340.689247) (xy 335.157851 -340.738824) (xy 335.173206 -340.791119) (xy 335.180962 -340.845067)
			(xy 335.181448 -340.872318) (xy 335.180927 -340.902008) (xy 335.171724 -340.960669) (xy 335.153543 -341.017197)
			(xy 335.126824 -341.070225) (xy 335.114749 -341.087057) (xy 335.434825 -341.087057) (xy 335.434825 -341.032543)
			(xy 335.442584 -340.978584) (xy 335.457943 -340.926279) (xy 335.48059 -340.876692) (xy 335.510064 -340.830834)
			(xy 335.545765 -340.789637) (xy 335.586966 -340.75394) (xy 335.632828 -340.724471) (xy 335.682417 -340.701829)
			(xy 335.734724 -340.686475) (xy 335.788683 -340.678722) (xy 335.81594 -340.678262) (xy 335.816194 -340.678262)
			(xy 335.841398 -340.678661) (xy 335.891366 -340.6853) (xy 335.94002 -340.698477) (xy 335.98651 -340.71796)
			(xy 336.008472 -340.730332) (xy 336.021462 -340.737322) (xy 336.050089 -340.744366) (xy 336.079535 -340.742932)
			(xy 336.107342 -340.733139) (xy 336.131189 -340.715805) (xy 336.149085 -340.692377) (xy 336.154776 -340.67877)
			(xy 336.16546 -340.651988) (xy 336.19375 -340.601747) (xy 336.229282 -340.556338) (xy 336.271246 -340.516797)
			(xy 336.318685 -340.484024) (xy 336.370517 -340.458767) (xy 336.425562 -340.441602) (xy 336.482563 -340.432919)
			(xy 336.511392 -340.43239) (xy 336.538645 -340.432863) (xy 336.592595 -340.440619) (xy 336.644893 -340.455974)
			(xy 336.694473 -340.478615) (xy 336.740326 -340.508082) (xy 336.781518 -340.543775) (xy 336.817212 -340.584966)
			(xy 336.84668 -340.630819) (xy 336.869323 -340.680398) (xy 336.884679 -340.732695) (xy 336.892437 -340.786645)
			(xy 336.8929 -340.813898) (xy 336.8929 -340.814152) (xy 336.89233 -340.843991) (xy 336.883011 -340.902937)
			(xy 336.874358 -340.9315) (xy 336.870419 -340.945432) (xy 336.869498 -340.974349) (xy 336.876747 -341.002357)
			(xy 336.89158 -341.027197) (xy 336.9128 -341.046861) (xy 336.938695 -341.059765) (xy 336.952844 -341.062818)
			(xy 336.978919 -341.067975) (xy 337.029423 -341.084548) (xy 337.077136 -341.107974) (xy 337.121134 -341.137797)
			(xy 337.160564 -341.173442) (xy 337.194662 -341.214216) (xy 337.222769 -341.25933) (xy 337.244338 -341.30791)
			(xy 337.258953 -341.359015) (xy 337.26633 -341.411653) (xy 337.266788 -341.43823) (xy 337.266302 -341.465481)
			(xy 337.258546 -341.519429) (xy 337.243191 -341.571724) (xy 337.220549 -341.621301) (xy 337.203042 -341.648542)
			(xy 375.220992 -341.648542) (xy 375.221581 -341.618855) (xy 375.230773 -341.560198) (xy 375.248942 -341.503673)
			(xy 375.275649 -341.450645) (xy 375.310249 -341.402396) (xy 375.351906 -341.360089) (xy 375.375424 -341.341964)
			(xy 375.386 -341.333502) (xy 375.402704 -341.312197) (xy 375.413223 -341.287251) (xy 375.416816 -341.260418)
			(xy 375.413232 -341.233583) (xy 375.402723 -341.208634) (xy 375.386026 -341.187323) (xy 375.375424 -341.178896)
			(xy 375.351917 -341.160756) (xy 375.310255 -341.118454) (xy 375.275649 -341.070208) (xy 375.248936 -341.017184)
			(xy 375.230759 -340.960661) (xy 375.221558 -340.902005) (xy 375.220992 -340.872318) (xy 375.221478 -340.845067)
			(xy 375.229234 -340.791119) (xy 375.244589 -340.738824) (xy 375.267231 -340.689247) (xy 375.296697 -340.643397)
			(xy 375.332388 -340.602206) (xy 375.373579 -340.566515) (xy 375.419429 -340.537049) (xy 375.469006 -340.514407)
			(xy 375.521301 -340.499052) (xy 375.575249 -340.491296) (xy 375.629751 -340.491296) (xy 375.683699 -340.499052)
			(xy 375.735994 -340.514407) (xy 375.785571 -340.537049) (xy 375.831421 -340.566515) (xy 375.872612 -340.602206)
			(xy 375.908303 -340.643397) (xy 375.937769 -340.689247) (xy 375.960411 -340.738824) (xy 375.975766 -340.791119)
			(xy 375.983522 -340.845067) (xy 375.984008 -340.872318) (xy 375.983463 -340.902006) (xy 375.974262 -340.960666)
			(xy 375.956084 -341.017192) (xy 375.929369 -341.070219) (xy 375.917294 -341.087053) (xy 376.237448 -341.087053)
			(xy 376.237448 -341.032547) (xy 376.245205 -340.978595) (xy 376.260561 -340.926296) (xy 376.283204 -340.876715)
			(xy 376.312673 -340.830861) (xy 376.348367 -340.789667) (xy 376.389561 -340.753973) (xy 376.435415 -340.724504)
			(xy 376.484996 -340.701861) (xy 376.537295 -340.686505) (xy 376.591247 -340.678748) (xy 376.6185 -340.678262)
			(xy 376.618754 -340.678262) (xy 376.643957 -340.678679) (xy 376.693925 -340.685313) (xy 376.742579 -340.698484)
			(xy 376.78907 -340.717962) (xy 376.811032 -340.730332) (xy 376.823986 -340.737393) (xy 376.852628 -340.744427)
			(xy 376.882085 -340.74298) (xy 376.909899 -340.733173) (xy 376.93375 -340.715825) (xy 376.951646 -340.692384)
			(xy 376.957336 -340.67877) (xy 376.968053 -340.652003) (xy 376.996339 -340.601763) (xy 377.031867 -340.556355)
			(xy 377.073826 -340.516813) (xy 377.12126 -340.484038) (xy 377.173088 -340.458779) (xy 377.228127 -340.44161)
			(xy 377.285124 -340.432922) (xy 377.313952 -340.43239) (xy 377.341204 -340.4329) (xy 377.395153 -340.44065)
			(xy 377.44745 -340.456) (xy 377.497029 -340.478637) (xy 377.542883 -340.5081) (xy 377.584076 -340.543789)
			(xy 377.61977 -340.584977) (xy 377.649239 -340.630827) (xy 377.671882 -340.680403) (xy 377.687239 -340.732698)
			(xy 377.694996 -340.786646) (xy 377.69546 -340.813898) (xy 377.69546 -340.814152) (xy 377.694888 -340.843991)
			(xy 377.68557 -340.902937) (xy 377.676918 -340.9315) (xy 377.672932 -340.945422) (xy 377.672009 -340.974348)
			(xy 377.679262 -341.002366) (xy 377.694105 -341.027211) (xy 377.715339 -341.046875) (xy 377.741249 -341.059771)
			(xy 377.755404 -341.062818) (xy 377.781473 -341.068005) (xy 377.831977 -341.084573) (xy 377.87969 -341.107993)
			(xy 377.923689 -341.137813) (xy 377.96312 -341.173454) (xy 377.99722 -341.214225) (xy 378.025327 -341.259337)
			(xy 378.046897 -341.307914) (xy 378.061513 -341.359017) (xy 378.06889 -341.411654) (xy 378.069348 -341.43823)
			(xy 378.068862 -341.465481) (xy 378.061106 -341.519429) (xy 378.045751 -341.571724) (xy 378.023109 -341.621301)
			(xy 377.993643 -341.667151) (xy 377.957952 -341.708342) (xy 377.916761 -341.744033) (xy 377.870911 -341.773499)
			(xy 377.821334 -341.796141) (xy 377.769039 -341.811496) (xy 377.715091 -341.819252) (xy 377.660589 -341.819252)
			(xy 377.606641 -341.811496) (xy 377.554346 -341.796141) (xy 377.504769 -341.773499) (xy 377.458919 -341.744033)
			(xy 377.417728 -341.708342) (xy 377.382037 -341.667151) (xy 377.352571 -341.621301) (xy 377.329929 -341.571724)
			(xy 377.314574 -341.519429) (xy 377.306818 -341.465481) (xy 377.306332 -341.43823) (xy 377.306332 -341.437976)
			(xy 377.306911 -341.408137) (xy 377.316224 -341.349191) (xy 377.324874 -341.320628) (xy 377.328947 -341.306729)
			(xy 377.329854 -341.27779) (xy 377.322584 -341.249764) (xy 377.307724 -341.224915) (xy 377.286474 -341.205249)
			(xy 377.26055 -341.192355) (xy 377.246388 -341.18931) (xy 377.213548 -341.182731) (xy 377.150696 -341.159605)
			(xy 377.12142 -341.143336) (xy 377.108428 -341.136353) (xy 377.079802 -341.129314) (xy 377.050359 -341.13075)
			(xy 377.022554 -341.140542) (xy 376.998708 -341.157871) (xy 376.980809 -341.181294) (xy 376.975116 -341.194898)
			(xy 376.964422 -341.221675) (xy 376.936135 -341.271918) (xy 376.900605 -341.317328) (xy 376.858643 -341.356871)
			(xy 376.811205 -341.389645) (xy 376.759374 -341.414902) (xy 376.70433 -341.432068) (xy 376.647329 -341.440749)
			(xy 376.6185 -341.441278) (xy 376.591247 -341.440852) (xy 376.537295 -341.433095) (xy 376.484996 -341.417739)
			(xy 376.435415 -341.395096) (xy 376.389561 -341.365627) (xy 376.348367 -341.329933) (xy 376.312673 -341.288739)
			(xy 376.283204 -341.242885) (xy 376.260561 -341.193304) (xy 376.245205 -341.141005) (xy 376.237448 -341.087053)
			(xy 375.917294 -341.087053) (xy 375.894761 -341.118468) (xy 375.853097 -341.160772) (xy 375.829576 -341.178896)
			(xy 375.81894 -341.187288) (xy 375.802236 -341.208609) (xy 375.791721 -341.233571) (xy 375.788136 -341.260418)
			(xy 375.791731 -341.287264) (xy 375.802254 -341.312222) (xy 375.818966 -341.333537) (xy 375.829576 -341.341964)
			(xy 375.853064 -341.360127) (xy 375.894727 -341.402425) (xy 375.929335 -341.450666) (xy 375.956052 -341.503686)
			(xy 375.974232 -341.560204) (xy 375.983439 -341.618857) (xy 375.984008 -341.648542) (xy 375.983522 -341.675793)
			(xy 375.975766 -341.729741) (xy 375.960411 -341.782036) (xy 375.937769 -341.831613) (xy 375.908303 -341.877463)
			(xy 375.872612 -341.918654) (xy 375.831421 -341.954345) (xy 375.785571 -341.983811) (xy 375.735994 -342.006453)
			(xy 375.683699 -342.021808) (xy 375.629751 -342.029564) (xy 375.575249 -342.029564) (xy 375.521301 -342.021808)
			(xy 375.469006 -342.006453) (xy 375.419429 -341.983811) (xy 375.373579 -341.954345) (xy 375.332388 -341.918654)
			(xy 375.296697 -341.877463) (xy 375.267231 -341.831613) (xy 375.244589 -341.782036) (xy 375.229234 -341.729741)
			(xy 375.221478 -341.675793) (xy 375.220992 -341.648542) (xy 337.203042 -341.648542) (xy 337.191083 -341.667151)
			(xy 337.155392 -341.708342) (xy 337.114201 -341.744033) (xy 337.068351 -341.773499) (xy 337.018774 -341.796141)
			(xy 336.966479 -341.811496) (xy 336.912531 -341.819252) (xy 336.858029 -341.819252) (xy 336.804081 -341.811496)
			(xy 336.751786 -341.796141) (xy 336.702209 -341.773499) (xy 336.656359 -341.744033) (xy 336.615168 -341.708342)
			(xy 336.579477 -341.667151) (xy 336.550011 -341.621301) (xy 336.527369 -341.571724) (xy 336.512014 -341.519429)
			(xy 336.504258 -341.465481) (xy 336.503772 -341.43823) (xy 336.503772 -341.437976) (xy 336.50435 -341.408137)
			(xy 336.513664 -341.349191) (xy 336.522314 -341.320628) (xy 336.526356 -341.306722) (xy 336.527261 -341.277789)
			(xy 336.519994 -341.24977) (xy 336.505141 -341.224924) (xy 336.4839 -341.205258) (xy 336.457986 -341.19236)
			(xy 336.443828 -341.18931) (xy 336.41099 -341.182721) (xy 336.348137 -341.159602) (xy 336.31886 -341.143336)
			(xy 336.305903 -341.136282) (xy 336.277264 -341.129254) (xy 336.24781 -341.130702) (xy 336.219998 -341.140507)
			(xy 336.196148 -341.157851) (xy 336.178248 -341.181287) (xy 336.172556 -341.194898) (xy 336.161829 -341.221661)
			(xy 336.133545 -341.271902) (xy 336.09802 -341.317312) (xy 336.056063 -341.356855) (xy 336.00863 -341.38963)
			(xy 335.956803 -341.414891) (xy 335.901764 -341.43206) (xy 335.844767 -341.440746) (xy 335.81594 -341.441278)
			(xy 335.788683 -341.440878) (xy 335.734724 -341.433125) (xy 335.682417 -341.417771) (xy 335.632828 -341.395129)
			(xy 335.586966 -341.36566) (xy 335.545765 -341.329963) (xy 335.510064 -341.288766) (xy 335.48059 -341.242908)
			(xy 335.457943 -341.193321) (xy 335.442584 -341.141016) (xy 335.434825 -341.087057) (xy 335.114749 -341.087057)
			(xy 335.092211 -341.118472) (xy 335.05054 -341.160774) (xy 335.027016 -341.178896) (xy 335.016377 -341.187286)
			(xy 334.999666 -341.208606) (xy 334.989147 -341.233568) (xy 334.98556 -341.260418) (xy 334.989156 -341.287267)
			(xy 334.999684 -341.312225) (xy 335.016403 -341.333539) (xy 335.027016 -341.341964) (xy 335.050513 -341.360117)
			(xy 335.092173 -341.402418) (xy 335.126779 -341.450661) (xy 335.153494 -341.503683) (xy 335.171673 -341.560203)
			(xy 335.180879 -341.618856) (xy 335.181448 -341.648542) (xy 335.180993 -341.675276) (xy 335.173534 -341.728222)
			(xy 335.158753 -341.779607) (xy 335.136942 -341.828425) (xy 335.108527 -341.873718) (xy 335.074065 -341.914599)
			(xy 335.054448 -341.932768) (xy 335.054448 -343.944632) (xy 344.389706 -343.944632) (xy 344.389706 -343.859936)
			(xy 344.397757 -343.775622) (xy 344.413786 -343.692456) (xy 344.437647 -343.611189) (xy 344.469126 -343.532559)
			(xy 344.507937 -343.457278) (xy 344.553727 -343.386026) (xy 344.606083 -343.31945) (xy 344.664531 -343.258152)
			(xy 344.728541 -343.202687) (xy 344.797533 -343.153558) (xy 344.870883 -343.111209) (xy 344.947926 -343.076025)
			(xy 345.027965 -343.048323) (xy 345.110274 -343.028355) (xy 345.194109 -343.016302) (xy 345.27871 -343.012272)
			(xy 345.363311 -343.016302) (xy 345.447146 -343.028355) (xy 345.529455 -343.048323) (xy 345.609494 -343.076025)
			(xy 345.686537 -343.111209) (xy 345.759887 -343.153558) (xy 345.828879 -343.202687) (xy 345.892889 -343.258152)
			(xy 345.951337 -343.31945) (xy 346.003693 -343.386026) (xy 346.049483 -343.457278) (xy 346.088294 -343.532559)
			(xy 346.119773 -343.611189) (xy 346.143634 -343.692456) (xy 346.159663 -343.775622) (xy 346.167714 -343.859936)
			(xy 346.168218 -343.902284) (xy 346.914219 -343.902284) (xy 346.918255 -343.818837) (xy 346.930327 -343.736169)
			(xy 346.95032 -343.655052) (xy 346.978049 -343.576243) (xy 347.013255 -343.500478) (xy 347.055609 -343.428465)
			(xy 347.104715 -343.360876) (xy 347.160116 -343.298342) (xy 347.221293 -343.241447) (xy 347.287676 -343.190721)
			(xy 347.358644 -343.14664) (xy 347.433536 -343.109614) (xy 347.511652 -343.079988) (xy 347.592262 -343.05804)
			(xy 347.674614 -343.043975) (xy 347.75794 -343.037923) (xy 347.84146 -343.039942) (xy 347.924396 -343.050012)
			(xy 348.005972 -343.06804) (xy 348.085428 -343.093857) (xy 348.162021 -343.127222) (xy 348.235037 -343.167823)
			(xy 348.303793 -343.215282) (xy 348.367647 -343.269155) (xy 348.426004 -343.32894) (xy 348.478319 -343.394077)
			(xy 348.524102 -343.46396) (xy 348.562927 -343.537935) (xy 348.594432 -343.615312) (xy 348.618321 -343.695369)
			(xy 348.634372 -343.777357) (xy 348.642435 -343.860512) (xy 348.64294 -343.902284) (xy 348.642435 -343.944056)
			(xy 348.642379 -343.944632) (xy 351.95027 -343.944632) (xy 351.95027 -343.859936) (xy 351.958321 -343.775622)
			(xy 351.97435 -343.692456) (xy 351.998211 -343.611189) (xy 352.02969 -343.532559) (xy 352.068501 -343.457278)
			(xy 352.114291 -343.386026) (xy 352.166647 -343.31945) (xy 352.225095 -343.258152) (xy 352.289105 -343.202687)
			(xy 352.358097 -343.153558) (xy 352.431447 -343.111209) (xy 352.50849 -343.076025) (xy 352.588529 -343.048323)
			(xy 352.670838 -343.028355) (xy 352.754673 -343.016302) (xy 352.839274 -343.012272) (xy 352.923875 -343.016302)
			(xy 353.00771 -343.028355) (xy 353.090019 -343.048323) (xy 353.170058 -343.076025) (xy 353.247101 -343.111209)
			(xy 353.320451 -343.153558) (xy 353.389443 -343.202687) (xy 353.453453 -343.258152) (xy 353.511901 -343.31945)
			(xy 353.564257 -343.386026) (xy 353.610047 -343.457278) (xy 353.648858 -343.532559) (xy 353.680337 -343.611189)
			(xy 353.704198 -343.692456) (xy 353.720227 -343.775622) (xy 353.728278 -343.859936) (xy 353.728782 -343.902284)
			(xy 354.474783 -343.902284) (xy 354.478819 -343.818837) (xy 354.490891 -343.736169) (xy 354.510884 -343.655052)
			(xy 354.538613 -343.576243) (xy 354.573819 -343.500478) (xy 354.616173 -343.428465) (xy 354.665279 -343.360876)
			(xy 354.72068 -343.298342) (xy 354.781857 -343.241447) (xy 354.84824 -343.190721) (xy 354.919208 -343.14664)
			(xy 354.9941 -343.109614) (xy 355.072216 -343.079988) (xy 355.152826 -343.05804) (xy 355.235178 -343.043975)
			(xy 355.318504 -343.037923) (xy 355.402024 -343.039942) (xy 355.48496 -343.050012) (xy 355.566536 -343.06804)
			(xy 355.645992 -343.093857) (xy 355.722585 -343.127222) (xy 355.795601 -343.167823) (xy 355.864357 -343.215282)
			(xy 355.928211 -343.269155) (xy 355.986568 -343.32894) (xy 356.038883 -343.394077) (xy 356.084666 -343.46396)
			(xy 356.123491 -343.537935) (xy 356.154996 -343.615312) (xy 356.178885 -343.695369) (xy 356.194936 -343.777357)
			(xy 356.202999 -343.860512) (xy 356.203504 -343.902284) (xy 356.202999 -343.944056) (xy 356.202943 -343.944632)
			(xy 359.655614 -343.944632) (xy 359.655614 -343.859936) (xy 359.663665 -343.775622) (xy 359.679694 -343.692456)
			(xy 359.703555 -343.611189) (xy 359.735034 -343.532559) (xy 359.773845 -343.457278) (xy 359.819635 -343.386026)
			(xy 359.871991 -343.31945) (xy 359.930439 -343.258152) (xy 359.994449 -343.202687) (xy 360.063441 -343.153558)
			(xy 360.136791 -343.111209) (xy 360.213834 -343.076025) (xy 360.293873 -343.048323) (xy 360.376182 -343.028355)
			(xy 360.460017 -343.016302) (xy 360.544618 -343.012272) (xy 360.629219 -343.016302) (xy 360.713054 -343.028355)
			(xy 360.795363 -343.048323) (xy 360.875402 -343.076025) (xy 360.952445 -343.111209) (xy 361.025795 -343.153558)
			(xy 361.094787 -343.202687) (xy 361.158797 -343.258152) (xy 361.217245 -343.31945) (xy 361.269601 -343.386026)
			(xy 361.315391 -343.457278) (xy 361.354202 -343.532559) (xy 361.385681 -343.611189) (xy 361.409542 -343.692456)
			(xy 361.425571 -343.775622) (xy 361.433622 -343.859936) (xy 361.434126 -343.902284) (xy 362.180127 -343.902284)
			(xy 362.184163 -343.818837) (xy 362.196235 -343.736169) (xy 362.216228 -343.655052) (xy 362.243957 -343.576243)
			(xy 362.279163 -343.500478) (xy 362.321517 -343.428465) (xy 362.370623 -343.360876) (xy 362.426024 -343.298342)
			(xy 362.487201 -343.241447) (xy 362.553584 -343.190721) (xy 362.624552 -343.14664) (xy 362.699444 -343.109614)
			(xy 362.77756 -343.079988) (xy 362.85817 -343.05804) (xy 362.940522 -343.043975) (xy 363.023848 -343.037923)
			(xy 363.107368 -343.039942) (xy 363.190304 -343.050012) (xy 363.27188 -343.06804) (xy 363.351336 -343.093857)
			(xy 363.427929 -343.127222) (xy 363.500945 -343.167823) (xy 363.569701 -343.215282) (xy 363.633555 -343.269155)
			(xy 363.691912 -343.32894) (xy 363.744227 -343.394077) (xy 363.79001 -343.46396) (xy 363.828835 -343.537935)
			(xy 363.86034 -343.615312) (xy 363.884229 -343.695369) (xy 363.90028 -343.777357) (xy 363.908343 -343.860512)
			(xy 363.908848 -343.902284) (xy 363.908343 -343.944056) (xy 363.908287 -343.944632) (xy 367.216178 -343.944632)
			(xy 367.216178 -343.859936) (xy 367.224229 -343.775622) (xy 367.240258 -343.692456) (xy 367.264119 -343.611189)
			(xy 367.295598 -343.532559) (xy 367.334409 -343.457278) (xy 367.380199 -343.386026) (xy 367.432555 -343.31945)
			(xy 367.491003 -343.258152) (xy 367.555013 -343.202687) (xy 367.624005 -343.153558) (xy 367.697355 -343.111209)
			(xy 367.774398 -343.076025) (xy 367.854437 -343.048323) (xy 367.936746 -343.028355) (xy 368.020581 -343.016302)
			(xy 368.105182 -343.012272) (xy 368.189783 -343.016302) (xy 368.273618 -343.028355) (xy 368.355927 -343.048323)
			(xy 368.435966 -343.076025) (xy 368.513009 -343.111209) (xy 368.586359 -343.153558) (xy 368.655351 -343.202687)
			(xy 368.719361 -343.258152) (xy 368.777809 -343.31945) (xy 368.830165 -343.386026) (xy 368.875955 -343.457278)
			(xy 368.914766 -343.532559) (xy 368.946245 -343.611189) (xy 368.970106 -343.692456) (xy 368.986135 -343.775622)
			(xy 368.994186 -343.859936) (xy 368.99469 -343.902284) (xy 369.740691 -343.902284) (xy 369.744727 -343.818837)
			(xy 369.756799 -343.736169) (xy 369.776792 -343.655052) (xy 369.804521 -343.576243) (xy 369.839727 -343.500478)
			(xy 369.882081 -343.428465) (xy 369.931187 -343.360876) (xy 369.986588 -343.298342) (xy 370.047765 -343.241447)
			(xy 370.114148 -343.190721) (xy 370.185116 -343.14664) (xy 370.260008 -343.109614) (xy 370.338124 -343.079988)
			(xy 370.418734 -343.05804) (xy 370.501086 -343.043975) (xy 370.584412 -343.037923) (xy 370.667932 -343.039942)
			(xy 370.750868 -343.050012) (xy 370.832444 -343.06804) (xy 370.9119 -343.093857) (xy 370.988493 -343.127222)
			(xy 371.061509 -343.167823) (xy 371.130265 -343.215282) (xy 371.194119 -343.269155) (xy 371.252476 -343.32894)
			(xy 371.304791 -343.394077) (xy 371.350574 -343.46396) (xy 371.389399 -343.537935) (xy 371.420904 -343.615312)
			(xy 371.444793 -343.695369) (xy 371.460844 -343.777357) (xy 371.468907 -343.860512) (xy 371.469412 -343.902284)
			(xy 371.468907 -343.944056) (xy 371.460844 -344.027211) (xy 371.444793 -344.109199) (xy 371.420904 -344.189256)
			(xy 371.389399 -344.266633) (xy 371.350574 -344.340608) (xy 371.326559 -344.377264) (xy 381.783844 -344.377264)
			(xy 381.784278 -344.349892) (xy 381.792102 -344.295712) (xy 381.807598 -344.243208) (xy 381.830447 -344.193461)
			(xy 381.860179 -344.147496) (xy 381.877824 -344.126566) (xy 381.887094 -344.115264) (xy 381.899264 -344.088697)
			(xy 381.903429 -344.059773) (xy 381.899248 -344.030851) (xy 381.887064 -344.00429) (xy 381.877824 -343.992962)
			(xy 381.860204 -343.972014) (xy 381.830489 -343.926046) (xy 381.807649 -343.876303) (xy 381.792153 -343.823805)
			(xy 381.78432 -343.769632) (xy 381.783844 -343.742264) (xy 381.78433 -343.715013) (xy 381.792086 -343.661065)
			(xy 381.807441 -343.60877) (xy 381.830083 -343.559193) (xy 381.859549 -343.513343) (xy 381.89524 -343.472152)
			(xy 381.936431 -343.436461) (xy 381.982281 -343.406995) (xy 382.031858 -343.384353) (xy 382.084153 -343.368998)
			(xy 382.138101 -343.361242) (xy 382.192603 -343.361242) (xy 382.246551 -343.368998) (xy 382.298846 -343.384353)
			(xy 382.348423 -343.406995) (xy 382.394273 -343.436461) (xy 382.435464 -343.472152) (xy 382.471155 -343.513343)
			(xy 382.500621 -343.559193) (xy 382.523263 -343.60877) (xy 382.538618 -343.661065) (xy 382.546374 -343.715013)
			(xy 382.54686 -343.742264) (xy 382.546383 -343.769634) (xy 382.538569 -343.823813) (xy 382.523083 -343.876316)
			(xy 382.500244 -343.926063) (xy 382.470521 -343.97203) (xy 382.45288 -343.992962) (xy 382.443679 -344.004316)
			(xy 382.4315 -344.030864) (xy 382.427322 -344.059773) (xy 382.431485 -344.088683) (xy 382.44365 -344.115238)
			(xy 382.45288 -344.126566) (xy 382.470514 -344.147503) (xy 382.500227 -344.193474) (xy 382.523064 -344.24322)
			(xy 382.538557 -344.29572) (xy 382.546386 -344.349895) (xy 382.54686 -344.377264) (xy 382.546374 -344.404515)
			(xy 382.538618 -344.458463) (xy 382.523263 -344.510758) (xy 382.500621 -344.560335) (xy 382.471155 -344.606185)
			(xy 382.435464 -344.647376) (xy 382.394273 -344.683067) (xy 382.348423 -344.712533) (xy 382.298846 -344.735175)
			(xy 382.246551 -344.75053) (xy 382.192603 -344.758286) (xy 382.138101 -344.758286) (xy 382.084153 -344.75053)
			(xy 382.031858 -344.735175) (xy 381.982281 -344.712533) (xy 381.936431 -344.683067) (xy 381.89524 -344.647376)
			(xy 381.859549 -344.606185) (xy 381.830083 -344.560335) (xy 381.807441 -344.510758) (xy 381.792086 -344.458463)
			(xy 381.78433 -344.404515) (xy 381.783844 -344.377264) (xy 371.326559 -344.377264) (xy 371.304791 -344.410491)
			(xy 371.252476 -344.475628) (xy 371.194119 -344.535413) (xy 371.130265 -344.589286) (xy 371.061509 -344.636745)
			(xy 370.988493 -344.677346) (xy 370.9119 -344.710711) (xy 370.832444 -344.736528) (xy 370.750868 -344.754556)
			(xy 370.667932 -344.764626) (xy 370.584412 -344.766645) (xy 370.501086 -344.760593) (xy 370.418734 -344.746528)
			(xy 370.338124 -344.72458) (xy 370.260008 -344.694954) (xy 370.185116 -344.657928) (xy 370.114148 -344.613847)
			(xy 370.047765 -344.563121) (xy 369.986588 -344.506226) (xy 369.931187 -344.443692) (xy 369.882081 -344.376103)
			(xy 369.839727 -344.30409) (xy 369.804521 -344.228325) (xy 369.776792 -344.149516) (xy 369.756799 -344.068399)
			(xy 369.744727 -343.985731) (xy 369.740691 -343.902284) (xy 368.99469 -343.902284) (xy 368.994186 -343.944632)
			(xy 368.986135 -344.028946) (xy 368.970106 -344.112112) (xy 368.946245 -344.193379) (xy 368.914766 -344.272009)
			(xy 368.875955 -344.34729) (xy 368.830165 -344.418542) (xy 368.777809 -344.485118) (xy 368.719361 -344.546416)
			(xy 368.655351 -344.601881) (xy 368.586359 -344.65101) (xy 368.513009 -344.693359) (xy 368.435966 -344.728543)
			(xy 368.355927 -344.756245) (xy 368.273618 -344.776213) (xy 368.247973 -344.7799) (xy 386.032387 -344.7799)
			(xy 386.036556 -344.724273) (xy 386.04897 -344.669889) (xy 386.069351 -344.617962) (xy 386.097243 -344.569653)
			(xy 386.132025 -344.526041) (xy 386.172918 -344.488101) (xy 386.21901 -344.456679) (xy 386.26927 -344.432478)
			(xy 386.322576 -344.416039) (xy 386.377736 -344.407729) (xy 386.405628 -344.407236) (xy 386.432959 -344.407731)
			(xy 386.487038 -344.415696) (xy 386.539372 -344.43148) (xy 386.588836 -344.454744) (xy 386.634369 -344.484988)
			(xy 386.674992 -344.521563) (xy 386.709832 -344.563683) (xy 386.724398 -344.586814) (xy 386.732342 -344.599023)
			(xy 386.753808 -344.618693) (xy 386.779956 -344.631498) (xy 386.808656 -344.636398) (xy 386.837571 -344.632992)
			(xy 386.851144 -344.627708) (xy 386.874352 -344.618213) (xy 386.922686 -344.604864) (xy 386.972376 -344.598138)
			(xy 386.997448 -344.597736) (xy 387.022517 -344.598156) (xy 387.072201 -344.604907) (xy 387.120535 -344.618241)
			(xy 387.143752 -344.627708) (xy 387.157334 -344.63294) (xy 387.186232 -344.636309) (xy 387.214909 -344.631401)
			(xy 387.241043 -344.618616) (xy 387.262517 -344.598987) (xy 387.270498 -344.586814) (xy 387.285067 -344.563683)
			(xy 387.31991 -344.521562) (xy 387.360533 -344.484983) (xy 387.406064 -344.454732) (xy 387.455526 -344.431456)
			(xy 387.507857 -344.415656) (xy 387.561936 -344.40767) (xy 387.6166 -344.40767) (xy 387.670679 -344.415656)
			(xy 387.72301 -344.431456) (xy 387.772472 -344.454732) (xy 387.818003 -344.484983) (xy 387.858626 -344.521562)
			(xy 387.893469 -344.563683) (xy 387.908038 -344.586814) (xy 387.915944 -344.59905) (xy 387.937421 -344.61872)
			(xy 387.963579 -344.631522) (xy 387.992288 -344.636414) (xy 388.021209 -344.632998) (xy 388.034784 -344.627708)
			(xy 388.057999 -344.618232) (xy 388.106329 -344.604875) (xy 388.156017 -344.598142) (xy 388.181088 -344.597736)
			(xy 388.207932 -344.598171) (xy 388.261065 -344.605875) (xy 388.312542 -344.621125) (xy 388.361297 -344.643606)
			(xy 388.406321 -344.672851) (xy 388.446681 -344.708256) (xy 388.481541 -344.749087) (xy 388.510181 -344.794499)
			(xy 388.532006 -344.843551) (xy 388.539736 -344.869262) (xy 388.544362 -344.883773) (xy 388.560887 -344.909341)
			(xy 388.584211 -344.928907) (xy 388.612263 -344.940734) (xy 388.642554 -344.943775) (xy 388.672397 -344.937757)
			(xy 388.68604 -344.930984) (xy 388.714189 -344.916356) (xy 388.774138 -344.895627) (xy 388.836696 -344.885126)
			(xy 388.868412 -344.884502) (xy 388.886431 -344.884725) (xy 388.922306 -344.888158) (xy 388.94004 -344.89136)
			(xy 388.955244 -344.893737) (xy 388.985802 -344.890199) (xy 389.013922 -344.877728) (xy 389.037058 -344.857454)
			(xy 389.053113 -344.831214) (xy 389.057388 -344.81643) (xy 389.064795 -344.789389) (xy 389.086426 -344.737665)
			(xy 389.11539 -344.689661) (xy 389.151065 -344.64641) (xy 389.192683 -344.608844) (xy 389.239348 -344.577769)
			(xy 389.290058 -344.553856) (xy 389.343719 -344.537617) (xy 389.39918 -344.529403) (xy 389.427212 -344.528902)
			(xy 389.454464 -344.529367) (xy 389.508413 -344.537125) (xy 389.560709 -344.552482) (xy 389.610287 -344.575125)
			(xy 389.656138 -344.604594) (xy 389.697328 -344.640288) (xy 389.733019 -344.68148) (xy 389.762485 -344.727333)
			(xy 389.785125 -344.776912) (xy 389.80048 -344.829209) (xy 389.808235 -344.883158) (xy 389.80872 -344.91041)
			(xy 389.808185 -344.937982) (xy 389.800246 -344.992551) (xy 389.784534 -345.04541) (xy 389.761377 -345.095456)
			(xy 389.731257 -345.141647) (xy 389.694801 -345.183022) (xy 389.6741 -345.20124) (xy 389.663193 -345.211129)
			(xy 389.647122 -345.235782) (xy 389.638739 -345.263992) (xy 389.638741 -345.293421) (xy 389.647127 -345.32163)
			(xy 389.663202 -345.346281) (xy 389.6741 -345.35618) (xy 389.694815 -345.374385) (xy 389.731279 -345.415758)
			(xy 389.761405 -345.461949) (xy 389.784567 -345.511998) (xy 389.800281 -345.564859) (xy 389.808221 -345.619433)
			(xy 389.80822 -345.67458) (xy 389.800279 -345.729153) (xy 389.784563 -345.782015) (xy 389.761399 -345.832062)
			(xy 389.731271 -345.878253) (xy 389.694806 -345.919624) (xy 389.6741 -345.93784) (xy 389.663193 -345.947729)
			(xy 389.647122 -345.972382) (xy 389.638739 -346.000592) (xy 389.638741 -346.030021) (xy 389.647127 -346.05823)
			(xy 389.663202 -346.082881) (xy 389.6741 -346.09278) (xy 389.694805 -346.110998) (xy 389.731275 -346.152365)
			(xy 389.761408 -346.198554) (xy 389.784575 -346.2486) (xy 389.800293 -346.301462) (xy 389.808234 -346.356036)
			(xy 389.80872 -346.38361) (xy 389.808232 -346.410861) (xy 389.800474 -346.464808) (xy 389.785118 -346.517102)
			(xy 389.762477 -346.566678) (xy 389.733011 -346.612528) (xy 389.697319 -346.653718) (xy 389.65613 -346.689409)
			(xy 389.61028 -346.718876) (xy 389.560704 -346.741517) (xy 389.50841 -346.756874) (xy 389.454463 -346.764631)
			(xy 389.427212 -346.765118) (xy 389.399358 -346.764571) (xy 389.344244 -346.756449) (xy 389.290895 -346.740406)
			(xy 389.240443 -346.716782) (xy 389.193959 -346.686078) (xy 389.152429 -346.648946) (xy 389.116736 -346.606174)
			(xy 389.087635 -346.55867) (xy 389.065746 -346.507442) (xy 389.05815 -346.480638) (xy 389.053874 -346.466522)
			(xy 389.038487 -346.441374) (xy 389.01657 -346.421656) (xy 388.98994 -346.409005) (xy 388.96081 -346.404471)
			(xy 388.946136 -346.405962) (xy 388.933182 -346.40762) (xy 388.907125 -346.409403) (xy 388.894066 -346.409518)
			(xy 388.893812 -346.409518) (xy 388.879663 -346.409423) (xy 388.85144 -346.40739) (xy 388.837424 -346.405454)
			(xy 388.82408 -346.403805) (xy 388.797379 -346.40691) (xy 388.772419 -346.416889) (xy 388.750936 -346.433048)
			(xy 388.734426 -346.454261) (xy 388.724036 -346.479053) (xy 388.721854 -346.492322) (xy 388.717712 -346.519466)
			(xy 388.702744 -346.572294) (xy 388.680358 -346.62243) (xy 388.651017 -346.668839) (xy 388.615326 -346.710563)
			(xy 388.574022 -346.74674) (xy 388.527959 -346.776623) (xy 388.478089 -346.799595) (xy 388.42544 -346.81518)
			(xy 388.371101 -346.823057) (xy 388.343648 -346.823538) (xy 388.316398 -346.823) (xy 388.262451 -346.81525)
			(xy 388.210156 -346.799902) (xy 388.160578 -346.777267) (xy 388.114726 -346.747807) (xy 388.073534 -346.712121)
			(xy 388.03784 -346.670936) (xy 388.00837 -346.62509) (xy 387.985725 -346.575517) (xy 387.970366 -346.523225)
			(xy 387.962605 -346.46928) (xy 387.96214 -346.44203) (xy 387.962612 -346.414456) (xy 387.970562 -346.359882)
			(xy 387.986284 -346.307022) (xy 388.009453 -346.256976) (xy 388.039585 -346.210786) (xy 388.076053 -346.169415)
			(xy 388.09676 -346.1512) (xy 388.10763 -346.141273) (xy 388.12371 -346.116632) (xy 388.1321 -346.088431)
			(xy 388.132106 -346.059008) (xy 388.123726 -346.030803) (xy 388.107656 -346.006157) (xy 388.09676 -345.99626)
			(xy 388.076067 -345.97803) (xy 388.039597 -345.936664) (xy 388.009463 -345.890478) (xy 387.986295 -345.840434)
			(xy 387.970574 -345.787575) (xy 387.962629 -345.733003) (xy 387.96214 -345.70543) (xy 387.962563 -345.678928)
			(xy 387.969914 -345.626435) (xy 387.984465 -345.575466) (xy 388.005935 -345.527005) (xy 388.033911 -345.481984)
			(xy 388.050532 -345.461336) (xy 388.059995 -345.449205) (xy 388.071785 -345.4208) (xy 388.074606 -345.390175)
			(xy 388.068206 -345.360093) (xy 388.05316 -345.33327) (xy 388.030828 -345.312125) (xy 388.017258 -345.304872)
			(xy 387.993566 -345.292774) (xy 387.949585 -345.262851) (xy 387.910304 -345.226979) (xy 387.876521 -345.185887)
			(xy 387.862318 -345.163394) (xy 387.854357 -345.151197) (xy 387.832896 -345.131527) (xy 387.806753 -345.118719)
			(xy 387.778056 -345.113816) (xy 387.749144 -345.117218) (xy 387.735572 -345.1225) (xy 387.712363 -345.13199)
			(xy 387.664029 -345.145341) (xy 387.61434 -345.152069) (xy 387.589268 -345.152472) (xy 387.564199 -345.152047)
			(xy 387.514516 -345.145298) (xy 387.466181 -345.131966) (xy 387.442964 -345.1225) (xy 387.429377 -345.117281)
			(xy 387.400481 -345.113909) (xy 387.371806 -345.118813) (xy 387.345673 -345.131595) (xy 387.324198 -345.151222)
			(xy 387.316218 -345.163394) (xy 387.301649 -345.186525) (xy 387.266806 -345.228646) (xy 387.226183 -345.265225)
			(xy 387.180652 -345.295476) (xy 387.13119 -345.318752) (xy 387.078859 -345.334552) (xy 387.02478 -345.342538)
			(xy 386.970116 -345.342538) (xy 386.916037 -345.334552) (xy 386.863706 -345.318752) (xy 386.814244 -345.295476)
			(xy 386.768713 -345.265225) (xy 386.72809 -345.228646) (xy 386.693247 -345.186525) (xy 386.678678 -345.163394)
			(xy 386.670755 -345.15117) (xy 386.649283 -345.131499) (xy 386.62313 -345.118695) (xy 386.594425 -345.1138)
			(xy 386.565506 -345.117212) (xy 386.551932 -345.1225) (xy 386.528715 -345.131972) (xy 386.480386 -345.14533)
			(xy 386.430699 -345.152065) (xy 386.405628 -345.152472) (xy 386.377736 -345.152071) (xy 386.322576 -345.143761)
			(xy 386.26927 -345.127322) (xy 386.21901 -345.103121) (xy 386.172918 -345.071699) (xy 386.132025 -345.033759)
			(xy 386.097243 -344.990147) (xy 386.069351 -344.941838) (xy 386.04897 -344.889911) (xy 386.036556 -344.835527)
			(xy 386.032387 -344.7799) (xy 368.247973 -344.7799) (xy 368.189783 -344.788266) (xy 368.105182 -344.792297)
			(xy 368.020581 -344.788266) (xy 367.936746 -344.776213) (xy 367.854437 -344.756245) (xy 367.774398 -344.728543)
			(xy 367.697355 -344.693359) (xy 367.624005 -344.65101) (xy 367.555013 -344.601881) (xy 367.491003 -344.546416)
			(xy 367.432555 -344.485118) (xy 367.380199 -344.418542) (xy 367.334409 -344.34729) (xy 367.295598 -344.272009)
			(xy 367.264119 -344.193379) (xy 367.240258 -344.112112) (xy 367.224229 -344.028946) (xy 367.216178 -343.944632)
			(xy 363.908287 -343.944632) (xy 363.90028 -344.027211) (xy 363.884229 -344.109199) (xy 363.86034 -344.189256)
			(xy 363.828835 -344.266633) (xy 363.79001 -344.340608) (xy 363.744227 -344.410491) (xy 363.691912 -344.475628)
			(xy 363.633555 -344.535413) (xy 363.569701 -344.589286) (xy 363.500945 -344.636745) (xy 363.427929 -344.677346)
			(xy 363.351336 -344.710711) (xy 363.27188 -344.736528) (xy 363.190304 -344.754556) (xy 363.107368 -344.764626)
			(xy 363.023848 -344.766645) (xy 362.940522 -344.760593) (xy 362.85817 -344.746528) (xy 362.77756 -344.72458)
			(xy 362.699444 -344.694954) (xy 362.624552 -344.657928) (xy 362.553584 -344.613847) (xy 362.487201 -344.563121)
			(xy 362.426024 -344.506226) (xy 362.370623 -344.443692) (xy 362.321517 -344.376103) (xy 362.279163 -344.30409)
			(xy 362.243957 -344.228325) (xy 362.216228 -344.149516) (xy 362.196235 -344.068399) (xy 362.184163 -343.985731)
			(xy 362.180127 -343.902284) (xy 361.434126 -343.902284) (xy 361.433622 -343.944632) (xy 361.425571 -344.028946)
			(xy 361.409542 -344.112112) (xy 361.385681 -344.193379) (xy 361.354202 -344.272009) (xy 361.315391 -344.34729)
			(xy 361.269601 -344.418542) (xy 361.217245 -344.485118) (xy 361.158797 -344.546416) (xy 361.094787 -344.601881)
			(xy 361.025795 -344.65101) (xy 360.952445 -344.693359) (xy 360.875402 -344.728543) (xy 360.795363 -344.756245)
			(xy 360.713054 -344.776213) (xy 360.629219 -344.788266) (xy 360.544618 -344.792297) (xy 360.460017 -344.788266)
			(xy 360.376182 -344.776213) (xy 360.293873 -344.756245) (xy 360.213834 -344.728543) (xy 360.136791 -344.693359)
			(xy 360.063441 -344.65101) (xy 359.994449 -344.601881) (xy 359.930439 -344.546416) (xy 359.871991 -344.485118)
			(xy 359.819635 -344.418542) (xy 359.773845 -344.34729) (xy 359.735034 -344.272009) (xy 359.703555 -344.193379)
			(xy 359.679694 -344.112112) (xy 359.663665 -344.028946) (xy 359.655614 -343.944632) (xy 356.202943 -343.944632)
			(xy 356.194936 -344.027211) (xy 356.178885 -344.109199) (xy 356.154996 -344.189256) (xy 356.123491 -344.266633)
			(xy 356.084666 -344.340608) (xy 356.038883 -344.410491) (xy 355.986568 -344.475628) (xy 355.928211 -344.535413)
			(xy 355.864357 -344.589286) (xy 355.795601 -344.636745) (xy 355.722585 -344.677346) (xy 355.645992 -344.710711)
			(xy 355.566536 -344.736528) (xy 355.48496 -344.754556) (xy 355.402024 -344.764626) (xy 355.318504 -344.766645)
			(xy 355.235178 -344.760593) (xy 355.152826 -344.746528) (xy 355.072216 -344.72458) (xy 354.9941 -344.694954)
			(xy 354.919208 -344.657928) (xy 354.84824 -344.613847) (xy 354.781857 -344.563121) (xy 354.72068 -344.506226)
			(xy 354.665279 -344.443692) (xy 354.616173 -344.376103) (xy 354.573819 -344.30409) (xy 354.538613 -344.228325)
			(xy 354.510884 -344.149516) (xy 354.490891 -344.068399) (xy 354.478819 -343.985731) (xy 354.474783 -343.902284)
			(xy 353.728782 -343.902284) (xy 353.728278 -343.944632) (xy 353.720227 -344.028946) (xy 353.704198 -344.112112)
			(xy 353.680337 -344.193379) (xy 353.648858 -344.272009) (xy 353.610047 -344.34729) (xy 353.564257 -344.418542)
			(xy 353.511901 -344.485118) (xy 353.453453 -344.546416) (xy 353.389443 -344.601881) (xy 353.320451 -344.65101)
			(xy 353.247101 -344.693359) (xy 353.170058 -344.728543) (xy 353.090019 -344.756245) (xy 353.00771 -344.776213)
			(xy 352.923875 -344.788266) (xy 352.839274 -344.792297) (xy 352.754673 -344.788266) (xy 352.670838 -344.776213)
			(xy 352.588529 -344.756245) (xy 352.50849 -344.728543) (xy 352.431447 -344.693359) (xy 352.358097 -344.65101)
			(xy 352.289105 -344.601881) (xy 352.225095 -344.546416) (xy 352.166647 -344.485118) (xy 352.114291 -344.418542)
			(xy 352.068501 -344.34729) (xy 352.02969 -344.272009) (xy 351.998211 -344.193379) (xy 351.97435 -344.112112)
			(xy 351.958321 -344.028946) (xy 351.95027 -343.944632) (xy 348.642379 -343.944632) (xy 348.634372 -344.027211)
			(xy 348.618321 -344.109199) (xy 348.594432 -344.189256) (xy 348.562927 -344.266633) (xy 348.524102 -344.340608)
			(xy 348.478319 -344.410491) (xy 348.426004 -344.475628) (xy 348.367647 -344.535413) (xy 348.303793 -344.589286)
			(xy 348.235037 -344.636745) (xy 348.162021 -344.677346) (xy 348.085428 -344.710711) (xy 348.005972 -344.736528)
			(xy 347.924396 -344.754556) (xy 347.84146 -344.764626) (xy 347.75794 -344.766645) (xy 347.674614 -344.760593)
			(xy 347.592262 -344.746528) (xy 347.511652 -344.72458) (xy 347.433536 -344.694954) (xy 347.358644 -344.657928)
			(xy 347.287676 -344.613847) (xy 347.221293 -344.563121) (xy 347.160116 -344.506226) (xy 347.104715 -344.443692)
			(xy 347.055609 -344.376103) (xy 347.013255 -344.30409) (xy 346.978049 -344.228325) (xy 346.95032 -344.149516)
			(xy 346.930327 -344.068399) (xy 346.918255 -343.985731) (xy 346.914219 -343.902284) (xy 346.168218 -343.902284)
			(xy 346.167714 -343.944632) (xy 346.159663 -344.028946) (xy 346.143634 -344.112112) (xy 346.119773 -344.193379)
			(xy 346.088294 -344.272009) (xy 346.049483 -344.34729) (xy 346.003693 -344.418542) (xy 345.951337 -344.485118)
			(xy 345.892889 -344.546416) (xy 345.828879 -344.601881) (xy 345.759887 -344.65101) (xy 345.686537 -344.693359)
			(xy 345.609494 -344.728543) (xy 345.529455 -344.756245) (xy 345.447146 -344.776213) (xy 345.363311 -344.788266)
			(xy 345.27871 -344.792297) (xy 345.194109 -344.788266) (xy 345.110274 -344.776213) (xy 345.027965 -344.756245)
			(xy 344.947926 -344.728543) (xy 344.870883 -344.693359) (xy 344.797533 -344.65101) (xy 344.728541 -344.601881)
			(xy 344.664531 -344.546416) (xy 344.606083 -344.485118) (xy 344.553727 -344.418542) (xy 344.507937 -344.34729)
			(xy 344.469126 -344.272009) (xy 344.437647 -344.193379) (xy 344.413786 -344.112112) (xy 344.397757 -344.028946)
			(xy 344.389706 -343.944632) (xy 335.054448 -343.944632) (xy 335.054448 -346.220288) (xy 335.053813 -346.245284)
			(xy 335.04401 -346.294307) (xy 335.024836 -346.340478) (xy 334.997028 -346.382024) (xy 334.979772 -346.40012)
			(xy 334.842848 -346.537044) (xy 382.033826 -346.537044) (xy 382.033826 -346.482551) (xy 382.041582 -346.428612)
			(xy 382.056934 -346.376326) (xy 382.079571 -346.326756) (xy 382.109032 -346.280913) (xy 382.144717 -346.239729)
			(xy 382.185899 -346.204042) (xy 382.231741 -346.174579) (xy 382.281309 -346.15194) (xy 382.333595 -346.136585)
			(xy 382.387533 -346.128828) (xy 382.41478 -346.12834) (xy 382.43435 -346.128544) (xy 382.473291 -346.132488)
			(xy 382.492504 -346.136214) (xy 382.506172 -346.138647) (xy 382.533865 -346.136801) (xy 382.560034 -346.127559)
			(xy 382.582744 -346.111605) (xy 382.600312 -346.090118) (xy 382.611437 -346.064692) (xy 382.615296 -346.037208)
			(xy 382.611603 -346.009701) (xy 382.60655 -345.996768) (xy 382.596661 -345.972815) (xy 382.582754 -345.922894)
			(xy 382.57574 -345.871549) (xy 382.575308 -345.845638) (xy 382.575714 -345.818382) (xy 382.583467 -345.764424)
			(xy 382.59882 -345.712119) (xy 382.62146 -345.662531) (xy 382.650927 -345.61667) (xy 382.686621 -345.57547)
			(xy 382.727815 -345.539768) (xy 382.773671 -345.510293) (xy 382.823255 -345.487644) (xy 382.875557 -345.472281)
			(xy 382.929513 -345.464519) (xy 382.984025 -345.464515) (xy 383.037983 -345.472268) (xy 383.090288 -345.487622)
			(xy 383.139875 -345.510263) (xy 383.185736 -345.539731) (xy 383.226936 -345.575426) (xy 383.262636 -345.616621)
			(xy 383.292111 -345.662477) (xy 383.314759 -345.712061) (xy 383.33012 -345.764364) (xy 383.337881 -345.818321)
			(xy 383.337885 -345.872833) (xy 383.33013 -345.92679) (xy 383.314775 -345.979095) (xy 383.292133 -346.028682)
			(xy 383.262664 -346.074542) (xy 383.226969 -346.115741) (xy 383.185773 -346.151441) (xy 383.139916 -346.180914)
			(xy 383.090332 -346.203562) (xy 383.038029 -346.218922) (xy 382.984072 -346.226682) (xy 382.956816 -346.227146)
			(xy 382.937246 -346.226943) (xy 382.898305 -346.222999) (xy 382.879092 -346.219272) (xy 382.865405 -346.216953)
			(xy 382.837722 -346.218776) (xy 382.811557 -346.227999) (xy 382.78885 -346.243937) (xy 382.771282 -346.265408)
			(xy 382.760157 -346.290823) (xy 382.756298 -346.318296) (xy 382.759992 -346.345791) (xy 382.765046 -346.358718)
			(xy 382.774931 -346.382673) (xy 382.78884 -346.432593) (xy 382.795855 -346.483937) (xy 382.796288 -346.509848)
			(xy 382.79577 -346.537095) (xy 382.788009 -346.591033) (xy 382.77265 -346.643317) (xy 382.750007 -346.692884)
			(xy 382.720541 -346.738723) (xy 382.684851 -346.779903) (xy 382.643665 -346.815585) (xy 382.597819 -346.845042)
			(xy 382.548248 -346.867676) (xy 382.495961 -346.883024) (xy 382.442021 -346.890776) (xy 382.387528 -346.890772)
			(xy 382.33359 -346.883014) (xy 382.281304 -346.867658) (xy 382.231736 -346.845018) (xy 382.185895 -346.815555)
			(xy 382.144713 -346.779867) (xy 382.109029 -346.738683) (xy 382.079568 -346.692839) (xy 382.056932 -346.643269)
			(xy 382.04158 -346.590983) (xy 382.033826 -346.537044) (xy 334.842848 -346.537044) (xy 333.940658 -347.439234)
			(xy 383.381504 -347.439234) (xy 383.382082 -347.409547) (xy 383.391276 -347.350889) (xy 383.409446 -347.294363)
			(xy 383.436155 -347.241336) (xy 383.470757 -347.193086) (xy 383.512417 -347.15078) (xy 383.535936 -347.132656)
			(xy 383.546519 -347.124203) (xy 383.563221 -347.102895) (xy 383.573738 -347.077948) (xy 383.57733 -347.051113)
			(xy 383.573745 -347.024278) (xy 383.563235 -346.999328) (xy 383.546538 -346.978015) (xy 383.535936 -346.969588)
			(xy 383.512428 -346.95145) (xy 383.470765 -346.909147) (xy 383.436159 -346.860901) (xy 383.409446 -346.807877)
			(xy 383.39127 -346.751353) (xy 383.38207 -346.692697) (xy 383.381504 -346.66301) (xy 383.38199 -346.635759)
			(xy 383.389746 -346.581811) (xy 383.405101 -346.529516) (xy 383.427743 -346.479939) (xy 383.457209 -346.434089)
			(xy 383.4929 -346.392898) (xy 383.534091 -346.357207) (xy 383.579941 -346.327741) (xy 383.629518 -346.305099)
			(xy 383.681813 -346.289744) (xy 383.735761 -346.281988) (xy 383.790263 -346.281988) (xy 383.844211 -346.289744)
			(xy 383.896506 -346.305099) (xy 383.946083 -346.327741) (xy 383.991933 -346.357207) (xy 384.033124 -346.392898)
			(xy 384.068815 -346.434089) (xy 384.098281 -346.479939) (xy 384.120923 -346.529516) (xy 384.136278 -346.581811)
			(xy 384.144034 -346.635759) (xy 384.14452 -346.66301) (xy 384.143964 -346.692698) (xy 384.134764 -346.751357)
			(xy 384.116589 -346.807882) (xy 384.089876 -346.860909) (xy 384.077793 -346.877756) (xy 384.397917 -346.877756)
			(xy 384.397917 -346.823244) (xy 384.405675 -346.769286) (xy 384.421033 -346.716982) (xy 384.443679 -346.667396)
			(xy 384.473151 -346.621538) (xy 384.50885 -346.580341) (xy 384.550048 -346.544644) (xy 384.595907 -346.515173)
			(xy 384.645494 -346.492529) (xy 384.697798 -346.477172) (xy 384.751756 -346.469416) (xy 384.779012 -346.468954)
			(xy 384.779266 -346.468954) (xy 384.804469 -346.469366) (xy 384.854437 -346.476002) (xy 384.903091 -346.489175)
			(xy 384.949582 -346.508654) (xy 384.971544 -346.521024) (xy 384.984489 -346.528103) (xy 385.013135 -346.535136)
			(xy 385.042595 -346.533686) (xy 385.070411 -346.523876) (xy 385.094263 -346.506524) (xy 385.112159 -346.483078)
			(xy 385.117848 -346.469462) (xy 385.128551 -346.442689) (xy 385.156839 -346.392449) (xy 385.192369 -346.347041)
			(xy 385.23433 -346.307499) (xy 385.281766 -346.274725) (xy 385.333596 -346.249467) (xy 385.388637 -346.232299)
			(xy 385.445636 -346.223613) (xy 385.474464 -346.223082) (xy 385.501716 -346.223589) (xy 385.555664 -346.231341)
			(xy 385.607961 -346.246692) (xy 385.65754 -346.269329) (xy 385.703393 -346.298792) (xy 385.744586 -346.334482)
			(xy 385.78028 -346.37567) (xy 385.809749 -346.421519) (xy 385.832392 -346.471096) (xy 385.84775 -346.523391)
			(xy 385.855508 -346.577339) (xy 385.855972 -346.60459) (xy 385.855972 -346.604844) (xy 385.855401 -346.634683)
			(xy 385.846083 -346.693629) (xy 385.83743 -346.722192) (xy 385.833331 -346.736085) (xy 385.832428 -346.765028)
			(xy 385.839703 -346.793056) (xy 385.854568 -346.817907) (xy 385.875823 -346.837573) (xy 385.901752 -346.850466)
			(xy 385.915916 -346.85351) (xy 385.941986 -346.858696) (xy 385.992488 -346.875265) (xy 386.040201 -346.898686)
			(xy 386.084199 -346.928506) (xy 386.12363 -346.964147) (xy 386.157729 -347.004918) (xy 386.185837 -347.05003)
			(xy 386.207407 -347.098607) (xy 386.222023 -347.149709) (xy 386.229401 -347.202346) (xy 386.22986 -347.228922)
			(xy 386.229374 -347.256173) (xy 386.221618 -347.310121) (xy 386.206263 -347.362416) (xy 386.183621 -347.411993)
			(xy 386.154155 -347.457843) (xy 386.118464 -347.499034) (xy 386.077273 -347.534725) (xy 386.031423 -347.564191)
			(xy 385.981846 -347.586833) (xy 385.929551 -347.602188) (xy 385.875603 -347.609944) (xy 385.821101 -347.609944)
			(xy 385.767153 -347.602188) (xy 385.714858 -347.586833) (xy 385.665281 -347.564191) (xy 385.619431 -347.534725)
			(xy 385.57824 -347.499034) (xy 385.542549 -347.457843) (xy 385.513083 -347.411993) (xy 385.490441 -347.362416)
			(xy 385.475086 -347.310121) (xy 385.46733 -347.256173) (xy 385.466844 -347.228922) (xy 385.466844 -347.228668)
			(xy 385.467421 -347.198829) (xy 385.476735 -347.139883) (xy 385.485386 -347.11132) (xy 385.489459 -347.097421)
			(xy 385.490364 -347.068483) (xy 385.483092 -347.040458) (xy 385.468233 -347.015609) (xy 385.446984 -346.995944)
			(xy 385.421061 -346.983049) (xy 385.4069 -346.980002) (xy 385.37406 -346.973421) (xy 385.311208 -346.950297)
			(xy 385.281932 -346.934028) (xy 385.26899 -346.926946) (xy 385.240345 -346.919923) (xy 385.210887 -346.921377)
			(xy 385.183072 -346.931188) (xy 385.159221 -346.948537) (xy 385.141321 -346.971977) (xy 385.135628 -346.98559)
			(xy 385.12492 -347.012361) (xy 385.096635 -347.062604) (xy 385.061107 -347.108014) (xy 385.019147 -347.147557)
			(xy 384.971711 -347.180332) (xy 384.919882 -347.20559) (xy 384.86484 -347.222757) (xy 384.80784 -347.23144)
			(xy 384.779012 -347.23197) (xy 384.751756 -347.231584) (xy 384.697798 -347.223828) (xy 384.645494 -347.208471)
			(xy 384.595907 -347.185827) (xy 384.550048 -347.156356) (xy 384.50885 -347.120659) (xy 384.473151 -347.079462)
			(xy 384.443679 -347.033604) (xy 384.421033 -346.984018) (xy 384.405675 -346.931714) (xy 384.397917 -346.877756)
			(xy 384.077793 -346.877756) (xy 384.05527 -346.909158) (xy 384.013608 -346.951464) (xy 383.990088 -346.969588)
			(xy 383.979459 -346.977989) (xy 383.962753 -346.999307) (xy 383.952237 -347.024267) (xy 383.948649 -347.051113)
			(xy 383.952243 -347.077958) (xy 383.962766 -347.102915) (xy 383.979478 -347.12423) (xy 383.990088 -347.132656)
			(xy 384.013622 -347.150762) (xy 384.055282 -347.193072) (xy 384.089884 -347.241325) (xy 384.116593 -347.294356)
			(xy 384.134764 -347.350884) (xy 384.143958 -347.409545) (xy 384.14452 -347.439234) (xy 384.144034 -347.466485)
			(xy 384.136278 -347.520433) (xy 384.120923 -347.572728) (xy 384.098281 -347.622305) (xy 384.068815 -347.668155)
			(xy 384.033124 -347.709346) (xy 383.991933 -347.745037) (xy 383.946083 -347.774503) (xy 383.896506 -347.797145)
			(xy 383.844211 -347.8125) (xy 383.790263 -347.820256) (xy 383.735761 -347.820256) (xy 383.681813 -347.8125)
			(xy 383.629518 -347.797145) (xy 383.579941 -347.774503) (xy 383.534091 -347.745037) (xy 383.4929 -347.709346)
			(xy 383.457209 -347.668155) (xy 383.427743 -347.622305) (xy 383.405101 -347.572728) (xy 383.389746 -347.520433)
			(xy 383.38199 -347.466485) (xy 383.381504 -347.439234) (xy 333.940658 -347.439234) (xy 331.781912 -349.59798)
			(xy 331.763802 -349.61522) (xy 331.722262 -349.643034) (xy 331.676096 -349.662212) (xy 331.627075 -349.672016)
			(xy 331.60208 -349.672656) (xy 328.588878 -349.672656) (xy 328.563881 -349.672039) (xy 328.514857 -349.66223)
			(xy 328.468686 -349.643051) (xy 328.427141 -349.615238) (xy 328.409046 -349.59798) (xy 326.691752 -347.880686)
			(xy 326.670416 -347.880686) (xy 326.643139 -347.880271) (xy 326.589131 -347.872574) (xy 326.536771 -347.857262)
			(xy 326.487125 -347.834647) (xy 326.441207 -347.805192) (xy 326.399953 -347.769497) (xy 326.364204 -347.728289)
			(xy 326.334689 -347.682409) (xy 326.312011 -347.632793) (xy 326.296631 -347.580452) (xy 326.288863 -347.526455)
			(xy 326.2884 -347.499178) (xy 322.707196 -347.499178) (xy 322.71007 -347.519171) (xy 322.710556 -347.546422)
			(xy 322.710072 -347.5728) (xy 322.702818 -347.625054) (xy 322.688437 -347.675812) (xy 322.667203 -347.724105)
			(xy 322.63952 -347.769015) (xy 322.605918 -347.809684) (xy 322.567034 -347.845339) (xy 322.523611 -347.875299)
			(xy 322.500244 -347.887544) (xy 322.487865 -347.894212) (xy 322.467132 -347.913193) (xy 322.452369 -347.937113)
			(xy 322.444697 -347.964155) (xy 322.4447 -347.992264) (xy 322.452377 -348.019305) (xy 322.467145 -348.043222)
			(xy 322.487881 -348.062199) (xy 322.500244 -348.0689) (xy 322.523634 -348.081106) (xy 322.567057 -348.111075)
			(xy 322.60594 -348.146736) (xy 322.639544 -348.187411) (xy 322.667229 -348.232325) (xy 322.688466 -348.280622)
			(xy 322.702852 -348.331383) (xy 322.710112 -348.383642) (xy 322.710556 -348.410022) (xy 322.71007 -348.437273)
			(xy 322.702314 -348.491221) (xy 322.686959 -348.543516) (xy 322.664317 -348.593093) (xy 322.634851 -348.638943)
			(xy 322.59916 -348.680134) (xy 322.557969 -348.715825) (xy 322.512119 -348.745291) (xy 322.462542 -348.767933)
			(xy 322.410247 -348.783288) (xy 322.356299 -348.791044) (xy 322.301797 -348.791044) (xy 322.247849 -348.783288)
			(xy 322.195554 -348.767933) (xy 322.145977 -348.745291) (xy 322.100127 -348.715825) (xy 322.058936 -348.680134)
			(xy 322.023245 -348.638943) (xy 321.993779 -348.593093) (xy 321.971137 -348.543516) (xy 321.955782 -348.491221)
			(xy 321.948026 -348.437273) (xy 321.94754 -348.410022) (xy 320.131453 -348.410022) (xy 320.683957 -350.895412)
			(xy 336.039206 -350.895412) (xy 336.039731 -350.866495) (xy 336.048458 -350.809324) (xy 336.065715 -350.754126)
			(xy 336.091105 -350.702164) (xy 336.124048 -350.65463) (xy 336.163787 -350.612612) (xy 336.186272 -350.594422)
			(xy 336.198067 -350.584512) (xy 336.215587 -350.559193) (xy 336.224765 -350.529802) (xy 336.224768 -350.499012)
			(xy 336.215593 -350.469621) (xy 336.198077 -350.444299) (xy 336.186272 -350.434402) (xy 336.163784 -350.416217)
			(xy 336.12405 -350.374195) (xy 336.091112 -350.326659) (xy 336.065725 -350.274696) (xy 336.04847 -350.219498)
			(xy 336.039741 -350.162328) (xy 336.039206 -350.133412) (xy 336.039743 -350.1044) (xy 336.048511 -350.047042)
			(xy 336.065861 -349.991673) (xy 336.091395 -349.939569) (xy 336.124522 -349.891931) (xy 336.144108 -349.870522)
			(xy 336.154365 -349.858964) (xy 336.167938 -349.831216) (xy 336.1726 -349.80068) (xy 336.167925 -349.770145)
			(xy 336.154342 -349.742403) (xy 336.144108 -349.730822) (xy 336.124536 -349.709401) (xy 336.091417 -349.661761)
			(xy 336.065886 -349.609659) (xy 336.04853 -349.554295) (xy 336.039748 -349.496942) (xy 336.039206 -349.467932)
			(xy 336.039729 -349.440676) (xy 336.04749 -349.386719) (xy 336.062846 -349.334415) (xy 336.085484 -349.284826)
			(xy 336.114944 -349.23896) (xy 336.150627 -349.19775) (xy 336.191808 -349.162033) (xy 336.214466 -349.146876)
			(xy 336.226362 -349.138554) (xy 336.245364 -349.116627) (xy 336.25742 -349.090236) (xy 336.261553 -349.061517)
			(xy 336.25743 -349.032797) (xy 336.245383 -349.006402) (xy 336.226389 -348.984469) (xy 336.214466 -348.976188)
			(xy 336.19178 -348.961065) (xy 336.150579 -348.925356) (xy 336.11488 -348.884147) (xy 336.085409 -348.838276)
			(xy 336.062767 -348.788677) (xy 336.047415 -348.736361) (xy 336.039664 -348.682393) (xy 336.039206 -348.655132)
			(xy 336.039685 -348.627879) (xy 336.047438 -348.573928) (xy 336.062791 -348.52163) (xy 336.085431 -348.472049)
			(xy 336.114897 -348.426195) (xy 336.150589 -348.385001) (xy 336.19178 -348.349307) (xy 336.237633 -348.319839)
			(xy 336.287213 -348.297197) (xy 336.339511 -348.281842) (xy 336.393461 -348.274086) (xy 336.420714 -348.273624)
			(xy 336.446635 -348.274074) (xy 336.497997 -348.281107) (xy 336.547935 -348.295027) (xy 336.595529 -348.315578)
			(xy 336.639903 -348.342383) (xy 336.680241 -348.374947) (xy 336.698336 -348.393512) (xy 336.707692 -348.402998)
			(xy 336.730329 -348.417038) (xy 336.755831 -348.424737) (xy 336.782456 -348.425569) (xy 336.808389 -348.419477)
			(xy 336.831858 -348.406876) (xy 336.851264 -348.388627) (xy 336.85861 -348.37751) (xy 336.873637 -348.354274)
			(xy 336.909342 -348.312) (xy 336.950778 -348.275326) (xy 336.997075 -348.245019) (xy 337.047264 -348.221716)
			(xy 337.100292 -348.205904) (xy 337.155047 -348.197915) (xy 337.182714 -348.197424) (xy 337.209967 -348.197847)
			(xy 337.263918 -348.205606) (xy 337.316215 -348.220963) (xy 337.365795 -348.243607) (xy 337.411647 -348.273076)
			(xy 337.452839 -348.308771) (xy 337.488532 -348.349964) (xy 337.518 -348.395818) (xy 337.540642 -348.445398)
			(xy 337.555997 -348.497696) (xy 337.563754 -348.551647) (xy 337.563754 -348.606153) (xy 337.560749 -348.627052)
			(xy 337.766138 -348.627052) (xy 337.766138 -348.572548) (xy 337.773894 -348.518599) (xy 337.789248 -348.466303)
			(xy 337.811888 -348.416723) (xy 337.841353 -348.37087) (xy 337.877043 -348.329677) (xy 337.918232 -348.293982)
			(xy 337.964081 -348.264511) (xy 338.013657 -348.241865) (xy 338.065952 -348.226504) (xy 338.1199 -348.218741)
			(xy 338.147152 -348.218252) (xy 338.176069 -348.218785) (xy 338.23324 -348.227508) (xy 338.288439 -348.244762)
			(xy 338.340402 -348.270151) (xy 338.387936 -348.303093) (xy 338.429952 -348.342833) (xy 338.448142 -348.365318)
			(xy 338.458039 -348.377123) (xy 338.483363 -348.394642) (xy 338.512756 -348.403818) (xy 338.543548 -348.403818)
			(xy 338.572941 -348.394642) (xy 338.598265 -348.377123) (xy 338.608162 -348.365318) (xy 338.624915 -348.344535)
			(xy 338.663269 -348.307405) (xy 338.706423 -348.275983) (xy 338.753537 -348.250884) (xy 338.803689 -348.232598)
			(xy 338.8559 -348.221481) (xy 338.909152 -348.217751) (xy 338.962404 -348.221481) (xy 339.014615 -348.232598)
			(xy 339.064767 -348.250884) (xy 339.111881 -348.275983) (xy 339.155035 -348.307405) (xy 339.193389 -348.344535)
			(xy 339.210142 -348.365318) (xy 339.220039 -348.377123) (xy 339.245363 -348.394642) (xy 339.274756 -348.403818)
			(xy 339.305548 -348.403818) (xy 339.334941 -348.394642) (xy 339.360265 -348.377123) (xy 339.370162 -348.365318)
			(xy 339.386915 -348.344535) (xy 339.425269 -348.307405) (xy 339.468423 -348.275983) (xy 339.515537 -348.250884)
			(xy 339.565689 -348.232598) (xy 339.6179 -348.221481) (xy 339.671152 -348.217751) (xy 339.724404 -348.221481)
			(xy 339.776615 -348.232598) (xy 339.826767 -348.250884) (xy 339.873881 -348.275983) (xy 339.917035 -348.307405)
			(xy 339.955389 -348.344535) (xy 339.972142 -348.365318) (xy 339.982039 -348.377123) (xy 340.007363 -348.394642)
			(xy 340.036756 -348.403818) (xy 340.067548 -348.403818) (xy 340.096941 -348.394642) (xy 340.122265 -348.377123)
			(xy 340.132162 -348.365318) (xy 340.150379 -348.342856) (xy 340.192393 -348.303119) (xy 340.239922 -348.270177)
			(xy 340.291878 -348.244785) (xy 340.347072 -348.227524) (xy 340.404237 -348.21879) (xy 340.433152 -348.218252)
			(xy 340.461719 -348.218782) (xy 340.518214 -348.227316) (xy 340.572807 -348.244169) (xy 340.624281 -348.268966)
			(xy 340.671487 -348.301155) (xy 340.713371 -348.340015) (xy 340.731602 -348.362016) (xy 340.741172 -348.373259)
			(xy 340.765411 -348.390096) (xy 340.793451 -348.399307) (xy 340.822953 -348.400124) (xy 340.851459 -348.392478)
			(xy 340.876593 -348.377006) (xy 340.886796 -348.366334) (xy 340.904952 -348.346705) (xy 340.945838 -348.312247)
			(xy 340.991134 -348.283834) (xy 341.039954 -348.262024) (xy 341.09134 -348.247243) (xy 341.144287 -348.239782)
			(xy 341.171022 -348.239334) (xy 341.199937 -348.239896) (xy 341.257107 -348.248614) (xy 341.312306 -348.265862)
			(xy 341.364268 -348.291246) (xy 341.411803 -348.324183) (xy 341.453821 -348.363917) (xy 341.472012 -348.3864)
			(xy 341.481909 -348.398205) (xy 341.507233 -348.415724) (xy 341.536626 -348.4249) (xy 341.567418 -348.4249)
			(xy 341.596811 -348.415724) (xy 341.622135 -348.398205) (xy 341.632032 -348.3864) (xy 341.650205 -348.363901)
			(xy 341.692228 -348.324167) (xy 341.739767 -348.29123) (xy 341.791732 -348.265844) (xy 341.846933 -348.248591)
			(xy 341.904105 -348.239867) (xy 341.933022 -348.239334) (xy 341.960275 -348.239737) (xy 342.014227 -348.247497)
			(xy 342.066524 -348.262856) (xy 342.116104 -348.285501) (xy 342.161957 -348.314971) (xy 342.203149 -348.350666)
			(xy 342.238842 -348.391861) (xy 342.26831 -348.437715) (xy 342.290952 -348.487296) (xy 342.306307 -348.539595)
			(xy 342.314064 -348.593547) (xy 342.314064 -348.648053) (xy 342.306307 -348.702005) (xy 342.290952 -348.754304)
			(xy 342.26831 -348.803885) (xy 342.238842 -348.849739) (xy 342.203149 -348.890934) (xy 342.161957 -348.926629)
			(xy 342.116104 -348.956099) (xy 342.066524 -348.978744) (xy 342.014227 -348.994103) (xy 341.960275 -349.001863)
			(xy 341.933022 -349.00235) (xy 341.904105 -349.001835) (xy 341.846933 -348.993108) (xy 341.791733 -348.975851)
			(xy 341.739771 -348.950458) (xy 341.692237 -348.917513) (xy 341.650221 -348.877771) (xy 341.632032 -348.855284)
			(xy 341.622135 -348.843479) (xy 341.596811 -348.82596) (xy 341.567418 -348.816784) (xy 341.536626 -348.816784)
			(xy 341.507233 -348.82596) (xy 341.481909 -348.843479) (xy 341.472012 -348.855284) (xy 341.45381 -348.877758)
			(xy 341.411793 -348.917495) (xy 341.364261 -348.950435) (xy 341.312301 -348.975826) (xy 341.257106 -348.993084)
			(xy 341.199937 -349.001814) (xy 341.171022 -349.00235) (xy 341.142456 -349.001766) (xy 341.085964 -348.993244)
			(xy 341.031372 -348.976401) (xy 340.979898 -348.951614) (xy 340.932691 -348.919435) (xy 340.890804 -348.880583)
			(xy 340.872572 -348.858586) (xy 340.86303 -348.847318) (xy 340.838783 -348.83048) (xy 340.810736 -348.821272)
			(xy 340.781228 -348.82046) (xy 340.752717 -348.828113) (xy 340.727582 -348.843592) (xy 340.717378 -348.854268)
			(xy 340.699186 -348.873862) (xy 340.658307 -348.908323) (xy 340.613018 -348.93674) (xy 340.564206 -348.958556)
			(xy 340.512826 -348.973344) (xy 340.459885 -348.980815) (xy 340.433152 -348.981268) (xy 340.404236 -348.980725)
			(xy 340.347065 -348.972002) (xy 340.291866 -348.95475) (xy 340.239904 -348.929363) (xy 340.19237 -348.896424)
			(xy 340.150352 -348.856686) (xy 340.132162 -348.834202) (xy 340.122265 -348.822397) (xy 340.096941 -348.804878)
			(xy 340.067548 -348.795702) (xy 340.036756 -348.795702) (xy 340.007363 -348.804878) (xy 339.982039 -348.822397)
			(xy 339.972142 -348.834202) (xy 339.955389 -348.854985) (xy 339.917035 -348.892115) (xy 339.873881 -348.923537)
			(xy 339.826767 -348.948636) (xy 339.776615 -348.966922) (xy 339.724404 -348.978039) (xy 339.671152 -348.981769)
			(xy 339.6179 -348.978039) (xy 339.565689 -348.966922) (xy 339.515537 -348.948636) (xy 339.468423 -348.923537)
			(xy 339.425269 -348.892115) (xy 339.386915 -348.854985) (xy 339.370162 -348.834202) (xy 339.360265 -348.822397)
			(xy 339.334941 -348.804878) (xy 339.305548 -348.795702) (xy 339.274756 -348.795702) (xy 339.245363 -348.804878)
			(xy 339.220039 -348.822397) (xy 339.210142 -348.834202) (xy 339.193389 -348.854985) (xy 339.155035 -348.892115)
			(xy 339.111881 -348.923537) (xy 339.064767 -348.948636) (xy 339.014615 -348.966922) (xy 338.962404 -348.978039)
			(xy 338.909152 -348.981769) (xy 338.8559 -348.978039) (xy 338.803689 -348.966922) (xy 338.753537 -348.948636)
			(xy 338.706423 -348.923537) (xy 338.663269 -348.892115) (xy 338.624915 -348.854985) (xy 338.608162 -348.834202)
			(xy 338.598265 -348.822397) (xy 338.572941 -348.804878) (xy 338.543548 -348.795702) (xy 338.512756 -348.795702)
			(xy 338.483363 -348.804878) (xy 338.458039 -348.822397) (xy 338.448142 -348.834202) (xy 338.429928 -348.856666)
			(xy 338.387913 -348.896402) (xy 338.340383 -348.929343) (xy 338.288426 -348.954735) (xy 338.233233 -348.971996)
			(xy 338.176067 -348.98073) (xy 338.147152 -348.981268) (xy 338.1199 -348.980859) (xy 338.065952 -348.973096)
			(xy 338.013657 -348.957735) (xy 337.964081 -348.935089) (xy 337.918232 -348.905618) (xy 337.877043 -348.869923)
			(xy 337.841353 -348.82873) (xy 337.811888 -348.782877) (xy 337.789248 -348.733297) (xy 337.773894 -348.681001)
			(xy 337.766138 -348.627052) (xy 337.560749 -348.627052) (xy 337.555997 -348.660104) (xy 337.540642 -348.712402)
			(xy 337.518 -348.761982) (xy 337.488532 -348.807836) (xy 337.452839 -348.849029) (xy 337.411647 -348.884724)
			(xy 337.365795 -348.914193) (xy 337.316215 -348.936837) (xy 337.263918 -348.952194) (xy 337.209967 -348.959953)
			(xy 337.182714 -348.96044) (xy 337.156793 -348.960017) (xy 337.10543 -348.952976) (xy 337.055492 -348.939049)
			(xy 337.007899 -348.918493) (xy 336.963525 -348.891684) (xy 336.923187 -348.859117) (xy 336.905092 -348.840552)
			(xy 336.895703 -348.831104) (xy 336.873072 -348.817068) (xy 336.84758 -348.809369) (xy 336.820963 -348.808534)
			(xy 336.795038 -348.814618) (xy 336.771572 -348.827208) (xy 336.752166 -348.845443) (xy 336.744818 -348.856554)
			(xy 336.729487 -348.880269) (xy 336.692936 -348.923312) (xy 336.650442 -348.960499) (xy 336.626962 -348.976188)
			(xy 336.614968 -348.984388) (xy 336.595949 -349.006342) (xy 336.583886 -349.032766) (xy 336.579756 -349.061517)
			(xy 336.583895 -349.090268) (xy 336.595967 -349.116687) (xy 336.614994 -349.138635) (xy 336.626962 -349.146876)
			(xy 336.653745 -349.164882) (xy 336.701371 -349.208427) (xy 336.721704 -349.23349) (xy 336.731601 -349.245295)
			(xy 336.756925 -349.262814) (xy 336.786318 -349.27199) (xy 336.81711 -349.27199) (xy 336.846503 -349.262814)
			(xy 336.871827 -349.245295) (xy 336.881724 -349.23349) (xy 336.899899 -349.210993) (xy 336.941922 -349.171259)
			(xy 336.989461 -349.138322) (xy 337.041425 -349.112936) (xy 337.096625 -349.095683) (xy 337.153797 -349.086957)
			(xy 337.182714 -349.086424) (xy 337.209969 -349.086842) (xy 337.263923 -349.094602) (xy 337.316224 -349.109961)
			(xy 337.365806 -349.132608) (xy 337.411661 -349.16208) (xy 337.452854 -349.197779) (xy 337.488548 -349.238976)
			(xy 337.518015 -349.284834) (xy 337.540655 -349.33442) (xy 337.556008 -349.386722) (xy 337.563761 -349.440677)
			(xy 337.564222 -349.467932) (xy 337.563704 -349.496945) (xy 337.554931 -349.554303) (xy 337.537575 -349.609672)
			(xy 337.512038 -349.661775) (xy 337.478908 -349.709413) (xy 337.45932 -349.730822) (xy 337.449116 -349.742424)
			(xy 337.435534 -349.770156) (xy 337.43086 -349.80068) (xy 337.435521 -349.831205) (xy 337.449093 -349.858943)
			(xy 337.45932 -349.870522) (xy 337.478917 -349.891921) (xy 337.512032 -349.939567) (xy 337.537558 -349.991675)
			(xy 337.554908 -350.047044) (xy 337.563683 -350.1044) (xy 337.564222 -350.133412) (xy 337.563824 -350.15424)
			(xy 337.765644 -350.15424) (xy 337.766188 -350.125228) (xy 337.774952 -350.06787) (xy 337.792301 -350.012501)
			(xy 337.817833 -349.960397) (xy 337.85096 -349.912759) (xy 337.870546 -349.89135) (xy 337.880781 -349.879772)
			(xy 337.894365 -349.852032) (xy 337.899035 -349.8215) (xy 337.894365 -349.790968) (xy 337.880781 -349.763228)
			(xy 337.870546 -349.75165) (xy 337.850977 -349.730227) (xy 337.81786 -349.682586) (xy 337.79233 -349.630485)
			(xy 337.774972 -349.575122) (xy 337.766188 -349.51777) (xy 337.765644 -349.48876) (xy 337.76614 -349.46151)
			(xy 337.773901 -349.407565) (xy 337.789259 -349.355274) (xy 337.811901 -349.305699) (xy 337.841367 -349.259851)
			(xy 337.877057 -349.218663) (xy 337.918245 -349.182972) (xy 337.964092 -349.153505) (xy 338.013666 -349.130862)
			(xy 338.065957 -349.115503) (xy 338.119902 -349.107741) (xy 338.147152 -349.107252) (xy 338.176069 -349.107785)
			(xy 338.23324 -349.116508) (xy 338.288439 -349.133762) (xy 338.340402 -349.159151) (xy 338.387936 -349.192093)
			(xy 338.429952 -349.231833) (xy 338.448142 -349.254318) (xy 338.458039 -349.266123) (xy 338.483363 -349.283642)
			(xy 338.512756 -349.292818) (xy 338.543548 -349.292818) (xy 338.572941 -349.283642) (xy 338.598265 -349.266123)
			(xy 338.608162 -349.254318) (xy 338.624915 -349.233535) (xy 338.663269 -349.196405) (xy 338.706423 -349.164983)
			(xy 338.753537 -349.139884) (xy 338.803689 -349.121598) (xy 338.8559 -349.110481) (xy 338.909152 -349.106751)
			(xy 338.962404 -349.110481) (xy 339.014615 -349.121598) (xy 339.064767 -349.139884) (xy 339.111881 -349.164983)
			(xy 339.155035 -349.196405) (xy 339.193389 -349.233535) (xy 339.210142 -349.254318) (xy 339.220039 -349.266123)
			(xy 339.245363 -349.283642) (xy 339.274756 -349.292818) (xy 339.305548 -349.292818) (xy 339.334941 -349.283642)
			(xy 339.360265 -349.266123) (xy 339.370162 -349.254318) (xy 339.386915 -349.233535) (xy 339.425269 -349.196405)
			(xy 339.468423 -349.164983) (xy 339.515537 -349.139884) (xy 339.565689 -349.121598) (xy 339.6179 -349.110481)
			(xy 339.671152 -349.106751) (xy 339.724404 -349.110481) (xy 339.776615 -349.121598) (xy 339.826767 -349.139884)
			(xy 339.873881 -349.164983) (xy 339.917035 -349.196405) (xy 339.955389 -349.233535) (xy 339.972142 -349.254318)
			(xy 339.982039 -349.266123) (xy 340.007363 -349.283642) (xy 340.036756 -349.292818) (xy 340.067548 -349.292818)
			(xy 340.096941 -349.283642) (xy 340.122265 -349.266123) (xy 340.132162 -349.254318) (xy 340.150379 -349.231856)
			(xy 340.192393 -349.192119) (xy 340.239922 -349.159177) (xy 340.291878 -349.133785) (xy 340.347072 -349.116524)
			(xy 340.404237 -349.10779) (xy 340.433152 -349.107252) (xy 340.461719 -349.107782) (xy 340.518214 -349.116316)
			(xy 340.572807 -349.133169) (xy 340.624281 -349.157966) (xy 340.671487 -349.190155) (xy 340.713371 -349.229015)
			(xy 340.731602 -349.251016) (xy 340.741172 -349.262259) (xy 340.765411 -349.279096) (xy 340.793451 -349.288307)
			(xy 340.822953 -349.289124) (xy 340.851459 -349.281478) (xy 340.876593 -349.266006) (xy 340.886796 -349.255334)
			(xy 340.904952 -349.235705) (xy 340.945838 -349.201247) (xy 340.991134 -349.172834) (xy 341.039954 -349.151024)
			(xy 341.09134 -349.136243) (xy 341.144287 -349.128782) (xy 341.171022 -349.128334) (xy 341.199937 -349.128896)
			(xy 341.257107 -349.137614) (xy 341.312306 -349.154862) (xy 341.364268 -349.180246) (xy 341.411803 -349.213183)
			(xy 341.453821 -349.252917) (xy 341.472012 -349.2754) (xy 341.481909 -349.287205) (xy 341.507233 -349.304724)
			(xy 341.536626 -349.3139) (xy 341.567418 -349.3139) (xy 341.596811 -349.304724) (xy 341.622135 -349.287205)
			(xy 341.632032 -349.2754) (xy 341.650205 -349.252901) (xy 341.692228 -349.213167) (xy 341.739767 -349.18023)
			(xy 341.791732 -349.154844) (xy 341.846933 -349.137591) (xy 341.904105 -349.128867) (xy 341.933022 -349.128334)
			(xy 341.960275 -349.128737) (xy 342.014227 -349.136497) (xy 342.066524 -349.151856) (xy 342.116104 -349.174501)
			(xy 342.161957 -349.203971) (xy 342.203149 -349.239666) (xy 342.238842 -349.280861) (xy 342.26831 -349.326715)
			(xy 342.290952 -349.376296) (xy 342.306307 -349.428595) (xy 342.314064 -349.482547) (xy 342.314064 -349.537053)
			(xy 342.306307 -349.591005) (xy 342.290952 -349.643304) (xy 342.26831 -349.692885) (xy 342.238842 -349.738739)
			(xy 342.203149 -349.779934) (xy 342.161957 -349.815629) (xy 342.116104 -349.845099) (xy 342.066524 -349.867744)
			(xy 342.014227 -349.883103) (xy 341.960275 -349.890863) (xy 341.933022 -349.89135) (xy 341.904105 -349.890835)
			(xy 341.846933 -349.882108) (xy 341.791733 -349.864851) (xy 341.739771 -349.839458) (xy 341.692237 -349.806513)
			(xy 341.650221 -349.766771) (xy 341.632032 -349.744284) (xy 341.622135 -349.732479) (xy 341.596811 -349.71496)
			(xy 341.567418 -349.705784) (xy 341.536626 -349.705784) (xy 341.507233 -349.71496) (xy 341.481909 -349.732479)
			(xy 341.472012 -349.744284) (xy 341.45381 -349.766758) (xy 341.411793 -349.806495) (xy 341.364261 -349.839435)
			(xy 341.312301 -349.864826) (xy 341.257106 -349.882084) (xy 341.199937 -349.890814) (xy 341.171022 -349.89135)
			(xy 341.142456 -349.890766) (xy 341.085964 -349.882244) (xy 341.031372 -349.865401) (xy 340.979898 -349.840614)
			(xy 340.932691 -349.808435) (xy 340.890804 -349.769583) (xy 340.872572 -349.747586) (xy 340.86303 -349.736318)
			(xy 340.838783 -349.71948) (xy 340.810736 -349.710272) (xy 340.781228 -349.70946) (xy 340.752717 -349.717113)
			(xy 340.727582 -349.732592) (xy 340.717378 -349.743268) (xy 340.699186 -349.762862) (xy 340.658307 -349.797323)
			(xy 340.613018 -349.82574) (xy 340.564206 -349.847556) (xy 340.512826 -349.862344) (xy 340.459885 -349.869815)
			(xy 340.433152 -349.870268) (xy 340.404236 -349.869725) (xy 340.347065 -349.861002) (xy 340.291866 -349.84375)
			(xy 340.239904 -349.818363) (xy 340.19237 -349.785424) (xy 340.150352 -349.745686) (xy 340.132162 -349.723202)
			(xy 340.122265 -349.711397) (xy 340.096941 -349.693878) (xy 340.067548 -349.684702) (xy 340.036756 -349.684702)
			(xy 340.007363 -349.693878) (xy 339.982039 -349.711397) (xy 339.972142 -349.723202) (xy 339.955389 -349.743985)
			(xy 339.917035 -349.781115) (xy 339.873881 -349.812537) (xy 339.826767 -349.837636) (xy 339.776615 -349.855922)
			(xy 339.724404 -349.867039) (xy 339.671152 -349.870769) (xy 339.6179 -349.867039) (xy 339.565689 -349.855922)
			(xy 339.515537 -349.837636) (xy 339.468423 -349.812537) (xy 339.425269 -349.781115) (xy 339.386915 -349.743985)
			(xy 339.370162 -349.723202) (xy 339.360265 -349.711397) (xy 339.334941 -349.693878) (xy 339.305548 -349.684702)
			(xy 339.274756 -349.684702) (xy 339.245363 -349.693878) (xy 339.220039 -349.711397) (xy 339.210142 -349.723202)
			(xy 339.193389 -349.743985) (xy 339.155035 -349.781115) (xy 339.111881 -349.812537) (xy 339.064767 -349.837636)
			(xy 339.014615 -349.855922) (xy 338.962404 -349.867039) (xy 338.909152 -349.870769) (xy 338.8559 -349.867039)
			(xy 338.803689 -349.855922) (xy 338.753537 -349.837636) (xy 338.706423 -349.812537) (xy 338.663269 -349.781115)
			(xy 338.624915 -349.743985) (xy 338.608162 -349.723202) (xy 338.598265 -349.711397) (xy 338.572941 -349.693878)
			(xy 338.543548 -349.684702) (xy 338.512756 -349.684702) (xy 338.483363 -349.693878) (xy 338.458039 -349.711397)
			(xy 338.448142 -349.723202) (xy 338.423758 -349.75165) (xy 338.413523 -349.763228) (xy 338.399939 -349.790968)
			(xy 338.395268 -349.8215) (xy 338.399939 -349.852032) (xy 338.413523 -349.879772) (xy 338.423758 -349.89135)
			(xy 338.443327 -349.912773) (xy 338.476444 -349.960414) (xy 338.501975 -350.012515) (xy 338.519332 -350.067878)
			(xy 338.528116 -350.12523) (xy 338.52866 -350.15424) (xy 338.528174 -350.181491) (xy 338.520418 -350.235439)
			(xy 338.505063 -350.287734) (xy 338.482421 -350.337311) (xy 338.452955 -350.383161) (xy 338.417264 -350.424352)
			(xy 338.376073 -350.460043) (xy 338.330223 -350.489509) (xy 338.280646 -350.512151) (xy 338.228351 -350.527506)
			(xy 338.174403 -350.535262) (xy 338.119901 -350.535262) (xy 338.065953 -350.527506) (xy 338.013658 -350.512151)
			(xy 337.964081 -350.489509) (xy 337.918231 -350.460043) (xy 337.87704 -350.424352) (xy 337.841349 -350.383161)
			(xy 337.811883 -350.337311) (xy 337.789241 -350.287734) (xy 337.773886 -350.235439) (xy 337.76613 -350.181491)
			(xy 337.765644 -350.15424) (xy 337.563824 -350.15424) (xy 337.56367 -350.162328) (xy 337.554952 -350.219499)
			(xy 337.537703 -350.274698) (xy 337.512318 -350.326661) (xy 337.479378 -350.374195) (xy 337.43964 -350.416212)
			(xy 337.417156 -350.434402) (xy 337.405335 -350.444284) (xy 337.38781 -350.46961) (xy 337.378631 -350.499008)
			(xy 337.378634 -350.529806) (xy 337.387816 -350.559204) (xy 337.405345 -350.584527) (xy 337.417156 -350.594422)
			(xy 337.439641 -350.612612) (xy 337.479378 -350.65463) (xy 337.512318 -350.702165) (xy 337.537707 -350.754127)
			(xy 337.554962 -350.809325) (xy 337.563689 -350.866496) (xy 337.564222 -350.895412) (xy 337.563848 -350.91624)
			(xy 342.433656 -350.91624) (xy 342.434182 -350.887323) (xy 342.442906 -350.830151) (xy 342.460161 -350.774952)
			(xy 342.485551 -350.722989) (xy 342.518495 -350.675455) (xy 342.558236 -350.633439) (xy 342.580722 -350.61525)
			(xy 342.592484 -350.605307) (xy 342.609996 -350.579994) (xy 342.619172 -350.550614) (xy 342.61918 -350.519835)
			(xy 342.610018 -350.49045) (xy 342.592518 -350.465129) (xy 342.580722 -350.45523) (xy 342.558257 -350.437016)
			(xy 342.51852 -350.395002) (xy 342.485578 -350.347472) (xy 342.460186 -350.295515) (xy 342.442926 -350.240321)
			(xy 342.434193 -350.183155) (xy 342.433656 -350.15424) (xy 342.434224 -350.125229) (xy 342.442986 -350.067874)
			(xy 342.46033 -350.012505) (xy 342.485856 -349.960401) (xy 342.518976 -349.912761) (xy 342.538558 -349.89135)
			(xy 342.548791 -349.879771) (xy 342.562374 -349.852032) (xy 342.567044 -349.8215) (xy 342.562374 -349.790968)
			(xy 342.548791 -349.763229) (xy 342.538558 -349.75165) (xy 342.518991 -349.730225) (xy 342.485874 -349.682585)
			(xy 342.460342 -349.630484) (xy 342.442985 -349.575121) (xy 342.4342 -349.51777) (xy 342.433656 -349.48876)
			(xy 342.43414 -349.461509) (xy 342.441902 -349.407564) (xy 342.45726 -349.355271) (xy 342.479903 -349.305696)
			(xy 342.50937 -349.259848) (xy 342.545062 -349.218659) (xy 342.586251 -349.182968) (xy 342.632099 -349.153501)
			(xy 342.681675 -349.130858) (xy 342.733967 -349.115501) (xy 342.787913 -349.10774) (xy 342.815164 -349.107252)
			(xy 342.844081 -349.107776) (xy 342.901253 -349.116501) (xy 342.956452 -349.133757) (xy 343.008415 -349.159147)
			(xy 343.055948 -349.192091) (xy 343.097965 -349.231832) (xy 343.116154 -349.254318) (xy 343.126051 -349.266123)
			(xy 343.151375 -349.283642) (xy 343.180768 -349.292818) (xy 343.21156 -349.292818) (xy 343.240953 -349.283642)
			(xy 343.266277 -349.266123) (xy 343.276174 -349.254318) (xy 343.294384 -349.231851) (xy 343.336399 -349.192114)
			(xy 343.38393 -349.159172) (xy 343.435888 -349.133781) (xy 343.491082 -349.116521) (xy 343.548249 -349.107789)
			(xy 343.577164 -349.107252) (xy 343.604413 -349.107812) (xy 343.658355 -349.115562) (xy 343.710646 -349.130911)
			(xy 343.760221 -349.153545) (xy 343.806069 -349.183003) (xy 343.847259 -349.218687) (xy 343.882951 -349.25987)
			(xy 343.912419 -349.305713) (xy 343.935063 -349.355282) (xy 343.950422 -349.40757) (xy 343.958183 -349.461512)
			(xy 343.958672 -349.48876) (xy 343.958124 -349.517772) (xy 343.94936 -349.575129) (xy 343.932012 -349.630498)
			(xy 343.906481 -349.682603) (xy 343.873356 -349.730241) (xy 343.85377 -349.75165) (xy 343.843534 -349.763227)
			(xy 343.829948 -349.790967) (xy 343.825277 -349.8215) (xy 343.829948 -349.852033) (xy 343.843534 -349.879773)
			(xy 343.85377 -349.89135) (xy 343.873341 -349.912771) (xy 343.906457 -349.960413) (xy 343.931987 -350.012514)
			(xy 343.949344 -350.067878) (xy 343.958128 -350.12523) (xy 343.958672 -350.15424) (xy 343.958121 -350.183156)
			(xy 343.949401 -350.240326) (xy 343.93215 -350.295525) (xy 343.906764 -350.347487) (xy 343.873826 -350.395021)
			(xy 343.834089 -350.437039) (xy 343.811606 -350.45523) (xy 343.799761 -350.465084) (xy 343.782246 -350.49042)
			(xy 343.773075 -350.519824) (xy 343.773082 -350.550625) (xy 343.782267 -350.580025) (xy 343.799795 -350.605352)
			(xy 343.811606 -350.61525) (xy 343.834067 -350.633468) (xy 343.866564 -350.667828) (xy 354.882702 -350.667828)
			(xy 354.886773 -350.612206) (xy 354.898899 -350.557769) (xy 354.918822 -350.505678) (xy 354.946118 -350.457043)
			(xy 354.980204 -350.4129) (xy 355.020353 -350.374191) (xy 355.065711 -350.34174) (xy 355.115311 -350.316239)
			(xy 355.168095 -350.298232) (xy 355.222938 -350.288102) (xy 355.278672 -350.286065) (xy 355.334109 -350.292165)
			(xy 355.388066 -350.306271) (xy 355.439395 -350.328083) (xy 355.487001 -350.357137) (xy 355.529869 -350.392812)
			(xy 355.536575 -350.400296) (xy 363.397796 -350.400296) (xy 363.397796 -350.3156) (xy 363.405847 -350.231286)
			(xy 363.421876 -350.14812) (xy 363.445737 -350.066853) (xy 363.477216 -349.988223) (xy 363.516027 -349.912942)
			(xy 363.561817 -349.84169) (xy 363.614173 -349.775114) (xy 363.672621 -349.713816) (xy 363.736631 -349.658351)
			(xy 363.805623 -349.609222) (xy 363.878973 -349.566873) (xy 363.956016 -349.531689) (xy 364.036055 -349.503987)
			(xy 364.118364 -349.484019) (xy 364.202199 -349.471966) (xy 364.2868 -349.467936) (xy 364.371401 -349.471966)
			(xy 364.455236 -349.484019) (xy 364.537545 -349.503987) (xy 364.617584 -349.531689) (xy 364.694627 -349.566873)
			(xy 364.767977 -349.609222) (xy 364.836969 -349.658351) (xy 364.900979 -349.713816) (xy 364.959427 -349.775114)
			(xy 365.011783 -349.84169) (xy 365.057573 -349.912942) (xy 365.096384 -349.988223) (xy 365.127863 -350.066853)
			(xy 365.151724 -350.14812) (xy 365.167753 -350.231286) (xy 365.175804 -350.3156) (xy 365.176308 -350.357948)
			(xy 365.922309 -350.357948) (xy 365.926345 -350.274501) (xy 365.938417 -350.191833) (xy 365.95841 -350.110716)
			(xy 365.986139 -350.031907) (xy 366.021345 -349.956142) (xy 366.063699 -349.884129) (xy 366.112805 -349.81654)
			(xy 366.168206 -349.754006) (xy 366.229383 -349.697111) (xy 366.295766 -349.646385) (xy 366.366734 -349.602304)
			(xy 366.441626 -349.565278) (xy 366.519742 -349.535652) (xy 366.600352 -349.513704) (xy 366.682704 -349.499639)
			(xy 366.76603 -349.493587) (xy 366.84955 -349.495606) (xy 366.932486 -349.505676) (xy 367.014062 -349.523704)
			(xy 367.093518 -349.549521) (xy 367.170111 -349.582886) (xy 367.243127 -349.623487) (xy 367.311883 -349.670946)
			(xy 367.375737 -349.724819) (xy 367.434094 -349.784604) (xy 367.486409 -349.849741) (xy 367.532192 -349.919624)
			(xy 367.571017 -349.993599) (xy 367.602522 -350.070976) (xy 367.626411 -350.151033) (xy 367.642462 -350.233021)
			(xy 367.650525 -350.316176) (xy 367.65103 -350.357948) (xy 367.650525 -350.39972) (xy 367.642462 -350.482875)
			(xy 367.626411 -350.564863) (xy 367.602522 -350.64492) (xy 367.571017 -350.722297) (xy 367.532192 -350.796272)
			(xy 367.486409 -350.866155) (xy 367.434094 -350.931292) (xy 367.375737 -350.991077) (xy 367.311883 -351.04495)
			(xy 367.243127 -351.092409) (xy 367.170111 -351.13301) (xy 367.093518 -351.166375) (xy 367.014062 -351.192192)
			(xy 366.932486 -351.21022) (xy 366.84955 -351.22029) (xy 366.76603 -351.222309) (xy 366.682704 -351.216257)
			(xy 366.600352 -351.202192) (xy 366.519742 -351.180244) (xy 366.441626 -351.150618) (xy 366.366734 -351.113592)
			(xy 366.295766 -351.069511) (xy 366.229383 -351.018785) (xy 366.168206 -350.96189) (xy 366.112805 -350.899356)
			(xy 366.063699 -350.831767) (xy 366.021345 -350.759754) (xy 365.986139 -350.683989) (xy 365.95841 -350.60518)
			(xy 365.938417 -350.524063) (xy 365.926345 -350.441395) (xy 365.922309 -350.357948) (xy 365.176308 -350.357948)
			(xy 365.175804 -350.400296) (xy 365.167753 -350.48461) (xy 365.151724 -350.567776) (xy 365.127863 -350.649043)
			(xy 365.096384 -350.727673) (xy 365.057573 -350.802954) (xy 365.011783 -350.874206) (xy 364.959427 -350.940782)
			(xy 364.900979 -351.00208) (xy 364.836969 -351.057545) (xy 364.767977 -351.106674) (xy 364.694627 -351.149023)
			(xy 364.617584 -351.184207) (xy 364.537545 -351.211909) (xy 364.455236 -351.231877) (xy 364.371401 -351.24393)
			(xy 364.2868 -351.247961) (xy 364.202199 -351.24393) (xy 364.118364 -351.231877) (xy 364.036055 -351.211909)
			(xy 363.956016 -351.184207) (xy 363.878973 -351.149023) (xy 363.805623 -351.106674) (xy 363.736631 -351.057545)
			(xy 363.672621 -351.00208) (xy 363.614173 -350.940782) (xy 363.561817 -350.874206) (xy 363.516027 -350.802954)
			(xy 363.477216 -350.727673) (xy 363.445737 -350.649043) (xy 363.421876 -350.567776) (xy 363.405847 -350.48461)
			(xy 363.397796 -350.400296) (xy 355.536575 -350.400296) (xy 355.567086 -350.434349) (xy 355.597859 -350.480862)
			(xy 355.621531 -350.531359) (xy 355.637599 -350.584766) (xy 355.645719 -350.639942) (xy 355.646228 -350.667828)
			(xy 355.645719 -350.695714) (xy 355.637599 -350.75089) (xy 355.621531 -350.804297) (xy 355.597859 -350.854794)
			(xy 355.567086 -350.901307) (xy 355.529869 -350.942844) (xy 355.487001 -350.978519) (xy 355.439395 -351.007573)
			(xy 355.388066 -351.029385) (xy 355.334109 -351.043491) (xy 355.278672 -351.049591) (xy 355.222938 -351.047554)
			(xy 355.168095 -351.037424) (xy 355.115311 -351.019417) (xy 355.065711 -350.993916) (xy 355.020353 -350.961465)
			(xy 354.980204 -350.922756) (xy 354.946118 -350.878613) (xy 354.918822 -350.829978) (xy 354.898899 -350.777887)
			(xy 354.886773 -350.72345) (xy 354.882702 -350.667828) (xy 343.866564 -350.667828) (xy 343.873803 -350.675482)
			(xy 343.906745 -350.723012) (xy 343.932137 -350.774968) (xy 343.949398 -350.83016) (xy 343.958133 -350.887326)
			(xy 343.958672 -350.91624) (xy 343.958259 -350.943494) (xy 343.950496 -350.997446) (xy 343.935134 -351.049744)
			(xy 343.912486 -351.099324) (xy 343.883012 -351.145176) (xy 343.847313 -351.186367) (xy 343.806115 -351.222058)
			(xy 343.760257 -351.251522) (xy 343.710673 -351.274161) (xy 343.658372 -351.289513) (xy 343.604418 -351.297265)
			(xy 343.577164 -351.297748) (xy 343.548248 -351.297203) (xy 343.491077 -351.288482) (xy 343.435878 -351.271231)
			(xy 343.383916 -351.245844) (xy 343.336381 -351.212904) (xy 343.294364 -351.173166) (xy 343.276174 -351.150682)
			(xy 343.266277 -351.138877) (xy 343.240953 -351.121358) (xy 343.21156 -351.112182) (xy 343.180768 -351.112182)
			(xy 343.151375 -351.121358) (xy 343.126051 -351.138877) (xy 343.116154 -351.150682) (xy 343.097928 -351.173136)
			(xy 343.055916 -351.212874) (xy 343.008389 -351.245817) (xy 342.956434 -351.27121) (xy 342.901243 -351.288473)
			(xy 342.844078 -351.297209) (xy 342.815164 -351.297748) (xy 342.787914 -351.297256) (xy 342.733968 -351.289495)
			(xy 342.681676 -351.274138) (xy 342.632101 -351.251495) (xy 342.586253 -351.222029) (xy 342.545064 -351.186338)
			(xy 342.509373 -351.14515) (xy 342.479907 -351.099302) (xy 342.457264 -351.049728) (xy 342.441905 -350.997436)
			(xy 342.434144 -350.94349) (xy 342.433656 -350.91624) (xy 337.563848 -350.91624) (xy 337.563733 -350.922663)
			(xy 337.555976 -350.97661) (xy 337.54062 -351.028904) (xy 337.517978 -351.07848) (xy 337.488512 -351.12433)
			(xy 337.452821 -351.165519) (xy 337.411631 -351.201211) (xy 337.365782 -351.230677) (xy 337.316206 -351.253319)
			(xy 337.263912 -351.268675) (xy 337.209965 -351.276433) (xy 337.182714 -351.27692) (xy 337.153796 -351.276422)
			(xy 337.096622 -351.267693) (xy 337.041422 -351.250433) (xy 336.98946 -351.225038) (xy 336.941926 -351.192089)
			(xy 336.899912 -351.152342) (xy 336.881724 -351.129854) (xy 336.871827 -351.118049) (xy 336.846503 -351.10053)
			(xy 336.81711 -351.091354) (xy 336.786318 -351.091354) (xy 336.756925 -351.10053) (xy 336.731601 -351.118049)
			(xy 336.721704 -351.129854) (xy 336.703524 -351.152347) (xy 336.661501 -351.192079) (xy 336.613963 -351.225015)
			(xy 336.562 -351.250402) (xy 336.506801 -351.267656) (xy 336.44963 -351.276385) (xy 336.420714 -351.27692)
			(xy 336.393462 -351.276432) (xy 336.339513 -351.268677) (xy 336.287216 -351.253323) (xy 336.237637 -351.230683)
			(xy 336.191784 -351.201218) (xy 336.150592 -351.165527) (xy 336.114898 -351.124337) (xy 336.085429 -351.078486)
			(xy 336.062786 -351.028908) (xy 336.047429 -350.976613) (xy 336.03967 -350.922664) (xy 336.039206 -350.895412)
			(xy 320.683957 -350.895412) (xy 320.841718 -351.605088) (xy 351.934778 -351.605088) (xy 351.938849 -351.549466)
			(xy 351.950975 -351.495029) (xy 351.970898 -351.442938) (xy 351.998194 -351.394303) (xy 352.03228 -351.35016)
			(xy 352.072429 -351.311451) (xy 352.117787 -351.279) (xy 352.167387 -351.253499) (xy 352.220171 -351.235492)
			(xy 352.275014 -351.225362) (xy 352.330748 -351.223325) (xy 352.386185 -351.229425) (xy 352.440142 -351.243531)
			(xy 352.491471 -351.265343) (xy 352.539077 -351.294397) (xy 352.581945 -351.330072) (xy 352.619162 -351.371609)
			(xy 352.649935 -351.418122) (xy 352.673607 -351.468619) (xy 352.689675 -351.522026) (xy 352.697795 -351.577202)
			(xy 352.698304 -351.605088) (xy 352.697795 -351.632974) (xy 352.689675 -351.68815) (xy 352.673607 -351.741557)
			(xy 352.649935 -351.792054) (xy 352.627431 -351.826068) (xy 352.798378 -351.826068) (xy 352.802449 -351.770446)
			(xy 352.814575 -351.716009) (xy 352.834498 -351.663918) (xy 352.861794 -351.615283) (xy 352.89588 -351.57114)
			(xy 352.936029 -351.532431) (xy 352.981387 -351.49998) (xy 353.030987 -351.474479) (xy 353.083771 -351.456472)
			(xy 353.138614 -351.446342) (xy 353.194348 -351.444305) (xy 353.249785 -351.450405) (xy 353.303742 -351.464511)
			(xy 353.355071 -351.486323) (xy 353.402677 -351.515377) (xy 353.445545 -351.551052) (xy 353.482762 -351.592589)
			(xy 353.513535 -351.639102) (xy 353.537207 -351.689599) (xy 353.553275 -351.743006) (xy 353.561395 -351.798182)
			(xy 353.561904 -351.826068) (xy 353.561395 -351.853954) (xy 353.553275 -351.90913) (xy 353.537207 -351.962537)
			(xy 353.533311 -351.970848) (xy 354.280976 -351.970848) (xy 354.285047 -351.915226) (xy 354.297173 -351.860789)
			(xy 354.317096 -351.808698) (xy 354.344392 -351.760063) (xy 354.378478 -351.71592) (xy 354.418627 -351.677211)
			(xy 354.463985 -351.64476) (xy 354.513585 -351.619259) (xy 354.566369 -351.601252) (xy 354.621212 -351.591122)
			(xy 354.676946 -351.589085) (xy 354.732383 -351.595185) (xy 354.78634 -351.609291) (xy 354.837669 -351.631103)
			(xy 354.885275 -351.660157) (xy 354.928143 -351.695832) (xy 354.93878 -351.707704) (xy 355.638352 -351.707704)
			(xy 355.642423 -351.652082) (xy 355.654549 -351.597645) (xy 355.674472 -351.545554) (xy 355.701768 -351.496919)
			(xy 355.735854 -351.452776) (xy 355.776003 -351.414067) (xy 355.821361 -351.381616) (xy 355.870961 -351.356115)
			(xy 355.923745 -351.338108) (xy 355.978588 -351.327978) (xy 356.034322 -351.325941) (xy 356.089759 -351.332041)
			(xy 356.143716 -351.346147) (xy 356.195045 -351.367959) (xy 356.242651 -351.397013) (xy 356.285519 -351.432688)
			(xy 356.322736 -351.474225) (xy 356.340416 -351.500948) (xy 356.859076 -351.500948) (xy 356.863147 -351.445326)
			(xy 356.875273 -351.390889) (xy 356.895196 -351.338798) (xy 356.922492 -351.290163) (xy 356.956578 -351.24602)
			(xy 356.996727 -351.207311) (xy 357.042085 -351.17486) (xy 357.091685 -351.149359) (xy 357.144469 -351.131352)
			(xy 357.199312 -351.121222) (xy 357.255046 -351.119185) (xy 357.310483 -351.125285) (xy 357.36444 -351.139391)
			(xy 357.415769 -351.161203) (xy 357.463375 -351.190257) (xy 357.506243 -351.225932) (xy 357.54346 -351.267469)
			(xy 357.574233 -351.313982) (xy 357.597905 -351.364479) (xy 357.613973 -351.417886) (xy 357.619842 -351.457768)
			(xy 359.071416 -351.457768) (xy 359.075487 -351.402146) (xy 359.087613 -351.347709) (xy 359.107536 -351.295618)
			(xy 359.134832 -351.246983) (xy 359.168918 -351.20284) (xy 359.209067 -351.164131) (xy 359.254425 -351.13168)
			(xy 359.304025 -351.106179) (xy 359.356809 -351.088172) (xy 359.411652 -351.078042) (xy 359.467386 -351.076005)
			(xy 359.522823 -351.082105) (xy 359.57678 -351.096211) (xy 359.628109 -351.118023) (xy 359.675715 -351.147077)
			(xy 359.718583 -351.182752) (xy 359.7558 -351.224289) (xy 359.786573 -351.270802) (xy 359.810245 -351.321299)
			(xy 359.821423 -351.358454) (xy 360.956858 -351.358454) (xy 360.960929 -351.302832) (xy 360.973055 -351.248395)
			(xy 360.992978 -351.196304) (xy 361.020274 -351.147669) (xy 361.05436 -351.103526) (xy 361.094509 -351.064817)
			(xy 361.139867 -351.032366) (xy 361.189467 -351.006865) (xy 361.242251 -350.988858) (xy 361.297094 -350.978728)
			(xy 361.352828 -350.976691) (xy 361.408265 -350.982791) (xy 361.462222 -350.996897) (xy 361.513551 -351.018709)
			(xy 361.561157 -351.047763) (xy 361.604025 -351.083438) (xy 361.641242 -351.124975) (xy 361.672015 -351.171488)
			(xy 361.695687 -351.221985) (xy 361.711755 -351.275392) (xy 361.719875 -351.330568) (xy 361.720384 -351.358454)
			(xy 361.719875 -351.38634) (xy 361.711755 -351.441516) (xy 361.695687 -351.494923) (xy 361.672015 -351.54542)
			(xy 361.641242 -351.591933) (xy 361.604025 -351.63347) (xy 361.561157 -351.669145) (xy 361.513551 -351.698199)
			(xy 361.462222 -351.720011) (xy 361.408265 -351.734117) (xy 361.352828 -351.740217) (xy 361.297094 -351.73818)
			(xy 361.242251 -351.72805) (xy 361.189467 -351.710043) (xy 361.139867 -351.684542) (xy 361.094509 -351.652091)
			(xy 361.05436 -351.613382) (xy 361.020274 -351.569239) (xy 360.992978 -351.520604) (xy 360.973055 -351.468513)
			(xy 360.960929 -351.414076) (xy 360.956858 -351.358454) (xy 359.821423 -351.358454) (xy 359.826313 -351.374706)
			(xy 359.834433 -351.429882) (xy 359.834942 -351.457768) (xy 359.834433 -351.485654) (xy 359.826313 -351.54083)
			(xy 359.810245 -351.594237) (xy 359.786573 -351.644734) (xy 359.7558 -351.691247) (xy 359.718583 -351.732784)
			(xy 359.675715 -351.768459) (xy 359.628109 -351.797513) (xy 359.57678 -351.819325) (xy 359.522823 -351.833431)
			(xy 359.467386 -351.839531) (xy 359.411652 -351.837494) (xy 359.356809 -351.827364) (xy 359.304025 -351.809357)
			(xy 359.254425 -351.783856) (xy 359.209067 -351.751405) (xy 359.168918 -351.712696) (xy 359.134832 -351.668553)
			(xy 359.107536 -351.619918) (xy 359.087613 -351.567827) (xy 359.075487 -351.51339) (xy 359.071416 -351.457768)
			(xy 357.619842 -351.457768) (xy 357.622093 -351.473062) (xy 357.622602 -351.500948) (xy 357.622093 -351.528834)
			(xy 357.613973 -351.58401) (xy 357.597905 -351.637417) (xy 357.574233 -351.687914) (xy 357.54346 -351.734427)
			(xy 357.506243 -351.775964) (xy 357.463375 -351.811639) (xy 357.415769 -351.840693) (xy 357.36444 -351.862505)
			(xy 357.310483 -351.876611) (xy 357.255046 -351.882711) (xy 357.199312 -351.880674) (xy 357.144469 -351.870544)
			(xy 357.091685 -351.852537) (xy 357.042085 -351.827036) (xy 356.996727 -351.794585) (xy 356.956578 -351.755876)
			(xy 356.922492 -351.711733) (xy 356.895196 -351.663098) (xy 356.875273 -351.611007) (xy 356.863147 -351.55657)
			(xy 356.859076 -351.500948) (xy 356.340416 -351.500948) (xy 356.353509 -351.520738) (xy 356.377181 -351.571235)
			(xy 356.393249 -351.624642) (xy 356.401369 -351.679818) (xy 356.401878 -351.707704) (xy 356.401369 -351.73559)
			(xy 356.393249 -351.790766) (xy 356.377181 -351.844173) (xy 356.353509 -351.89467) (xy 356.322736 -351.941183)
			(xy 356.285519 -351.98272) (xy 356.242651 -352.018395) (xy 356.195045 -352.047449) (xy 356.143716 -352.069261)
			(xy 356.089759 -352.083367) (xy 356.034322 -352.089467) (xy 355.978588 -352.08743) (xy 355.923745 -352.0773)
			(xy 355.870961 -352.059293) (xy 355.821361 -352.033792) (xy 355.776003 -352.001341) (xy 355.735854 -351.962632)
			(xy 355.701768 -351.918489) (xy 355.674472 -351.869854) (xy 355.654549 -351.817763) (xy 355.642423 -351.763326)
			(xy 355.638352 -351.707704) (xy 354.93878 -351.707704) (xy 354.96536 -351.737369) (xy 354.996133 -351.783882)
			(xy 355.019805 -351.834379) (xy 355.035873 -351.887786) (xy 355.043993 -351.942962) (xy 355.044502 -351.970848)
			(xy 355.043993 -351.998734) (xy 355.035873 -352.05391) (xy 355.019805 -352.107317) (xy 354.996133 -352.157814)
			(xy 354.96536 -352.204327) (xy 354.928143 -352.245864) (xy 354.885275 -352.281539) (xy 354.837669 -352.310593)
			(xy 354.78634 -352.332405) (xy 354.732383 -352.346511) (xy 354.676946 -352.352611) (xy 354.621212 -352.350574)
			(xy 354.566369 -352.340444) (xy 354.513585 -352.322437) (xy 354.463985 -352.296936) (xy 354.418627 -352.264485)
			(xy 354.378478 -352.225776) (xy 354.344392 -352.181633) (xy 354.317096 -352.132998) (xy 354.297173 -352.080907)
			(xy 354.285047 -352.02647) (xy 354.280976 -351.970848) (xy 353.533311 -351.970848) (xy 353.513535 -352.013034)
			(xy 353.482762 -352.059547) (xy 353.445545 -352.101084) (xy 353.402677 -352.136759) (xy 353.355071 -352.165813)
			(xy 353.303742 -352.187625) (xy 353.249785 -352.201731) (xy 353.194348 -352.207831) (xy 353.138614 -352.205794)
			(xy 353.083771 -352.195664) (xy 353.030987 -352.177657) (xy 352.981387 -352.152156) (xy 352.936029 -352.119705)
			(xy 352.89588 -352.080996) (xy 352.861794 -352.036853) (xy 352.834498 -351.988218) (xy 352.814575 -351.936127)
			(xy 352.802449 -351.88169) (xy 352.798378 -351.826068) (xy 352.627431 -351.826068) (xy 352.619162 -351.838567)
			(xy 352.581945 -351.880104) (xy 352.539077 -351.915779) (xy 352.491471 -351.944833) (xy 352.440142 -351.966645)
			(xy 352.386185 -351.980751) (xy 352.330748 -351.986851) (xy 352.275014 -351.984814) (xy 352.220171 -351.974684)
			(xy 352.167387 -351.956677) (xy 352.117787 -351.931176) (xy 352.072429 -351.898725) (xy 352.03228 -351.860016)
			(xy 351.998194 -351.815873) (xy 351.970898 -351.767238) (xy 351.950975 -351.715147) (xy 351.938849 -351.66071)
			(xy 351.934778 -351.605088) (xy 320.841718 -351.605088) (xy 321.017605 -352.396298) (xy 358.510076 -352.396298)
			(xy 358.514147 -352.340676) (xy 358.526273 -352.286239) (xy 358.546196 -352.234148) (xy 358.573492 -352.185513)
			(xy 358.607578 -352.14137) (xy 358.647727 -352.102661) (xy 358.693085 -352.07021) (xy 358.742685 -352.044709)
			(xy 358.795469 -352.026702) (xy 358.850312 -352.016572) (xy 358.906046 -352.014535) (xy 358.961483 -352.020635)
			(xy 359.01544 -352.034741) (xy 359.066769 -352.056553) (xy 359.114375 -352.085607) (xy 359.157243 -352.121282)
			(xy 359.19446 -352.162819) (xy 359.225233 -352.209332) (xy 359.248905 -352.259829) (xy 359.264973 -352.313236)
			(xy 359.273093 -352.368412) (xy 359.273602 -352.396298) (xy 359.273301 -352.412808) (xy 360.041442 -352.412808)
			(xy 360.045513 -352.357186) (xy 360.057639 -352.302749) (xy 360.077562 -352.250658) (xy 360.104858 -352.202023)
			(xy 360.138944 -352.15788) (xy 360.179093 -352.119171) (xy 360.224451 -352.08672) (xy 360.274051 -352.061219)
			(xy 360.326835 -352.043212) (xy 360.381678 -352.033082) (xy 360.437412 -352.031045) (xy 360.492849 -352.037145)
			(xy 360.546806 -352.051251) (xy 360.598135 -352.073063) (xy 360.645741 -352.102117) (xy 360.688609 -352.137792)
			(xy 360.725826 -352.179329) (xy 360.756599 -352.225842) (xy 360.780271 -352.276339) (xy 360.796339 -352.329746)
			(xy 360.804459 -352.384922) (xy 360.804968 -352.412808) (xy 360.804459 -352.440694) (xy 360.796339 -352.49587)
			(xy 360.780271 -352.549277) (xy 360.756599 -352.599774) (xy 360.725826 -352.646287) (xy 360.688609 -352.687824)
			(xy 360.645741 -352.723499) (xy 360.598135 -352.752553) (xy 360.546806 -352.774365) (xy 360.492849 -352.788471)
			(xy 360.437412 -352.794571) (xy 360.381678 -352.792534) (xy 360.326835 -352.782404) (xy 360.274051 -352.764397)
			(xy 360.224451 -352.738896) (xy 360.179093 -352.706445) (xy 360.138944 -352.667736) (xy 360.104858 -352.623593)
			(xy 360.077562 -352.574958) (xy 360.057639 -352.522867) (xy 360.045513 -352.46843) (xy 360.041442 -352.412808)
			(xy 359.273301 -352.412808) (xy 359.273093 -352.424184) (xy 359.264973 -352.47936) (xy 359.248905 -352.532767)
			(xy 359.225233 -352.583264) (xy 359.19446 -352.629777) (xy 359.157243 -352.671314) (xy 359.114375 -352.706989)
			(xy 359.066769 -352.736043) (xy 359.01544 -352.757855) (xy 358.961483 -352.771961) (xy 358.906046 -352.778061)
			(xy 358.850312 -352.776024) (xy 358.795469 -352.765894) (xy 358.742685 -352.747887) (xy 358.693085 -352.722386)
			(xy 358.647727 -352.689935) (xy 358.607578 -352.651226) (xy 358.573492 -352.607083) (xy 358.546196 -352.558448)
			(xy 358.526273 -352.506357) (xy 358.514147 -352.45192) (xy 358.510076 -352.396298) (xy 321.017605 -352.396298)
			(xy 321.260402 -353.488498) (xy 358.420414 -353.488498) (xy 358.424485 -353.432876) (xy 358.436611 -353.378439)
			(xy 358.456534 -353.326348) (xy 358.48383 -353.277713) (xy 358.517916 -353.23357) (xy 358.558065 -353.194861)
			(xy 358.603423 -353.16241) (xy 358.653023 -353.136909) (xy 358.705807 -353.118902) (xy 358.76065 -353.108772)
			(xy 358.816384 -353.106735) (xy 358.871821 -353.112835) (xy 358.925778 -353.126941) (xy 358.977107 -353.148753)
			(xy 359.024713 -353.177807) (xy 359.067581 -353.213482) (xy 359.104798 -353.255019) (xy 359.135571 -353.301532)
			(xy 359.159243 -353.352029) (xy 359.175311 -353.405436) (xy 359.183431 -353.460612) (xy 359.18394 -353.488498)
			(xy 359.183431 -353.516384) (xy 359.175311 -353.57156) (xy 359.159243 -353.624967) (xy 359.135571 -353.675464)
			(xy 359.12315 -353.694238) (xy 360.057952 -353.694238) (xy 360.062023 -353.638616) (xy 360.074149 -353.584179)
			(xy 360.094072 -353.532088) (xy 360.121368 -353.483453) (xy 360.155454 -353.43931) (xy 360.195603 -353.400601)
			(xy 360.240961 -353.36815) (xy 360.290561 -353.342649) (xy 360.343345 -353.324642) (xy 360.398188 -353.314512)
			(xy 360.453922 -353.312475) (xy 360.509359 -353.318575) (xy 360.563316 -353.332681) (xy 360.614645 -353.354493)
			(xy 360.662251 -353.383547) (xy 360.705119 -353.419222) (xy 360.742336 -353.460759) (xy 360.773109 -353.507272)
			(xy 360.796781 -353.557769) (xy 360.812849 -353.611176) (xy 360.820969 -353.666352) (xy 360.821478 -353.694238)
			(xy 360.820969 -353.722124) (xy 360.812849 -353.7773) (xy 360.796781 -353.830707) (xy 360.773109 -353.881204)
			(xy 360.742336 -353.927717) (xy 360.705119 -353.969254) (xy 360.662251 -354.004929) (xy 360.614645 -354.033983)
			(xy 360.563316 -354.055795) (xy 360.509359 -354.069901) (xy 360.453922 -354.076001) (xy 360.398188 -354.073964)
			(xy 360.343345 -354.063834) (xy 360.290561 -354.045827) (xy 360.240961 -354.020326) (xy 360.195603 -353.987875)
			(xy 360.155454 -353.949166) (xy 360.121368 -353.905023) (xy 360.094072 -353.856388) (xy 360.074149 -353.804297)
			(xy 360.062023 -353.74986) (xy 360.057952 -353.694238) (xy 359.12315 -353.694238) (xy 359.104798 -353.721977)
			(xy 359.067581 -353.763514) (xy 359.024713 -353.799189) (xy 358.977107 -353.828243) (xy 358.925778 -353.850055)
			(xy 358.871821 -353.864161) (xy 358.816384 -353.870261) (xy 358.76065 -353.868224) (xy 358.705807 -353.858094)
			(xy 358.653023 -353.840087) (xy 358.603423 -353.814586) (xy 358.558065 -353.782135) (xy 358.517916 -353.743426)
			(xy 358.48383 -353.699283) (xy 358.456534 -353.650648) (xy 358.436611 -353.598557) (xy 358.424485 -353.54412)
			(xy 358.420414 -353.488498) (xy 321.260402 -353.488498) (xy 321.392585 -354.083112) (xy 349.389698 -354.083112)
			(xy 349.393769 -354.02749) (xy 349.405895 -353.973053) (xy 349.425818 -353.920962) (xy 349.453114 -353.872327)
			(xy 349.4872 -353.828184) (xy 349.527349 -353.789475) (xy 349.572707 -353.757024) (xy 349.622307 -353.731523)
			(xy 349.675091 -353.713516) (xy 349.729934 -353.703386) (xy 349.785668 -353.701349) (xy 349.841105 -353.707449)
			(xy 349.895062 -353.721555) (xy 349.946391 -353.743367) (xy 349.993997 -353.772421) (xy 350.036865 -353.808096)
			(xy 350.074082 -353.849633) (xy 350.104855 -353.896146) (xy 350.128527 -353.946643) (xy 350.144595 -354.00005)
			(xy 350.152715 -354.055226) (xy 350.153224 -354.083112) (xy 350.152715 -354.110998) (xy 350.144595 -354.166174)
			(xy 350.128527 -354.219581) (xy 350.104855 -354.270078) (xy 350.074082 -354.316591) (xy 350.036865 -354.358128)
			(xy 349.993997 -354.393803) (xy 349.946391 -354.422857) (xy 349.895062 -354.444669) (xy 349.89453 -354.444808)
			(xy 352.80803 -354.444808) (xy 352.812103 -354.389149) (xy 352.824238 -354.334676) (xy 352.844174 -354.28255)
			(xy 352.871488 -354.233882) (xy 352.905596 -354.18971) (xy 352.945773 -354.150975) (xy 352.991161 -354.118503)
			(xy 353.040793 -354.092985) (xy 353.093613 -354.074966) (xy 353.148492 -354.064829) (xy 353.204263 -354.062791)
			(xy 353.259737 -354.068894) (xy 353.31373 -354.08301) (xy 353.365093 -354.104837) (xy 353.412731 -354.13391)
			(xy 353.455627 -354.169609) (xy 353.492869 -354.211173) (xy 353.523663 -354.257717) (xy 353.547351 -354.308248)
			(xy 353.563429 -354.36169) (xy 353.571555 -354.416904) (xy 353.572064 -354.444808) (xy 353.571555 -354.472712)
			(xy 353.563429 -354.527926) (xy 353.547351 -354.581368) (xy 353.523663 -354.631899) (xy 353.492869 -354.678443)
			(xy 353.455627 -354.720007) (xy 353.420058 -354.749608) (xy 359.185462 -354.749608) (xy 359.189533 -354.693986)
			(xy 359.201659 -354.639549) (xy 359.221582 -354.587458) (xy 359.248878 -354.538823) (xy 359.282964 -354.49468)
			(xy 359.323113 -354.455971) (xy 359.368471 -354.42352) (xy 359.418071 -354.398019) (xy 359.470855 -354.380012)
			(xy 359.525698 -354.369882) (xy 359.581432 -354.367845) (xy 359.636869 -354.373945) (xy 359.690826 -354.388051)
			(xy 359.742155 -354.409863) (xy 359.789761 -354.438917) (xy 359.832629 -354.474592) (xy 359.869846 -354.516129)
			(xy 359.900619 -354.562642) (xy 359.924291 -354.613139) (xy 359.940359 -354.666546) (xy 359.948479 -354.721722)
			(xy 359.948988 -354.749608) (xy 359.948479 -354.777494) (xy 359.940359 -354.83267) (xy 359.924291 -354.886077)
			(xy 359.900619 -354.936574) (xy 359.883157 -354.962968) (xy 360.296712 -354.962968) (xy 360.300783 -354.907346)
			(xy 360.312909 -354.852909) (xy 360.332832 -354.800818) (xy 360.360128 -354.752183) (xy 360.394214 -354.70804)
			(xy 360.434363 -354.669331) (xy 360.479721 -354.63688) (xy 360.529321 -354.611379) (xy 360.582105 -354.593372)
			(xy 360.636948 -354.583242) (xy 360.692682 -354.581205) (xy 360.748119 -354.587305) (xy 360.802076 -354.601411)
			(xy 360.853405 -354.623223) (xy 360.901011 -354.652277) (xy 360.943879 -354.687952) (xy 360.981096 -354.729489)
			(xy 360.987685 -354.739448) (xy 361.378752 -354.739448) (xy 361.382823 -354.683826) (xy 361.394949 -354.629389)
			(xy 361.414872 -354.577298) (xy 361.442168 -354.528663) (xy 361.476254 -354.48452) (xy 361.516403 -354.445811)
			(xy 361.561761 -354.41336) (xy 361.611361 -354.387859) (xy 361.664145 -354.369852) (xy 361.718988 -354.359722)
			(xy 361.774722 -354.357685) (xy 361.830159 -354.363785) (xy 361.884116 -354.377891) (xy 361.935445 -354.399703)
			(xy 361.983051 -354.428757) (xy 362.025919 -354.464432) (xy 362.063136 -354.505969) (xy 362.093909 -354.552482)
			(xy 362.117581 -354.602979) (xy 362.133649 -354.656386) (xy 362.138285 -354.687886) (xy 364.22584 -354.687886)
			(xy 364.226278 -354.661506) (xy 364.233533 -354.609247) (xy 364.247918 -354.558486) (xy 364.269157 -354.51019)
			(xy 364.296845 -354.46528) (xy 364.330456 -354.424611) (xy 364.369348 -354.38896) (xy 364.41278 -354.359006)
			(xy 364.436152 -354.346764) (xy 364.448524 -354.340084) (xy 364.469257 -354.321106) (xy 364.484021 -354.297188)
			(xy 364.491693 -354.270148) (xy 364.491692 -354.24204) (xy 364.484016 -354.215001) (xy 364.469249 -354.191084)
			(xy 364.448514 -354.172109) (xy 364.436152 -354.165408) (xy 364.412765 -354.153197) (xy 364.369342 -354.123229)
			(xy 364.330458 -354.087569) (xy 364.296855 -354.046894) (xy 364.26917 -354.001981) (xy 364.247932 -353.953685)
			(xy 364.233546 -353.902924) (xy 364.226284 -353.850666) (xy 364.22584 -353.824286) (xy 364.226326 -353.797035)
			(xy 364.234082 -353.743087) (xy 364.249437 -353.690792) (xy 364.272079 -353.641215) (xy 364.301545 -353.595365)
			(xy 364.337236 -353.554174) (xy 364.378427 -353.518483) (xy 364.424277 -353.489017) (xy 364.473854 -353.466375)
			(xy 364.526149 -353.45102) (xy 364.580097 -353.443264) (xy 364.634599 -353.443264) (xy 364.688547 -353.45102)
			(xy 364.740842 -353.466375) (xy 364.790419 -353.489017) (xy 364.836269 -353.518483) (xy 364.87746 -353.554174)
			(xy 364.913151 -353.595365) (xy 364.942617 -353.641215) (xy 364.965259 -353.690792) (xy 364.980614 -353.743087)
			(xy 364.98776 -353.79279) (xy 366.64722 -353.79279) (xy 366.651291 -353.737168) (xy 366.663417 -353.682731)
			(xy 366.68334 -353.63064) (xy 366.710636 -353.582005) (xy 366.744722 -353.537862) (xy 366.784871 -353.499153)
			(xy 366.830229 -353.466702) (xy 366.879829 -353.441201) (xy 366.932613 -353.423194) (xy 366.987456 -353.413064)
			(xy 367.04319 -353.411027) (xy 367.098627 -353.417127) (xy 367.152584 -353.431233) (xy 367.203913 -353.453045)
			(xy 367.251519 -353.482099) (xy 367.294387 -353.517774) (xy 367.331604 -353.559311) (xy 367.362377 -353.605824)
			(xy 367.386049 -353.656321) (xy 367.402117 -353.709728) (xy 367.410237 -353.764904) (xy 367.410746 -353.79279)
			(xy 367.410237 -353.820676) (xy 367.402117 -353.875852) (xy 367.386049 -353.929259) (xy 367.362377 -353.979756)
			(xy 367.331604 -354.026269) (xy 367.294387 -354.067806) (xy 367.251519 -354.103481) (xy 367.203913 -354.132535)
			(xy 367.152584 -354.154347) (xy 367.098627 -354.168453) (xy 367.04319 -354.174553) (xy 366.987456 -354.172516)
			(xy 366.932613 -354.162386) (xy 366.879829 -354.144379) (xy 366.830229 -354.118878) (xy 366.784871 -354.086427)
			(xy 366.744722 -354.047718) (xy 366.710636 -354.003575) (xy 366.68334 -353.95494) (xy 366.663417 -353.902849)
			(xy 366.651291 -353.848412) (xy 366.64722 -353.79279) (xy 364.98776 -353.79279) (xy 364.98837 -353.797035)
			(xy 364.988856 -353.824286) (xy 364.988425 -353.850666) (xy 364.981162 -353.902922) (xy 364.966772 -353.953681)
			(xy 364.945531 -354.001975) (xy 364.917841 -354.046884) (xy 364.884232 -354.087552) (xy 364.845342 -354.123205)
			(xy 364.801914 -354.153164) (xy 364.778544 -354.165408) (xy 364.766197 -354.17213) (xy 364.745467 -354.191101)
			(xy 364.730705 -354.215011) (xy 364.723031 -354.242044) (xy 364.72303 -354.270144) (xy 364.7307 -354.297177)
			(xy 364.745459 -354.321089) (xy 364.766186 -354.340063) (xy 364.778544 -354.346764) (xy 364.801919 -354.358998)
			(xy 364.845341 -354.388962) (xy 364.884225 -354.42462) (xy 364.91783 -354.465291) (xy 364.945516 -354.5102)
			(xy 364.966756 -354.558494) (xy 364.981145 -354.609252) (xy 364.98841 -354.661507) (xy 364.988856 -354.687886)
			(xy 364.98837 -354.715137) (xy 364.980614 -354.769085) (xy 364.965259 -354.82138) (xy 364.942617 -354.870957)
			(xy 364.913151 -354.916807) (xy 364.87746 -354.957998) (xy 364.836269 -354.993689) (xy 364.790419 -355.023155)
			(xy 364.740842 -355.045797) (xy 364.688547 -355.061152) (xy 364.634599 -355.068908) (xy 364.580097 -355.068908)
			(xy 364.526149 -355.061152) (xy 364.473854 -355.045797) (xy 364.424277 -355.023155) (xy 364.378427 -354.993689)
			(xy 364.337236 -354.957998) (xy 364.301545 -354.916807) (xy 364.272079 -354.870957) (xy 364.249437 -354.82138)
			(xy 364.234082 -354.769085) (xy 364.226326 -354.715137) (xy 364.22584 -354.687886) (xy 362.138285 -354.687886)
			(xy 362.141769 -354.711562) (xy 362.142278 -354.739448) (xy 362.141769 -354.767334) (xy 362.133649 -354.82251)
			(xy 362.117581 -354.875917) (xy 362.093909 -354.926414) (xy 362.063136 -354.972927) (xy 362.025919 -355.014464)
			(xy 361.983051 -355.050139) (xy 361.935445 -355.079193) (xy 361.884116 -355.101005) (xy 361.830159 -355.115111)
			(xy 361.774722 -355.121211) (xy 361.718988 -355.119174) (xy 361.664145 -355.109044) (xy 361.611361 -355.091037)
			(xy 361.561761 -355.065536) (xy 361.516403 -355.033085) (xy 361.476254 -354.994376) (xy 361.442168 -354.950233)
			(xy 361.414872 -354.901598) (xy 361.394949 -354.849507) (xy 361.382823 -354.79507) (xy 361.378752 -354.739448)
			(xy 360.987685 -354.739448) (xy 361.011869 -354.776002) (xy 361.035541 -354.826499) (xy 361.051609 -354.879906)
			(xy 361.059729 -354.935082) (xy 361.060238 -354.962968) (xy 361.059729 -354.990854) (xy 361.051609 -355.04603)
			(xy 361.035541 -355.099437) (xy 361.011869 -355.149934) (xy 360.981096 -355.196447) (xy 360.943879 -355.237984)
			(xy 360.901011 -355.273659) (xy 360.853405 -355.302713) (xy 360.802076 -355.324525) (xy 360.748119 -355.338631)
			(xy 360.692682 -355.344731) (xy 360.636948 -355.342694) (xy 360.582105 -355.332564) (xy 360.529321 -355.314557)
			(xy 360.479721 -355.289056) (xy 360.434363 -355.256605) (xy 360.394214 -355.217896) (xy 360.360128 -355.173753)
			(xy 360.332832 -355.125118) (xy 360.312909 -355.073027) (xy 360.300783 -355.01859) (xy 360.296712 -354.962968)
			(xy 359.883157 -354.962968) (xy 359.869846 -354.983087) (xy 359.832629 -355.024624) (xy 359.789761 -355.060299)
			(xy 359.742155 -355.089353) (xy 359.690826 -355.111165) (xy 359.636869 -355.125271) (xy 359.581432 -355.131371)
			(xy 359.525698 -355.129334) (xy 359.470855 -355.119204) (xy 359.418071 -355.101197) (xy 359.368471 -355.075696)
			(xy 359.323113 -355.043245) (xy 359.282964 -355.004536) (xy 359.248878 -354.960393) (xy 359.221582 -354.911758)
			(xy 359.201659 -354.859667) (xy 359.189533 -354.80523) (xy 359.185462 -354.749608) (xy 353.420058 -354.749608)
			(xy 353.412731 -354.755706) (xy 353.365093 -354.784779) (xy 353.31373 -354.806606) (xy 353.259737 -354.820722)
			(xy 353.204263 -354.826825) (xy 353.148492 -354.824787) (xy 353.093613 -354.81465) (xy 353.040793 -354.796631)
			(xy 352.991161 -354.771113) (xy 352.945773 -354.738641) (xy 352.905596 -354.699906) (xy 352.871488 -354.655734)
			(xy 352.844174 -354.607066) (xy 352.824238 -354.55494) (xy 352.812103 -354.500467) (xy 352.80803 -354.444808)
			(xy 349.89453 -354.444808) (xy 349.841105 -354.458775) (xy 349.785668 -354.464875) (xy 349.729934 -354.462838)
			(xy 349.675091 -354.452708) (xy 349.622307 -354.434701) (xy 349.572707 -354.4092) (xy 349.527349 -354.376749)
			(xy 349.4872 -354.33804) (xy 349.453114 -354.293897) (xy 349.425818 -354.245262) (xy 349.405895 -354.193171)
			(xy 349.393769 -354.138734) (xy 349.389698 -354.083112) (xy 321.392585 -354.083112) (xy 321.676318 -355.359462)
			(xy 346.916246 -355.359462) (xy 346.920317 -355.30384) (xy 346.932443 -355.249403) (xy 346.952366 -355.197312)
			(xy 346.979662 -355.148677) (xy 347.013748 -355.104534) (xy 347.053897 -355.065825) (xy 347.099255 -355.033374)
			(xy 347.148855 -355.007873) (xy 347.201639 -354.989866) (xy 347.256482 -354.979736) (xy 347.312216 -354.977699)
			(xy 347.367653 -354.983799) (xy 347.42161 -354.997905) (xy 347.472939 -355.019717) (xy 347.520545 -355.048771)
			(xy 347.563413 -355.084446) (xy 347.60063 -355.125983) (xy 347.631403 -355.172496) (xy 347.655075 -355.222993)
			(xy 347.671143 -355.2764) (xy 347.679263 -355.331576) (xy 347.679647 -355.352604) (xy 368.216686 -355.352604)
			(xy 368.220757 -355.296982) (xy 368.232883 -355.242545) (xy 368.252806 -355.190454) (xy 368.280102 -355.141819)
			(xy 368.314188 -355.097676) (xy 368.354337 -355.058967) (xy 368.399695 -355.026516) (xy 368.449295 -355.001015)
			(xy 368.502079 -354.983008) (xy 368.556922 -354.972878) (xy 368.612656 -354.970841) (xy 368.668093 -354.976941)
			(xy 368.72205 -354.991047) (xy 368.773379 -355.012859) (xy 368.820985 -355.041913) (xy 368.863853 -355.077588)
			(xy 368.90107 -355.119125) (xy 368.931843 -355.165638) (xy 368.955515 -355.216135) (xy 368.971583 -355.269542)
			(xy 368.979703 -355.324718) (xy 368.980212 -355.352604) (xy 368.979703 -355.38049) (xy 368.971583 -355.435666)
			(xy 368.955515 -355.489073) (xy 368.931843 -355.53957) (xy 368.90107 -355.586083) (xy 368.863853 -355.62762)
			(xy 368.820985 -355.663295) (xy 368.773379 -355.692349) (xy 368.72205 -355.714161) (xy 368.668093 -355.728267)
			(xy 368.612656 -355.734367) (xy 368.556922 -355.73233) (xy 368.502079 -355.7222) (xy 368.449295 -355.704193)
			(xy 368.399695 -355.678692) (xy 368.354337 -355.646241) (xy 368.314188 -355.607532) (xy 368.280102 -355.563389)
			(xy 368.252806 -355.514754) (xy 368.232883 -355.462663) (xy 368.220757 -355.408226) (xy 368.216686 -355.352604)
			(xy 347.679647 -355.352604) (xy 347.679772 -355.359462) (xy 347.679263 -355.387348) (xy 347.671143 -355.442524)
			(xy 347.655075 -355.495931) (xy 347.631403 -355.546428) (xy 347.60063 -355.592941) (xy 347.563413 -355.634478)
			(xy 347.520545 -355.670153) (xy 347.472939 -355.699207) (xy 347.42161 -355.721019) (xy 347.367653 -355.735125)
			(xy 347.312216 -355.741225) (xy 347.256482 -355.739188) (xy 347.201639 -355.729058) (xy 347.148855 -355.711051)
			(xy 347.099255 -355.68555) (xy 347.053897 -355.653099) (xy 347.013748 -355.61439) (xy 346.979662 -355.570247)
			(xy 346.952366 -355.521612) (xy 346.932443 -355.469521) (xy 346.920317 -355.415084) (xy 346.916246 -355.359462)
			(xy 321.676318 -355.359462) (xy 322.017369 -356.89365) (xy 336.912199 -356.89365) (xy 336.912199 -356.83915)
			(xy 336.919955 -356.785205) (xy 336.93531 -356.732913) (xy 336.95795 -356.683338) (xy 336.987415 -356.63749)
			(xy 337.023105 -356.596302) (xy 337.064293 -356.560613) (xy 337.110142 -356.531148) (xy 337.159717 -356.508508)
			(xy 337.212009 -356.493155) (xy 337.265954 -356.485399) (xy 337.293204 -356.484936) (xy 337.319273 -356.485399)
			(xy 337.370924 -356.492507) (xy 337.421127 -356.506577) (xy 337.468949 -356.527347) (xy 337.5135 -356.55443)
			(xy 337.553953 -356.587323) (xy 337.589553 -356.625414) (xy 337.619639 -356.667995) (xy 337.63204 -356.69093)
			(xy 337.638853 -356.703047) (xy 337.65782 -356.723352) (xy 337.681561 -356.737788) (xy 337.708317 -356.745284)
			(xy 337.736103 -356.745284) (xy 337.762859 -356.737788) (xy 337.7866 -356.723352) (xy 337.805567 -356.703047)
			(xy 337.81238 -356.69093) (xy 337.825437 -356.666805) (xy 337.857419 -356.622237) (xy 337.895431 -356.582687)
			(xy 337.916774 -356.565454) (xy 337.928536 -356.555509) (xy 337.946057 -356.530199) (xy 337.955239 -356.500818)
			(xy 337.955247 -356.470036) (xy 337.946081 -356.44065) (xy 337.928574 -356.41533) (xy 337.916774 -356.405434)
			(xy 337.894301 -356.38723) (xy 337.854567 -356.345212) (xy 337.821627 -356.29768) (xy 337.796237 -356.245721)
			(xy 337.778978 -356.190526) (xy 337.770245 -356.133359) (xy 337.769708 -356.104444) (xy 337.770196 -356.077192)
			(xy 337.777948 -356.023241) (xy 337.793299 -355.970942) (xy 337.815937 -355.921361) (xy 337.845402 -355.875507)
			(xy 337.881094 -355.834314) (xy 337.922285 -355.798619) (xy 337.968137 -355.769151) (xy 338.017716 -355.746509)
			(xy 338.070013 -355.731154) (xy 338.123964 -355.723398) (xy 338.151216 -355.722936) (xy 338.180131 -355.723501)
			(xy 338.237301 -355.732219) (xy 338.292499 -355.749466) (xy 338.344462 -355.774849) (xy 338.391997 -355.807785)
			(xy 338.434015 -355.84752) (xy 338.452206 -355.870002) (xy 338.462103 -355.881807) (xy 338.487427 -355.899326)
			(xy 338.51682 -355.908502) (xy 338.547612 -355.908502) (xy 338.577005 -355.899326) (xy 338.602329 -355.881807)
			(xy 338.612226 -355.870002) (xy 338.628979 -355.849219) (xy 338.667333 -355.812089) (xy 338.710487 -355.780667)
			(xy 338.757601 -355.755568) (xy 338.807753 -355.737282) (xy 338.859964 -355.726165) (xy 338.913216 -355.722435)
			(xy 338.966468 -355.726165) (xy 339.018679 -355.737282) (xy 339.068831 -355.755568) (xy 339.115945 -355.780667)
			(xy 339.159099 -355.812089) (xy 339.197453 -355.849219) (xy 339.214206 -355.870002) (xy 339.224103 -355.881807)
			(xy 339.249427 -355.899326) (xy 339.27882 -355.908502) (xy 339.309612 -355.908502) (xy 339.339005 -355.899326)
			(xy 339.364329 -355.881807) (xy 339.374226 -355.870002) (xy 339.390979 -355.849219) (xy 339.429333 -355.812089)
			(xy 339.472487 -355.780667) (xy 339.519601 -355.755568) (xy 339.569753 -355.737282) (xy 339.621964 -355.726165)
			(xy 339.675216 -355.722435) (xy 339.728468 -355.726165) (xy 339.780679 -355.737282) (xy 339.830831 -355.755568)
			(xy 339.877945 -355.780667) (xy 339.921099 -355.812089) (xy 339.959453 -355.849219) (xy 339.976206 -355.870002)
			(xy 339.986103 -355.881807) (xy 340.011427 -355.899326) (xy 340.04082 -355.908502) (xy 340.071612 -355.908502)
			(xy 340.101005 -355.899326) (xy 340.126329 -355.881807) (xy 340.136226 -355.870002) (xy 340.152979 -355.849219)
			(xy 340.191333 -355.812089) (xy 340.234487 -355.780667) (xy 340.281601 -355.755568) (xy 340.331753 -355.737282)
			(xy 340.383964 -355.726165) (xy 340.437216 -355.722435) (xy 340.490468 -355.726165) (xy 340.542679 -355.737282)
			(xy 340.592831 -355.755568) (xy 340.639945 -355.780667) (xy 340.683099 -355.812089) (xy 340.721453 -355.849219)
			(xy 340.738206 -355.870002) (xy 340.748103 -355.881807) (xy 340.773427 -355.899326) (xy 340.80282 -355.908502)
			(xy 340.833612 -355.908502) (xy 340.863005 -355.899326) (xy 340.888329 -355.881807) (xy 340.898226 -355.870002)
			(xy 340.914979 -355.849219) (xy 340.953333 -355.812089) (xy 340.996487 -355.780667) (xy 341.043601 -355.755568)
			(xy 341.093753 -355.737282) (xy 341.145964 -355.726165) (xy 341.199216 -355.722435) (xy 341.252468 -355.726165)
			(xy 341.304679 -355.737282) (xy 341.354831 -355.755568) (xy 341.401945 -355.780667) (xy 341.445099 -355.812089)
			(xy 341.483453 -355.849219) (xy 341.500206 -355.870002) (xy 341.510103 -355.881807) (xy 341.535427 -355.899326)
			(xy 341.56482 -355.908502) (xy 341.595612 -355.908502) (xy 341.625005 -355.899326) (xy 341.650329 -355.881807)
			(xy 341.660226 -355.870002) (xy 341.678403 -355.847506) (xy 341.720425 -355.807772) (xy 341.767963 -355.774834)
			(xy 341.819927 -355.749448) (xy 341.875127 -355.732194) (xy 341.932299 -355.723469) (xy 341.961216 -355.722936)
			(xy 341.987469 -355.723337) (xy 342.03948 -355.730528) (xy 342.090012 -355.744786) (xy 342.138112 -355.76584)
			(xy 342.182868 -355.793294) (xy 342.223436 -355.826627) (xy 342.259047 -355.86521) (xy 342.274398 -355.886512)
			(xy 342.282762 -355.897725) (xy 342.304387 -355.915451) (xy 342.330011 -355.926648) (xy 342.35771 -355.930476)
			(xy 342.385409 -355.926648) (xy 342.411033 -355.915451) (xy 342.432658 -355.897725) (xy 342.441022 -355.886512)
			(xy 342.456356 -355.865201) (xy 342.491981 -355.826635) (xy 342.532557 -355.793316) (xy 342.577317 -355.765873)
			(xy 342.625416 -355.744825) (xy 342.675946 -355.730568) (xy 342.727953 -355.723372) (xy 342.754204 -355.722936)
			(xy 342.784327 -355.723508) (xy 342.843823 -355.73299) (xy 342.901091 -355.7517) (xy 342.954708 -355.779176)
			(xy 343.003343 -355.814733) (xy 343.024968 -355.835712) (xy 343.03469 -355.84493) (xy 343.057852 -355.858375)
			(xy 343.083713 -355.865337) (xy 343.110495 -355.865337) (xy 343.136356 -355.858375) (xy 343.159518 -355.84493)
			(xy 343.16924 -355.835712) (xy 343.19087 -355.814737) (xy 343.239497 -355.779168) (xy 343.293112 -355.751687)
			(xy 343.350382 -355.732977) (xy 343.40988 -355.723505) (xy 343.440004 -355.722936) (xy 343.467259 -355.723352)
			(xy 343.521214 -355.73111) (xy 343.573515 -355.746469) (xy 343.623098 -355.769115) (xy 343.668954 -355.798588)
			(xy 343.710147 -355.834287) (xy 343.745841 -355.875485) (xy 343.775308 -355.921344) (xy 343.797948 -355.97093)
			(xy 343.8133 -356.023233) (xy 343.815772 -356.040436) (xy 351.932492 -356.040436) (xy 351.936565 -355.984777)
			(xy 351.9487 -355.930304) (xy 351.968636 -355.878178) (xy 351.99595 -355.82951) (xy 352.030058 -355.785338)
			(xy 352.070235 -355.746603) (xy 352.115623 -355.714131) (xy 352.165255 -355.688613) (xy 352.218075 -355.670594)
			(xy 352.272954 -355.660457) (xy 352.328725 -355.658419) (xy 352.384199 -355.664522) (xy 352.438192 -355.678638)
			(xy 352.489555 -355.700465) (xy 352.537193 -355.729538) (xy 352.580089 -355.765237) (xy 352.617331 -355.806801)
			(xy 352.648125 -355.853345) (xy 352.671813 -355.903876) (xy 352.687891 -355.957318) (xy 352.696017 -356.012532)
			(xy 352.696526 -356.040436) (xy 352.696017 -356.06834) (xy 352.687891 -356.123554) (xy 352.677975 -356.156514)
			(xy 358.86593 -356.156514) (xy 358.870001 -356.100892) (xy 358.882127 -356.046455) (xy 358.90205 -355.994364)
			(xy 358.929346 -355.945729) (xy 358.963432 -355.901586) (xy 359.003581 -355.862877) (xy 359.048939 -355.830426)
			(xy 359.098539 -355.804925) (xy 359.151323 -355.786918) (xy 359.206166 -355.776788) (xy 359.2619 -355.774751)
			(xy 359.317337 -355.780851) (xy 359.371294 -355.794957) (xy 359.422623 -355.816769) (xy 359.470229 -355.845823)
			(xy 359.513097 -355.881498) (xy 359.550314 -355.923035) (xy 359.581087 -355.969548) (xy 359.604759 -356.020045)
			(xy 359.620827 -356.073452) (xy 359.628947 -356.128628) (xy 359.629456 -356.156514) (xy 359.628947 -356.1844)
			(xy 359.620827 -356.239576) (xy 359.604759 -356.292983) (xy 359.581087 -356.34348) (xy 359.550314 -356.389993)
			(xy 359.513097 -356.43153) (xy 359.470229 -356.467205) (xy 359.422623 -356.496259) (xy 359.371294 -356.518071)
			(xy 359.317337 -356.532177) (xy 359.2619 -356.538277) (xy 359.206166 -356.53624) (xy 359.151323 -356.52611)
			(xy 359.098539 -356.508103) (xy 359.048939 -356.482602) (xy 359.003581 -356.450151) (xy 358.963432 -356.411442)
			(xy 358.929346 -356.367299) (xy 358.90205 -356.318664) (xy 358.882127 -356.266573) (xy 358.870001 -356.212136)
			(xy 358.86593 -356.156514) (xy 352.677975 -356.156514) (xy 352.671813 -356.176996) (xy 352.648125 -356.227527)
			(xy 352.617331 -356.274071) (xy 352.580089 -356.315635) (xy 352.537193 -356.351334) (xy 352.489555 -356.380407)
			(xy 352.438192 -356.402234) (xy 352.384199 -356.41635) (xy 352.328725 -356.422453) (xy 352.272954 -356.420415)
			(xy 352.218075 -356.410278) (xy 352.165255 -356.392259) (xy 352.115623 -356.366741) (xy 352.070235 -356.334269)
			(xy 352.030058 -356.295534) (xy 351.99595 -356.251362) (xy 351.968636 -356.202694) (xy 351.9487 -356.150568)
			(xy 351.936565 -356.096095) (xy 351.932492 -356.040436) (xy 343.815772 -356.040436) (xy 343.821052 -356.077189)
			(xy 343.821512 -356.104444) (xy 343.820987 -356.133361) (xy 343.812264 -356.190533) (xy 343.795009 -356.245734)
			(xy 343.769619 -356.297696) (xy 343.736675 -356.34523) (xy 343.696932 -356.387245) (xy 343.674446 -356.405434)
			(xy 343.662593 -356.415281) (xy 343.645071 -356.440617) (xy 343.635897 -356.470024) (xy 343.635899 -356.478332)
			(xy 346.916246 -356.478332) (xy 346.920317 -356.42271) (xy 346.932443 -356.368273) (xy 346.952366 -356.316182)
			(xy 346.979662 -356.267547) (xy 347.013748 -356.223404) (xy 347.053897 -356.184695) (xy 347.099255 -356.152244)
			(xy 347.148855 -356.126743) (xy 347.201639 -356.108736) (xy 347.256482 -356.098606) (xy 347.312216 -356.096569)
			(xy 347.367653 -356.102669) (xy 347.42161 -356.116775) (xy 347.472939 -356.138587) (xy 347.520545 -356.167641)
			(xy 347.563413 -356.203316) (xy 347.60063 -356.244853) (xy 347.631403 -356.291366) (xy 347.655075 -356.341863)
			(xy 347.671143 -356.39527) (xy 347.679263 -356.450446) (xy 347.679772 -356.478332) (xy 347.679263 -356.506218)
			(xy 347.673274 -356.546912) (xy 361.125006 -356.546912) (xy 361.129077 -356.49129) (xy 361.141203 -356.436853)
			(xy 361.161126 -356.384762) (xy 361.188422 -356.336127) (xy 361.222508 -356.291984) (xy 361.262657 -356.253275)
			(xy 361.308015 -356.220824) (xy 361.357615 -356.195323) (xy 361.410399 -356.177316) (xy 361.465242 -356.167186)
			(xy 361.520976 -356.165149) (xy 361.576413 -356.171249) (xy 361.63037 -356.185355) (xy 361.681699 -356.207167)
			(xy 361.729305 -356.236221) (xy 361.772173 -356.271896) (xy 361.80939 -356.313433) (xy 361.840163 -356.359946)
			(xy 361.846722 -356.373938) (xy 368.222274 -356.373938) (xy 368.226345 -356.318316) (xy 368.238471 -356.263879)
			(xy 368.258394 -356.211788) (xy 368.28569 -356.163153) (xy 368.319776 -356.11901) (xy 368.359925 -356.080301)
			(xy 368.405283 -356.04785) (xy 368.454883 -356.022349) (xy 368.507667 -356.004342) (xy 368.56251 -355.994212)
			(xy 368.618244 -355.992175) (xy 368.673681 -355.998275) (xy 368.727638 -356.012381) (xy 368.778967 -356.034193)
			(xy 368.826573 -356.063247) (xy 368.869441 -356.098922) (xy 368.906658 -356.140459) (xy 368.937431 -356.186972)
			(xy 368.961103 -356.237469) (xy 368.977171 -356.290876) (xy 368.978854 -356.30231) (xy 370.449854 -356.30231)
			(xy 370.453925 -356.246688) (xy 370.466051 -356.192251) (xy 370.485974 -356.14016) (xy 370.51327 -356.091525)
			(xy 370.547356 -356.047382) (xy 370.587505 -356.008673) (xy 370.632863 -355.976222) (xy 370.682463 -355.950721)
			(xy 370.735247 -355.932714) (xy 370.79009 -355.922584) (xy 370.845824 -355.920547) (xy 370.901261 -355.926647)
			(xy 370.955218 -355.940753) (xy 371.006547 -355.962565) (xy 371.054153 -355.991619) (xy 371.097021 -356.027294)
			(xy 371.134238 -356.068831) (xy 371.165011 -356.115344) (xy 371.188683 -356.165841) (xy 371.204751 -356.219248)
			(xy 371.212871 -356.274424) (xy 371.21338 -356.30231) (xy 371.212871 -356.330196) (xy 371.204751 -356.385372)
			(xy 371.188683 -356.438779) (xy 371.165011 -356.489276) (xy 371.134238 -356.535789) (xy 371.097021 -356.577326)
			(xy 371.054153 -356.613001) (xy 371.006547 -356.642055) (xy 370.955218 -356.663867) (xy 370.901261 -356.677973)
			(xy 370.845824 -356.684073) (xy 370.79009 -356.682036) (xy 370.735247 -356.671906) (xy 370.682463 -356.653899)
			(xy 370.632863 -356.628398) (xy 370.587505 -356.595947) (xy 370.547356 -356.557238) (xy 370.51327 -356.513095)
			(xy 370.485974 -356.46446) (xy 370.466051 -356.412369) (xy 370.453925 -356.357932) (xy 370.449854 -356.30231)
			(xy 368.978854 -356.30231) (xy 368.985291 -356.346052) (xy 368.9858 -356.373938) (xy 368.985291 -356.401824)
			(xy 368.977171 -356.457) (xy 368.961103 -356.510407) (xy 368.937431 -356.560904) (xy 368.906658 -356.607417)
			(xy 368.869441 -356.648954) (xy 368.826573 -356.684629) (xy 368.778967 -356.713683) (xy 368.727638 -356.735495)
			(xy 368.673681 -356.749601) (xy 368.618244 -356.755701) (xy 368.56251 -356.753664) (xy 368.507667 -356.743534)
			(xy 368.454883 -356.725527) (xy 368.405283 -356.700026) (xy 368.359925 -356.667575) (xy 368.319776 -356.628866)
			(xy 368.28569 -356.584723) (xy 368.258394 -356.536088) (xy 368.238471 -356.483997) (xy 368.226345 -356.42956)
			(xy 368.222274 -356.373938) (xy 361.846722 -356.373938) (xy 361.863835 -356.410443) (xy 361.879903 -356.46385)
			(xy 361.888023 -356.519026) (xy 361.888532 -356.546912) (xy 361.888023 -356.574798) (xy 361.879903 -356.629974)
			(xy 361.863835 -356.683381) (xy 361.840163 -356.733878) (xy 361.80939 -356.780391) (xy 361.772173 -356.821928)
			(xy 361.729305 -356.857603) (xy 361.681699 -356.886657) (xy 361.63037 -356.908469) (xy 361.576413 -356.922575)
			(xy 361.520976 -356.928675) (xy 361.465242 -356.926638) (xy 361.410399 -356.916508) (xy 361.357615 -356.898501)
			(xy 361.308015 -356.873) (xy 361.262657 -356.840549) (xy 361.222508 -356.80184) (xy 361.188422 -356.757697)
			(xy 361.161126 -356.709062) (xy 361.141203 -356.656971) (xy 361.129077 -356.602534) (xy 361.125006 -356.546912)
			(xy 347.673274 -356.546912) (xy 347.671143 -356.561394) (xy 347.655075 -356.614801) (xy 347.631403 -356.665298)
			(xy 347.60063 -356.711811) (xy 347.563413 -356.753348) (xy 347.520545 -356.789023) (xy 347.472939 -356.818077)
			(xy 347.42161 -356.839889) (xy 347.367653 -356.853995) (xy 347.312216 -356.860095) (xy 347.256482 -356.858058)
			(xy 347.201639 -356.847928) (xy 347.148855 -356.829921) (xy 347.099255 -356.80442) (xy 347.053897 -356.771969)
			(xy 347.013748 -356.73326) (xy 346.979662 -356.689117) (xy 346.952366 -356.640482) (xy 346.932443 -356.588391)
			(xy 346.920317 -356.533954) (xy 346.916246 -356.478332) (xy 343.635899 -356.478332) (xy 343.635905 -356.500829)
			(xy 343.645095 -356.530232) (xy 343.662631 -356.555558) (xy 343.674446 -356.565454) (xy 343.696917 -356.583659)
			(xy 343.736651 -356.625678) (xy 343.76959 -356.67321) (xy 343.79498 -356.725168) (xy 343.81224 -356.780362)
			(xy 343.820974 -356.837529) (xy 343.821512 -356.866444) (xy 343.821063 -356.893696) (xy 343.813301 -356.947645)
			(xy 343.79794 -356.99994) (xy 343.775294 -357.049517) (xy 343.758276 -357.075994) (xy 362.04347 -357.075994)
			(xy 362.047541 -357.020372) (xy 362.059667 -356.965935) (xy 362.07959 -356.913844) (xy 362.106886 -356.865209)
			(xy 362.140972 -356.821066) (xy 362.181121 -356.782357) (xy 362.226479 -356.749906) (xy 362.276079 -356.724405)
			(xy 362.328863 -356.706398) (xy 362.383706 -356.696268) (xy 362.43944 -356.694231) (xy 362.494877 -356.700331)
			(xy 362.548834 -356.714437) (xy 362.600163 -356.736249) (xy 362.647769 -356.765303) (xy 362.690637 -356.800978)
			(xy 362.727854 -356.842515) (xy 362.758627 -356.889028) (xy 362.782299 -356.939525) (xy 362.798367 -356.992932)
			(xy 362.806487 -357.048108) (xy 362.806996 -357.075994) (xy 362.806487 -357.10388) (xy 362.798367 -357.159056)
			(xy 362.786829 -357.197406) (xy 364.728504 -357.197406) (xy 364.732575 -357.141784) (xy 364.744701 -357.087347)
			(xy 364.764624 -357.035256) (xy 364.79192 -356.986621) (xy 364.826006 -356.942478) (xy 364.866155 -356.903769)
			(xy 364.911513 -356.871318) (xy 364.961113 -356.845817) (xy 365.013897 -356.82781) (xy 365.06874 -356.81768)
			(xy 365.124474 -356.815643) (xy 365.179911 -356.821743) (xy 365.233868 -356.835849) (xy 365.285197 -356.857661)
			(xy 365.332803 -356.886715) (xy 365.375671 -356.92239) (xy 365.412888 -356.963927) (xy 365.443661 -357.01044)
			(xy 365.467333 -357.060937) (xy 365.483401 -357.114344) (xy 365.491521 -357.16952) (xy 365.49203 -357.197406)
			(xy 365.491521 -357.225292) (xy 365.483401 -357.280468) (xy 365.467333 -357.333875) (xy 365.443661 -357.384372)
			(xy 365.412888 -357.430885) (xy 365.375671 -357.472422) (xy 365.332803 -357.508097) (xy 365.285197 -357.537151)
			(xy 365.233868 -357.558963) (xy 365.179911 -357.573069) (xy 365.124474 -357.579169) (xy 365.06874 -357.577132)
			(xy 365.013897 -357.567002) (xy 364.961113 -357.548995) (xy 364.911513 -357.523494) (xy 364.866155 -357.491043)
			(xy 364.826006 -357.452334) (xy 364.79192 -357.408191) (xy 364.764624 -357.359556) (xy 364.744701 -357.307465)
			(xy 364.732575 -357.253028) (xy 364.728504 -357.197406) (xy 362.786829 -357.197406) (xy 362.782299 -357.212463)
			(xy 362.758627 -357.26296) (xy 362.727854 -357.309473) (xy 362.690637 -357.35101) (xy 362.647769 -357.386685)
			(xy 362.600163 -357.415739) (xy 362.548834 -357.437551) (xy 362.494877 -357.451657) (xy 362.43944 -357.457757)
			(xy 362.383706 -357.45572) (xy 362.328863 -357.44559) (xy 362.276079 -357.427583) (xy 362.226479 -357.402082)
			(xy 362.181121 -357.369631) (xy 362.140972 -357.330922) (xy 362.106886 -357.286779) (xy 362.07959 -357.238144)
			(xy 362.059667 -357.186053) (xy 362.047541 -357.131616) (xy 362.04347 -357.075994) (xy 343.758276 -357.075994)
			(xy 343.745824 -357.095367) (xy 343.710129 -357.136557) (xy 343.668935 -357.172248) (xy 343.623082 -357.201713)
			(xy 343.573503 -357.224354) (xy 343.521206 -357.239709) (xy 343.467256 -357.247466) (xy 343.440004 -357.247952)
			(xy 343.409881 -357.247378) (xy 343.350384 -357.237898) (xy 343.293117 -357.219188) (xy 343.2395 -357.191712)
			(xy 343.190865 -357.156155) (xy 343.16924 -357.135176) (xy 343.159518 -357.125958) (xy 343.136356 -357.112513)
			(xy 343.110495 -357.105551) (xy 343.083713 -357.105551) (xy 343.057852 -357.112513) (xy 343.03469 -357.125958)
			(xy 343.024968 -357.135176) (xy 343.003332 -357.156145) (xy 342.954707 -357.191715) (xy 342.901093 -357.219198)
			(xy 342.843825 -357.237909) (xy 342.784328 -357.247383) (xy 342.754204 -357.247952) (xy 342.727951 -357.247541)
			(xy 342.675941 -357.240352) (xy 342.625408 -357.226097) (xy 342.577309 -357.205044) (xy 342.532552 -357.177592)
			(xy 342.491984 -357.14426) (xy 342.456373 -357.105677) (xy 342.441022 -357.084376) (xy 342.432658 -357.073163)
			(xy 342.411033 -357.055437) (xy 342.385409 -357.04424) (xy 342.35771 -357.040412) (xy 342.330011 -357.04424)
			(xy 342.304387 -357.055437) (xy 342.282762 -357.073163) (xy 342.274398 -357.084376) (xy 342.259048 -357.105675)
			(xy 342.223426 -357.144242) (xy 342.182853 -357.177562) (xy 342.138096 -357.205006) (xy 342.09 -357.226057)
			(xy 342.039472 -357.240316) (xy 341.987467 -357.247514) (xy 341.961216 -357.247952) (xy 341.932299 -357.24744)
			(xy 341.875126 -357.238713) (xy 341.819927 -357.221454) (xy 341.767964 -357.196062) (xy 341.720431 -357.163116)
			(xy 341.678415 -357.123373) (xy 341.660226 -357.100886) (xy 341.650329 -357.089081) (xy 341.625005 -357.071562)
			(xy 341.595612 -357.062386) (xy 341.56482 -357.062386) (xy 341.535427 -357.071562) (xy 341.510103 -357.089081)
			(xy 341.500206 -357.100886) (xy 341.483453 -357.121669) (xy 341.445099 -357.158799) (xy 341.401945 -357.190221)
			(xy 341.354831 -357.21532) (xy 341.304679 -357.233606) (xy 341.252468 -357.244723) (xy 341.199216 -357.248453)
			(xy 341.145964 -357.244723) (xy 341.093753 -357.233606) (xy 341.043601 -357.21532) (xy 340.996487 -357.190221)
			(xy 340.953333 -357.158799) (xy 340.914979 -357.121669) (xy 340.898226 -357.100886) (xy 340.888329 -357.089081)
			(xy 340.863005 -357.071562) (xy 340.833612 -357.062386) (xy 340.80282 -357.062386) (xy 340.773427 -357.071562)
			(xy 340.748103 -357.089081) (xy 340.738206 -357.100886) (xy 340.721453 -357.121669) (xy 340.683099 -357.158799)
			(xy 340.639945 -357.190221) (xy 340.592831 -357.21532) (xy 340.542679 -357.233606) (xy 340.490468 -357.244723)
			(xy 340.437216 -357.248453) (xy 340.383964 -357.244723) (xy 340.331753 -357.233606) (xy 340.281601 -357.21532)
			(xy 340.234487 -357.190221) (xy 340.191333 -357.158799) (xy 340.152979 -357.121669) (xy 340.136226 -357.100886)
			(xy 340.126329 -357.089081) (xy 340.101005 -357.071562) (xy 340.071612 -357.062386) (xy 340.04082 -357.062386)
			(xy 340.011427 -357.071562) (xy 339.986103 -357.089081) (xy 339.976206 -357.100886) (xy 339.959453 -357.121669)
			(xy 339.921099 -357.158799) (xy 339.877945 -357.190221) (xy 339.830831 -357.21532) (xy 339.780679 -357.233606)
			(xy 339.728468 -357.244723) (xy 339.675216 -357.248453) (xy 339.621964 -357.244723) (xy 339.569753 -357.233606)
			(xy 339.519601 -357.21532) (xy 339.472487 -357.190221) (xy 339.429333 -357.158799) (xy 339.390979 -357.121669)
			(xy 339.374226 -357.100886) (xy 339.364329 -357.089081) (xy 339.339005 -357.071562) (xy 339.309612 -357.062386)
			(xy 339.27882 -357.062386) (xy 339.249427 -357.071562) (xy 339.224103 -357.089081) (xy 339.214206 -357.100886)
			(xy 339.197453 -357.121669) (xy 339.159099 -357.158799) (xy 339.115945 -357.190221) (xy 339.068831 -357.21532)
			(xy 339.018679 -357.233606) (xy 338.966468 -357.244723) (xy 338.913216 -357.248453) (xy 338.859964 -357.244723)
			(xy 338.807753 -357.233606) (xy 338.757601 -357.21532) (xy 338.710487 -357.190221) (xy 338.667333 -357.158799)
			(xy 338.628979 -357.121669) (xy 338.612226 -357.100886) (xy 338.602329 -357.089081) (xy 338.577005 -357.071562)
			(xy 338.547612 -357.062386) (xy 338.51682 -357.062386) (xy 338.487427 -357.071562) (xy 338.462103 -357.089081)
			(xy 338.452206 -357.100886) (xy 338.434008 -357.123364) (xy 338.39199 -357.1631) (xy 338.344457 -357.19604)
			(xy 338.292497 -357.221429) (xy 338.2373 -357.238687) (xy 338.180132 -357.247417) (xy 338.151216 -357.247952)
			(xy 338.125148 -357.247479) (xy 338.073497 -357.240373) (xy 338.023293 -357.226305) (xy 337.975471 -357.205538)
			(xy 337.93092 -357.178456) (xy 337.890467 -357.145564) (xy 337.854867 -357.107473) (xy 337.82478 -357.064893)
			(xy 337.81238 -357.041958) (xy 337.805567 -357.029841) (xy 337.7866 -357.009536) (xy 337.762859 -356.9951)
			(xy 337.736103 -356.987604) (xy 337.708317 -356.987604) (xy 337.681561 -356.9951) (xy 337.65782 -357.009536)
			(xy 337.638853 -357.029841) (xy 337.63204 -357.041958) (xy 337.619684 -357.064922) (xy 337.589607 -357.107522)
			(xy 337.554009 -357.145628) (xy 337.513553 -357.178532) (xy 337.468992 -357.20562) (xy 337.421158 -357.226386)
			(xy 337.370941 -357.240445) (xy 337.319278 -357.247534) (xy 337.293204 -357.247952) (xy 337.265954 -357.247401)
			(xy 337.212009 -357.239645) (xy 337.159717 -357.224292) (xy 337.110142 -357.201652) (xy 337.064293 -357.172187)
			(xy 337.023105 -357.136498) (xy 336.987415 -357.09531) (xy 336.95795 -357.049462) (xy 336.93531 -356.999887)
			(xy 336.919955 -356.947595) (xy 336.912199 -356.89365) (xy 322.017369 -356.89365) (xy 322.538698 -359.238802)
			(xy 335.453223 -359.238802) (xy 335.456952 -359.18555) (xy 335.46807 -359.133337) (xy 335.486358 -359.083185)
			(xy 335.511459 -359.036072) (xy 335.542884 -358.992918) (xy 335.580018 -358.954566) (xy 335.600802 -358.937814)
			(xy 335.612602 -358.927911) (xy 335.630117 -358.902589) (xy 335.639292 -358.873197) (xy 335.639292 -358.842407)
			(xy 335.630119 -358.813016) (xy 335.612605 -358.787692) (xy 335.600802 -358.777794) (xy 335.578316 -358.759606)
			(xy 335.538581 -358.717586) (xy 335.505642 -358.67005) (xy 335.480254 -358.618088) (xy 335.462999 -358.56289)
			(xy 335.45427 -358.50572) (xy 335.453736 -358.476804) (xy 335.454159 -358.449549) (xy 335.461917 -358.395595)
			(xy 335.477275 -358.343293) (xy 335.49992 -358.29371) (xy 335.529391 -358.247855) (xy 335.565089 -358.206661)
			(xy 335.606287 -358.170967) (xy 335.652145 -358.141501) (xy 335.701731 -358.118861) (xy 335.754034 -358.103508)
			(xy 335.807989 -358.095756) (xy 335.835244 -358.095296) (xy 335.864296 -358.095875) (xy 335.92173 -358.104666)
			(xy 335.977166 -358.122067) (xy 336.029321 -358.147676) (xy 336.076988 -358.1809) (xy 336.119063 -358.220971)
			(xy 336.13725 -358.243632) (xy 336.146504 -358.254707) (xy 336.169828 -358.271677) (xy 336.196969 -358.281442)
			(xy 336.225758 -358.283222) (xy 336.253895 -358.276877) (xy 336.279133 -358.262911) (xy 336.28965 -358.25303)
			(xy 336.298332 -358.244396) (xy 336.316634 -358.228128) (xy 336.326226 -358.220518) (xy 336.33802 -358.21061)
			(xy 336.355531 -358.185287) (xy 336.364703 -358.155898) (xy 336.364705 -358.125111) (xy 336.355535 -358.095721)
			(xy 336.338026 -358.070397) (xy 336.326226 -358.060498) (xy 336.303747 -358.042302) (xy 336.26401 -358.000284)
			(xy 336.23107 -357.95275) (xy 336.205681 -357.90079) (xy 336.188424 -357.845593) (xy 336.179695 -357.788424)
			(xy 336.17916 -357.759508) (xy 336.179685 -357.732258) (xy 336.18744 -357.678314) (xy 336.202792 -357.626022)
			(xy 336.22543 -357.576447) (xy 336.254893 -357.530598) (xy 336.29058 -357.489408) (xy 336.331766 -357.453717)
			(xy 336.377611 -357.424249) (xy 336.427184 -357.401606) (xy 336.479475 -357.386248) (xy 336.533418 -357.378488)
			(xy 336.560668 -357.378) (xy 336.588047 -357.378477) (xy 336.64224 -357.386314) (xy 336.694757 -357.401816)
			(xy 336.744519 -357.424665) (xy 336.790505 -357.454393) (xy 336.831769 -357.490388) (xy 336.849974 -357.510842)
			(xy 336.860022 -357.521832) (xy 336.885087 -357.537887) (xy 336.913716 -357.54604) (xy 336.943479 -357.545599)
			(xy 336.971854 -357.536602) (xy 336.996433 -357.519812) (xy 337.006184 -357.508556) (xy 337.024421 -357.486776)
			(xy 337.066213 -357.448305) (xy 337.113247 -357.416454) (xy 337.164482 -357.391927) (xy 337.218787 -357.375267)
			(xy 337.274962 -357.366841) (xy 337.303364 -357.366316) (xy 337.331062 -357.366795) (xy 337.385876 -357.374797)
			(xy 337.438957 -357.390639) (xy 337.489191 -357.413988) (xy 337.535522 -357.444352) (xy 337.576978 -357.481096)
			(xy 337.59521 -357.501952) (xy 337.604729 -357.512643) (xy 337.628495 -357.528585) (xy 337.655753 -357.537301)
			(xy 337.684359 -357.538106) (xy 337.712064 -357.530938) (xy 337.736689 -357.516359) (xy 337.746848 -357.50627)
			(xy 337.764952 -357.487755) (xy 337.805259 -357.455249) (xy 337.849593 -357.428494) (xy 337.897138 -357.407982)
			(xy 337.947021 -357.394091) (xy 337.998325 -357.387075) (xy 338.024216 -357.386636) (xy 338.051471 -357.38704)
			(xy 338.105427 -357.3948) (xy 338.157728 -357.410161) (xy 338.207312 -357.432808) (xy 338.253167 -357.462282)
			(xy 338.29436 -357.497982) (xy 338.330054 -357.539181) (xy 338.35952 -357.585041) (xy 338.38216 -357.634628)
			(xy 338.397512 -357.686932) (xy 338.405264 -357.740889) (xy 338.405724 -357.768144) (xy 338.405194 -357.797061)
			(xy 338.396471 -357.854233) (xy 338.379218 -357.909433) (xy 338.353828 -357.961395) (xy 338.320885 -358.008929)
			(xy 338.281144 -358.050945) (xy 338.258658 -358.069134) (xy 338.246804 -358.078981) (xy 338.22928 -358.104316)
			(xy 338.220104 -358.133724) (xy 338.220112 -358.16453) (xy 338.229303 -358.193933) (xy 338.246842 -358.219259)
			(xy 338.258658 -358.229154) (xy 338.281111 -358.247382) (xy 338.32085 -358.289392) (xy 338.353794 -358.336919)
			(xy 338.379188 -358.388874) (xy 338.39645 -358.444065) (xy 338.405186 -358.50123) (xy 338.405724 -358.530144)
			(xy 338.405225 -358.557347) (xy 338.397493 -358.611202) (xy 338.382179 -358.663409) (xy 338.359595 -358.712906)
			(xy 338.330198 -358.758688) (xy 338.31276 -358.779572) (xy 338.303282 -358.791464) (xy 338.291054 -358.819286)
			(xy 338.287557 -358.849474) (xy 338.293099 -358.879354) (xy 338.307191 -358.906279) (xy 338.328583 -358.927865)
			(xy 338.341716 -358.935528) (xy 338.364879 -358.948451) (xy 338.407693 -358.979759) (xy 338.445736 -359.016719)
			(xy 338.462366 -359.037382) (xy 338.472263 -359.049187) (xy 338.497587 -359.066706) (xy 338.52698 -359.075882)
			(xy 338.557772 -359.075882) (xy 338.587165 -359.066706) (xy 338.612489 -359.049187) (xy 338.622386 -359.037382)
			(xy 338.639139 -359.016599) (xy 338.677493 -358.979469) (xy 338.720647 -358.948047) (xy 338.767761 -358.922948)
			(xy 338.817913 -358.904662) (xy 338.870124 -358.893545) (xy 338.923376 -358.889815) (xy 338.976628 -358.893545)
			(xy 339.028839 -358.904662) (xy 339.078991 -358.922948) (xy 339.126105 -358.948047) (xy 339.169259 -358.979469)
			(xy 339.207613 -359.016599) (xy 339.224366 -359.037382) (xy 339.234263 -359.049187) (xy 339.259587 -359.066706)
			(xy 339.28898 -359.075882) (xy 339.319772 -359.075882) (xy 339.349165 -359.066706) (xy 339.374489 -359.049187)
			(xy 339.384386 -359.037382) (xy 339.401139 -359.016599) (xy 339.439493 -358.979469) (xy 339.482647 -358.948047)
			(xy 339.529761 -358.922948) (xy 339.579913 -358.904662) (xy 339.632124 -358.893545) (xy 339.685376 -358.889815)
			(xy 339.738628 -358.893545) (xy 339.790839 -358.904662) (xy 339.840991 -358.922948) (xy 339.888105 -358.948047)
			(xy 339.931259 -358.979469) (xy 339.969613 -359.016599) (xy 339.986366 -359.037382) (xy 339.996263 -359.049187)
			(xy 340.021587 -359.066706) (xy 340.05098 -359.075882) (xy 340.081772 -359.075882) (xy 340.111165 -359.066706)
			(xy 340.136489 -359.049187) (xy 340.146386 -359.037382) (xy 340.163139 -359.016599) (xy 340.201493 -358.979469)
			(xy 340.244647 -358.948047) (xy 340.291761 -358.922948) (xy 340.341913 -358.904662) (xy 340.394124 -358.893545)
			(xy 340.447376 -358.889815) (xy 340.500628 -358.893545) (xy 340.552839 -358.904662) (xy 340.602991 -358.922948)
			(xy 340.650105 -358.948047) (xy 340.693259 -358.979469) (xy 340.731613 -359.016599) (xy 340.748366 -359.037382)
			(xy 340.758263 -359.049187) (xy 340.783587 -359.066706) (xy 340.81298 -359.075882) (xy 340.843772 -359.075882)
			(xy 340.873165 -359.066706) (xy 340.898489 -359.049187) (xy 340.908386 -359.037382) (xy 340.925139 -359.016599)
			(xy 340.963493 -358.979469) (xy 341.006647 -358.948047) (xy 341.053761 -358.922948) (xy 341.103913 -358.904662)
			(xy 341.156124 -358.893545) (xy 341.209376 -358.889815) (xy 341.262628 -358.893545) (xy 341.314839 -358.904662)
			(xy 341.364991 -358.922948) (xy 341.412105 -358.948047) (xy 341.455259 -358.979469) (xy 341.493613 -359.016599)
			(xy 341.510366 -359.037382) (xy 341.520263 -359.049187) (xy 341.545587 -359.066706) (xy 341.57498 -359.075882)
			(xy 341.605772 -359.075882) (xy 341.635165 -359.066706) (xy 341.660489 -359.049187) (xy 341.670386 -359.037382)
			(xy 341.688207 -359.015359) (xy 341.729273 -358.976336) (xy 341.752174 -358.959658) (xy 341.764272 -358.950505)
			(xy 341.782866 -358.926555) (xy 341.793608 -358.8982) (xy 341.795551 -358.867941) (xy 341.788523 -358.838446)
			(xy 341.773144 -358.812314) (xy 341.762334 -358.80167) (xy 341.743114 -358.783539) (xy 341.709397 -358.742857)
			(xy 341.681616 -358.697912) (xy 341.660303 -358.649563) (xy 341.645864 -358.598736) (xy 341.638575 -358.546403)
			(xy 341.638128 -358.519984) (xy 341.638696 -358.491069) (xy 341.647413 -358.4339) (xy 341.664661 -358.378701)
			(xy 341.690043 -358.326739) (xy 341.722978 -358.279204) (xy 341.762712 -358.237186) (xy 341.785194 -358.218994)
			(xy 341.797015 -358.209114) (xy 341.814531 -358.183785) (xy 341.823704 -358.154388) (xy 341.823701 -358.123593)
			(xy 341.814522 -358.094197) (xy 341.797001 -358.068872) (xy 341.785194 -358.058974) (xy 341.762697 -358.040799)
			(xy 341.722963 -357.998776) (xy 341.690026 -357.951238) (xy 341.66464 -357.899273) (xy 341.647386 -357.844073)
			(xy 341.638661 -357.786901) (xy 341.638128 -357.757984) (xy 341.63854 -357.730729) (xy 341.6463 -357.676774)
			(xy 341.66166 -357.624473) (xy 341.684307 -357.574891) (xy 341.71378 -357.529036) (xy 341.749479 -357.487842)
			(xy 341.790678 -357.452149) (xy 341.836536 -357.422682) (xy 341.886122 -357.400042) (xy 341.938425 -357.384689)
			(xy 341.992381 -357.376936) (xy 342.019636 -357.376476) (xy 342.01989 -357.376476) (xy 342.047433 -357.37695)
			(xy 342.101943 -357.384895) (xy 342.154745 -357.400592) (xy 342.204743 -357.423715) (xy 342.250898 -357.453785)
			(xy 342.292251 -357.490176) (xy 342.310466 -357.510842) (xy 342.320577 -357.521809) (xy 342.345631 -357.537962)
			(xy 342.374281 -357.5462) (xy 342.404088 -357.545822) (xy 342.432519 -357.536859) (xy 342.457154 -357.520074)
			(xy 342.46693 -357.50881) (xy 342.485142 -357.486967) (xy 342.526959 -357.448426) (xy 342.574034 -357.416519)
			(xy 342.625322 -357.39195) (xy 342.679689 -357.375266) (xy 342.735929 -357.366836) (xy 342.764364 -357.366316)
			(xy 342.794486 -357.366919) (xy 342.85398 -357.376394) (xy 342.911248 -357.395098) (xy 342.964865 -357.422566)
			(xy 343.013502 -357.458117) (xy 343.035128 -357.479092) (xy 343.04485 -357.48831) (xy 343.068012 -357.501755)
			(xy 343.093873 -357.508717) (xy 343.120655 -357.508717) (xy 343.146516 -357.501755) (xy 343.169678 -357.48831)
			(xy 343.1794 -357.479092) (xy 343.201 -357.458085) (xy 343.249636 -357.422521) (xy 343.303259 -357.395046)
			(xy 343.360534 -357.376344) (xy 343.420038 -357.36688) (xy 343.450164 -357.366316) (xy 343.477417 -357.366789)
			(xy 343.531369 -357.374542) (xy 343.583668 -357.389894) (xy 343.63325 -357.412534) (xy 343.679104 -357.442001)
			(xy 343.720298 -357.477694) (xy 343.734715 -357.494332) (xy 346.916246 -357.494332) (xy 346.920317 -357.43871)
			(xy 346.932443 -357.384273) (xy 346.952366 -357.332182) (xy 346.979662 -357.283547) (xy 347.013748 -357.239404)
			(xy 347.053897 -357.200695) (xy 347.099255 -357.168244) (xy 347.148855 -357.142743) (xy 347.201639 -357.124736)
			(xy 347.256482 -357.114606) (xy 347.312216 -357.112569) (xy 347.367653 -357.118669) (xy 347.42161 -357.132775)
			(xy 347.472939 -357.154587) (xy 347.520545 -357.183641) (xy 347.563413 -357.219316) (xy 347.60063 -357.260853)
			(xy 347.631403 -357.307366) (xy 347.655075 -357.357863) (xy 347.671143 -357.41127) (xy 347.679263 -357.466446)
			(xy 347.679772 -357.494332) (xy 347.679263 -357.522218) (xy 347.671143 -357.577394) (xy 347.655075 -357.630801)
			(xy 347.631403 -357.681298) (xy 347.60063 -357.727811) (xy 347.563413 -357.769348) (xy 347.520545 -357.805023)
			(xy 347.472939 -357.834077) (xy 347.42161 -357.855889) (xy 347.367653 -357.869995) (xy 347.312216 -357.876095)
			(xy 347.256482 -357.874058) (xy 347.201639 -357.863928) (xy 347.148855 -357.845921) (xy 347.099255 -357.82042)
			(xy 347.053897 -357.787969) (xy 347.013748 -357.74926) (xy 346.979662 -357.705117) (xy 346.952366 -357.656482)
			(xy 346.932443 -357.604391) (xy 346.920317 -357.549954) (xy 346.916246 -357.494332) (xy 343.734715 -357.494332)
			(xy 343.755992 -357.518886) (xy 343.78546 -357.56474) (xy 343.808102 -357.614321) (xy 343.823456 -357.666619)
			(xy 343.83121 -357.720571) (xy 343.831672 -357.747824) (xy 343.83111 -357.776739) (xy 343.822392 -357.833909)
			(xy 343.805143 -357.889108) (xy 343.77976 -357.94107) (xy 343.746823 -357.988605) (xy 343.707089 -358.030623)
			(xy 343.684606 -358.048814) (xy 343.672777 -358.058686) (xy 343.655261 -358.084017) (xy 343.646089 -358.113416)
			(xy 343.646093 -358.144213) (xy 343.655274 -358.17361) (xy 343.672798 -358.198936) (xy 343.684606 -358.208834)
			(xy 343.695667 -358.217724) (xy 347.824296 -358.217724) (xy 347.828367 -358.162102) (xy 347.840493 -358.107665)
			(xy 347.860416 -358.055574) (xy 347.887712 -358.006939) (xy 347.921798 -357.962796) (xy 347.961947 -357.924087)
			(xy 348.007305 -357.891636) (xy 348.056905 -357.866135) (xy 348.109689 -357.848128) (xy 348.164532 -357.837998)
			(xy 348.220266 -357.835961) (xy 348.275703 -357.842061) (xy 348.32966 -357.856167) (xy 348.380989 -357.877979)
			(xy 348.428595 -357.907033) (xy 348.471463 -357.942708) (xy 348.50868 -357.984245) (xy 348.539453 -358.030758)
			(xy 348.563125 -358.081255) (xy 348.579193 -358.134662) (xy 348.587313 -358.189838) (xy 348.587822 -358.217724)
			(xy 348.587313 -358.24561) (xy 348.582877 -358.275754) (xy 351.436636 -358.275754) (xy 351.436636 -358.221246)
			(xy 351.444393 -358.167294) (xy 351.459749 -358.114995) (xy 351.482392 -358.065413) (xy 351.51186 -358.019558)
			(xy 351.547554 -357.978364) (xy 351.588747 -357.942668) (xy 351.634601 -357.913198) (xy 351.684181 -357.890554)
			(xy 351.73648 -357.875196) (xy 351.790432 -357.867437) (xy 351.817686 -357.86695) (xy 351.833829 -357.867091)
			(xy 351.866003 -357.869764) (xy 351.881948 -357.872284) (xy 351.89597 -357.874265) (xy 351.924113 -357.871202)
			(xy 351.950334 -357.86053) (xy 351.972617 -357.843069) (xy 351.989249 -357.82016) (xy 351.998953 -357.793566)
			(xy 352.000981 -357.765329) (xy 351.998534 -357.75138) (xy 351.994727 -357.732111) (xy 351.990659 -357.693042)
			(xy 351.990406 -357.673402) (xy 351.990857 -357.646149) (xy 351.998614 -357.592196) (xy 352.013971 -357.539898)
			(xy 352.036614 -357.490317) (xy 352.066083 -357.444463) (xy 352.101778 -357.40327) (xy 352.142972 -357.367576)
			(xy 352.188827 -357.338108) (xy 352.238409 -357.315467) (xy 352.290708 -357.300112) (xy 352.344661 -357.292356)
			(xy 352.371914 -357.291894) (xy 352.399165 -357.292377) (xy 352.453111 -357.300135) (xy 352.505405 -357.315491)
			(xy 352.55498 -357.338133) (xy 352.600829 -357.3676) (xy 352.642018 -357.403292) (xy 352.677708 -357.444482)
			(xy 352.707173 -357.490332) (xy 352.729814 -357.539909) (xy 352.736121 -357.561388) (xy 360.900216 -357.561388)
			(xy 360.904287 -357.505766) (xy 360.916413 -357.451329) (xy 360.936336 -357.399238) (xy 360.963632 -357.350603)
			(xy 360.997718 -357.30646) (xy 361.037867 -357.267751) (xy 361.083225 -357.2353) (xy 361.132825 -357.209799)
			(xy 361.185609 -357.191792) (xy 361.240452 -357.181662) (xy 361.296186 -357.179625) (xy 361.351623 -357.185725)
			(xy 361.40558 -357.199831) (xy 361.456909 -357.221643) (xy 361.504515 -357.250697) (xy 361.547383 -357.286372)
			(xy 361.5846 -357.327909) (xy 361.615373 -357.374422) (xy 361.639045 -357.424919) (xy 361.655113 -357.478326)
			(xy 361.663233 -357.533502) (xy 361.663742 -357.561388) (xy 361.663233 -357.589274) (xy 361.655113 -357.64445)
			(xy 361.639045 -357.697857) (xy 361.615373 -357.748354) (xy 361.5846 -357.794867) (xy 361.547383 -357.836404)
			(xy 361.504515 -357.872079) (xy 361.456909 -357.901133) (xy 361.40558 -357.922945) (xy 361.351623 -357.937051)
			(xy 361.296186 -357.943151) (xy 361.240452 -357.941114) (xy 361.185609 -357.930984) (xy 361.132825 -357.912977)
			(xy 361.083225 -357.887476) (xy 361.037867 -357.855025) (xy 360.997718 -357.816316) (xy 360.963632 -357.772173)
			(xy 360.936336 -357.723538) (xy 360.916413 -357.671447) (xy 360.904287 -357.61701) (xy 360.900216 -357.561388)
			(xy 352.736121 -357.561388) (xy 352.745168 -357.592202) (xy 352.752924 -357.646149) (xy 352.752924 -357.700651)
			(xy 352.745168 -357.754598) (xy 352.729814 -357.806891) (xy 352.707173 -357.856468) (xy 352.677708 -357.902318)
			(xy 352.642018 -357.943508) (xy 352.600829 -357.9792) (xy 352.55498 -358.008667) (xy 352.505405 -358.031309)
			(xy 352.453111 -358.046665) (xy 352.399165 -358.054423) (xy 352.371914 -358.05491) (xy 352.355771 -358.05477)
			(xy 352.323597 -358.052097) (xy 352.307652 -358.049576) (xy 352.293627 -358.047643) (xy 352.265492 -358.050705)
			(xy 352.239279 -358.061372) (xy 352.217001 -358.078825) (xy 352.200612 -358.101389) (xy 369.986045 -358.101389)
			(xy 369.993796 -358.047437) (xy 370.009146 -357.995136) (xy 370.031783 -357.945553) (xy 370.061246 -357.899696)
			(xy 370.096935 -357.858499) (xy 370.138124 -357.8228) (xy 370.183974 -357.793326) (xy 370.233552 -357.770678)
			(xy 370.285848 -357.755315) (xy 370.339799 -357.747551) (xy 370.367052 -357.747062) (xy 370.380048 -357.747169)
			(xy 370.405979 -357.748949) (xy 370.418868 -357.750618) (xy 370.433246 -357.752024) (xy 370.461801 -357.747758)
			(xy 370.488017 -357.735664) (xy 370.509796 -357.71671) (xy 370.525393 -357.692414) (xy 370.533559 -357.664721)
			(xy 370.53364 -357.635849) (xy 370.53012 -357.62184) (xy 370.523261 -357.596222) (xy 370.515862 -357.543708)
			(xy 370.515388 -357.517192) (xy 370.515388 -357.51643) (xy 370.515823 -357.489174) (xy 370.523576 -357.435218)
			(xy 370.53893 -357.382913) (xy 370.561571 -357.333327) (xy 370.591039 -357.287467) (xy 370.626734 -357.246268)
			(xy 370.667928 -357.210568) (xy 370.713784 -357.181095) (xy 370.763368 -357.158447) (xy 370.81567 -357.143087)
			(xy 370.869626 -357.135326) (xy 370.924137 -357.135324) (xy 370.978093 -357.143079) (xy 371.030397 -357.158434)
			(xy 371.079983 -357.181077) (xy 371.125842 -357.210546) (xy 371.16704 -357.246242) (xy 371.202738 -357.287437)
			(xy 371.232211 -357.333294) (xy 371.254857 -357.382878) (xy 371.270216 -357.435181) (xy 371.277975 -357.489137)
			(xy 371.277976 -357.543648) (xy 371.270219 -357.597605) (xy 371.254862 -357.649908) (xy 371.232218 -357.699493)
			(xy 371.202747 -357.745351) (xy 371.16705 -357.786548) (xy 371.125854 -357.822245) (xy 371.079996 -357.851716)
			(xy 371.030411 -357.874361) (xy 370.978108 -357.889718) (xy 370.924152 -357.897475) (xy 370.896896 -357.897938)
			(xy 370.8839 -357.897826) (xy 370.857969 -357.896049) (xy 370.84508 -357.894382) (xy 370.830698 -357.893022)
			(xy 370.802146 -357.897276) (xy 370.77593 -357.909361) (xy 370.754151 -357.928308) (xy 370.738553 -357.952598)
			(xy 370.730387 -357.980286) (xy 370.730307 -358.009153) (xy 370.733828 -358.02316) (xy 370.740688 -358.048778)
			(xy 370.748086 -358.101292) (xy 370.74856 -358.127808) (xy 370.74856 -358.12857) (xy 370.748154 -358.155823)
			(xy 370.740402 -358.209775) (xy 370.72505 -358.262075) (xy 370.702411 -358.311657) (xy 370.672947 -358.357513)
			(xy 370.637256 -358.398709) (xy 370.596066 -358.434407) (xy 370.550215 -358.463879) (xy 370.500637 -358.486527)
			(xy 370.44834 -358.501888) (xy 370.394389 -358.50965) (xy 370.339883 -358.509655) (xy 370.285931 -358.501903)
			(xy 370.233631 -358.486552) (xy 370.184048 -358.463914) (xy 370.138191 -358.43445) (xy 370.096995 -358.39876)
			(xy 370.061297 -358.357571) (xy 370.031823 -358.311721) (xy 370.009176 -358.262142) (xy 369.993814 -358.209846)
			(xy 369.986051 -358.155895) (xy 369.986045 -358.101389) (xy 352.200612 -358.101389) (xy 352.200369 -358.101723)
			(xy 352.190662 -358.128307) (xy 352.188624 -358.156534) (xy 352.191066 -358.17048) (xy 352.194867 -358.18975)
			(xy 352.198939 -358.228818) (xy 352.199194 -358.248458) (xy 352.198706 -358.27571) (xy 352.190954 -358.329661)
			(xy 352.175603 -358.381959) (xy 352.152964 -358.43154) (xy 352.123499 -358.477394) (xy 352.087808 -358.518588)
			(xy 352.046617 -358.554282) (xy 352.01185 -358.576626) (xy 360.646216 -358.576626) (xy 360.650287 -358.521004)
			(xy 360.662413 -358.466567) (xy 360.682336 -358.414476) (xy 360.709632 -358.365841) (xy 360.743718 -358.321698)
			(xy 360.783867 -358.282989) (xy 360.829225 -358.250538) (xy 360.878825 -358.225037) (xy 360.931609 -358.20703)
			(xy 360.986452 -358.1969) (xy 361.042186 -358.194863) (xy 361.097623 -358.200963) (xy 361.15158 -358.215069)
			(xy 361.202909 -358.236881) (xy 361.250515 -358.265935) (xy 361.293383 -358.30161) (xy 361.3306 -358.343147)
			(xy 361.361373 -358.38966) (xy 361.385045 -358.440157) (xy 361.401113 -358.493564) (xy 361.409233 -358.54874)
			(xy 361.409742 -358.576626) (xy 361.409233 -358.604512) (xy 361.401113 -358.659688) (xy 361.385045 -358.713095)
			(xy 361.361373 -358.763592) (xy 361.3306 -358.810105) (xy 361.32291 -358.818688) (xy 366.653062 -358.818688)
			(xy 366.657133 -358.763066) (xy 366.669259 -358.708629) (xy 366.689182 -358.656538) (xy 366.716478 -358.607903)
			(xy 366.750564 -358.56376) (xy 366.790713 -358.525051) (xy 366.836071 -358.4926) (xy 366.885671 -358.467099)
			(xy 366.938455 -358.449092) (xy 366.993298 -358.438962) (xy 367.049032 -358.436925) (xy 367.104469 -358.443025)
			(xy 367.158426 -358.457131) (xy 367.209755 -358.478943) (xy 367.257361 -358.507997) (xy 367.300229 -358.543672)
			(xy 367.337446 -358.585209) (xy 367.368219 -358.631722) (xy 367.391891 -358.682219) (xy 367.407959 -358.735626)
			(xy 367.416079 -358.790802) (xy 367.416588 -358.818688) (xy 367.416079 -358.846574) (xy 367.407959 -358.90175)
			(xy 367.391891 -358.955157) (xy 367.387519 -358.964484) (xy 370.72773 -358.964484) (xy 370.731801 -358.908862)
			(xy 370.743927 -358.854425) (xy 370.76385 -358.802334) (xy 370.791146 -358.753699) (xy 370.825232 -358.709556)
			(xy 370.865381 -358.670847) (xy 370.910739 -358.638396) (xy 370.960339 -358.612895) (xy 371.013123 -358.594888)
			(xy 371.067966 -358.584758) (xy 371.1237 -358.582721) (xy 371.179137 -358.588821) (xy 371.233094 -358.602927)
			(xy 371.284423 -358.624739) (xy 371.332029 -358.653793) (xy 371.374897 -358.689468) (xy 371.412114 -358.731005)
			(xy 371.442887 -358.777518) (xy 371.466559 -358.828015) (xy 371.482627 -358.881422) (xy 371.490747 -358.936598)
			(xy 371.491256 -358.964484) (xy 371.490747 -358.99237) (xy 371.482627 -359.047546) (xy 371.466559 -359.100953)
			(xy 371.442887 -359.15145) (xy 371.412114 -359.197963) (xy 371.374897 -359.2395) (xy 371.332029 -359.275175)
			(xy 371.284423 -359.304229) (xy 371.233094 -359.326041) (xy 371.179137 -359.340147) (xy 371.1237 -359.346247)
			(xy 371.067966 -359.34421) (xy 371.013123 -359.33408) (xy 370.960339 -359.316073) (xy 370.910739 -359.290572)
			(xy 370.865381 -359.258121) (xy 370.825232 -359.219412) (xy 370.791146 -359.175269) (xy 370.76385 -359.126634)
			(xy 370.743927 -359.074543) (xy 370.731801 -359.020106) (xy 370.72773 -358.964484) (xy 367.387519 -358.964484)
			(xy 367.368219 -359.005654) (xy 367.337446 -359.052167) (xy 367.300229 -359.093704) (xy 367.257361 -359.129379)
			(xy 367.209755 -359.158433) (xy 367.158426 -359.180245) (xy 367.104469 -359.194351) (xy 367.049032 -359.200451)
			(xy 366.993298 -359.198414) (xy 366.938455 -359.188284) (xy 366.885671 -359.170277) (xy 366.836071 -359.144776)
			(xy 366.790713 -359.112325) (xy 366.750564 -359.073616) (xy 366.716478 -359.029473) (xy 366.689182 -358.980838)
			(xy 366.669259 -358.928747) (xy 366.657133 -358.87431) (xy 366.653062 -358.818688) (xy 361.32291 -358.818688)
			(xy 361.293383 -358.851642) (xy 361.250515 -358.887317) (xy 361.202909 -358.916371) (xy 361.15158 -358.938183)
			(xy 361.097623 -358.952289) (xy 361.042186 -358.958389) (xy 360.986452 -358.956352) (xy 360.931609 -358.946222)
			(xy 360.878825 -358.928215) (xy 360.829225 -358.902714) (xy 360.783867 -358.870263) (xy 360.743718 -358.831554)
			(xy 360.709632 -358.787411) (xy 360.682336 -358.738776) (xy 360.662413 -358.686685) (xy 360.650287 -358.632248)
			(xy 360.646216 -358.576626) (xy 352.01185 -358.576626) (xy 352.000765 -358.58375) (xy 351.951186 -358.606393)
			(xy 351.898889 -358.621748) (xy 351.844938 -358.629504) (xy 351.817686 -358.629966) (xy 351.790432 -358.629563)
			(xy 351.73648 -358.621804) (xy 351.684181 -358.606446) (xy 351.634601 -358.583802) (xy 351.588747 -358.554332)
			(xy 351.547554 -358.518636) (xy 351.51186 -358.477442) (xy 351.482392 -358.431587) (xy 351.459749 -358.382005)
			(xy 351.444393 -358.329706) (xy 351.436636 -358.275754) (xy 348.582877 -358.275754) (xy 348.579193 -358.300786)
			(xy 348.563125 -358.354193) (xy 348.539453 -358.40469) (xy 348.50868 -358.451203) (xy 348.471463 -358.49274)
			(xy 348.428595 -358.528415) (xy 348.380989 -358.557469) (xy 348.32966 -358.579281) (xy 348.275703 -358.593387)
			(xy 348.220266 -358.599487) (xy 348.164532 -358.59745) (xy 348.109689 -358.58732) (xy 348.056905 -358.569313)
			(xy 348.007305 -358.543812) (xy 347.961947 -358.511361) (xy 347.921798 -358.472652) (xy 347.887712 -358.428509)
			(xy 347.860416 -358.379874) (xy 347.840493 -358.327783) (xy 347.828367 -358.273346) (xy 347.824296 -358.217724)
			(xy 343.695667 -358.217724) (xy 343.705414 -358.225558) (xy 343.742548 -358.263913) (xy 343.773972 -358.307071)
			(xy 343.799073 -358.354188) (xy 343.81736 -358.404344) (xy 343.828477 -358.456559) (xy 343.832205 -358.509815)
			(xy 343.828473 -358.56307) (xy 343.817352 -358.615285) (xy 343.799061 -358.665439) (xy 343.773957 -358.712554)
			(xy 343.742529 -358.755709) (xy 343.705392 -358.794062) (xy 343.684606 -358.810814) (xy 343.672777 -358.820686)
			(xy 343.655261 -358.846017) (xy 343.646089 -358.875416) (xy 343.646093 -358.906213) (xy 343.655274 -358.93561)
			(xy 343.672798 -358.960936) (xy 343.684606 -358.970834) (xy 343.705414 -358.987558) (xy 343.742548 -359.025913)
			(xy 343.773972 -359.069071) (xy 343.799073 -359.116188) (xy 343.81736 -359.166344) (xy 343.828477 -359.218559)
			(xy 343.832205 -359.271815) (xy 343.828473 -359.32507) (xy 343.822394 -359.353612) (xy 346.946726 -359.353612)
			(xy 346.950797 -359.29799) (xy 346.962923 -359.243553) (xy 346.982846 -359.191462) (xy 347.010142 -359.142827)
			(xy 347.044228 -359.098684) (xy 347.084377 -359.059975) (xy 347.129735 -359.027524) (xy 347.179335 -359.002023)
			(xy 347.232119 -358.984016) (xy 347.286962 -358.973886) (xy 347.342696 -358.971849) (xy 347.398133 -358.977949)
			(xy 347.45209 -358.992055) (xy 347.503419 -359.013867) (xy 347.551025 -359.042921) (xy 347.593893 -359.078596)
			(xy 347.63111 -359.120133) (xy 347.661883 -359.166646) (xy 347.685555 -359.217143) (xy 347.701623 -359.27055)
			(xy 347.709743 -359.325726) (xy 347.710252 -359.353612) (xy 347.709743 -359.381498) (xy 347.701623 -359.436674)
			(xy 347.687334 -359.484168) (xy 349.7359 -359.484168) (xy 349.739971 -359.428546) (xy 349.752097 -359.374109)
			(xy 349.77202 -359.322018) (xy 349.799316 -359.273383) (xy 349.833402 -359.22924) (xy 349.873551 -359.190531)
			(xy 349.918909 -359.15808) (xy 349.968509 -359.132579) (xy 350.021293 -359.114572) (xy 350.076136 -359.104442)
			(xy 350.13187 -359.102405) (xy 350.187307 -359.108505) (xy 350.241264 -359.122611) (xy 350.292593 -359.144423)
			(xy 350.307817 -359.153714) (xy 351.933254 -359.153714) (xy 351.937325 -359.098092) (xy 351.949451 -359.043655)
			(xy 351.969374 -358.991564) (xy 351.99667 -358.942929) (xy 352.030756 -358.898786) (xy 352.070905 -358.860077)
			(xy 352.116263 -358.827626) (xy 352.165863 -358.802125) (xy 352.218647 -358.784118) (xy 352.27349 -358.773988)
			(xy 352.329224 -358.771951) (xy 352.384661 -358.778051) (xy 352.438618 -358.792157) (xy 352.489947 -358.813969)
			(xy 352.537553 -358.843023) (xy 352.580421 -358.878698) (xy 352.617638 -358.920235) (xy 352.648411 -358.966748)
			(xy 352.672083 -359.017245) (xy 352.688151 -359.070652) (xy 352.696271 -359.125828) (xy 352.69678 -359.153714)
			(xy 352.696271 -359.1816) (xy 352.688151 -359.236776) (xy 352.672083 -359.290183) (xy 352.648411 -359.34068)
			(xy 352.617638 -359.387193) (xy 352.580421 -359.42873) (xy 352.537553 -359.464405) (xy 352.489947 -359.493459)
			(xy 352.438618 -359.515271) (xy 352.384661 -359.529377) (xy 352.329224 -359.535477) (xy 352.27349 -359.53344)
			(xy 352.218647 -359.52331) (xy 352.165863 -359.505303) (xy 352.116263 -359.479802) (xy 352.070905 -359.447351)
			(xy 352.030756 -359.408642) (xy 351.99667 -359.364499) (xy 351.969374 -359.315864) (xy 351.949451 -359.263773)
			(xy 351.937325 -359.209336) (xy 351.933254 -359.153714) (xy 350.307817 -359.153714) (xy 350.340199 -359.173477)
			(xy 350.383067 -359.209152) (xy 350.420284 -359.250689) (xy 350.451057 -359.297202) (xy 350.474729 -359.347699)
			(xy 350.490797 -359.401106) (xy 350.498917 -359.456282) (xy 350.499426 -359.484168) (xy 350.498917 -359.512054)
			(xy 350.490797 -359.56723) (xy 350.482239 -359.595674) (xy 360.673902 -359.595674) (xy 360.677973 -359.540052)
			(xy 360.690099 -359.485615) (xy 360.710022 -359.433524) (xy 360.737318 -359.384889) (xy 360.771404 -359.340746)
			(xy 360.811553 -359.302037) (xy 360.856911 -359.269586) (xy 360.906511 -359.244085) (xy 360.959295 -359.226078)
			(xy 361.014138 -359.215948) (xy 361.069872 -359.213911) (xy 361.125309 -359.220011) (xy 361.179266 -359.234117)
			(xy 361.230595 -359.255929) (xy 361.278201 -359.284983) (xy 361.321069 -359.320658) (xy 361.358286 -359.362195)
			(xy 361.389059 -359.408708) (xy 361.412731 -359.459205) (xy 361.412982 -359.460038) (xy 363.93323 -359.460038)
			(xy 363.937301 -359.404416) (xy 363.949427 -359.349979) (xy 363.96935 -359.297888) (xy 363.996646 -359.249253)
			(xy 364.030732 -359.20511) (xy 364.070881 -359.166401) (xy 364.116239 -359.13395) (xy 364.165839 -359.108449)
			(xy 364.218623 -359.090442) (xy 364.273466 -359.080312) (xy 364.3292 -359.078275) (xy 364.384637 -359.084375)
			(xy 364.438594 -359.098481) (xy 364.489923 -359.120293) (xy 364.537529 -359.149347) (xy 364.580397 -359.185022)
			(xy 364.617614 -359.226559) (xy 364.648387 -359.273072) (xy 364.672059 -359.323569) (xy 364.688127 -359.376976)
			(xy 364.696247 -359.432152) (xy 364.696756 -359.460038) (xy 364.696247 -359.487924) (xy 364.688127 -359.5431)
			(xy 364.672059 -359.596507) (xy 364.648387 -359.647004) (xy 364.617614 -359.693517) (xy 364.580397 -359.735054)
			(xy 364.537529 -359.770729) (xy 364.489923 -359.799783) (xy 364.438594 -359.821595) (xy 364.384637 -359.835701)
			(xy 364.3292 -359.841801) (xy 364.273466 -359.839764) (xy 364.218623 -359.829634) (xy 364.165839 -359.811627)
			(xy 364.116239 -359.786126) (xy 364.070881 -359.753675) (xy 364.030732 -359.714966) (xy 363.996646 -359.670823)
			(xy 363.96935 -359.622188) (xy 363.949427 -359.570097) (xy 363.937301 -359.51566) (xy 363.93323 -359.460038)
			(xy 361.412982 -359.460038) (xy 361.428799 -359.512612) (xy 361.436919 -359.567788) (xy 361.437428 -359.595674)
			(xy 361.436919 -359.62356) (xy 361.428799 -359.678736) (xy 361.412731 -359.732143) (xy 361.389059 -359.78264)
			(xy 361.358286 -359.829153) (xy 361.321069 -359.87069) (xy 361.278201 -359.906365) (xy 361.230595 -359.935419)
			(xy 361.179266 -359.957231) (xy 361.125309 -359.971337) (xy 361.069872 -359.977437) (xy 361.014138 -359.9754)
			(xy 360.959295 -359.96527) (xy 360.906511 -359.947263) (xy 360.856911 -359.921762) (xy 360.811553 -359.889311)
			(xy 360.771404 -359.850602) (xy 360.737318 -359.806459) (xy 360.710022 -359.757824) (xy 360.690099 -359.705733)
			(xy 360.677973 -359.651296) (xy 360.673902 -359.595674) (xy 350.482239 -359.595674) (xy 350.474729 -359.620637)
			(xy 350.451057 -359.671134) (xy 350.420284 -359.717647) (xy 350.383067 -359.759184) (xy 350.340199 -359.794859)
			(xy 350.292593 -359.823913) (xy 350.241264 -359.845725) (xy 350.187307 -359.859831) (xy 350.13187 -359.865931)
			(xy 350.076136 -359.863894) (xy 350.021293 -359.853764) (xy 349.968509 -359.835757) (xy 349.918909 -359.810256)
			(xy 349.873551 -359.777805) (xy 349.833402 -359.739096) (xy 349.799316 -359.694953) (xy 349.77202 -359.646318)
			(xy 349.752097 -359.594227) (xy 349.739971 -359.53979) (xy 349.7359 -359.484168) (xy 347.687334 -359.484168)
			(xy 347.685555 -359.490081) (xy 347.661883 -359.540578) (xy 347.63111 -359.587091) (xy 347.593893 -359.628628)
			(xy 347.551025 -359.664303) (xy 347.503419 -359.693357) (xy 347.45209 -359.715169) (xy 347.398133 -359.729275)
			(xy 347.342696 -359.735375) (xy 347.286962 -359.733338) (xy 347.232119 -359.723208) (xy 347.179335 -359.705201)
			(xy 347.129735 -359.6797) (xy 347.084377 -359.647249) (xy 347.044228 -359.60854) (xy 347.010142 -359.564397)
			(xy 346.982846 -359.515762) (xy 346.962923 -359.463671) (xy 346.950797 -359.409234) (xy 346.946726 -359.353612)
			(xy 343.822394 -359.353612) (xy 343.817352 -359.377285) (xy 343.799061 -359.427439) (xy 343.773957 -359.474554)
			(xy 343.742529 -359.517709) (xy 343.705392 -359.556062) (xy 343.684606 -359.572814) (xy 343.672777 -359.582686)
			(xy 343.655261 -359.608017) (xy 343.646089 -359.637416) (xy 343.646093 -359.668213) (xy 343.655274 -359.69761)
			(xy 343.672798 -359.722936) (xy 343.684606 -359.732834) (xy 343.705414 -359.749558) (xy 343.742548 -359.787913)
			(xy 343.773972 -359.831071) (xy 343.799073 -359.878188) (xy 343.81736 -359.928344) (xy 343.828477 -359.980559)
			(xy 343.832205 -360.033815) (xy 343.828473 -360.08707) (xy 343.817352 -360.139285) (xy 343.799061 -360.189439)
			(xy 343.773957 -360.236554) (xy 343.742529 -360.279709) (xy 343.705392 -360.318062) (xy 343.684606 -360.334814)
			(xy 343.672777 -360.344686) (xy 343.655261 -360.370017) (xy 343.646089 -360.399416) (xy 343.646093 -360.430213)
			(xy 343.655274 -360.45961) (xy 343.672798 -360.484936) (xy 343.684606 -360.494834) (xy 343.707107 -360.513004)
			(xy 343.746841 -360.555029) (xy 343.779778 -360.602568) (xy 343.805163 -360.654533) (xy 343.822415 -360.709734)
			(xy 343.83114 -360.766907) (xy 343.831672 -360.795824) (xy 343.831267 -360.823079) (xy 343.823506 -360.877034)
			(xy 343.808145 -360.929335) (xy 343.785497 -360.978918) (xy 343.756023 -361.024773) (xy 343.720324 -361.065966)
			(xy 343.679125 -361.101659) (xy 343.633265 -361.131126) (xy 343.583679 -361.153766) (xy 343.531375 -361.169119)
			(xy 343.477419 -361.176872) (xy 343.450164 -361.177332) (xy 343.422456 -361.176856) (xy 343.367623 -361.168847)
			(xy 343.314525 -361.152987) (xy 343.264282 -361.129612) (xy 343.217949 -361.099212) (xy 343.176503 -361.062427)
			(xy 343.140816 -361.020033) (xy 343.125806 -360.996738) (xy 343.113614 -360.976926) (xy 343.037414 -360.964734)
			(xy 343.025147 -360.972677) (xy 343.005341 -360.994147) (xy 342.992406 -361.020336) (xy 342.987396 -361.049113)
			(xy 342.990719 -361.078133) (xy 343.002104 -361.105032) (xy 343.010998 -361.116626) (xy 343.027386 -361.137204)
			(xy 343.054961 -361.182004) (xy 343.076115 -361.23017) (xy 343.090444 -361.280787) (xy 343.097678 -361.332893)
			(xy 343.09812 -361.359196) (xy 343.097619 -361.386447) (xy 343.089863 -361.440393) (xy 343.074509 -361.492687)
			(xy 343.051869 -361.542263) (xy 343.022404 -361.588113) (xy 342.986714 -361.629303) (xy 342.945526 -361.664995)
			(xy 342.899677 -361.694461) (xy 342.850102 -361.717103) (xy 342.797809 -361.732459) (xy 342.743863 -361.740217)
			(xy 342.716612 -361.740704) (xy 342.687694 -361.740214) (xy 342.630519 -361.731484) (xy 342.575318 -361.714223)
			(xy 342.523356 -361.688826) (xy 342.475823 -361.655876) (xy 342.43381 -361.616127) (xy 342.415622 -361.593638)
			(xy 342.405725 -361.581833) (xy 342.380401 -361.564314) (xy 342.351008 -361.555138) (xy 342.320216 -361.555138)
			(xy 342.290823 -361.564314) (xy 342.265499 -361.581833) (xy 342.255602 -361.593638) (xy 342.248333 -361.602813)
			(xy 342.232828 -361.620351) (xy 342.224614 -361.62869) (xy 342.214238 -361.639813) (xy 342.200039 -361.666701)
			(xy 342.19437 -361.696575) (xy 342.197731 -361.726795) (xy 342.209827 -361.754692) (xy 342.21928 -361.766612)
			(xy 342.236469 -361.78743) (xy 342.265387 -361.833019) (xy 342.287596 -361.882227) (xy 342.302652 -361.934073)
			(xy 342.310254 -361.987522) (xy 342.31072 -362.014516) (xy 342.310237 -362.041767) (xy 342.302479 -362.095714)
			(xy 342.287122 -362.148008) (xy 342.26448 -362.197585) (xy 342.235013 -362.243435) (xy 342.199322 -362.284624)
			(xy 342.158131 -362.320316) (xy 342.112281 -362.349782) (xy 342.062705 -362.372424) (xy 342.01041 -362.38778)
			(xy 341.956463 -362.395537) (xy 341.929212 -362.396024) (xy 341.901243 -362.395556) (xy 341.845902 -362.3874)
			(xy 341.792347 -362.371247) (xy 341.741726 -362.347444) (xy 341.695126 -362.3165) (xy 341.653546 -362.279081)
			(xy 341.635334 -362.257848) (xy 341.625758 -362.247132) (xy 341.601994 -362.231) (xy 341.574677 -362.222124)
			(xy 341.545969 -362.221208) (xy 341.518142 -362.228325) (xy 341.493398 -362.24291) (xy 341.483188 -362.253022)
			(xy 341.465075 -362.271613) (xy 341.424725 -362.30426) (xy 341.38032 -362.331132) (xy 341.33268 -362.351734)
			(xy 341.282687 -362.365685) (xy 341.231264 -362.372726) (xy 341.205312 -362.373164) (xy 341.176395 -362.372651)
			(xy 341.119223 -362.363923) (xy 341.064023 -362.346664) (xy 341.012061 -362.321272) (xy 340.964528 -362.288327)
			(xy 340.922511 -362.248584) (xy 340.904322 -362.226098) (xy 340.894425 -362.214293) (xy 340.869101 -362.196774)
			(xy 340.839708 -362.187598) (xy 340.808916 -362.187598) (xy 340.779523 -362.196774) (xy 340.754199 -362.214293)
			(xy 340.744302 -362.226098) (xy 340.727549 -362.246881) (xy 340.689195 -362.284011) (xy 340.646041 -362.315433)
			(xy 340.598927 -362.340532) (xy 340.548775 -362.358818) (xy 340.496564 -362.369935) (xy 340.443312 -362.373665)
			(xy 340.39006 -362.369935) (xy 340.337849 -362.358818) (xy 340.287697 -362.340532) (xy 340.240583 -362.315433)
			(xy 340.197429 -362.284011) (xy 340.159075 -362.246881) (xy 340.142322 -362.226098) (xy 340.132425 -362.214293)
			(xy 340.107101 -362.196774) (xy 340.077708 -362.187598) (xy 340.046916 -362.187598) (xy 340.017523 -362.196774)
			(xy 339.992199 -362.214293) (xy 339.982302 -362.226098) (xy 339.964109 -362.24858) (xy 339.92209 -362.288315)
			(xy 339.874555 -362.321255) (xy 339.822594 -362.346643) (xy 339.767397 -362.3639) (xy 339.710228 -362.372629)
			(xy 339.681312 -362.373164) (xy 339.654097 -362.372702) (xy 339.600221 -362.364968) (xy 339.54799 -362.349654)
			(xy 339.498466 -362.327072) (xy 339.452655 -362.297681) (xy 339.411486 -362.262076) (xy 339.393276 -362.241846)
			(xy 339.383459 -362.231266) (xy 339.359238 -362.215595) (xy 339.331598 -362.207332) (xy 339.302751 -362.207139)
			(xy 339.275003 -362.215032) (xy 339.250575 -362.230378) (xy 339.240622 -362.24083) (xy 339.222462 -362.260636)
			(xy 339.18151 -362.295429) (xy 339.13608 -362.324127) (xy 339.08707 -362.346163) (xy 339.035452 -362.3611)
			(xy 338.982248 -362.368642) (xy 338.95538 -362.3691) (xy 338.926465 -362.368524) (xy 338.869297 -362.359807)
			(xy 338.814099 -362.342561) (xy 338.762137 -362.31718) (xy 338.714602 -362.284246) (xy 338.672582 -362.244515)
			(xy 338.65439 -362.222034) (xy 338.644493 -362.210229) (xy 338.619169 -362.19271) (xy 338.589776 -362.183534)
			(xy 338.558984 -362.183534) (xy 338.529591 -362.19271) (xy 338.504267 -362.210229) (xy 338.49437 -362.222034)
			(xy 338.476205 -362.244539) (xy 338.434178 -362.284271) (xy 338.386638 -362.317207) (xy 338.334672 -362.342591)
			(xy 338.27947 -362.359843) (xy 338.222297 -362.368567) (xy 338.19338 -362.3691) (xy 338.167312 -362.36863)
			(xy 338.115662 -362.361521) (xy 338.06546 -362.347451) (xy 338.017638 -362.326681) (xy 337.973087 -362.299599)
			(xy 337.932635 -362.266708) (xy 337.897034 -362.228618) (xy 337.866946 -362.18604) (xy 337.854544 -362.163106)
			(xy 337.847731 -362.150989) (xy 337.828764 -362.130684) (xy 337.805023 -362.116248) (xy 337.778267 -362.108752)
			(xy 337.750481 -362.108752) (xy 337.723725 -362.116248) (xy 337.699984 -362.130684) (xy 337.681017 -362.150989)
			(xy 337.674204 -362.163106) (xy 337.661804 -362.186044) (xy 337.63173 -362.228638) (xy 337.596136 -362.266741)
			(xy 337.555686 -362.299643) (xy 337.511132 -362.326731) (xy 337.463305 -362.347499) (xy 337.413096 -362.361562)
			(xy 337.361439 -362.368658) (xy 337.335368 -362.3691) (xy 337.30799 -362.368598) (xy 337.253798 -362.360767)
			(xy 337.201281 -362.345269) (xy 337.151519 -362.322425) (xy 337.105533 -362.292702) (xy 337.064268 -362.256711)
			(xy 337.046062 -362.236258) (xy 337.035978 -362.225304) (xy 337.010922 -362.209248) (xy 336.982304 -362.201091)
			(xy 336.952548 -362.201525) (xy 336.924179 -362.210513) (xy 336.899603 -362.227293) (xy 336.889852 -362.238544)
			(xy 336.871595 -362.260307) (xy 336.829807 -362.298779) (xy 336.782778 -362.330632) (xy 336.731546 -362.355162)
			(xy 336.677245 -362.371826) (xy 336.621073 -362.380257) (xy 336.592672 -362.380784) (xy 336.563618 -362.380272)
			(xy 336.50618 -362.371469) (xy 336.450742 -362.354055) (xy 336.398587 -362.328433) (xy 336.350922 -362.295197)
			(xy 336.30885 -362.255115) (xy 336.290666 -362.232448) (xy 336.281394 -362.221386) (xy 336.258079 -362.204404)
			(xy 336.230941 -362.19463) (xy 336.202152 -362.192845) (xy 336.174014 -362.199193) (xy 336.14878 -362.213165)
			(xy 336.138266 -362.22305) (xy 336.116651 -362.244093) (xy 336.067986 -362.279738) (xy 336.014317 -362.307277)
			(xy 335.956981 -362.326024) (xy 335.897409 -362.335512) (xy 335.867248 -362.33608) (xy 335.839995 -362.3356)
			(xy 335.786043 -362.327849) (xy 335.733744 -362.312497) (xy 335.684162 -362.289858) (xy 335.638307 -362.260393)
			(xy 335.597114 -362.224701) (xy 335.561419 -362.183509) (xy 335.531951 -362.137655) (xy 335.50931 -362.088075)
			(xy 335.493955 -362.035776) (xy 335.486201 -361.981825) (xy 335.48574 -361.954572) (xy 335.486232 -361.926969)
			(xy 335.494193 -361.872338) (xy 335.509943 -361.819426) (xy 335.533154 -361.769336) (xy 335.563343 -361.723113)
			(xy 335.581244 -361.702096) (xy 335.590775 -361.690438) (xy 335.603212 -361.663031) (xy 335.607139 -361.633191)
			(xy 335.602218 -361.6035) (xy 335.588874 -361.576523) (xy 335.578958 -361.56519) (xy 335.559564 -361.54383)
			(xy 335.526755 -361.496377) (xy 335.501471 -361.444522) (xy 335.484288 -361.389449) (xy 335.4756 -361.332416)
			(xy 335.475072 -361.30357) (xy 335.475072 -361.303316) (xy 335.475523 -361.275711) (xy 335.483492 -361.221079)
			(xy 335.499252 -361.168165) (xy 335.522473 -361.118076) (xy 335.55267 -361.071856) (xy 335.570576 -361.05084)
			(xy 335.580061 -361.039148) (xy 335.592499 -361.011753) (xy 335.596433 -360.981925) (xy 335.591524 -360.952241)
			(xy 335.578196 -360.925268) (xy 335.56829 -360.913934) (xy 335.548875 -360.892593) (xy 335.516067 -360.845135)
			(xy 335.490786 -360.793275) (xy 335.473609 -360.738198) (xy 335.464928 -360.681161) (xy 335.464404 -360.652314)
			(xy 335.464404 -360.65206) (xy 335.464898 -360.624457) (xy 335.472859 -360.569827) (xy 335.48861 -360.516915)
			(xy 335.511821 -360.466825) (xy 335.542007 -360.420602) (xy 335.559908 -360.399584) (xy 335.569445 -360.387932)
			(xy 335.581872 -360.360522) (xy 335.585794 -360.330682) (xy 335.580873 -360.300991) (xy 335.567534 -360.274013)
			(xy 335.557622 -360.262678) (xy 335.538216 -360.241329) (xy 335.50541 -360.193872) (xy 335.480129 -360.142014)
			(xy 335.462949 -360.086939) (xy 335.454263 -360.029904) (xy 335.453736 -360.001058) (xy 335.453736 -360.000804)
			(xy 335.454244 -359.971887) (xy 335.462973 -359.914714) (xy 335.480232 -359.859515) (xy 335.505626 -359.807553)
			(xy 335.538572 -359.760019) (xy 335.578315 -359.718003) (xy 335.600802 -359.699814) (xy 335.612602 -359.689911)
			(xy 335.630117 -359.664589) (xy 335.639292 -359.635197) (xy 335.639292 -359.604407) (xy 335.630119 -359.575016)
			(xy 335.612605 -359.549692) (xy 335.600802 -359.539794) (xy 335.580021 -359.523037) (xy 335.542887 -359.484686)
			(xy 335.511462 -359.441533) (xy 335.48636 -359.39442) (xy 335.468071 -359.344267) (xy 335.456953 -359.292055)
			(xy 335.453223 -359.238802) (xy 322.538698 -359.238802) (xy 322.654676 -359.76052) (xy 325.767954 -362.873798)
			(xy 346.387672 -362.873798) (xy 346.391743 -362.818176) (xy 346.403869 -362.763739) (xy 346.423792 -362.711648)
			(xy 346.451088 -362.663013) (xy 346.485174 -362.61887) (xy 346.525323 -362.580161) (xy 346.570681 -362.54771)
			(xy 346.620281 -362.522209) (xy 346.673065 -362.504202) (xy 346.727908 -362.494072) (xy 346.783642 -362.492035)
			(xy 346.839079 -362.498135) (xy 346.893036 -362.512241) (xy 346.944365 -362.534053) (xy 346.991971 -362.563107)
			(xy 347.034839 -362.598782) (xy 347.072056 -362.640319) (xy 347.102829 -362.686832) (xy 347.126501 -362.737329)
			(xy 347.142569 -362.790736) (xy 347.150689 -362.845912) (xy 347.151198 -362.873798) (xy 347.150689 -362.901684)
			(xy 347.142569 -362.95686) (xy 347.126501 -363.010267) (xy 347.102829 -363.060764) (xy 347.072056 -363.107277)
			(xy 347.034839 -363.148814) (xy 346.991971 -363.184489) (xy 346.944365 -363.213543) (xy 346.893036 -363.235355)
			(xy 346.839079 -363.249461) (xy 346.783642 -363.255561) (xy 346.727908 -363.253524) (xy 346.673065 -363.243394)
			(xy 346.620281 -363.225387) (xy 346.570681 -363.199886) (xy 346.525323 -363.167435) (xy 346.485174 -363.128726)
			(xy 346.451088 -363.084583) (xy 346.423792 -363.035948) (xy 346.403869 -362.983857) (xy 346.391743 -362.92942)
			(xy 346.387672 -362.873798) (xy 325.767954 -362.873798) (xy 326.488044 -363.593888) (xy 346.993462 -363.593888)
			(xy 346.997533 -363.538266) (xy 347.009659 -363.483829) (xy 347.029582 -363.431738) (xy 347.056878 -363.383103)
			(xy 347.090964 -363.33896) (xy 347.131113 -363.300251) (xy 347.176471 -363.2678) (xy 347.226071 -363.242299)
			(xy 347.278855 -363.224292) (xy 347.333698 -363.214162) (xy 347.389432 -363.212125) (xy 347.444869 -363.218225)
			(xy 347.498826 -363.232331) (xy 347.550155 -363.254143) (xy 347.597761 -363.283197) (xy 347.640629 -363.318872)
			(xy 347.677846 -363.360409) (xy 347.708619 -363.406922) (xy 347.732291 -363.457419) (xy 347.748359 -363.510826)
			(xy 347.756479 -363.566002) (xy 347.756988 -363.593888) (xy 347.756479 -363.621774) (xy 347.748359 -363.67695)
			(xy 347.732291 -363.730357) (xy 347.708619 -363.780854) (xy 347.677846 -363.827367) (xy 347.640629 -363.868904)
			(xy 347.597761 -363.904579) (xy 347.550155 -363.933633) (xy 347.498826 -363.955445) (xy 347.444869 -363.969551)
			(xy 347.389432 -363.975651) (xy 347.333698 -363.973614) (xy 347.278855 -363.963484) (xy 347.226071 -363.945477)
			(xy 347.176471 -363.919976) (xy 347.131113 -363.887525) (xy 347.090964 -363.848816) (xy 347.056878 -363.804673)
			(xy 347.029582 -363.756038) (xy 347.009659 -363.703947) (xy 346.997533 -363.64951) (xy 346.993462 -363.593888)
			(xy 326.488044 -363.593888) (xy 327.057766 -364.16361) (xy 347.661482 -364.16361) (xy 347.665553 -364.107988)
			(xy 347.677679 -364.053551) (xy 347.697602 -364.00146) (xy 347.724898 -363.952825) (xy 347.758984 -363.908682)
			(xy 347.799133 -363.869973) (xy 347.844491 -363.837522) (xy 347.894091 -363.812021) (xy 347.946875 -363.794014)
			(xy 348.001718 -363.783884) (xy 348.057452 -363.781847) (xy 348.112889 -363.787947) (xy 348.166846 -363.802053)
			(xy 348.218175 -363.823865) (xy 348.265781 -363.852919) (xy 348.308649 -363.888594) (xy 348.345866 -363.930131)
			(xy 348.376639 -363.976644) (xy 348.400311 -364.027141) (xy 348.416379 -364.080548) (xy 348.424499 -364.135724)
			(xy 348.425008 -364.16361) (xy 348.424499 -364.191496) (xy 348.416379 -364.246672) (xy 348.400311 -364.300079)
			(xy 348.376639 -364.350576) (xy 348.345866 -364.397089) (xy 348.308649 -364.438626) (xy 348.265781 -364.474301)
			(xy 348.218175 -364.503355) (xy 348.166846 -364.525167) (xy 348.112889 -364.539273) (xy 348.057452 -364.545373)
			(xy 348.001718 -364.543336) (xy 347.946875 -364.533206) (xy 347.894091 -364.515199) (xy 347.844491 -364.489698)
			(xy 347.799133 -364.457247) (xy 347.758984 -364.418538) (xy 347.724898 -364.374395) (xy 347.697602 -364.32576)
			(xy 347.677679 -364.273669) (xy 347.665553 -364.219232) (xy 347.661482 -364.16361) (xy 327.057766 -364.16361)
			(xy 329.993244 -367.099088) (xy 345.670122 -367.099088) (xy 345.674193 -367.043466) (xy 345.686319 -366.989029)
			(xy 345.706242 -366.936938) (xy 345.733538 -366.888303) (xy 345.767624 -366.84416) (xy 345.807773 -366.805451)
			(xy 345.853131 -366.773) (xy 345.902731 -366.747499) (xy 345.955515 -366.729492) (xy 346.010358 -366.719362)
			(xy 346.066092 -366.717325) (xy 346.121529 -366.723425) (xy 346.175486 -366.737531) (xy 346.226815 -366.759343)
			(xy 346.274421 -366.788397) (xy 346.317289 -366.824072) (xy 346.354506 -366.865609) (xy 346.385279 -366.912122)
			(xy 346.408951 -366.962619) (xy 346.425019 -367.016026) (xy 346.433139 -367.071202) (xy 346.433648 -367.099088)
			(xy 346.433139 -367.126974) (xy 346.425019 -367.18215) (xy 346.408951 -367.235557) (xy 346.385279 -367.286054)
			(xy 346.354506 -367.332567) (xy 346.317289 -367.374104) (xy 346.274421 -367.409779) (xy 346.226815 -367.438833)
			(xy 346.175486 -367.460645) (xy 346.121529 -367.474751) (xy 346.066092 -367.480851) (xy 346.010358 -367.478814)
			(xy 345.955515 -367.468684) (xy 345.902731 -367.450677) (xy 345.853131 -367.425176) (xy 345.807773 -367.392725)
			(xy 345.767624 -367.354016) (xy 345.733538 -367.309873) (xy 345.706242 -367.261238) (xy 345.686319 -367.209147)
			(xy 345.674193 -367.15471) (xy 345.670122 -367.099088) (xy 329.993244 -367.099088) (xy 330.99883 -368.104674)
			(xy 346.277182 -368.104674) (xy 346.281253 -368.049052) (xy 346.293379 -367.994615) (xy 346.313302 -367.942524)
			(xy 346.340598 -367.893889) (xy 346.374684 -367.849746) (xy 346.414833 -367.811037) (xy 346.460191 -367.778586)
			(xy 346.509791 -367.753085) (xy 346.562575 -367.735078) (xy 346.617418 -367.724948) (xy 346.673152 -367.722911)
			(xy 346.728589 -367.729011) (xy 346.782546 -367.743117) (xy 346.833875 -367.764929) (xy 346.881481 -367.793983)
			(xy 346.924349 -367.829658) (xy 346.961566 -367.871195) (xy 346.992339 -367.917708) (xy 347.016011 -367.968205)
			(xy 347.032079 -368.021612) (xy 347.040199 -368.076788) (xy 347.040708 -368.104674) (xy 347.040569 -368.112294)
			(xy 347.30385 -368.112294) (xy 347.307921 -368.056672) (xy 347.320047 -368.002235) (xy 347.33997 -367.950144)
			(xy 347.367266 -367.901509) (xy 347.401352 -367.857366) (xy 347.441501 -367.818657) (xy 347.486859 -367.786206)
			(xy 347.536459 -367.760705) (xy 347.589243 -367.742698) (xy 347.644086 -367.732568) (xy 347.69982 -367.730531)
			(xy 347.755257 -367.736631) (xy 347.809214 -367.750737) (xy 347.860543 -367.772549) (xy 347.908149 -367.801603)
			(xy 347.951017 -367.837278) (xy 347.988234 -367.878815) (xy 348.019007 -367.925328) (xy 348.042679 -367.975825)
			(xy 348.058747 -368.029232) (xy 348.066867 -368.084408) (xy 348.067376 -368.112294) (xy 348.066867 -368.14018)
			(xy 348.058747 -368.195356) (xy 348.042679 -368.248763) (xy 348.019007 -368.29926) (xy 347.988234 -368.345773)
			(xy 347.951017 -368.38731) (xy 347.908149 -368.422985) (xy 347.860543 -368.452039) (xy 347.809214 -368.473851)
			(xy 347.755257 -368.487957) (xy 347.69982 -368.494057) (xy 347.644086 -368.49202) (xy 347.589243 -368.48189)
			(xy 347.536459 -368.463883) (xy 347.486859 -368.438382) (xy 347.441501 -368.405931) (xy 347.401352 -368.367222)
			(xy 347.367266 -368.323079) (xy 347.33997 -368.274444) (xy 347.320047 -368.222353) (xy 347.307921 -368.167916)
			(xy 347.30385 -368.112294) (xy 347.040569 -368.112294) (xy 347.040199 -368.13256) (xy 347.032079 -368.187736)
			(xy 347.016011 -368.241143) (xy 346.992339 -368.29164) (xy 346.961566 -368.338153) (xy 346.924349 -368.37969)
			(xy 346.881481 -368.415365) (xy 346.833875 -368.444419) (xy 346.782546 -368.466231) (xy 346.728589 -368.480337)
			(xy 346.673152 -368.486437) (xy 346.617418 -368.4844) (xy 346.562575 -368.47427) (xy 346.509791 -368.456263)
			(xy 346.460191 -368.430762) (xy 346.414833 -368.398311) (xy 346.374684 -368.359602) (xy 346.340598 -368.315459)
			(xy 346.313302 -368.266824) (xy 346.293379 -368.214733) (xy 346.281253 -368.160296) (xy 346.277182 -368.104674)
			(xy 330.99883 -368.104674) (xy 332.535088 -369.640932) (xy 346.293341 -369.640932) (xy 346.293345 -369.586423)
			(xy 346.301105 -369.532469) (xy 346.316466 -369.480169) (xy 346.339113 -369.430588) (xy 346.368587 -369.384734)
			(xy 346.404286 -369.343541) (xy 346.445484 -369.307849) (xy 346.491343 -369.278383) (xy 346.540928 -369.255744)
			(xy 346.59323 -369.240392) (xy 346.647185 -369.23264) (xy 346.67444 -369.23218) (xy 346.695505 -369.232424)
			(xy 346.737385 -369.237011) (xy 346.758006 -369.241324) (xy 346.77144 -369.243944) (xy 346.79877 -369.24259)
			(xy 346.824757 -369.234019) (xy 346.847531 -369.218848) (xy 346.865453 -369.19817) (xy 346.877234 -369.173471)
			(xy 346.882025 -369.14653) (xy 346.881196 -369.132866) (xy 346.879672 -369.098068) (xy 346.880212 -369.070819)
			(xy 346.887973 -369.016877) (xy 346.903331 -368.964588) (xy 346.925974 -368.915018) (xy 346.955441 -368.869174)
			(xy 346.991133 -368.82799) (xy 347.032322 -368.792305) (xy 347.07817 -368.762845) (xy 347.127745 -368.74021)
			(xy 347.180036 -368.72486) (xy 347.233979 -368.717108) (xy 347.288477 -368.717112) (xy 347.342419 -368.724872)
			(xy 347.394708 -368.740229) (xy 347.444279 -368.762872) (xy 347.490123 -368.792339) (xy 347.531307 -368.82803)
			(xy 347.566993 -368.869219) (xy 347.596453 -368.915067) (xy 347.619089 -368.964641) (xy 347.634439 -369.016932)
			(xy 347.642192 -369.070875) (xy 347.642188 -369.125373) (xy 347.634429 -369.179315) (xy 347.619072 -369.231604)
			(xy 347.59643 -369.281175) (xy 347.566964 -369.32702) (xy 347.531273 -369.368204) (xy 347.490085 -369.40389)
			(xy 347.444237 -369.433351) (xy 347.394663 -369.455987) (xy 347.342372 -369.471338) (xy 347.288429 -369.479091)
			(xy 347.26118 -369.479576) (xy 347.240115 -369.479329) (xy 347.198235 -369.474745) (xy 347.177614 -369.470432)
			(xy 347.16417 -369.467881) (xy 347.136851 -369.469231) (xy 347.110873 -369.477794) (xy 347.088105 -369.492953)
			(xy 347.070184 -369.513618) (xy 347.0584 -369.538303) (xy 347.053601 -369.565231) (xy 347.054424 -369.57889)
			(xy 347.055948 -369.613688) (xy 347.055458 -369.640943) (xy 347.047702 -369.694897) (xy 347.032346 -369.747198)
			(xy 347.009703 -369.796782) (xy 346.980234 -369.842638) (xy 346.944539 -369.883834) (xy 346.903344 -369.91953)
			(xy 346.857488 -369.949) (xy 346.807905 -369.971644) (xy 346.755604 -369.987001) (xy 346.701649 -369.994757)
			(xy 346.64714 -369.994757) (xy 346.593186 -369.986998) (xy 346.540885 -369.97164) (xy 346.491303 -369.948995)
			(xy 346.445448 -369.919524) (xy 346.404254 -369.883826) (xy 346.368559 -369.84263) (xy 346.339092 -369.796773)
			(xy 346.31645 -369.747188) (xy 346.301096 -369.694887) (xy 346.293341 -369.640932) (xy 332.535088 -369.640932)
			(xy 334.146906 -371.25275)
		)
		(stroke
			(width 0)
			(type solid)
		)
		(fill yes)
		(layer "In15.Cu")
		(net "GND")
	)
	(gr_poly
		(pts
			(xy 370.1796 -288.757868) (xy 370.191782 -288.734558) (xy 370.221967 -288.691486) (xy 370.258158 -288.653323)
			(xy 370.299569 -288.620898) (xy 370.345299 -288.594917) (xy 370.394353 -288.575944) (xy 370.445664 -288.564393)
			(xy 370.498116 -288.560514) (xy 370.550568 -288.564393) (xy 370.601879 -288.575944) (xy 370.650933 -288.594917)
			(xy 370.696663 -288.620898) (xy 370.738074 -288.653323) (xy 370.774265 -288.691486) (xy 370.80445 -288.734558)
			(xy 370.816632 -288.757868) (xy 370.942108 -288.757868) (xy 370.957334 -288.757288) (xy 370.986429 -288.748297)
			(xy 371.01159 -288.731142) (xy 371.03059 -288.707344) (xy 371.041746 -288.679009) (xy 371.044071 -288.648645)
			(xy 371.037359 -288.618941) (xy 371.030246 -288.605468) (xy 370.945918 -288.459418) (xy 370.921026 -288.456116)
			(xy 370.895683 -288.452293) (xy 370.846373 -288.438315) (xy 370.799577 -288.417412) (xy 370.756262 -288.390015)
			(xy 370.717324 -288.356689) (xy 370.683566 -288.318125) (xy 370.655687 -288.275118) (xy 370.634263 -288.228559)
			(xy 370.619736 -288.179408) (xy 370.612407 -288.128682) (xy 370.611908 -288.103056) (xy 370.612406 -288.076407)
			(xy 370.620349 -288.023703) (xy 370.636059 -287.972773) (xy 370.659185 -287.924752) (xy 370.689209 -287.880715)
			(xy 370.725461 -287.841644) (xy 370.767132 -287.808413) (xy 370.81329 -287.781764) (xy 370.862904 -287.762292)
			(xy 370.914866 -287.750432) (xy 370.968016 -287.746449) (xy 371.021166 -287.750432) (xy 371.073128 -287.762292)
			(xy 371.122742 -287.781764) (xy 371.1689 -287.808413) (xy 371.210571 -287.841644) (xy 371.246823 -287.880715)
			(xy 371.276847 -287.924752) (xy 371.299973 -287.972773) (xy 371.315683 -288.023703) (xy 371.323626 -288.076407)
			(xy 371.324124 -288.103056) (xy 371.323751 -288.126302) (xy 371.317712 -288.172399) (xy 371.305731 -288.217319)
			(xy 371.2972 -288.238946) (xy 371.287802 -288.261806) (xy 371.460268 -288.560764) (xy 371.484906 -288.564066)
			(xy 371.509443 -288.567762) (xy 371.557245 -288.58107) (xy 371.602736 -288.600888) (xy 371.645033 -288.626833)
			(xy 371.683316 -288.658401) (xy 371.716843 -288.694981) (xy 371.744964 -288.735863) (xy 371.756432 -288.757868)
			(xy 372.0592 -288.757868) (xy 372.071382 -288.734558) (xy 372.101567 -288.691486) (xy 372.137758 -288.653323)
			(xy 372.179169 -288.620898) (xy 372.224899 -288.594917) (xy 372.273953 -288.575944) (xy 372.325264 -288.564393)
			(xy 372.377716 -288.560514) (xy 372.430168 -288.564393) (xy 372.481479 -288.575944) (xy 372.530533 -288.594917)
			(xy 372.576263 -288.620898) (xy 372.617674 -288.653323) (xy 372.653865 -288.691486) (xy 372.68405 -288.734558)
			(xy 372.696232 -288.757868) (xy 372.821708 -288.757868) (xy 372.836934 -288.757288) (xy 372.866029 -288.748297)
			(xy 372.89119 -288.731142) (xy 372.91019 -288.707344) (xy 372.921346 -288.679009) (xy 372.923671 -288.648645)
			(xy 372.916959 -288.618941) (xy 372.909846 -288.605468) (xy 372.825518 -288.459418) (xy 372.800626 -288.456116)
			(xy 372.775283 -288.452293) (xy 372.725973 -288.438315) (xy 372.679177 -288.417412) (xy 372.635862 -288.390015)
			(xy 372.596924 -288.356689) (xy 372.563166 -288.318125) (xy 372.535287 -288.275118) (xy 372.513863 -288.228559)
			(xy 372.499336 -288.179408) (xy 372.492007 -288.128682) (xy 372.491508 -288.103056) (xy 372.492006 -288.076407)
			(xy 372.499949 -288.023703) (xy 372.515659 -287.972773) (xy 372.538785 -287.924752) (xy 372.568809 -287.880715)
			(xy 372.605061 -287.841644) (xy 372.646732 -287.808413) (xy 372.69289 -287.781764) (xy 372.742504 -287.762292)
			(xy 372.794466 -287.750432) (xy 372.847616 -287.746449) (xy 372.900766 -287.750432) (xy 372.952728 -287.762292)
			(xy 373.002342 -287.781764) (xy 373.0485 -287.808413) (xy 373.090171 -287.841644) (xy 373.126423 -287.880715)
			(xy 373.156447 -287.924752) (xy 373.179573 -287.972773) (xy 373.195283 -288.023703) (xy 373.203226 -288.076407)
			(xy 373.203724 -288.103056) (xy 373.203351 -288.126302) (xy 373.197312 -288.172399) (xy 373.185331 -288.217319)
			(xy 373.1768 -288.238946) (xy 373.167402 -288.261806) (xy 373.339868 -288.560764) (xy 373.364506 -288.564066)
			(xy 373.389043 -288.567762) (xy 373.436845 -288.58107) (xy 373.482336 -288.600888) (xy 373.524633 -288.626833)
			(xy 373.562916 -288.658401) (xy 373.596443 -288.694981) (xy 373.624564 -288.735863) (xy 373.636032 -288.757868)
			(xy 373.9388 -288.757868) (xy 373.950982 -288.734558) (xy 373.981167 -288.691486) (xy 374.017358 -288.653323)
			(xy 374.058769 -288.620898) (xy 374.104499 -288.594917) (xy 374.153553 -288.575944) (xy 374.204864 -288.564393)
			(xy 374.257316 -288.560514) (xy 374.309768 -288.564393) (xy 374.361079 -288.575944) (xy 374.410133 -288.594917)
			(xy 374.455863 -288.620898) (xy 374.497274 -288.653323) (xy 374.533465 -288.691486) (xy 374.56365 -288.734558)
			(xy 374.575832 -288.757868) (xy 374.701308 -288.757868) (xy 374.716534 -288.757288) (xy 374.745629 -288.748297)
			(xy 374.77079 -288.731142) (xy 374.78979 -288.707344) (xy 374.800946 -288.679009) (xy 374.803271 -288.648645)
			(xy 374.796559 -288.618941) (xy 374.789446 -288.605468) (xy 374.705118 -288.459418) (xy 374.680226 -288.456116)
			(xy 374.654883 -288.452293) (xy 374.605573 -288.438315) (xy 374.558777 -288.417412) (xy 374.515462 -288.390015)
			(xy 374.476524 -288.356689) (xy 374.442766 -288.318125) (xy 374.414887 -288.275118) (xy 374.393463 -288.228559)
			(xy 374.378936 -288.179408) (xy 374.371607 -288.128682) (xy 374.371108 -288.103056) (xy 374.371606 -288.076407)
			(xy 374.379549 -288.023703) (xy 374.395259 -287.972773) (xy 374.418385 -287.924752) (xy 374.448409 -287.880715)
			(xy 374.484661 -287.841644) (xy 374.526332 -287.808413) (xy 374.57249 -287.781764) (xy 374.622104 -287.762292)
			(xy 374.674066 -287.750432) (xy 374.727216 -287.746449) (xy 374.780366 -287.750432) (xy 374.832328 -287.762292)
			(xy 374.881942 -287.781764) (xy 374.9281 -287.808413) (xy 374.969771 -287.841644) (xy 375.006023 -287.880715)
			(xy 375.036047 -287.924752) (xy 375.059173 -287.972773) (xy 375.074883 -288.023703) (xy 375.082826 -288.076407)
			(xy 375.083324 -288.103056) (xy 375.082951 -288.126302) (xy 375.076912 -288.172399) (xy 375.064931 -288.217319)
			(xy 375.0564 -288.238946) (xy 375.047002 -288.261806) (xy 375.219468 -288.560764) (xy 375.244106 -288.564066)
			(xy 375.268643 -288.567762) (xy 375.316445 -288.58107) (xy 375.361936 -288.600888) (xy 375.404233 -288.626833)
			(xy 375.442516 -288.658401) (xy 375.476043 -288.694981) (xy 375.504164 -288.735863) (xy 375.515632 -288.757868)
			(xy 375.8184 -288.757868) (xy 375.830582 -288.734558) (xy 375.860767 -288.691486) (xy 375.896958 -288.653323)
			(xy 375.938369 -288.620898) (xy 375.984099 -288.594917) (xy 376.033153 -288.575944) (xy 376.084464 -288.564393)
			(xy 376.136916 -288.560514) (xy 376.189368 -288.564393) (xy 376.240679 -288.575944) (xy 376.289733 -288.594917)
			(xy 376.335463 -288.620898) (xy 376.376874 -288.653323) (xy 376.413065 -288.691486) (xy 376.44325 -288.734558)
			(xy 376.455432 -288.757868) (xy 376.580908 -288.757868) (xy 376.596134 -288.757288) (xy 376.625229 -288.748297)
			(xy 376.65039 -288.731142) (xy 376.66939 -288.707344) (xy 376.680546 -288.679009) (xy 376.682871 -288.648645)
			(xy 376.676159 -288.618941) (xy 376.669046 -288.605468) (xy 376.584718 -288.459418) (xy 376.559826 -288.456116)
			(xy 376.534483 -288.452293) (xy 376.485173 -288.438315) (xy 376.438377 -288.417412) (xy 376.395062 -288.390015)
			(xy 376.356124 -288.356689) (xy 376.322366 -288.318125) (xy 376.294487 -288.275118) (xy 376.273063 -288.228559)
			(xy 376.258536 -288.179408) (xy 376.251207 -288.128682) (xy 376.250708 -288.103056) (xy 376.251206 -288.076407)
			(xy 376.259149 -288.023703) (xy 376.274859 -287.972773) (xy 376.297985 -287.924752) (xy 376.328009 -287.880715)
			(xy 376.364261 -287.841644) (xy 376.405932 -287.808413) (xy 376.45209 -287.781764) (xy 376.501704 -287.762292)
			(xy 376.553666 -287.750432) (xy 376.606816 -287.746449) (xy 376.659966 -287.750432) (xy 376.711928 -287.762292)
			(xy 376.761542 -287.781764) (xy 376.8077 -287.808413) (xy 376.849371 -287.841644) (xy 376.885623 -287.880715)
			(xy 376.915647 -287.924752) (xy 376.938773 -287.972773) (xy 376.954483 -288.023703) (xy 376.962426 -288.076407)
			(xy 376.962924 -288.103056) (xy 376.962551 -288.126302) (xy 376.956512 -288.172399) (xy 376.944531 -288.217319)
			(xy 376.936 -288.238946) (xy 376.926602 -288.261806) (xy 377.099068 -288.560764) (xy 377.123706 -288.564066)
			(xy 377.148243 -288.567762) (xy 377.196045 -288.58107) (xy 377.241536 -288.600888) (xy 377.283833 -288.626833)
			(xy 377.322116 -288.658401) (xy 377.355643 -288.694981) (xy 377.383764 -288.735863) (xy 377.395232 -288.757868)
			(xy 377.698 -288.757868) (xy 377.710182 -288.734558) (xy 377.740367 -288.691486) (xy 377.776558 -288.653323)
			(xy 377.817969 -288.620898) (xy 377.863699 -288.594917) (xy 377.912753 -288.575944) (xy 377.964064 -288.564393)
			(xy 378.016516 -288.560514) (xy 378.068968 -288.564393) (xy 378.120279 -288.575944) (xy 378.169333 -288.594917)
			(xy 378.215063 -288.620898) (xy 378.256474 -288.653323) (xy 378.292665 -288.691486) (xy 378.32285 -288.734558)
			(xy 378.335032 -288.757868) (xy 378.460508 -288.757868) (xy 378.475734 -288.757288) (xy 378.504829 -288.748297)
			(xy 378.52999 -288.731142) (xy 378.54899 -288.707344) (xy 378.560146 -288.679009) (xy 378.562471 -288.648645)
			(xy 378.555759 -288.618941) (xy 378.548646 -288.605468) (xy 378.464318 -288.459418) (xy 378.439426 -288.456116)
			(xy 378.414083 -288.452293) (xy 378.364773 -288.438315) (xy 378.317977 -288.417412) (xy 378.274662 -288.390015)
			(xy 378.235724 -288.356689) (xy 378.201966 -288.318125) (xy 378.174087 -288.275118) (xy 378.152663 -288.228559)
			(xy 378.138136 -288.179408) (xy 378.130807 -288.128682) (xy 378.130308 -288.103056) (xy 378.130806 -288.076407)
			(xy 378.138749 -288.023703) (xy 378.154459 -287.972773) (xy 378.177585 -287.924752) (xy 378.207609 -287.880715)
			(xy 378.243861 -287.841644) (xy 378.285532 -287.808413) (xy 378.33169 -287.781764) (xy 378.381304 -287.762292)
			(xy 378.433266 -287.750432) (xy 378.486416 -287.746449) (xy 378.539566 -287.750432) (xy 378.591528 -287.762292)
			(xy 378.641142 -287.781764) (xy 378.6873 -287.808413) (xy 378.728971 -287.841644) (xy 378.765223 -287.880715)
			(xy 378.795247 -287.924752) (xy 378.818373 -287.972773) (xy 378.834083 -288.023703) (xy 378.842026 -288.076407)
			(xy 378.842524 -288.103056) (xy 378.842151 -288.126302) (xy 378.836112 -288.172399) (xy 378.824131 -288.217319)
			(xy 378.8156 -288.238946) (xy 378.806202 -288.261806) (xy 378.978668 -288.560764) (xy 379.003306 -288.564066)
			(xy 379.027843 -288.567762) (xy 379.075645 -288.58107) (xy 379.121136 -288.600888) (xy 379.163433 -288.626833)
			(xy 379.201716 -288.658401) (xy 379.235243 -288.694981) (xy 379.263364 -288.735863) (xy 379.274832 -288.757868)
			(xy 379.5776 -288.757868) (xy 379.589782 -288.734558) (xy 379.619967 -288.691486) (xy 379.656158 -288.653323)
			(xy 379.697569 -288.620898) (xy 379.743299 -288.594917) (xy 379.792353 -288.575944) (xy 379.843664 -288.564393)
			(xy 379.896116 -288.560514) (xy 379.948568 -288.564393) (xy 379.999879 -288.575944) (xy 380.048933 -288.594917)
			(xy 380.094663 -288.620898) (xy 380.136074 -288.653323) (xy 380.172265 -288.691486) (xy 380.20245 -288.734558)
			(xy 380.214632 -288.757868) (xy 380.340108 -288.757868) (xy 380.355334 -288.757288) (xy 380.384429 -288.748297)
			(xy 380.40959 -288.731142) (xy 380.42859 -288.707344) (xy 380.439746 -288.679009) (xy 380.442071 -288.648645)
			(xy 380.435359 -288.618941) (xy 380.428246 -288.605468) (xy 380.343918 -288.459418) (xy 380.319026 -288.456116)
			(xy 380.293683 -288.452293) (xy 380.244373 -288.438315) (xy 380.197577 -288.417412) (xy 380.154262 -288.390015)
			(xy 380.115324 -288.356689) (xy 380.081566 -288.318125) (xy 380.053687 -288.275118) (xy 380.032263 -288.228559)
			(xy 380.017736 -288.179408) (xy 380.010407 -288.128682) (xy 380.009908 -288.103056) (xy 380.010406 -288.076407)
			(xy 380.018349 -288.023703) (xy 380.034059 -287.972773) (xy 380.057185 -287.924752) (xy 380.087209 -287.880715)
			(xy 380.123461 -287.841644) (xy 380.165132 -287.808413) (xy 380.21129 -287.781764) (xy 380.260904 -287.762292)
			(xy 380.312866 -287.750432) (xy 380.366016 -287.746449) (xy 380.419166 -287.750432) (xy 380.471128 -287.762292)
			(xy 380.520742 -287.781764) (xy 380.5669 -287.808413) (xy 380.608571 -287.841644) (xy 380.644823 -287.880715)
			(xy 380.674847 -287.924752) (xy 380.697973 -287.972773) (xy 380.713683 -288.023703) (xy 380.721626 -288.076407)
			(xy 380.722124 -288.103056) (xy 380.721751 -288.126302) (xy 380.721305 -288.129705) (xy 381.890006 -288.129705)
			(xy 381.890006 -288.076407) (xy 381.897949 -288.023703) (xy 381.913659 -287.972773) (xy 381.936785 -287.924752)
			(xy 381.966809 -287.880715) (xy 382.003061 -287.841644) (xy 382.044732 -287.808413) (xy 382.09089 -287.781764)
			(xy 382.140504 -287.762292) (xy 382.192466 -287.750432) (xy 382.245616 -287.746449) (xy 382.298766 -287.750432)
			(xy 382.350728 -287.762292) (xy 382.400342 -287.781764) (xy 382.4465 -287.808413) (xy 382.488171 -287.841644)
			(xy 382.524423 -287.880715) (xy 382.554447 -287.924752) (xy 382.577573 -287.972773) (xy 382.593283 -288.023703)
			(xy 382.601226 -288.076407) (xy 382.601724 -288.103056) (xy 382.601226 -288.129705) (xy 382.593283 -288.182409)
			(xy 382.577573 -288.233339) (xy 382.554447 -288.28136) (xy 382.524423 -288.325397) (xy 382.488171 -288.364468)
			(xy 382.4465 -288.397699) (xy 382.400342 -288.424348) (xy 382.350728 -288.44382) (xy 382.298766 -288.45568)
			(xy 382.245616 -288.459664) (xy 382.192466 -288.45568) (xy 382.140504 -288.44382) (xy 382.09089 -288.424348)
			(xy 382.044732 -288.397699) (xy 382.003061 -288.364468) (xy 381.966809 -288.325397) (xy 381.936785 -288.28136)
			(xy 381.913659 -288.233339) (xy 381.897949 -288.182409) (xy 381.890006 -288.129705) (xy 380.721305 -288.129705)
			(xy 380.715712 -288.172399) (xy 380.703731 -288.217319) (xy 380.6952 -288.238946) (xy 380.685802 -288.261806)
			(xy 380.858268 -288.560764) (xy 380.882906 -288.564066) (xy 380.907443 -288.567762) (xy 380.955245 -288.58107)
			(xy 381.000736 -288.600888) (xy 381.043033 -288.626833) (xy 381.081316 -288.658401) (xy 381.114843 -288.694981)
			(xy 381.142964 -288.735863) (xy 381.154432 -288.757868) (xy 381.4572 -288.757868) (xy 381.469382 -288.734558)
			(xy 381.499567 -288.691486) (xy 381.535758 -288.653323) (xy 381.577169 -288.620898) (xy 381.622899 -288.594917)
			(xy 381.671953 -288.575944) (xy 381.723264 -288.564393) (xy 381.775716 -288.560514) (xy 381.828168 -288.564393)
			(xy 381.879479 -288.575944) (xy 381.928533 -288.594917) (xy 381.974263 -288.620898) (xy 382.015674 -288.653323)
			(xy 382.051865 -288.691486) (xy 382.08205 -288.734558) (xy 382.094232 -288.757868) (xy 382.397 -288.757868)
			(xy 382.41008 -288.732903) (xy 382.442907 -288.687094) (xy 382.48254 -288.647027) (xy 382.52799 -288.613703)
			(xy 382.578122 -288.587954) (xy 382.631683 -288.570424) (xy 382.687337 -288.561549) (xy 382.715516 -288.561018)
			(xy 382.743409 -288.561561) (xy 382.798512 -288.57026) (xy 382.851585 -288.587444) (xy 382.90133 -288.612692)
			(xy 382.946531 -288.645386) (xy 382.986082 -288.684728) (xy 383.019016 -288.729754) (xy 383.032254 -288.754312)
			(xy 383.157476 -288.754312) (xy 383.172712 -288.753805) (xy 383.201829 -288.744824) (xy 383.227001 -288.727653)
			(xy 383.245989 -288.703822) (xy 383.257102 -288.675449) (xy 383.259351 -288.645061) (xy 383.252536 -288.615362)
			(xy 383.24536 -288.601912) (xy 383.163064 -288.459418) (xy 383.138426 -288.456116) (xy 383.113083 -288.452293)
			(xy 383.063773 -288.438315) (xy 383.016977 -288.417412) (xy 382.973662 -288.390015) (xy 382.934724 -288.356689)
			(xy 382.900966 -288.318125) (xy 382.873087 -288.275118) (xy 382.851663 -288.228559) (xy 382.837136 -288.179408)
			(xy 382.829807 -288.128682) (xy 382.829308 -288.103056) (xy 382.829806 -288.076407) (xy 382.837749 -288.023703)
			(xy 382.853459 -287.972773) (xy 382.876585 -287.924752) (xy 382.906609 -287.880715) (xy 382.942861 -287.841644)
			(xy 382.984532 -287.808413) (xy 383.03069 -287.781764) (xy 383.080304 -287.762292) (xy 383.132266 -287.750432)
			(xy 383.185416 -287.746449) (xy 383.238566 -287.750432) (xy 383.290528 -287.762292) (xy 383.340142 -287.781764)
			(xy 383.3863 -287.808413) (xy 383.427971 -287.841644) (xy 383.464223 -287.880715) (xy 383.494247 -287.924752)
			(xy 383.517373 -287.972773) (xy 383.533083 -288.023703) (xy 383.541026 -288.076407) (xy 383.541524 -288.103056)
			(xy 383.541151 -288.126302) (xy 383.540705 -288.129705) (xy 383.769606 -288.129705) (xy 383.769606 -288.076407)
			(xy 383.777549 -288.023703) (xy 383.793259 -287.972773) (xy 383.816385 -287.924752) (xy 383.846409 -287.880715)
			(xy 383.882661 -287.841644) (xy 383.924332 -287.808413) (xy 383.97049 -287.781764) (xy 384.020104 -287.762292)
			(xy 384.072066 -287.750432) (xy 384.125216 -287.746449) (xy 384.178366 -287.750432) (xy 384.230328 -287.762292)
			(xy 384.279942 -287.781764) (xy 384.3261 -287.808413) (xy 384.367771 -287.841644) (xy 384.404023 -287.880715)
			(xy 384.434047 -287.924752) (xy 384.457173 -287.972773) (xy 384.472883 -288.023703) (xy 384.480826 -288.076407)
			(xy 384.481324 -288.103056) (xy 384.480826 -288.129705) (xy 384.472883 -288.182409) (xy 384.457173 -288.233339)
			(xy 384.434047 -288.28136) (xy 384.404023 -288.325397) (xy 384.367771 -288.364468) (xy 384.3261 -288.397699)
			(xy 384.279942 -288.424348) (xy 384.230328 -288.44382) (xy 384.178366 -288.45568) (xy 384.125216 -288.459664)
			(xy 384.072066 -288.45568) (xy 384.020104 -288.44382) (xy 383.97049 -288.424348) (xy 383.924332 -288.397699)
			(xy 383.882661 -288.364468) (xy 383.846409 -288.325397) (xy 383.816385 -288.28136) (xy 383.793259 -288.233339)
			(xy 383.777549 -288.182409) (xy 383.769606 -288.129705) (xy 383.540705 -288.129705) (xy 383.535112 -288.172399)
			(xy 383.523131 -288.217319) (xy 383.5146 -288.238946) (xy 383.504948 -288.26206) (xy 383.677668 -288.560764)
			(xy 383.702306 -288.564066) (xy 383.730601 -288.568403) (xy 383.785403 -288.584924) (xy 383.836856 -288.61)
			(xy 383.883635 -288.642985) (xy 383.924534 -288.683029) (xy 383.958499 -288.729101) (xy 383.972054 -288.754312)
			(xy 386.180076 -288.754312) (xy 386.30479 -288.629598) (xy 386.392166 -286.837374) (xy 386.39242 -286.822771)
			(xy 386.385566 -286.794393) (xy 386.370958 -286.769116) (xy 386.349792 -286.749009) (xy 386.323799 -286.735716)
			(xy 386.295107 -286.730325) (xy 386.266063 -286.733277) (xy 386.239042 -286.744331) (xy 386.22732 -286.753046)
			(xy 386.20828 -286.767781) (xy 386.166987 -286.792537) (xy 386.122739 -286.811511) (xy 386.07634 -286.824359)
			(xy 386.028634 -286.830846) (xy 386.004562 -286.831278) (xy 385.977917 -286.830777) (xy 385.925222 -286.82283)
			(xy 385.874301 -286.807118) (xy 385.82629 -286.783992) (xy 385.782261 -286.75397) (xy 385.743198 -286.717721)
			(xy 385.709974 -286.676055) (xy 385.683331 -286.629903) (xy 385.663863 -286.580296) (xy 385.652005 -286.528341)
			(xy 385.648023 -286.4752) (xy 385.652005 -286.422059) (xy 385.663863 -286.370104) (xy 385.683331 -286.320497)
			(xy 385.709974 -286.274345) (xy 385.743198 -286.232679) (xy 385.782261 -286.19643) (xy 385.82629 -286.166408)
			(xy 385.874301 -286.143282) (xy 385.925222 -286.12757) (xy 385.977917 -286.119623) (xy 386.004562 -286.119062)
			(xy 386.0321 -286.119572) (xy 386.086523 -286.128038) (xy 386.138995 -286.144775) (xy 386.188268 -286.169384)
			(xy 386.23317 -286.201279) (xy 386.253228 -286.220154) (xy 386.263994 -286.230044) (xy 386.289799 -286.243758)
			(xy 386.318432 -286.249597) (xy 386.347546 -286.247084) (xy 386.374754 -286.236423) (xy 386.397827 -286.21849)
			(xy 386.414873 -286.194754) (xy 386.424494 -286.16716) (xy 386.425694 -286.15259) (xy 386.432298 -286.017462)
			(xy 386.391404 -286.007556) (xy 386.365823 -286.000917) (xy 386.316824 -285.981117) (xy 386.271288 -285.954295)
			(xy 386.230215 -285.921039) (xy 386.194506 -285.882079) (xy 386.164946 -285.838272) (xy 386.142182 -285.790577)
			(xy 386.126715 -285.740043) (xy 386.118884 -285.687778) (xy 386.118354 -285.661354) (xy 386.118795 -285.63583)
			(xy 386.126088 -285.585307) (xy 386.140517 -285.536341) (xy 386.161788 -285.489936) (xy 386.189465 -285.447043)
			(xy 386.222981 -285.408539) (xy 386.261649 -285.375213) (xy 386.304678 -285.347748) (xy 386.351187 -285.326706)
			(xy 386.400223 -285.312518) (xy 386.42544 -285.308548) (xy 386.467096 -285.30296) (xy 386.511546 -284.392116)
			(xy 386.460492 -284.389576) (xy 386.433248 -284.387989) (xy 386.379682 -284.377561) (xy 386.328334 -284.359082)
			(xy 386.280408 -284.332983) (xy 386.237026 -284.299877) (xy 386.199204 -284.260539) (xy 386.167827 -284.21589)
			(xy 386.143632 -284.166975) (xy 386.127183 -284.114942) (xy 386.118868 -284.061008) (xy 386.118354 -284.033722)
			(xy 386.118901 -284.005737) (xy 386.127653 -283.950455) (xy 386.144945 -283.897222) (xy 386.170352 -283.84735)
			(xy 386.203247 -283.802066) (xy 386.242821 -283.762486) (xy 386.288099 -283.729583) (xy 386.337967 -283.704168)
			(xy 386.391196 -283.686867) (xy 386.446477 -283.678106) (xy 386.474462 -283.677614) (xy 386.495036 -283.678122)
			(xy 386.49529 -283.678122) (xy 386.546344 -283.680662) (xy 386.585968 -282.86837) (xy 386.586148 -282.854462)
			(xy 386.579916 -282.827366) (xy 386.566609 -282.802954) (xy 386.547213 -282.783035) (xy 386.523164 -282.769082)
			(xy 386.496244 -282.762131) (xy 386.482336 -282.761944) (xy 386.474462 -282.761944) (xy 386.447812 -282.761444)
			(xy 386.395108 -282.753494) (xy 386.344177 -282.737779) (xy 386.296156 -282.71465) (xy 386.252119 -282.684622)
			(xy 386.213049 -282.648366) (xy 386.179819 -282.606692) (xy 386.153171 -282.560532) (xy 386.133699 -282.510916)
			(xy 386.121839 -282.458951) (xy 386.117856 -282.4058) (xy 386.121839 -282.352649) (xy 386.133699 -282.300684)
			(xy 386.153171 -282.251068) (xy 386.179819 -282.204908) (xy 386.213049 -282.163234) (xy 386.252119 -282.126978)
			(xy 386.296156 -282.09695) (xy 386.344177 -282.073821) (xy 386.395108 -282.058106) (xy 386.447812 -282.050156)
			(xy 386.474462 -282.049728) (xy 386.485093 -282.049805) (xy 386.506316 -282.051077) (xy 386.51688 -282.052268)
			(xy 386.530766 -282.053515) (xy 386.558307 -282.049254) (xy 386.583665 -282.037693) (xy 386.604944 -282.019696)
			(xy 386.620553 -281.996608) (xy 386.629325 -281.970155) (xy 386.630418 -281.956256) (xy 386.647182 -281.61615)
			(xy 386.533644 -281.502612) (xy 386.523754 -281.493377) (xy 386.500235 -281.480016) (xy 386.474034 -281.473299)
			(xy 386.446988 -281.473697) (xy 386.420995 -281.481182) (xy 386.39788 -281.495229) (xy 386.379264 -281.514853)
			(xy 386.366453 -281.538676) (xy 386.360347 -281.565026) (xy 386.360416 -281.578558) (xy 386.36067 -281.59202)
			(xy 386.360172 -281.618669) (xy 386.352229 -281.671373) (xy 386.336519 -281.722303) (xy 386.313393 -281.770324)
			(xy 386.283369 -281.814361) (xy 386.247117 -281.853432) (xy 386.205446 -281.886663) (xy 386.159288 -281.913312)
			(xy 386.109674 -281.932784) (xy 386.057712 -281.944644) (xy 386.004562 -281.948628) (xy 385.951412 -281.944644)
			(xy 385.89945 -281.932784) (xy 385.849836 -281.913312) (xy 385.803678 -281.886663) (xy 385.762007 -281.853432)
			(xy 385.725755 -281.814361) (xy 385.695731 -281.770324) (xy 385.672605 -281.722303) (xy 385.656895 -281.671373)
			(xy 385.648952 -281.618669) (xy 385.648454 -281.59202) (xy 385.649019 -281.563063) (xy 385.658386 -281.505911)
			(xy 385.676878 -281.451027) (xy 385.704005 -281.399859) (xy 385.739055 -281.353754) (xy 385.759706 -281.333448)
			(xy 385.770308 -281.322619) (xy 385.785193 -281.29624) (xy 385.791686 -281.266655) (xy 385.789214 -281.236467)
			(xy 385.777997 -281.208331) (xy 385.759019 -281.184724) (xy 385.733952 -281.167722) (xy 385.705 -281.158822)
			(xy 385.689856 -281.158188) (xy 385.252468 -281.158188) (xy 385.050284 -280.956004) (xy 385.039227 -280.945712)
			(xy 385.012575 -280.93153) (xy 384.982939 -280.925768) (xy 384.952915 -280.928931) (xy 384.92513 -280.940743)
			(xy 384.902019 -280.960168) (xy 384.893312 -280.972514) (xy 384.879146 -280.993467) (xy 384.845835 -281.031527)
			(xy 384.807474 -281.06449) (xy 384.764835 -281.091693) (xy 384.718774 -281.112587) (xy 384.670221 -281.126753)
			(xy 384.620151 -281.133905) (xy 384.594862 -281.134312) (xy 384.566881 -281.13376) (xy 384.511608 -281.125)
			(xy 384.458386 -281.107703) (xy 384.408524 -281.082293) (xy 384.363252 -281.049396) (xy 384.323682 -281.009822)
			(xy 384.29079 -280.964547) (xy 384.265384 -280.914683) (xy 384.248092 -280.861459) (xy 384.239337 -280.806185)
			(xy 384.238754 -280.778204) (xy 384.239196 -280.752916) (xy 384.246349 -280.702848) (xy 384.260511 -280.654295)
			(xy 384.281397 -280.608233) (xy 384.308588 -280.565588) (xy 384.341537 -280.527218) (xy 384.379582 -280.493893)
			(xy 384.400552 -280.479754) (xy 384.412886 -280.471058) (xy 384.43224 -280.447924) (xy 384.444002 -280.42015)
			(xy 384.447149 -280.390153) (xy 384.441407 -280.360542) (xy 384.427275 -280.333895) (xy 384.417062 -280.322782)
			(xy 384.342894 -280.248614) (xy 384.308858 -280.269188) (xy 384.287949 -280.281299) (xy 384.24356 -280.300391)
			(xy 384.197001 -280.313316) (xy 384.149122 -280.319835) (xy 384.124962 -280.320242) (xy 384.09698 -280.31969)
			(xy 384.041705 -280.310931) (xy 383.988481 -280.293633) (xy 383.938618 -280.268224) (xy 383.893342 -280.235327)
			(xy 383.85377 -280.195754) (xy 383.820874 -280.150479) (xy 383.795465 -280.100615) (xy 383.778168 -280.047391)
			(xy 383.769409 -279.992116) (xy 383.768854 -279.964134) (xy 383.769406 -279.935046) (xy 383.778818 -279.877638)
			(xy 383.797444 -279.822525) (xy 383.82479 -279.771178) (xy 383.842006 -279.747726) (xy 383.596134 -279.501854)
			(xy 383.581402 -279.498806) (xy 383.556346 -279.493047) (xy 383.508099 -279.47529) (xy 383.462906 -279.450781)
			(xy 383.421706 -279.420031) (xy 383.385354 -279.383676) (xy 383.354606 -279.342474) (xy 383.330101 -279.297279)
			(xy 383.312347 -279.249031) (xy 383.306574 -279.223978) (xy 383.303526 -279.209246) (xy 383.239772 -279.145492)
			(xy 383.229498 -279.13591) (xy 383.204943 -279.122282) (xy 383.177606 -279.115852) (xy 383.149551 -279.117107)
			(xy 383.122897 -279.125951) (xy 383.099656 -279.141716) (xy 383.081585 -279.163212) (xy 383.070047 -279.188816)
			(xy 383.06756 -279.202642) (xy 383.062895 -279.230438) (xy 383.045944 -279.284187) (xy 383.020738 -279.334594)
			(xy 382.987904 -279.380401) (xy 382.948263 -279.420462) (xy 382.902806 -279.453777) (xy 382.852667 -279.479514)
			(xy 382.7991 -279.497031) (xy 382.743441 -279.505889) (xy 382.715262 -279.506426) (xy 382.68728 -279.505874)
			(xy 382.632007 -279.497115) (xy 382.578784 -279.479817) (xy 382.528921 -279.454407) (xy 382.483647 -279.421511)
			(xy 382.444076 -279.381937) (xy 382.411182 -279.336662) (xy 382.385775 -279.286798) (xy 382.368481 -279.233574)
			(xy 382.359724 -279.1783) (xy 382.359154 -279.150318) (xy 382.359695 -279.122143) (xy 382.368579 -279.066497)
			(xy 382.386112 -279.012944) (xy 382.411858 -278.962819) (xy 382.445173 -278.917372) (xy 382.485228 -278.877736)
			(xy 382.531023 -278.844901) (xy 382.581417 -278.819684) (xy 382.635151 -278.802715) (xy 382.662938 -278.79802)
			(xy 382.67678 -278.795547) (xy 382.702431 -278.784055) (xy 382.723972 -278.765999) (xy 382.739767 -278.74275)
			(xy 382.748617 -278.716072) (xy 382.74985 -278.687991) (xy 382.743372 -278.66064) (xy 382.729675 -278.636096)
			(xy 382.720088 -278.625808) (xy 382.66116 -278.56688) (xy 382.651068 -278.557309) (xy 382.626888 -278.543581)
			(xy 382.599899 -278.536895) (xy 382.572107 -278.537748) (xy 382.545579 -278.546075) (xy 382.522286 -278.561258)
			(xy 382.512824 -278.571452) (xy 382.49585 -278.590128) (xy 382.45754 -278.622979) (xy 382.414973 -278.650088)
			(xy 382.369004 -278.670913) (xy 382.320554 -278.685036) (xy 382.270595 -278.692174) (xy 382.245362 -278.69261)
			(xy 382.217381 -278.692058) (xy 382.162108 -278.683298) (xy 382.108886 -278.666001) (xy 382.059025 -278.640591)
			(xy 382.013752 -278.607694) (xy 381.974183 -278.56812) (xy 381.941291 -278.522844) (xy 381.915886 -278.472981)
			(xy 381.898593 -278.419757) (xy 381.889839 -278.364483) (xy 381.889254 -278.336502) (xy 381.889694 -278.311269)
			(xy 381.896826 -278.261309) (xy 381.910947 -278.212859) (xy 381.931773 -278.16689) (xy 381.958886 -278.124326)
			(xy 381.991743 -278.086021) (xy 382.010412 -278.06904) (xy 382.020516 -278.059506) (xy 382.035635 -278.036216)
			(xy 382.04393 -278.009716) (xy 382.044791 -277.981962) (xy 382.038153 -277.955) (xy 382.024506 -277.930817)
			(xy 382.014984 -277.920704) (xy 381.936244 -277.841964) (xy 381.905256 -277.854156) (xy 381.874027 -277.865556)
			(xy 381.808699 -277.877829) (xy 381.775462 -277.87854) (xy 381.74748 -277.877988) (xy 381.692205 -277.869229)
			(xy 381.638981 -277.851931) (xy 381.589118 -277.826522) (xy 381.543843 -277.793625) (xy 381.504271 -277.754052)
			(xy 381.471375 -277.708777) (xy 381.445967 -277.658913) (xy 381.42867 -277.605689) (xy 381.419911 -277.550414)
			(xy 381.419354 -277.522432) (xy 381.420071 -277.489196) (xy 381.432343 -277.423868) (xy 381.443738 -277.392638)
			(xy 381.45593 -277.36165) (xy 381.067564 -276.973284) (xy 381.066548 -276.972522) (xy 381.04191 -276.947884)
			(xy 381.041148 -276.946868) (xy 380.872746 -276.778466) (xy 380.861894 -276.768321) (xy 380.835755 -276.754234)
			(xy 380.806667 -276.748263) (xy 380.777092 -276.750915) (xy 380.749531 -276.761964) (xy 380.726315 -276.780476)
			(xy 380.709407 -276.804886) (xy 380.704344 -276.818852) (xy 380.695165 -276.845277) (xy 380.669745 -276.895105)
			(xy 380.636848 -276.940346) (xy 380.597283 -276.979888) (xy 380.552022 -277.012758) (xy 380.502178 -277.038147)
			(xy 380.448978 -277.055432) (xy 380.393731 -277.064187) (xy 380.365762 -277.064724) (xy 380.33778 -277.064172)
			(xy 380.282507 -277.055413) (xy 380.229284 -277.038115) (xy 380.179422 -277.012705) (xy 380.134148 -276.979809)
			(xy 380.094577 -276.940235) (xy 380.061683 -276.894959) (xy 380.036277 -276.845096) (xy 380.018982 -276.791872)
			(xy 380.010226 -276.736598) (xy 380.009654 -276.708616) (xy 380.010201 -276.680647) (xy 380.018946 -276.625396)
			(xy 380.036225 -276.572193) (xy 380.06161 -276.522346) (xy 380.094479 -276.477083) (xy 380.134022 -276.437516)
			(xy 380.179266 -276.404621) (xy 380.229098 -276.379205) (xy 380.255526 -276.370034) (xy 380.269466 -276.364938)
			(xy 380.293826 -276.348004) (xy 380.3123 -276.324789) (xy 380.323332 -276.297249) (xy 380.325993 -276.2677)
			(xy 380.320059 -276.238632) (xy 380.306031 -276.212491) (xy 380.295912 -276.201632) (xy 380.265178 -276.170898)
			(xy 380.254031 -276.160538) (xy 380.227153 -276.1463) (xy 380.197276 -276.140606) (xy 380.167046 -276.14396)
			(xy 380.139142 -276.156064) (xy 380.127256 -276.165564) (xy 380.10781 -276.181588) (xy 380.065259 -276.208575)
			(xy 380.019331 -276.229299) (xy 379.970942 -276.243347) (xy 379.921056 -276.25044) (xy 379.895862 -276.250908)
			(xy 379.867881 -276.250356) (xy 379.812608 -276.241596) (xy 379.759386 -276.224299) (xy 379.709525 -276.198888)
			(xy 379.664253 -276.165992) (xy 379.624684 -276.126418) (xy 379.591792 -276.081142) (xy 379.566387 -276.031279)
			(xy 379.549095 -275.978055) (xy 379.540341 -275.922781) (xy 379.539754 -275.8948) (xy 379.54019 -275.869605)
			(xy 379.547288 -275.819718) (xy 379.561344 -275.771328) (xy 379.582076 -275.725401) (xy 379.609072 -275.682852)
			(xy 379.625098 -275.663406) (xy 379.634552 -275.651487) (xy 379.646648 -275.62359) (xy 379.650009 -275.59337)
			(xy 379.644338 -275.563498) (xy 379.630136 -275.536612) (xy 379.619764 -275.525484) (xy 379.519688 -275.425408)
			(xy 379.493272 -275.430488) (xy 379.47667 -275.433479) (xy 379.443084 -275.436662) (xy 379.426216 -275.436838)
			(xy 379.398231 -275.43629) (xy 379.34295 -275.427537) (xy 379.289719 -275.410245) (xy 379.239849 -275.384838)
			(xy 379.194566 -275.351943) (xy 379.154987 -275.312369) (xy 379.122086 -275.267091) (xy 379.096673 -275.217223)
			(xy 379.079373 -275.163994) (xy 379.070613 -275.108715) (xy 379.070108 -275.08073) (xy 379.070305 -275.063863)
			(xy 379.073482 -275.030278) (xy 379.076458 -275.013674) (xy 379.081538 -274.987258) (xy 378.496322 -274.402042)
			(xy 378.486301 -274.392647) (xy 378.46242 -274.379094) (xy 378.435792 -274.372391) (xy 378.408341 -274.373025)
			(xy 378.38205 -274.380947) (xy 378.358819 -274.395587) (xy 378.340328 -274.415886) (xy 378.333762 -274.42795)
			(xy 378.320629 -274.452716) (xy 378.28777 -274.498131) (xy 378.248196 -274.537832) (xy 378.202886 -274.570835)
			(xy 378.15296 -274.596324) (xy 378.099655 -274.613667) (xy 378.04429 -274.622437) (xy 378.016262 -274.623022)
			(xy 377.98828 -274.62247) (xy 377.933007 -274.613711) (xy 377.879784 -274.596413) (xy 377.829922 -274.571003)
			(xy 377.784649 -274.538106) (xy 377.745078 -274.498533) (xy 377.712185 -274.453257) (xy 377.686778 -274.403394)
			(xy 377.669484 -274.35017) (xy 377.660728 -274.294896) (xy 377.660154 -274.266914) (xy 377.660852 -274.235915)
			(xy 377.671626 -274.174857) (xy 377.692784 -274.116579) (xy 377.707652 -274.089368) (xy 377.71483 -274.075912)
			(xy 377.721603 -274.046189) (xy 377.719307 -274.01579) (xy 377.708146 -273.987422) (xy 377.689113 -273.963609)
			(xy 377.663902 -273.946469) (xy 377.634758 -273.93753) (xy 377.619514 -273.936968) (xy 377.47321 -273.936968)
			(xy 377.457986 -273.937546) (xy 377.428892 -273.946534) (xy 377.403733 -273.963686) (xy 377.384736 -273.987484)
			(xy 377.373585 -274.015819) (xy 377.371267 -274.04618) (xy 377.377988 -274.075879) (xy 377.385072 -274.089368)
			(xy 377.399968 -274.116565) (xy 377.421139 -274.174844) (xy 377.431877 -274.235911) (xy 377.43257 -274.266914)
			(xy 377.432072 -274.293563) (xy 377.424129 -274.346267) (xy 377.408419 -274.397197) (xy 377.385293 -274.445218)
			(xy 377.355269 -274.489255) (xy 377.319017 -274.528326) (xy 377.277346 -274.561557) (xy 377.231188 -274.588206)
			(xy 377.181574 -274.607678) (xy 377.129612 -274.619538) (xy 377.076462 -274.623522) (xy 377.023312 -274.619538)
			(xy 376.97135 -274.607678) (xy 376.921736 -274.588206) (xy 376.875578 -274.561557) (xy 376.833907 -274.528326)
			(xy 376.797655 -274.489255) (xy 376.767631 -274.445218) (xy 376.744505 -274.397197) (xy 376.728795 -274.346267)
			(xy 376.720852 -274.293563) (xy 376.720354 -274.266914) (xy 376.721052 -274.235915) (xy 376.731826 -274.174857)
			(xy 376.752984 -274.116579) (xy 376.767852 -274.089368) (xy 376.77503 -274.075912) (xy 376.781803 -274.046189)
			(xy 376.779507 -274.01579) (xy 376.768346 -273.987422) (xy 376.749313 -273.963609) (xy 376.724102 -273.946469)
			(xy 376.694958 -273.93753) (xy 376.679714 -273.936968) (xy 376.53341 -273.936968) (xy 376.518186 -273.937546)
			(xy 376.489092 -273.946534) (xy 376.463933 -273.963686) (xy 376.444936 -273.987484) (xy 376.433785 -274.015819)
			(xy 376.431467 -274.04618) (xy 376.438188 -274.075879) (xy 376.445272 -274.089368) (xy 376.460168 -274.116565)
			(xy 376.481339 -274.174844) (xy 376.492077 -274.235911) (xy 376.49277 -274.266914) (xy 376.492272 -274.293563)
			(xy 376.484329 -274.346267) (xy 376.468619 -274.397197) (xy 376.445493 -274.445218) (xy 376.415469 -274.489255)
			(xy 376.379217 -274.528326) (xy 376.337546 -274.561557) (xy 376.291388 -274.588206) (xy 376.241774 -274.607678)
			(xy 376.189812 -274.619538) (xy 376.136662 -274.623522) (xy 376.083512 -274.619538) (xy 376.03155 -274.607678)
			(xy 375.981936 -274.588206) (xy 375.935778 -274.561557) (xy 375.894107 -274.528326) (xy 375.857855 -274.489255)
			(xy 375.827831 -274.445218) (xy 375.804705 -274.397197) (xy 375.788995 -274.346267) (xy 375.781052 -274.293563)
			(xy 375.780554 -274.266914) (xy 375.781252 -274.235915) (xy 375.792026 -274.174857) (xy 375.813184 -274.116579)
			(xy 375.828052 -274.089368) (xy 375.83523 -274.075912) (xy 375.842003 -274.046189) (xy 375.839707 -274.01579)
			(xy 375.828546 -273.987422) (xy 375.809513 -273.963609) (xy 375.784302 -273.946469) (xy 375.755158 -273.93753)
			(xy 375.739914 -273.936968) (xy 375.59361 -273.936968) (xy 375.578386 -273.937546) (xy 375.549292 -273.946534)
			(xy 375.524133 -273.963686) (xy 375.505136 -273.987484) (xy 375.493985 -274.015819) (xy 375.491667 -274.04618)
			(xy 375.498388 -274.075879) (xy 375.505472 -274.089368) (xy 375.520368 -274.116565) (xy 375.541539 -274.174844)
			(xy 375.552277 -274.235911) (xy 375.55297 -274.266914) (xy 375.552472 -274.293563) (xy 375.544529 -274.346267)
			(xy 375.528819 -274.397197) (xy 375.505693 -274.445218) (xy 375.475669 -274.489255) (xy 375.439417 -274.528326)
			(xy 375.397746 -274.561557) (xy 375.351588 -274.588206) (xy 375.301974 -274.607678) (xy 375.250012 -274.619538)
			(xy 375.196862 -274.623522) (xy 375.143712 -274.619538) (xy 375.09175 -274.607678) (xy 375.042136 -274.588206)
			(xy 374.995978 -274.561557) (xy 374.954307 -274.528326) (xy 374.918055 -274.489255) (xy 374.888031 -274.445218)
			(xy 374.864905 -274.397197) (xy 374.849195 -274.346267) (xy 374.841252 -274.293563) (xy 374.840754 -274.266914)
			(xy 374.841452 -274.235915) (xy 374.852226 -274.174857) (xy 374.873384 -274.116579) (xy 374.888252 -274.089368)
			(xy 374.89543 -274.075912) (xy 374.902203 -274.046189) (xy 374.899907 -274.01579) (xy 374.888746 -273.987422)
			(xy 374.869713 -273.963609) (xy 374.844502 -273.946469) (xy 374.815358 -273.93753) (xy 374.800114 -273.936968)
			(xy 374.654064 -273.936968) (xy 374.638833 -273.937539) (xy 374.609725 -273.946518) (xy 374.584551 -273.963669)
			(xy 374.565543 -273.987472) (xy 374.554386 -274.015817) (xy 374.552068 -274.04619) (xy 374.558796 -274.075899)
			(xy 374.565926 -274.089368) (xy 374.580824 -274.116565) (xy 374.601997 -274.174843) (xy 374.612737 -274.235911)
			(xy 374.613424 -274.266914) (xy 374.612926 -274.293563) (xy 374.604983 -274.346267) (xy 374.589273 -274.397197)
			(xy 374.566147 -274.445218) (xy 374.536123 -274.489255) (xy 374.499871 -274.528326) (xy 374.4582 -274.561557)
			(xy 374.412042 -274.588206) (xy 374.362428 -274.607678) (xy 374.310466 -274.619538) (xy 374.257316 -274.623522)
			(xy 374.204166 -274.619538) (xy 374.152204 -274.607678) (xy 374.10259 -274.588206) (xy 374.056432 -274.561557)
			(xy 374.014761 -274.528326) (xy 373.978509 -274.489255) (xy 373.948485 -274.445218) (xy 373.925359 -274.397197)
			(xy 373.909649 -274.346267) (xy 373.901706 -274.293563) (xy 373.901208 -274.266914) (xy 373.901905 -274.235914)
			(xy 373.912679 -274.174856) (xy 373.933834 -274.116576) (xy 373.948706 -274.089368) (xy 373.955881 -274.075909)
			(xy 373.962651 -274.046183) (xy 373.960353 -274.015782) (xy 373.949193 -273.98741) (xy 373.930163 -273.963591)
			(xy 373.904956 -273.946443) (xy 373.875812 -273.937491) (xy 373.860568 -273.936968) (xy 373.71401 -273.936968)
			(xy 373.698786 -273.937546) (xy 373.669692 -273.946534) (xy 373.644533 -273.963686) (xy 373.625536 -273.987484)
			(xy 373.614385 -274.015819) (xy 373.612067 -274.04618) (xy 373.618788 -274.075879) (xy 373.625872 -274.089368)
			(xy 373.640768 -274.116565) (xy 373.661939 -274.174844) (xy 373.672677 -274.235911) (xy 373.67337 -274.266914)
			(xy 373.672872 -274.293563) (xy 373.664929 -274.346267) (xy 373.649219 -274.397197) (xy 373.626093 -274.445218)
			(xy 373.596069 -274.489255) (xy 373.559817 -274.528326) (xy 373.518146 -274.561557) (xy 373.471988 -274.588206)
			(xy 373.422374 -274.607678) (xy 373.370412 -274.619538) (xy 373.317262 -274.623522) (xy 373.264112 -274.619538)
			(xy 373.21215 -274.607678) (xy 373.162536 -274.588206) (xy 373.116378 -274.561557) (xy 373.074707 -274.528326)
			(xy 373.038455 -274.489255) (xy 373.008431 -274.445218) (xy 372.985305 -274.397197) (xy 372.969595 -274.346267)
			(xy 372.961652 -274.293563) (xy 372.961154 -274.266914) (xy 372.961852 -274.235915) (xy 372.972626 -274.174857)
			(xy 372.993784 -274.116579) (xy 373.008652 -274.089368) (xy 373.01583 -274.075912) (xy 373.022603 -274.046189)
			(xy 373.020307 -274.01579) (xy 373.009146 -273.987422) (xy 372.990113 -273.963609) (xy 372.964902 -273.946469)
			(xy 372.935758 -273.93753) (xy 372.920514 -273.936968) (xy 372.77421 -273.936968) (xy 372.758986 -273.937546)
			(xy 372.729892 -273.946534) (xy 372.704733 -273.963686) (xy 372.685736 -273.987484) (xy 372.674585 -274.015819)
			(xy 372.672267 -274.04618) (xy 372.678988 -274.075879) (xy 372.686072 -274.089368) (xy 372.700968 -274.116565)
			(xy 372.722139 -274.174844) (xy 372.732877 -274.235911) (xy 372.73357 -274.266914) (xy 372.733072 -274.293563)
			(xy 372.725129 -274.346267) (xy 372.709419 -274.397197) (xy 372.686293 -274.445218) (xy 372.656269 -274.489255)
			(xy 372.620017 -274.528326) (xy 372.578346 -274.561557) (xy 372.532188 -274.588206) (xy 372.482574 -274.607678)
			(xy 372.430612 -274.619538) (xy 372.377462 -274.623522) (xy 372.324312 -274.619538) (xy 372.27235 -274.607678)
			(xy 372.222736 -274.588206) (xy 372.176578 -274.561557) (xy 372.134907 -274.528326) (xy 372.098655 -274.489255)
			(xy 372.068631 -274.445218) (xy 372.045505 -274.397197) (xy 372.029795 -274.346267) (xy 372.021852 -274.293563)
			(xy 372.021354 -274.266914) (xy 372.022052 -274.235915) (xy 372.032826 -274.174857) (xy 372.053984 -274.116579)
			(xy 372.068852 -274.089368) (xy 372.07603 -274.075912) (xy 372.082803 -274.046189) (xy 372.080507 -274.01579)
			(xy 372.069346 -273.987422) (xy 372.050313 -273.963609) (xy 372.025102 -273.946469) (xy 371.995958 -273.93753)
			(xy 371.980714 -273.936968) (xy 371.83441 -273.936968) (xy 371.819186 -273.937546) (xy 371.790092 -273.946534)
			(xy 371.764933 -273.963686) (xy 371.745936 -273.987484) (xy 371.734785 -274.015819) (xy 371.732467 -274.04618)
			(xy 371.739188 -274.075879) (xy 371.746272 -274.089368) (xy 371.761168 -274.116565) (xy 371.782339 -274.174844)
			(xy 371.793077 -274.235911) (xy 371.79377 -274.266914) (xy 371.793272 -274.293563) (xy 371.785329 -274.346267)
			(xy 371.769619 -274.397197) (xy 371.746493 -274.445218) (xy 371.716469 -274.489255) (xy 371.680217 -274.528326)
			(xy 371.638546 -274.561557) (xy 371.592388 -274.588206) (xy 371.542774 -274.607678) (xy 371.490812 -274.619538)
			(xy 371.437662 -274.623522) (xy 371.384512 -274.619538) (xy 371.33255 -274.607678) (xy 371.282936 -274.588206)
			(xy 371.236778 -274.561557) (xy 371.195107 -274.528326) (xy 371.158855 -274.489255) (xy 371.128831 -274.445218)
			(xy 371.105705 -274.397197) (xy 371.089995 -274.346267) (xy 371.082052 -274.293563) (xy 371.081554 -274.266914)
			(xy 371.082252 -274.235915) (xy 371.093026 -274.174857) (xy 371.114184 -274.116579) (xy 371.129052 -274.089368)
			(xy 371.13623 -274.075912) (xy 371.143003 -274.046189) (xy 371.140707 -274.01579) (xy 371.129546 -273.987422)
			(xy 371.110513 -273.963609) (xy 371.085302 -273.946469) (xy 371.056158 -273.93753) (xy 371.040914 -273.936968)
			(xy 370.89461 -273.936968) (xy 370.879386 -273.937546) (xy 370.850292 -273.946534) (xy 370.825133 -273.963686)
			(xy 370.806136 -273.987484) (xy 370.794985 -274.015819) (xy 370.792667 -274.04618) (xy 370.799388 -274.075879)
			(xy 370.806472 -274.089368) (xy 370.821368 -274.116565) (xy 370.842539 -274.174844) (xy 370.853277 -274.235911)
			(xy 370.85397 -274.266914) (xy 370.853472 -274.293563) (xy 370.845529 -274.346267) (xy 370.829819 -274.397197)
			(xy 370.806693 -274.445218) (xy 370.776669 -274.489255) (xy 370.740417 -274.528326) (xy 370.698746 -274.561557)
			(xy 370.652588 -274.588206) (xy 370.602974 -274.607678) (xy 370.551012 -274.619538) (xy 370.497862 -274.623522)
			(xy 370.444712 -274.619538) (xy 370.39275 -274.607678) (xy 370.343136 -274.588206) (xy 370.296978 -274.561557)
			(xy 370.255307 -274.528326) (xy 370.219055 -274.489255) (xy 370.189031 -274.445218) (xy 370.165905 -274.397197)
			(xy 370.150195 -274.346267) (xy 370.142252 -274.293563) (xy 370.141754 -274.266914) (xy 370.142452 -274.235915)
			(xy 370.153226 -274.174857) (xy 370.174384 -274.116579) (xy 370.189252 -274.089368) (xy 370.19643 -274.075912)
			(xy 370.203203 -274.046189) (xy 370.200907 -274.01579) (xy 370.189746 -273.987422) (xy 370.170713 -273.963609)
			(xy 370.145502 -273.946469) (xy 370.116358 -273.93753) (xy 370.101114 -273.936968) (xy 369.955064 -273.936968)
			(xy 369.939833 -273.937539) (xy 369.910725 -273.946518) (xy 369.885551 -273.963669) (xy 369.866543 -273.987472)
			(xy 369.855386 -274.015817) (xy 369.853068 -274.04619) (xy 369.859796 -274.075899) (xy 369.866926 -274.089368)
			(xy 369.881824 -274.116565) (xy 369.902997 -274.174843) (xy 369.913737 -274.235911) (xy 369.914424 -274.266914)
			(xy 369.913926 -274.293563) (xy 369.905983 -274.346267) (xy 369.890273 -274.397197) (xy 369.867147 -274.445218)
			(xy 369.837123 -274.489255) (xy 369.800871 -274.528326) (xy 369.7592 -274.561557) (xy 369.713042 -274.588206)
			(xy 369.663428 -274.607678) (xy 369.611466 -274.619538) (xy 369.558316 -274.623522) (xy 369.505166 -274.619538)
			(xy 369.453204 -274.607678) (xy 369.40359 -274.588206) (xy 369.357432 -274.561557) (xy 369.315761 -274.528326)
			(xy 369.279509 -274.489255) (xy 369.249485 -274.445218) (xy 369.226359 -274.397197) (xy 369.210649 -274.346267)
			(xy 369.202706 -274.293563) (xy 369.202208 -274.266914) (xy 369.202905 -274.235914) (xy 369.213679 -274.174856)
			(xy 369.234834 -274.116576) (xy 369.249706 -274.089368) (xy 369.256881 -274.075909) (xy 369.263651 -274.046183)
			(xy 369.261353 -274.015782) (xy 369.250193 -273.98741) (xy 369.231163 -273.963591) (xy 369.205956 -273.946443)
			(xy 369.176812 -273.937491) (xy 369.161568 -273.936968) (xy 369.01501 -273.936968) (xy 368.999786 -273.937546)
			(xy 368.970692 -273.946534) (xy 368.945533 -273.963686) (xy 368.926536 -273.987484) (xy 368.915385 -274.015819)
			(xy 368.913067 -274.04618) (xy 368.919788 -274.075879) (xy 368.926872 -274.089368) (xy 368.941768 -274.116565)
			(xy 368.962939 -274.174844) (xy 368.973677 -274.235911) (xy 368.97437 -274.266914) (xy 368.973872 -274.293563)
			(xy 368.965929 -274.346267) (xy 368.950219 -274.397197) (xy 368.927093 -274.445218) (xy 368.897069 -274.489255)
			(xy 368.860817 -274.528326) (xy 368.819146 -274.561557) (xy 368.772988 -274.588206) (xy 368.723374 -274.607678)
			(xy 368.671412 -274.619538) (xy 368.618262 -274.623522) (xy 368.565112 -274.619538) (xy 368.51315 -274.607678)
			(xy 368.463536 -274.588206) (xy 368.417378 -274.561557) (xy 368.375707 -274.528326) (xy 368.339455 -274.489255)
			(xy 368.309431 -274.445218) (xy 368.286305 -274.397197) (xy 368.270595 -274.346267) (xy 368.262652 -274.293563)
			(xy 368.262154 -274.266914) (xy 368.262852 -274.235915) (xy 368.273626 -274.174857) (xy 368.294784 -274.116579)
			(xy 368.309652 -274.089368) (xy 368.31683 -274.075912) (xy 368.323603 -274.046189) (xy 368.321307 -274.01579)
			(xy 368.310146 -273.987422) (xy 368.291113 -273.963609) (xy 368.265902 -273.946469) (xy 368.236758 -273.93753)
			(xy 368.221514 -273.936968) (xy 368.07521 -273.936968) (xy 368.059986 -273.937546) (xy 368.030892 -273.946534)
			(xy 368.005733 -273.963686) (xy 367.986736 -273.987484) (xy 367.975585 -274.015819) (xy 367.973267 -274.04618)
			(xy 367.979988 -274.075879) (xy 367.987072 -274.089368) (xy 368.001968 -274.116565) (xy 368.023139 -274.174844)
			(xy 368.033877 -274.235911) (xy 368.03457 -274.266914) (xy 368.034072 -274.293563) (xy 368.026129 -274.346267)
			(xy 368.010419 -274.397197) (xy 367.987293 -274.445218) (xy 367.957269 -274.489255) (xy 367.921017 -274.528326)
			(xy 367.879346 -274.561557) (xy 367.833188 -274.588206) (xy 367.783574 -274.607678) (xy 367.731612 -274.619538)
			(xy 367.678462 -274.623522) (xy 367.625312 -274.619538) (xy 367.57335 -274.607678) (xy 367.523736 -274.588206)
			(xy 367.477578 -274.561557) (xy 367.435907 -274.528326) (xy 367.399655 -274.489255) (xy 367.369631 -274.445218)
			(xy 367.346505 -274.397197) (xy 367.330795 -274.346267) (xy 367.322852 -274.293563) (xy 367.322354 -274.266914)
			(xy 367.323052 -274.235915) (xy 367.333826 -274.174857) (xy 367.354984 -274.116579) (xy 367.369852 -274.089368)
			(xy 367.37703 -274.075912) (xy 367.383803 -274.046189) (xy 367.381507 -274.01579) (xy 367.370346 -273.987422)
			(xy 367.351313 -273.963609) (xy 367.326102 -273.946469) (xy 367.296958 -273.93753) (xy 367.281714 -273.936968)
			(xy 367.13541 -273.936968) (xy 367.120186 -273.937546) (xy 367.091092 -273.946534) (xy 367.065933 -273.963686)
			(xy 367.046936 -273.987484) (xy 367.035785 -274.015819) (xy 367.033467 -274.04618) (xy 367.040188 -274.075879)
			(xy 367.047272 -274.089368) (xy 367.062168 -274.116565) (xy 367.083339 -274.174844) (xy 367.094077 -274.235911)
			(xy 367.09477 -274.266914) (xy 367.094272 -274.293563) (xy 367.086329 -274.346267) (xy 367.070619 -274.397197)
			(xy 367.047493 -274.445218) (xy 367.017469 -274.489255) (xy 366.981217 -274.528326) (xy 366.939546 -274.561557)
			(xy 366.893388 -274.588206) (xy 366.843774 -274.607678) (xy 366.791812 -274.619538) (xy 366.738662 -274.623522)
			(xy 366.685512 -274.619538) (xy 366.63355 -274.607678) (xy 366.583936 -274.588206) (xy 366.537778 -274.561557)
			(xy 366.496107 -274.528326) (xy 366.459855 -274.489255) (xy 366.429831 -274.445218) (xy 366.406705 -274.397197)
			(xy 366.390995 -274.346267) (xy 366.383052 -274.293563) (xy 366.382554 -274.266914) (xy 366.383252 -274.235915)
			(xy 366.394026 -274.174857) (xy 366.415184 -274.116579) (xy 366.430052 -274.089368) (xy 366.43723 -274.075912)
			(xy 366.444003 -274.046189) (xy 366.441707 -274.01579) (xy 366.430546 -273.987422) (xy 366.411513 -273.963609)
			(xy 366.386302 -273.946469) (xy 366.357158 -273.93753) (xy 366.341914 -273.936968) (xy 366.195864 -273.936968)
			(xy 366.180633 -273.937539) (xy 366.151525 -273.946518) (xy 366.126351 -273.963669) (xy 366.107343 -273.987472)
			(xy 366.096186 -274.015817) (xy 366.093868 -274.04619) (xy 366.100596 -274.075899) (xy 366.107726 -274.089368)
			(xy 366.122624 -274.116565) (xy 366.143797 -274.174843) (xy 366.154537 -274.235911) (xy 366.155224 -274.266914)
			(xy 366.154726 -274.293563) (xy 366.146783 -274.346267) (xy 366.131073 -274.397197) (xy 366.107947 -274.445218)
			(xy 366.077923 -274.489255) (xy 366.041671 -274.528326) (xy 366 -274.561557) (xy 365.953842 -274.588206)
			(xy 365.904228 -274.607678) (xy 365.852266 -274.619538) (xy 365.799116 -274.623522) (xy 365.745966 -274.619538)
			(xy 365.694004 -274.607678) (xy 365.64439 -274.588206) (xy 365.598232 -274.561557) (xy 365.556561 -274.528326)
			(xy 365.520309 -274.489255) (xy 365.490285 -274.445218) (xy 365.467159 -274.397197) (xy 365.451449 -274.346267)
			(xy 365.443506 -274.293563) (xy 365.443008 -274.266914) (xy 365.443705 -274.235914) (xy 365.454479 -274.174856)
			(xy 365.475634 -274.116576) (xy 365.490506 -274.089368) (xy 365.497681 -274.075909) (xy 365.504451 -274.046183)
			(xy 365.502153 -274.015782) (xy 365.490993 -273.98741) (xy 365.471963 -273.963591) (xy 365.446756 -273.946443)
			(xy 365.417612 -273.937491) (xy 365.402368 -273.936968) (xy 365.256064 -273.936968) (xy 365.240833 -273.937539)
			(xy 365.211725 -273.946518) (xy 365.186551 -273.963669) (xy 365.167543 -273.987472) (xy 365.156386 -274.015817)
			(xy 365.154068 -274.04619) (xy 365.160796 -274.075899) (xy 365.167926 -274.089368) (xy 365.182824 -274.116565)
			(xy 365.203997 -274.174843) (xy 365.214737 -274.235911) (xy 365.215424 -274.266914) (xy 365.214926 -274.293563)
			(xy 365.206983 -274.346267) (xy 365.191273 -274.397197) (xy 365.168147 -274.445218) (xy 365.138123 -274.489255)
			(xy 365.101871 -274.528326) (xy 365.0602 -274.561557) (xy 365.014042 -274.588206) (xy 364.964428 -274.607678)
			(xy 364.912466 -274.619538) (xy 364.859316 -274.623522) (xy 364.806166 -274.619538) (xy 364.754204 -274.607678)
			(xy 364.70459 -274.588206) (xy 364.658432 -274.561557) (xy 364.616761 -274.528326) (xy 364.580509 -274.489255)
			(xy 364.550485 -274.445218) (xy 364.527359 -274.397197) (xy 364.511649 -274.346267) (xy 364.503706 -274.293563)
			(xy 364.503208 -274.266914) (xy 364.503905 -274.235914) (xy 364.514679 -274.174856) (xy 364.535834 -274.116576)
			(xy 364.550706 -274.089368) (xy 364.557881 -274.075909) (xy 364.564651 -274.046183) (xy 364.562353 -274.015782)
			(xy 364.551193 -273.98741) (xy 364.532163 -273.963591) (xy 364.506956 -273.946443) (xy 364.477812 -273.937491)
			(xy 364.462568 -273.936968) (xy 364.316264 -273.936968) (xy 364.301033 -273.937539) (xy 364.271925 -273.946518)
			(xy 364.246751 -273.963669) (xy 364.227743 -273.987472) (xy 364.216586 -274.015817) (xy 364.214268 -274.04619)
			(xy 364.220996 -274.075899) (xy 364.228126 -274.089368) (xy 364.243024 -274.116565) (xy 364.264197 -274.174843)
			(xy 364.274937 -274.235911) (xy 364.275624 -274.266914) (xy 364.275126 -274.293563) (xy 364.267183 -274.346267)
			(xy 364.251473 -274.397197) (xy 364.228347 -274.445218) (xy 364.198323 -274.489255) (xy 364.162071 -274.528326)
			(xy 364.1204 -274.561557) (xy 364.074242 -274.588206) (xy 364.024628 -274.607678) (xy 363.972666 -274.619538)
			(xy 363.919516 -274.623522) (xy 363.866366 -274.619538) (xy 363.814404 -274.607678) (xy 363.76479 -274.588206)
			(xy 363.718632 -274.561557) (xy 363.676961 -274.528326) (xy 363.640709 -274.489255) (xy 363.610685 -274.445218)
			(xy 363.587559 -274.397197) (xy 363.571849 -274.346267) (xy 363.563906 -274.293563) (xy 363.563408 -274.266914)
			(xy 363.564105 -274.235914) (xy 363.574879 -274.174856) (xy 363.596034 -274.116576) (xy 363.610906 -274.089368)
			(xy 363.618081 -274.075909) (xy 363.624851 -274.046183) (xy 363.622553 -274.015782) (xy 363.611393 -273.98741)
			(xy 363.592363 -273.963591) (xy 363.567156 -273.946443) (xy 363.538012 -273.937491) (xy 363.522768 -273.936968)
			(xy 363.37621 -273.936968) (xy 363.360986 -273.937546) (xy 363.331892 -273.946534) (xy 363.306733 -273.963686)
			(xy 363.287736 -273.987484) (xy 363.276585 -274.015819) (xy 363.274267 -274.04618) (xy 363.280988 -274.075879)
			(xy 363.288072 -274.089368) (xy 363.302968 -274.116565) (xy 363.324139 -274.174844) (xy 363.334877 -274.235911)
			(xy 363.33557 -274.266914) (xy 363.335048 -274.294898) (xy 363.326291 -274.350175) (xy 363.308993 -274.403402)
			(xy 363.283582 -274.453268) (xy 363.250682 -274.498544) (xy 363.211104 -274.538116) (xy 363.165823 -274.571009)
			(xy 363.115954 -274.596413) (xy 363.062725 -274.613703) (xy 363.007446 -274.622452) (xy 362.979462 -274.623022)
			(xy 362.953489 -274.622555) (xy 362.902094 -274.615015) (xy 362.85234 -274.600086) (xy 362.805283 -274.578085)
			(xy 362.761924 -274.54948) (xy 362.723181 -274.514877) (xy 362.689879 -274.475011) (xy 362.675932 -274.453096)
			(xy 362.667468 -274.44031) (xy 362.644411 -274.420115) (xy 362.616406 -274.407658) (xy 362.585968 -274.404056)
			(xy 362.555829 -274.409632) (xy 362.528695 -274.423886) (xy 362.517436 -274.4343) (xy 362.318808 -274.632928)
			(xy 362.318808 -274.74926) (xy 362.378498 -274.74926) (xy 362.387134 -274.746212) (xy 362.416662 -274.736116)
			(xy 362.478108 -274.72526) (xy 362.509308 -274.724622) (xy 362.535955 -274.725121) (xy 362.588653 -274.733065)
			(xy 362.639578 -274.748774) (xy 362.687593 -274.771898) (xy 362.731626 -274.80192) (xy 362.770692 -274.838169)
			(xy 362.803919 -274.879836) (xy 362.830566 -274.925989) (xy 362.850036 -274.975599) (xy 362.861894 -275.027556)
			(xy 362.865877 -275.0807) (xy 362.863877 -275.107379) (xy 363.093498 -275.107379) (xy 363.093498 -275.054081)
			(xy 363.101441 -275.001377) (xy 363.117151 -274.950447) (xy 363.140277 -274.902426) (xy 363.170301 -274.858389)
			(xy 363.206553 -274.819318) (xy 363.248224 -274.786087) (xy 363.294382 -274.759438) (xy 363.343996 -274.739966)
			(xy 363.395958 -274.728106) (xy 363.449108 -274.724123) (xy 363.502258 -274.728106) (xy 363.55422 -274.739966)
			(xy 363.603834 -274.759438) (xy 363.649992 -274.786087) (xy 363.691663 -274.819318) (xy 363.727915 -274.858389)
			(xy 363.757939 -274.902426) (xy 363.781065 -274.950447) (xy 363.796775 -275.001377) (xy 363.804718 -275.054081)
			(xy 363.805216 -275.08073) (xy 363.804718 -275.107379) (xy 364.033552 -275.107379) (xy 364.033552 -275.054081)
			(xy 364.041495 -275.001377) (xy 364.057205 -274.950447) (xy 364.080331 -274.902426) (xy 364.110355 -274.858389)
			(xy 364.146607 -274.819318) (xy 364.188278 -274.786087) (xy 364.234436 -274.759438) (xy 364.28405 -274.739966)
			(xy 364.336012 -274.728106) (xy 364.389162 -274.724123) (xy 364.442312 -274.728106) (xy 364.494274 -274.739966)
			(xy 364.543888 -274.759438) (xy 364.590046 -274.786087) (xy 364.631717 -274.819318) (xy 364.667969 -274.858389)
			(xy 364.697993 -274.902426) (xy 364.721119 -274.950447) (xy 364.736829 -275.001377) (xy 364.744772 -275.054081)
			(xy 364.74527 -275.08073) (xy 364.744772 -275.107379) (xy 367.793006 -275.107379) (xy 367.793006 -275.054081)
			(xy 367.800949 -275.001377) (xy 367.816659 -274.950447) (xy 367.839785 -274.902426) (xy 367.869809 -274.858389)
			(xy 367.906061 -274.819318) (xy 367.947732 -274.786087) (xy 367.99389 -274.759438) (xy 368.043504 -274.739966)
			(xy 368.095466 -274.728106) (xy 368.148616 -274.724123) (xy 368.201766 -274.728106) (xy 368.253728 -274.739966)
			(xy 368.303342 -274.759438) (xy 368.3495 -274.786087) (xy 368.391171 -274.819318) (xy 368.427423 -274.858389)
			(xy 368.457447 -274.902426) (xy 368.480573 -274.950447) (xy 368.496283 -275.001377) (xy 368.504226 -275.054081)
			(xy 368.504724 -275.08073) (xy 368.504231 -275.107125) (xy 368.732552 -275.107125) (xy 368.732552 -275.053827)
			(xy 368.740495 -275.001123) (xy 368.756205 -274.950193) (xy 368.779331 -274.902172) (xy 368.809355 -274.858135)
			(xy 368.845607 -274.819064) (xy 368.887278 -274.785833) (xy 368.933436 -274.759184) (xy 368.98305 -274.739712)
			(xy 369.035012 -274.727852) (xy 369.088162 -274.723869) (xy 369.141312 -274.727852) (xy 369.193274 -274.739712)
			(xy 369.242888 -274.759184) (xy 369.289046 -274.785833) (xy 369.330717 -274.819064) (xy 369.366969 -274.858135)
			(xy 369.396993 -274.902172) (xy 369.420119 -274.950193) (xy 369.435829 -275.001123) (xy 369.443772 -275.053827)
			(xy 369.44427 -275.080476) (xy 369.443772 -275.107125) (xy 369.443734 -275.107379) (xy 369.672606 -275.107379)
			(xy 369.672606 -275.054081) (xy 369.680549 -275.001377) (xy 369.696259 -274.950447) (xy 369.719385 -274.902426)
			(xy 369.749409 -274.858389) (xy 369.785661 -274.819318) (xy 369.827332 -274.786087) (xy 369.87349 -274.759438)
			(xy 369.923104 -274.739966) (xy 369.975066 -274.728106) (xy 370.028216 -274.724123) (xy 370.081366 -274.728106)
			(xy 370.133328 -274.739966) (xy 370.182942 -274.759438) (xy 370.2291 -274.786087) (xy 370.270771 -274.819318)
			(xy 370.307023 -274.858389) (xy 370.337047 -274.902426) (xy 370.360173 -274.950447) (xy 370.375883 -275.001377)
			(xy 370.383826 -275.054081) (xy 370.384324 -275.08073) (xy 370.383826 -275.107379) (xy 370.612406 -275.107379)
			(xy 370.612406 -275.054081) (xy 370.620349 -275.001377) (xy 370.636059 -274.950447) (xy 370.659185 -274.902426)
			(xy 370.689209 -274.858389) (xy 370.725461 -274.819318) (xy 370.767132 -274.786087) (xy 370.81329 -274.759438)
			(xy 370.862904 -274.739966) (xy 370.914866 -274.728106) (xy 370.968016 -274.724123) (xy 371.021166 -274.728106)
			(xy 371.073128 -274.739966) (xy 371.122742 -274.759438) (xy 371.1689 -274.786087) (xy 371.210571 -274.819318)
			(xy 371.246823 -274.858389) (xy 371.276847 -274.902426) (xy 371.299973 -274.950447) (xy 371.315683 -275.001377)
			(xy 371.323626 -275.054081) (xy 371.324124 -275.08073) (xy 371.323626 -275.107379) (xy 371.552206 -275.107379)
			(xy 371.552206 -275.054081) (xy 371.560149 -275.001377) (xy 371.575859 -274.950447) (xy 371.598985 -274.902426)
			(xy 371.629009 -274.858389) (xy 371.665261 -274.819318) (xy 371.706932 -274.786087) (xy 371.75309 -274.759438)
			(xy 371.802704 -274.739966) (xy 371.854666 -274.728106) (xy 371.907816 -274.724123) (xy 371.960966 -274.728106)
			(xy 372.012928 -274.739966) (xy 372.062542 -274.759438) (xy 372.1087 -274.786087) (xy 372.150371 -274.819318)
			(xy 372.186623 -274.858389) (xy 372.216647 -274.902426) (xy 372.239773 -274.950447) (xy 372.255483 -275.001377)
			(xy 372.263426 -275.054081) (xy 372.263924 -275.08073) (xy 372.263426 -275.107379) (xy 372.492006 -275.107379)
			(xy 372.492006 -275.054081) (xy 372.499949 -275.001377) (xy 372.515659 -274.950447) (xy 372.538785 -274.902426)
			(xy 372.568809 -274.858389) (xy 372.605061 -274.819318) (xy 372.646732 -274.786087) (xy 372.69289 -274.759438)
			(xy 372.742504 -274.739966) (xy 372.794466 -274.728106) (xy 372.847616 -274.724123) (xy 372.900766 -274.728106)
			(xy 372.952728 -274.739966) (xy 373.002342 -274.759438) (xy 373.0485 -274.786087) (xy 373.090171 -274.819318)
			(xy 373.126423 -274.858389) (xy 373.156447 -274.902426) (xy 373.179573 -274.950447) (xy 373.195283 -275.001377)
			(xy 373.203226 -275.054081) (xy 373.203724 -275.08073) (xy 373.203226 -275.107379) (xy 373.431806 -275.107379)
			(xy 373.431806 -275.054081) (xy 373.439749 -275.001377) (xy 373.455459 -274.950447) (xy 373.478585 -274.902426)
			(xy 373.508609 -274.858389) (xy 373.544861 -274.819318) (xy 373.586532 -274.786087) (xy 373.63269 -274.759438)
			(xy 373.682304 -274.739966) (xy 373.734266 -274.728106) (xy 373.787416 -274.724123) (xy 373.840566 -274.728106)
			(xy 373.892528 -274.739966) (xy 373.942142 -274.759438) (xy 373.9883 -274.786087) (xy 374.029971 -274.819318)
			(xy 374.066223 -274.858389) (xy 374.096247 -274.902426) (xy 374.119373 -274.950447) (xy 374.135083 -275.001377)
			(xy 374.143026 -275.054081) (xy 374.143524 -275.08073) (xy 374.143026 -275.107379) (xy 374.371352 -275.107379)
			(xy 374.371352 -275.054081) (xy 374.379295 -275.001377) (xy 374.395005 -274.950447) (xy 374.418131 -274.902426)
			(xy 374.448155 -274.858389) (xy 374.484407 -274.819318) (xy 374.526078 -274.786087) (xy 374.572236 -274.759438)
			(xy 374.62185 -274.739966) (xy 374.673812 -274.728106) (xy 374.726962 -274.724123) (xy 374.780112 -274.728106)
			(xy 374.832074 -274.739966) (xy 374.881688 -274.759438) (xy 374.927846 -274.786087) (xy 374.969517 -274.819318)
			(xy 375.005769 -274.858389) (xy 375.035793 -274.902426) (xy 375.058919 -274.950447) (xy 375.074629 -275.001377)
			(xy 375.082572 -275.054081) (xy 375.08307 -275.08073) (xy 375.082572 -275.107379) (xy 375.311406 -275.107379)
			(xy 375.311406 -275.054081) (xy 375.319349 -275.001377) (xy 375.335059 -274.950447) (xy 375.358185 -274.902426)
			(xy 375.388209 -274.858389) (xy 375.424461 -274.819318) (xy 375.466132 -274.786087) (xy 375.51229 -274.759438)
			(xy 375.561904 -274.739966) (xy 375.613866 -274.728106) (xy 375.667016 -274.724123) (xy 375.720166 -274.728106)
			(xy 375.772128 -274.739966) (xy 375.821742 -274.759438) (xy 375.8679 -274.786087) (xy 375.909571 -274.819318)
			(xy 375.945823 -274.858389) (xy 375.975847 -274.902426) (xy 375.998973 -274.950447) (xy 376.014683 -275.001377)
			(xy 376.022626 -275.054081) (xy 376.023124 -275.08073) (xy 376.022626 -275.107379) (xy 376.251206 -275.107379)
			(xy 376.251206 -275.054081) (xy 376.259149 -275.001377) (xy 376.274859 -274.950447) (xy 376.297985 -274.902426)
			(xy 376.328009 -274.858389) (xy 376.364261 -274.819318) (xy 376.405932 -274.786087) (xy 376.45209 -274.759438)
			(xy 376.501704 -274.739966) (xy 376.553666 -274.728106) (xy 376.606816 -274.724123) (xy 376.659966 -274.728106)
			(xy 376.711928 -274.739966) (xy 376.761542 -274.759438) (xy 376.8077 -274.786087) (xy 376.849371 -274.819318)
			(xy 376.885623 -274.858389) (xy 376.915647 -274.902426) (xy 376.938773 -274.950447) (xy 376.954483 -275.001377)
			(xy 376.962426 -275.054081) (xy 376.962924 -275.08073) (xy 376.962426 -275.107379) (xy 377.191006 -275.107379)
			(xy 377.191006 -275.054081) (xy 377.198949 -275.001377) (xy 377.214659 -274.950447) (xy 377.237785 -274.902426)
			(xy 377.267809 -274.858389) (xy 377.304061 -274.819318) (xy 377.345732 -274.786087) (xy 377.39189 -274.759438)
			(xy 377.441504 -274.739966) (xy 377.493466 -274.728106) (xy 377.546616 -274.724123) (xy 377.599766 -274.728106)
			(xy 377.651728 -274.739966) (xy 377.701342 -274.759438) (xy 377.7475 -274.786087) (xy 377.789171 -274.819318)
			(xy 377.825423 -274.858389) (xy 377.855447 -274.902426) (xy 377.878573 -274.950447) (xy 377.894283 -275.001377)
			(xy 377.902226 -275.054081) (xy 377.902724 -275.08073) (xy 377.902226 -275.107379) (xy 378.130806 -275.107379)
			(xy 378.130806 -275.054081) (xy 378.138749 -275.001377) (xy 378.154459 -274.950447) (xy 378.177585 -274.902426)
			(xy 378.207609 -274.858389) (xy 378.243861 -274.819318) (xy 378.285532 -274.786087) (xy 378.33169 -274.759438)
			(xy 378.381304 -274.739966) (xy 378.433266 -274.728106) (xy 378.486416 -274.724123) (xy 378.539566 -274.728106)
			(xy 378.591528 -274.739966) (xy 378.641142 -274.759438) (xy 378.6873 -274.786087) (xy 378.728971 -274.819318)
			(xy 378.765223 -274.858389) (xy 378.795247 -274.902426) (xy 378.818373 -274.950447) (xy 378.834083 -275.001377)
			(xy 378.842026 -275.054081) (xy 378.842524 -275.08073) (xy 378.842026 -275.107379) (xy 378.834083 -275.160083)
			(xy 378.818373 -275.211013) (xy 378.795247 -275.259034) (xy 378.765223 -275.303071) (xy 378.728971 -275.342142)
			(xy 378.6873 -275.375373) (xy 378.641142 -275.402022) (xy 378.591528 -275.421494) (xy 378.539566 -275.433354)
			(xy 378.486416 -275.437338) (xy 378.433266 -275.433354) (xy 378.381304 -275.421494) (xy 378.33169 -275.402022)
			(xy 378.285532 -275.375373) (xy 378.243861 -275.342142) (xy 378.207609 -275.303071) (xy 378.177585 -275.259034)
			(xy 378.154459 -275.211013) (xy 378.138749 -275.160083) (xy 378.130806 -275.107379) (xy 377.902226 -275.107379)
			(xy 377.894283 -275.160083) (xy 377.878573 -275.211013) (xy 377.855447 -275.259034) (xy 377.825423 -275.303071)
			(xy 377.789171 -275.342142) (xy 377.7475 -275.375373) (xy 377.701342 -275.402022) (xy 377.651728 -275.421494)
			(xy 377.599766 -275.433354) (xy 377.546616 -275.437338) (xy 377.493466 -275.433354) (xy 377.441504 -275.421494)
			(xy 377.39189 -275.402022) (xy 377.345732 -275.375373) (xy 377.304061 -275.342142) (xy 377.267809 -275.303071)
			(xy 377.237785 -275.259034) (xy 377.214659 -275.211013) (xy 377.198949 -275.160083) (xy 377.191006 -275.107379)
			(xy 376.962426 -275.107379) (xy 376.954483 -275.160083) (xy 376.938773 -275.211013) (xy 376.915647 -275.259034)
			(xy 376.885623 -275.303071) (xy 376.849371 -275.342142) (xy 376.8077 -275.375373) (xy 376.761542 -275.402022)
			(xy 376.711928 -275.421494) (xy 376.659966 -275.433354) (xy 376.606816 -275.437338) (xy 376.553666 -275.433354)
			(xy 376.501704 -275.421494) (xy 376.45209 -275.402022) (xy 376.405932 -275.375373) (xy 376.364261 -275.342142)
			(xy 376.328009 -275.303071) (xy 376.297985 -275.259034) (xy 376.274859 -275.211013) (xy 376.259149 -275.160083)
			(xy 376.251206 -275.107379) (xy 376.022626 -275.107379) (xy 376.014683 -275.160083) (xy 375.998973 -275.211013)
			(xy 375.975847 -275.259034) (xy 375.945823 -275.303071) (xy 375.909571 -275.342142) (xy 375.8679 -275.375373)
			(xy 375.821742 -275.402022) (xy 375.772128 -275.421494) (xy 375.720166 -275.433354) (xy 375.667016 -275.437338)
			(xy 375.613866 -275.433354) (xy 375.561904 -275.421494) (xy 375.51229 -275.402022) (xy 375.466132 -275.375373)
			(xy 375.424461 -275.342142) (xy 375.388209 -275.303071) (xy 375.358185 -275.259034) (xy 375.335059 -275.211013)
			(xy 375.319349 -275.160083) (xy 375.311406 -275.107379) (xy 375.082572 -275.107379) (xy 375.074629 -275.160083)
			(xy 375.058919 -275.211013) (xy 375.035793 -275.259034) (xy 375.005769 -275.303071) (xy 374.969517 -275.342142)
			(xy 374.927846 -275.375373) (xy 374.881688 -275.402022) (xy 374.832074 -275.421494) (xy 374.780112 -275.433354)
			(xy 374.726962 -275.437338) (xy 374.673812 -275.433354) (xy 374.62185 -275.421494) (xy 374.572236 -275.402022)
			(xy 374.526078 -275.375373) (xy 374.484407 -275.342142) (xy 374.448155 -275.303071) (xy 374.418131 -275.259034)
			(xy 374.395005 -275.211013) (xy 374.379295 -275.160083) (xy 374.371352 -275.107379) (xy 374.143026 -275.107379)
			(xy 374.135083 -275.160083) (xy 374.119373 -275.211013) (xy 374.096247 -275.259034) (xy 374.066223 -275.303071)
			(xy 374.029971 -275.342142) (xy 373.9883 -275.375373) (xy 373.942142 -275.402022) (xy 373.892528 -275.421494)
			(xy 373.840566 -275.433354) (xy 373.787416 -275.437338) (xy 373.734266 -275.433354) (xy 373.682304 -275.421494)
			(xy 373.63269 -275.402022) (xy 373.586532 -275.375373) (xy 373.544861 -275.342142) (xy 373.508609 -275.303071)
			(xy 373.478585 -275.259034) (xy 373.455459 -275.211013) (xy 373.439749 -275.160083) (xy 373.431806 -275.107379)
			(xy 373.203226 -275.107379) (xy 373.195283 -275.160083) (xy 373.179573 -275.211013) (xy 373.156447 -275.259034)
			(xy 373.126423 -275.303071) (xy 373.090171 -275.342142) (xy 373.0485 -275.375373) (xy 373.002342 -275.402022)
			(xy 372.952728 -275.421494) (xy 372.900766 -275.433354) (xy 372.847616 -275.437338) (xy 372.794466 -275.433354)
			(xy 372.742504 -275.421494) (xy 372.69289 -275.402022) (xy 372.646732 -275.375373) (xy 372.605061 -275.342142)
			(xy 372.568809 -275.303071) (xy 372.538785 -275.259034) (xy 372.515659 -275.211013) (xy 372.499949 -275.160083)
			(xy 372.492006 -275.107379) (xy 372.263426 -275.107379) (xy 372.255483 -275.160083) (xy 372.239773 -275.211013)
			(xy 372.216647 -275.259034) (xy 372.186623 -275.303071) (xy 372.150371 -275.342142) (xy 372.1087 -275.375373)
			(xy 372.062542 -275.402022) (xy 372.012928 -275.421494) (xy 371.960966 -275.433354) (xy 371.907816 -275.437338)
			(xy 371.854666 -275.433354) (xy 371.802704 -275.421494) (xy 371.75309 -275.402022) (xy 371.706932 -275.375373)
			(xy 371.665261 -275.342142) (xy 371.629009 -275.303071) (xy 371.598985 -275.259034) (xy 371.575859 -275.211013)
			(xy 371.560149 -275.160083) (xy 371.552206 -275.107379) (xy 371.323626 -275.107379) (xy 371.315683 -275.160083)
			(xy 371.299973 -275.211013) (xy 371.276847 -275.259034) (xy 371.246823 -275.303071) (xy 371.210571 -275.342142)
			(xy 371.1689 -275.375373) (xy 371.122742 -275.402022) (xy 371.073128 -275.421494) (xy 371.021166 -275.433354)
			(xy 370.968016 -275.437338) (xy 370.914866 -275.433354) (xy 370.862904 -275.421494) (xy 370.81329 -275.402022)
			(xy 370.767132 -275.375373) (xy 370.725461 -275.342142) (xy 370.689209 -275.303071) (xy 370.659185 -275.259034)
			(xy 370.636059 -275.211013) (xy 370.620349 -275.160083) (xy 370.612406 -275.107379) (xy 370.383826 -275.107379)
			(xy 370.375883 -275.160083) (xy 370.360173 -275.211013) (xy 370.337047 -275.259034) (xy 370.307023 -275.303071)
			(xy 370.270771 -275.342142) (xy 370.2291 -275.375373) (xy 370.182942 -275.402022) (xy 370.133328 -275.421494)
			(xy 370.081366 -275.433354) (xy 370.028216 -275.437338) (xy 369.975066 -275.433354) (xy 369.923104 -275.421494)
			(xy 369.87349 -275.402022) (xy 369.827332 -275.375373) (xy 369.785661 -275.342142) (xy 369.749409 -275.303071)
			(xy 369.719385 -275.259034) (xy 369.696259 -275.211013) (xy 369.680549 -275.160083) (xy 369.672606 -275.107379)
			(xy 369.443734 -275.107379) (xy 369.435829 -275.159829) (xy 369.420119 -275.210759) (xy 369.396993 -275.25878)
			(xy 369.366969 -275.302817) (xy 369.330717 -275.341888) (xy 369.289046 -275.375119) (xy 369.242888 -275.401768)
			(xy 369.193274 -275.42124) (xy 369.141312 -275.4331) (xy 369.088162 -275.437084) (xy 369.035012 -275.4331)
			(xy 368.98305 -275.42124) (xy 368.933436 -275.401768) (xy 368.887278 -275.375119) (xy 368.845607 -275.341888)
			(xy 368.809355 -275.302817) (xy 368.779331 -275.25878) (xy 368.756205 -275.210759) (xy 368.740495 -275.159829)
			(xy 368.732552 -275.107125) (xy 368.504231 -275.107125) (xy 368.504226 -275.107379) (xy 368.496283 -275.160083)
			(xy 368.480573 -275.211013) (xy 368.457447 -275.259034) (xy 368.427423 -275.303071) (xy 368.391171 -275.342142)
			(xy 368.3495 -275.375373) (xy 368.303342 -275.402022) (xy 368.253728 -275.421494) (xy 368.201766 -275.433354)
			(xy 368.148616 -275.437338) (xy 368.095466 -275.433354) (xy 368.043504 -275.421494) (xy 367.99389 -275.402022)
			(xy 367.947732 -275.375373) (xy 367.906061 -275.342142) (xy 367.869809 -275.303071) (xy 367.839785 -275.259034)
			(xy 367.816659 -275.211013) (xy 367.800949 -275.160083) (xy 367.793006 -275.107379) (xy 364.744772 -275.107379)
			(xy 364.736829 -275.160083) (xy 364.721119 -275.211013) (xy 364.697993 -275.259034) (xy 364.667969 -275.303071)
			(xy 364.631717 -275.342142) (xy 364.590046 -275.375373) (xy 364.543888 -275.402022) (xy 364.494274 -275.421494)
			(xy 364.442312 -275.433354) (xy 364.389162 -275.437338) (xy 364.336012 -275.433354) (xy 364.28405 -275.421494)
			(xy 364.234436 -275.402022) (xy 364.188278 -275.375373) (xy 364.146607 -275.342142) (xy 364.110355 -275.303071)
			(xy 364.080331 -275.259034) (xy 364.057205 -275.211013) (xy 364.041495 -275.160083) (xy 364.033552 -275.107379)
			(xy 363.804718 -275.107379) (xy 363.796775 -275.160083) (xy 363.781065 -275.211013) (xy 363.757939 -275.259034)
			(xy 363.727915 -275.303071) (xy 363.691663 -275.342142) (xy 363.649992 -275.375373) (xy 363.603834 -275.402022)
			(xy 363.55422 -275.421494) (xy 363.502258 -275.433354) (xy 363.449108 -275.437338) (xy 363.395958 -275.433354)
			(xy 363.343996 -275.421494) (xy 363.294382 -275.402022) (xy 363.248224 -275.375373) (xy 363.206553 -275.342142)
			(xy 363.170301 -275.303071) (xy 363.140277 -275.259034) (xy 363.117151 -275.211013) (xy 363.101441 -275.160083)
			(xy 363.093498 -275.107379) (xy 362.863877 -275.107379) (xy 362.861894 -275.133844) (xy 362.850036 -275.185801)
			(xy 362.830566 -275.235411) (xy 362.803919 -275.281564) (xy 362.770692 -275.323231) (xy 362.731626 -275.35948)
			(xy 362.687593 -275.389502) (xy 362.639578 -275.412626) (xy 362.588653 -275.428335) (xy 362.535955 -275.436279)
			(xy 362.509308 -275.436838) (xy 362.491921 -275.436601) (xy 362.457316 -275.433161) (xy 362.44022 -275.42998)
			(xy 362.425394 -275.427577) (xy 362.395521 -275.430529) (xy 362.367791 -275.442028) (xy 362.344597 -275.461086)
			(xy 362.327937 -275.486058) (xy 362.319248 -275.514792) (xy 362.318808 -275.529802) (xy 362.318808 -275.673312)
			(xy 362.336912 -275.697111) (xy 362.365738 -275.749495) (xy 362.385423 -275.805953) (xy 362.395414 -275.864904)
			(xy 362.396024 -275.8948) (xy 362.395518 -275.921263) (xy 362.39549 -275.921449) (xy 363.563652 -275.921449)
			(xy 363.563652 -275.868151) (xy 363.571595 -275.815447) (xy 363.587305 -275.764517) (xy 363.610431 -275.716496)
			(xy 363.640455 -275.672459) (xy 363.676707 -275.633388) (xy 363.718378 -275.600157) (xy 363.764536 -275.573508)
			(xy 363.81415 -275.554036) (xy 363.866112 -275.542176) (xy 363.919262 -275.538193) (xy 363.972412 -275.542176)
			(xy 364.024374 -275.554036) (xy 364.073988 -275.573508) (xy 364.120146 -275.600157) (xy 364.161817 -275.633388)
			(xy 364.198069 -275.672459) (xy 364.228093 -275.716496) (xy 364.251219 -275.764517) (xy 364.266929 -275.815447)
			(xy 364.274872 -275.868151) (xy 364.27537 -275.8948) (xy 364.274877 -275.921195) (xy 364.503706 -275.921195)
			(xy 364.503706 -275.867897) (xy 364.511649 -275.815193) (xy 364.527359 -275.764263) (xy 364.550485 -275.716242)
			(xy 364.580509 -275.672205) (xy 364.616761 -275.633134) (xy 364.658432 -275.599903) (xy 364.70459 -275.573254)
			(xy 364.754204 -275.553782) (xy 364.806166 -275.541922) (xy 364.859316 -275.537939) (xy 364.912466 -275.541922)
			(xy 364.964428 -275.553782) (xy 365.014042 -275.573254) (xy 365.0602 -275.599903) (xy 365.101871 -275.633134)
			(xy 365.138123 -275.672205) (xy 365.168147 -275.716242) (xy 365.191273 -275.764263) (xy 365.206983 -275.815193)
			(xy 365.214926 -275.867897) (xy 365.215424 -275.894546) (xy 365.214926 -275.921195) (xy 365.214888 -275.921449)
			(xy 365.443252 -275.921449) (xy 365.443252 -275.868151) (xy 365.451195 -275.815447) (xy 365.466905 -275.764517)
			(xy 365.490031 -275.716496) (xy 365.520055 -275.672459) (xy 365.556307 -275.633388) (xy 365.597978 -275.600157)
			(xy 365.644136 -275.573508) (xy 365.69375 -275.554036) (xy 365.745712 -275.542176) (xy 365.798862 -275.538193)
			(xy 365.852012 -275.542176) (xy 365.903974 -275.554036) (xy 365.953588 -275.573508) (xy 365.999746 -275.600157)
			(xy 366.041417 -275.633388) (xy 366.077669 -275.672459) (xy 366.107693 -275.716496) (xy 366.130819 -275.764517)
			(xy 366.146529 -275.815447) (xy 366.154472 -275.868151) (xy 366.15497 -275.8948) (xy 366.154472 -275.921449)
			(xy 366.383306 -275.921449) (xy 366.383306 -275.868151) (xy 366.391249 -275.815447) (xy 366.406959 -275.764517)
			(xy 366.430085 -275.716496) (xy 366.460109 -275.672459) (xy 366.496361 -275.633388) (xy 366.538032 -275.600157)
			(xy 366.58419 -275.573508) (xy 366.633804 -275.554036) (xy 366.685766 -275.542176) (xy 366.738916 -275.538193)
			(xy 366.792066 -275.542176) (xy 366.844028 -275.554036) (xy 366.893642 -275.573508) (xy 366.9398 -275.600157)
			(xy 366.981471 -275.633388) (xy 367.017723 -275.672459) (xy 367.047747 -275.716496) (xy 367.070873 -275.764517)
			(xy 367.086583 -275.815447) (xy 367.094526 -275.868151) (xy 367.095024 -275.8948) (xy 367.094531 -275.921195)
			(xy 367.323106 -275.921195) (xy 367.323106 -275.867897) (xy 367.331049 -275.815193) (xy 367.346759 -275.764263)
			(xy 367.369885 -275.716242) (xy 367.399909 -275.672205) (xy 367.436161 -275.633134) (xy 367.477832 -275.599903)
			(xy 367.52399 -275.573254) (xy 367.573604 -275.553782) (xy 367.625566 -275.541922) (xy 367.678716 -275.537939)
			(xy 367.731866 -275.541922) (xy 367.783828 -275.553782) (xy 367.833442 -275.573254) (xy 367.8796 -275.599903)
			(xy 367.921271 -275.633134) (xy 367.957523 -275.672205) (xy 367.987547 -275.716242) (xy 368.010673 -275.764263)
			(xy 368.026383 -275.815193) (xy 368.034326 -275.867897) (xy 368.034824 -275.894546) (xy 368.034326 -275.921195)
			(xy 368.262906 -275.921195) (xy 368.262906 -275.867897) (xy 368.270849 -275.815193) (xy 368.286559 -275.764263)
			(xy 368.309685 -275.716242) (xy 368.339709 -275.672205) (xy 368.375961 -275.633134) (xy 368.417632 -275.599903)
			(xy 368.46379 -275.573254) (xy 368.513404 -275.553782) (xy 368.565366 -275.541922) (xy 368.618516 -275.537939)
			(xy 368.671666 -275.541922) (xy 368.723628 -275.553782) (xy 368.773242 -275.573254) (xy 368.8194 -275.599903)
			(xy 368.861071 -275.633134) (xy 368.897323 -275.672205) (xy 368.927347 -275.716242) (xy 368.950473 -275.764263)
			(xy 368.966183 -275.815193) (xy 368.974126 -275.867897) (xy 368.974624 -275.894546) (xy 368.974126 -275.921195)
			(xy 369.202706 -275.921195) (xy 369.202706 -275.867897) (xy 369.210649 -275.815193) (xy 369.226359 -275.764263)
			(xy 369.249485 -275.716242) (xy 369.279509 -275.672205) (xy 369.315761 -275.633134) (xy 369.357432 -275.599903)
			(xy 369.40359 -275.573254) (xy 369.453204 -275.553782) (xy 369.505166 -275.541922) (xy 369.558316 -275.537939)
			(xy 369.611466 -275.541922) (xy 369.663428 -275.553782) (xy 369.713042 -275.573254) (xy 369.7592 -275.599903)
			(xy 369.800871 -275.633134) (xy 369.837123 -275.672205) (xy 369.867147 -275.716242) (xy 369.890273 -275.764263)
			(xy 369.905983 -275.815193) (xy 369.913926 -275.867897) (xy 369.914424 -275.894546) (xy 369.913926 -275.921195)
			(xy 369.913888 -275.921449) (xy 370.142506 -275.921449) (xy 370.142506 -275.868151) (xy 370.150449 -275.815447)
			(xy 370.166159 -275.764517) (xy 370.189285 -275.716496) (xy 370.219309 -275.672459) (xy 370.255561 -275.633388)
			(xy 370.297232 -275.600157) (xy 370.34339 -275.573508) (xy 370.393004 -275.554036) (xy 370.444966 -275.542176)
			(xy 370.498116 -275.538193) (xy 370.551266 -275.542176) (xy 370.603228 -275.554036) (xy 370.652842 -275.573508)
			(xy 370.699 -275.600157) (xy 370.740671 -275.633388) (xy 370.776923 -275.672459) (xy 370.806947 -275.716496)
			(xy 370.830073 -275.764517) (xy 370.845783 -275.815447) (xy 370.853726 -275.868151) (xy 370.854224 -275.8948)
			(xy 370.853726 -275.921449) (xy 371.082052 -275.921449) (xy 371.082052 -275.868151) (xy 371.089995 -275.815447)
			(xy 371.105705 -275.764517) (xy 371.128831 -275.716496) (xy 371.158855 -275.672459) (xy 371.195107 -275.633388)
			(xy 371.236778 -275.600157) (xy 371.282936 -275.573508) (xy 371.33255 -275.554036) (xy 371.384512 -275.542176)
			(xy 371.437662 -275.538193) (xy 371.490812 -275.542176) (xy 371.542774 -275.554036) (xy 371.592388 -275.573508)
			(xy 371.638546 -275.600157) (xy 371.680217 -275.633388) (xy 371.716469 -275.672459) (xy 371.746493 -275.716496)
			(xy 371.769619 -275.764517) (xy 371.785329 -275.815447) (xy 371.793272 -275.868151) (xy 371.79377 -275.8948)
			(xy 371.793272 -275.921449) (xy 372.021852 -275.921449) (xy 372.021852 -275.868151) (xy 372.029795 -275.815447)
			(xy 372.045505 -275.764517) (xy 372.068631 -275.716496) (xy 372.098655 -275.672459) (xy 372.134907 -275.633388)
			(xy 372.176578 -275.600157) (xy 372.222736 -275.573508) (xy 372.27235 -275.554036) (xy 372.324312 -275.542176)
			(xy 372.377462 -275.538193) (xy 372.430612 -275.542176) (xy 372.482574 -275.554036) (xy 372.532188 -275.573508)
			(xy 372.578346 -275.600157) (xy 372.620017 -275.633388) (xy 372.656269 -275.672459) (xy 372.686293 -275.716496)
			(xy 372.709419 -275.764517) (xy 372.725129 -275.815447) (xy 372.733072 -275.868151) (xy 372.73357 -275.8948)
			(xy 372.733072 -275.921449) (xy 372.961652 -275.921449) (xy 372.961652 -275.868151) (xy 372.969595 -275.815447)
			(xy 372.985305 -275.764517) (xy 373.008431 -275.716496) (xy 373.038455 -275.672459) (xy 373.074707 -275.633388)
			(xy 373.116378 -275.600157) (xy 373.162536 -275.573508) (xy 373.21215 -275.554036) (xy 373.264112 -275.542176)
			(xy 373.317262 -275.538193) (xy 373.370412 -275.542176) (xy 373.422374 -275.554036) (xy 373.471988 -275.573508)
			(xy 373.518146 -275.600157) (xy 373.559817 -275.633388) (xy 373.596069 -275.672459) (xy 373.626093 -275.716496)
			(xy 373.649219 -275.764517) (xy 373.664929 -275.815447) (xy 373.672872 -275.868151) (xy 373.67337 -275.8948)
			(xy 373.672872 -275.921449) (xy 373.901452 -275.921449) (xy 373.901452 -275.868151) (xy 373.909395 -275.815447)
			(xy 373.925105 -275.764517) (xy 373.948231 -275.716496) (xy 373.978255 -275.672459) (xy 374.014507 -275.633388)
			(xy 374.056178 -275.600157) (xy 374.102336 -275.573508) (xy 374.15195 -275.554036) (xy 374.203912 -275.542176)
			(xy 374.257062 -275.538193) (xy 374.310212 -275.542176) (xy 374.362174 -275.554036) (xy 374.411788 -275.573508)
			(xy 374.457946 -275.600157) (xy 374.499617 -275.633388) (xy 374.535869 -275.672459) (xy 374.565893 -275.716496)
			(xy 374.589019 -275.764517) (xy 374.604729 -275.815447) (xy 374.612672 -275.868151) (xy 374.61317 -275.8948)
			(xy 374.612672 -275.921449) (xy 374.841252 -275.921449) (xy 374.841252 -275.868151) (xy 374.849195 -275.815447)
			(xy 374.864905 -275.764517) (xy 374.888031 -275.716496) (xy 374.918055 -275.672459) (xy 374.954307 -275.633388)
			(xy 374.995978 -275.600157) (xy 375.042136 -275.573508) (xy 375.09175 -275.554036) (xy 375.143712 -275.542176)
			(xy 375.196862 -275.538193) (xy 375.250012 -275.542176) (xy 375.301974 -275.554036) (xy 375.351588 -275.573508)
			(xy 375.397746 -275.600157) (xy 375.439417 -275.633388) (xy 375.475669 -275.672459) (xy 375.505693 -275.716496)
			(xy 375.528819 -275.764517) (xy 375.544529 -275.815447) (xy 375.552472 -275.868151) (xy 375.55297 -275.8948)
			(xy 375.552472 -275.921449) (xy 375.781052 -275.921449) (xy 375.781052 -275.868151) (xy 375.788995 -275.815447)
			(xy 375.804705 -275.764517) (xy 375.827831 -275.716496) (xy 375.857855 -275.672459) (xy 375.894107 -275.633388)
			(xy 375.935778 -275.600157) (xy 375.981936 -275.573508) (xy 376.03155 -275.554036) (xy 376.083512 -275.542176)
			(xy 376.136662 -275.538193) (xy 376.189812 -275.542176) (xy 376.241774 -275.554036) (xy 376.291388 -275.573508)
			(xy 376.337546 -275.600157) (xy 376.379217 -275.633388) (xy 376.415469 -275.672459) (xy 376.445493 -275.716496)
			(xy 376.468619 -275.764517) (xy 376.484329 -275.815447) (xy 376.492272 -275.868151) (xy 376.49277 -275.8948)
			(xy 376.492272 -275.921449) (xy 376.721106 -275.921449) (xy 376.721106 -275.868151) (xy 376.729049 -275.815447)
			(xy 376.744759 -275.764517) (xy 376.767885 -275.716496) (xy 376.797909 -275.672459) (xy 376.834161 -275.633388)
			(xy 376.875832 -275.600157) (xy 376.92199 -275.573508) (xy 376.971604 -275.554036) (xy 377.023566 -275.542176)
			(xy 377.076716 -275.538193) (xy 377.129866 -275.542176) (xy 377.181828 -275.554036) (xy 377.231442 -275.573508)
			(xy 377.2776 -275.600157) (xy 377.319271 -275.633388) (xy 377.355523 -275.672459) (xy 377.385547 -275.716496)
			(xy 377.408673 -275.764517) (xy 377.424383 -275.815447) (xy 377.432326 -275.868151) (xy 377.432824 -275.8948)
			(xy 377.432326 -275.921449) (xy 377.660652 -275.921449) (xy 377.660652 -275.868151) (xy 377.668595 -275.815447)
			(xy 377.684305 -275.764517) (xy 377.707431 -275.716496) (xy 377.737455 -275.672459) (xy 377.773707 -275.633388)
			(xy 377.815378 -275.600157) (xy 377.861536 -275.573508) (xy 377.91115 -275.554036) (xy 377.963112 -275.542176)
			(xy 378.016262 -275.538193) (xy 378.069412 -275.542176) (xy 378.121374 -275.554036) (xy 378.170988 -275.573508)
			(xy 378.217146 -275.600157) (xy 378.258817 -275.633388) (xy 378.295069 -275.672459) (xy 378.325093 -275.716496)
			(xy 378.348219 -275.764517) (xy 378.363929 -275.815447) (xy 378.371872 -275.868151) (xy 378.37237 -275.8948)
			(xy 378.371872 -275.921449) (xy 378.600452 -275.921449) (xy 378.600452 -275.868151) (xy 378.608395 -275.815447)
			(xy 378.624105 -275.764517) (xy 378.647231 -275.716496) (xy 378.677255 -275.672459) (xy 378.713507 -275.633388)
			(xy 378.755178 -275.600157) (xy 378.801336 -275.573508) (xy 378.85095 -275.554036) (xy 378.902912 -275.542176)
			(xy 378.956062 -275.538193) (xy 379.009212 -275.542176) (xy 379.061174 -275.554036) (xy 379.110788 -275.573508)
			(xy 379.156946 -275.600157) (xy 379.198617 -275.633388) (xy 379.234869 -275.672459) (xy 379.264893 -275.716496)
			(xy 379.288019 -275.764517) (xy 379.303729 -275.815447) (xy 379.311672 -275.868151) (xy 379.31217 -275.8948)
			(xy 379.311672 -275.921449) (xy 379.303729 -275.974153) (xy 379.288019 -276.025083) (xy 379.264893 -276.073104)
			(xy 379.234869 -276.117141) (xy 379.198617 -276.156212) (xy 379.156946 -276.189443) (xy 379.110788 -276.216092)
			(xy 379.061174 -276.235564) (xy 379.009212 -276.247424) (xy 378.956062 -276.251408) (xy 378.902912 -276.247424)
			(xy 378.85095 -276.235564) (xy 378.801336 -276.216092) (xy 378.755178 -276.189443) (xy 378.713507 -276.156212)
			(xy 378.677255 -276.117141) (xy 378.647231 -276.073104) (xy 378.624105 -276.025083) (xy 378.608395 -275.974153)
			(xy 378.600452 -275.921449) (xy 378.371872 -275.921449) (xy 378.363929 -275.974153) (xy 378.348219 -276.025083)
			(xy 378.325093 -276.073104) (xy 378.295069 -276.117141) (xy 378.258817 -276.156212) (xy 378.217146 -276.189443)
			(xy 378.170988 -276.216092) (xy 378.121374 -276.235564) (xy 378.069412 -276.247424) (xy 378.016262 -276.251408)
			(xy 377.963112 -276.247424) (xy 377.91115 -276.235564) (xy 377.861536 -276.216092) (xy 377.815378 -276.189443)
			(xy 377.773707 -276.156212) (xy 377.737455 -276.117141) (xy 377.707431 -276.073104) (xy 377.684305 -276.025083)
			(xy 377.668595 -275.974153) (xy 377.660652 -275.921449) (xy 377.432326 -275.921449) (xy 377.424383 -275.974153)
			(xy 377.408673 -276.025083) (xy 377.385547 -276.073104) (xy 377.355523 -276.117141) (xy 377.319271 -276.156212)
			(xy 377.2776 -276.189443) (xy 377.231442 -276.216092) (xy 377.181828 -276.235564) (xy 377.129866 -276.247424)
			(xy 377.076716 -276.251408) (xy 377.023566 -276.247424) (xy 376.971604 -276.235564) (xy 376.92199 -276.216092)
			(xy 376.875832 -276.189443) (xy 376.834161 -276.156212) (xy 376.797909 -276.117141) (xy 376.767885 -276.073104)
			(xy 376.744759 -276.025083) (xy 376.729049 -275.974153) (xy 376.721106 -275.921449) (xy 376.492272 -275.921449)
			(xy 376.484329 -275.974153) (xy 376.468619 -276.025083) (xy 376.445493 -276.073104) (xy 376.415469 -276.117141)
			(xy 376.379217 -276.156212) (xy 376.337546 -276.189443) (xy 376.291388 -276.216092) (xy 376.241774 -276.235564)
			(xy 376.189812 -276.247424) (xy 376.136662 -276.251408) (xy 376.083512 -276.247424) (xy 376.03155 -276.235564)
			(xy 375.981936 -276.216092) (xy 375.935778 -276.189443) (xy 375.894107 -276.156212) (xy 375.857855 -276.117141)
			(xy 375.827831 -276.073104) (xy 375.804705 -276.025083) (xy 375.788995 -275.974153) (xy 375.781052 -275.921449)
			(xy 375.552472 -275.921449) (xy 375.544529 -275.974153) (xy 375.528819 -276.025083) (xy 375.505693 -276.073104)
			(xy 375.475669 -276.117141) (xy 375.439417 -276.156212) (xy 375.397746 -276.189443) (xy 375.351588 -276.216092)
			(xy 375.301974 -276.235564) (xy 375.250012 -276.247424) (xy 375.196862 -276.251408) (xy 375.143712 -276.247424)
			(xy 375.09175 -276.235564) (xy 375.042136 -276.216092) (xy 374.995978 -276.189443) (xy 374.954307 -276.156212)
			(xy 374.918055 -276.117141) (xy 374.888031 -276.073104) (xy 374.864905 -276.025083) (xy 374.849195 -275.974153)
			(xy 374.841252 -275.921449) (xy 374.612672 -275.921449) (xy 374.604729 -275.974153) (xy 374.589019 -276.025083)
			(xy 374.565893 -276.073104) (xy 374.535869 -276.117141) (xy 374.499617 -276.156212) (xy 374.457946 -276.189443)
			(xy 374.411788 -276.216092) (xy 374.362174 -276.235564) (xy 374.310212 -276.247424) (xy 374.257062 -276.251408)
			(xy 374.203912 -276.247424) (xy 374.15195 -276.235564) (xy 374.102336 -276.216092) (xy 374.056178 -276.189443)
			(xy 374.014507 -276.156212) (xy 373.978255 -276.117141) (xy 373.948231 -276.073104) (xy 373.925105 -276.025083)
			(xy 373.909395 -275.974153) (xy 373.901452 -275.921449) (xy 373.672872 -275.921449) (xy 373.664929 -275.974153)
			(xy 373.649219 -276.025083) (xy 373.626093 -276.073104) (xy 373.596069 -276.117141) (xy 373.559817 -276.156212)
			(xy 373.518146 -276.189443) (xy 373.471988 -276.216092) (xy 373.422374 -276.235564) (xy 373.370412 -276.247424)
			(xy 373.317262 -276.251408) (xy 373.264112 -276.247424) (xy 373.21215 -276.235564) (xy 373.162536 -276.216092)
			(xy 373.116378 -276.189443) (xy 373.074707 -276.156212) (xy 373.038455 -276.117141) (xy 373.008431 -276.073104)
			(xy 372.985305 -276.025083) (xy 372.969595 -275.974153) (xy 372.961652 -275.921449) (xy 372.733072 -275.921449)
			(xy 372.725129 -275.974153) (xy 372.709419 -276.025083) (xy 372.686293 -276.073104) (xy 372.656269 -276.117141)
			(xy 372.620017 -276.156212) (xy 372.578346 -276.189443) (xy 372.532188 -276.216092) (xy 372.482574 -276.235564)
			(xy 372.430612 -276.247424) (xy 372.377462 -276.251408) (xy 372.324312 -276.247424) (xy 372.27235 -276.235564)
			(xy 372.222736 -276.216092) (xy 372.176578 -276.189443) (xy 372.134907 -276.156212) (xy 372.098655 -276.117141)
			(xy 372.068631 -276.073104) (xy 372.045505 -276.025083) (xy 372.029795 -275.974153) (xy 372.021852 -275.921449)
			(xy 371.793272 -275.921449) (xy 371.785329 -275.974153) (xy 371.769619 -276.025083) (xy 371.746493 -276.073104)
			(xy 371.716469 -276.117141) (xy 371.680217 -276.156212) (xy 371.638546 -276.189443) (xy 371.592388 -276.216092)
			(xy 371.542774 -276.235564) (xy 371.490812 -276.247424) (xy 371.437662 -276.251408) (xy 371.384512 -276.247424)
			(xy 371.33255 -276.235564) (xy 371.282936 -276.216092) (xy 371.236778 -276.189443) (xy 371.195107 -276.156212)
			(xy 371.158855 -276.117141) (xy 371.128831 -276.073104) (xy 371.105705 -276.025083) (xy 371.089995 -275.974153)
			(xy 371.082052 -275.921449) (xy 370.853726 -275.921449) (xy 370.845783 -275.974153) (xy 370.830073 -276.025083)
			(xy 370.806947 -276.073104) (xy 370.776923 -276.117141) (xy 370.740671 -276.156212) (xy 370.699 -276.189443)
			(xy 370.652842 -276.216092) (xy 370.603228 -276.235564) (xy 370.551266 -276.247424) (xy 370.498116 -276.251408)
			(xy 370.444966 -276.247424) (xy 370.393004 -276.235564) (xy 370.34339 -276.216092) (xy 370.297232 -276.189443)
			(xy 370.255561 -276.156212) (xy 370.219309 -276.117141) (xy 370.189285 -276.073104) (xy 370.166159 -276.025083)
			(xy 370.150449 -275.974153) (xy 370.142506 -275.921449) (xy 369.913888 -275.921449) (xy 369.905983 -275.973899)
			(xy 369.890273 -276.024829) (xy 369.867147 -276.07285) (xy 369.837123 -276.116887) (xy 369.800871 -276.155958)
			(xy 369.7592 -276.189189) (xy 369.713042 -276.215838) (xy 369.663428 -276.23531) (xy 369.611466 -276.24717)
			(xy 369.558316 -276.251154) (xy 369.505166 -276.24717) (xy 369.453204 -276.23531) (xy 369.40359 -276.215838)
			(xy 369.357432 -276.189189) (xy 369.315761 -276.155958) (xy 369.279509 -276.116887) (xy 369.249485 -276.07285)
			(xy 369.226359 -276.024829) (xy 369.210649 -275.973899) (xy 369.202706 -275.921195) (xy 368.974126 -275.921195)
			(xy 368.966183 -275.973899) (xy 368.950473 -276.024829) (xy 368.927347 -276.07285) (xy 368.897323 -276.116887)
			(xy 368.861071 -276.155958) (xy 368.8194 -276.189189) (xy 368.773242 -276.215838) (xy 368.723628 -276.23531)
			(xy 368.671666 -276.24717) (xy 368.618516 -276.251154) (xy 368.565366 -276.24717) (xy 368.513404 -276.23531)
			(xy 368.46379 -276.215838) (xy 368.417632 -276.189189) (xy 368.375961 -276.155958) (xy 368.339709 -276.116887)
			(xy 368.309685 -276.07285) (xy 368.286559 -276.024829) (xy 368.270849 -275.973899) (xy 368.262906 -275.921195)
			(xy 368.034326 -275.921195) (xy 368.026383 -275.973899) (xy 368.010673 -276.024829) (xy 367.987547 -276.07285)
			(xy 367.957523 -276.116887) (xy 367.921271 -276.155958) (xy 367.8796 -276.189189) (xy 367.833442 -276.215838)
			(xy 367.783828 -276.23531) (xy 367.731866 -276.24717) (xy 367.678716 -276.251154) (xy 367.625566 -276.24717)
			(xy 367.573604 -276.23531) (xy 367.52399 -276.215838) (xy 367.477832 -276.189189) (xy 367.436161 -276.155958)
			(xy 367.399909 -276.116887) (xy 367.369885 -276.07285) (xy 367.346759 -276.024829) (xy 367.331049 -275.973899)
			(xy 367.323106 -275.921195) (xy 367.094531 -275.921195) (xy 367.094526 -275.921449) (xy 367.086583 -275.974153)
			(xy 367.070873 -276.025083) (xy 367.047747 -276.073104) (xy 367.017723 -276.117141) (xy 366.981471 -276.156212)
			(xy 366.9398 -276.189443) (xy 366.893642 -276.216092) (xy 366.844028 -276.235564) (xy 366.792066 -276.247424)
			(xy 366.738916 -276.251408) (xy 366.685766 -276.247424) (xy 366.633804 -276.235564) (xy 366.58419 -276.216092)
			(xy 366.538032 -276.189443) (xy 366.496361 -276.156212) (xy 366.460109 -276.117141) (xy 366.430085 -276.073104)
			(xy 366.406959 -276.025083) (xy 366.391249 -275.974153) (xy 366.383306 -275.921449) (xy 366.154472 -275.921449)
			(xy 366.146529 -275.974153) (xy 366.130819 -276.025083) (xy 366.107693 -276.073104) (xy 366.077669 -276.117141)
			(xy 366.041417 -276.156212) (xy 365.999746 -276.189443) (xy 365.953588 -276.216092) (xy 365.903974 -276.235564)
			(xy 365.852012 -276.247424) (xy 365.798862 -276.251408) (xy 365.745712 -276.247424) (xy 365.69375 -276.235564)
			(xy 365.644136 -276.216092) (xy 365.597978 -276.189443) (xy 365.556307 -276.156212) (xy 365.520055 -276.117141)
			(xy 365.490031 -276.073104) (xy 365.466905 -276.025083) (xy 365.451195 -275.974153) (xy 365.443252 -275.921449)
			(xy 365.214888 -275.921449) (xy 365.206983 -275.973899) (xy 365.191273 -276.024829) (xy 365.168147 -276.07285)
			(xy 365.138123 -276.116887) (xy 365.101871 -276.155958) (xy 365.0602 -276.189189) (xy 365.014042 -276.215838)
			(xy 364.964428 -276.23531) (xy 364.912466 -276.24717) (xy 364.859316 -276.251154) (xy 364.806166 -276.24717)
			(xy 364.754204 -276.23531) (xy 364.70459 -276.215838) (xy 364.658432 -276.189189) (xy 364.616761 -276.155958)
			(xy 364.580509 -276.116887) (xy 364.550485 -276.07285) (xy 364.527359 -276.024829) (xy 364.511649 -275.973899)
			(xy 364.503706 -275.921195) (xy 364.274877 -275.921195) (xy 364.274872 -275.921449) (xy 364.266929 -275.974153)
			(xy 364.251219 -276.025083) (xy 364.228093 -276.073104) (xy 364.198069 -276.117141) (xy 364.161817 -276.156212)
			(xy 364.120146 -276.189443) (xy 364.073988 -276.216092) (xy 364.024374 -276.235564) (xy 363.972412 -276.247424)
			(xy 363.919262 -276.251408) (xy 363.866112 -276.247424) (xy 363.81415 -276.235564) (xy 363.764536 -276.216092)
			(xy 363.718378 -276.189443) (xy 363.676707 -276.156212) (xy 363.640455 -276.117141) (xy 363.610431 -276.073104)
			(xy 363.587305 -276.025083) (xy 363.571595 -275.974153) (xy 363.563652 -275.921449) (xy 362.39549 -275.921449)
			(xy 362.38764 -275.973601) (xy 362.372103 -276.024197) (xy 362.349249 -276.071936) (xy 362.319581 -276.115767)
			(xy 362.302044 -276.135592) (xy 362.518452 -276.352) (xy 362.537248 -276.353524) (xy 362.565169 -276.356208)
			(xy 362.619722 -276.369244) (xy 362.671557 -276.390669) (xy 362.719393 -276.419955) (xy 362.762048 -276.456377)
			(xy 362.798466 -276.499035) (xy 362.827747 -276.546874) (xy 362.849167 -276.598711) (xy 362.862197 -276.653265)
			(xy 362.864908 -276.681184) (xy 362.866432 -276.69998) (xy 362.920534 -276.754082) (xy 362.931216 -276.764097)
			(xy 362.956923 -276.778089) (xy 362.985544 -276.784218) (xy 363.014727 -276.781978) (xy 363.042077 -276.771555)
			(xy 363.065348 -276.753804) (xy 363.082631 -276.730182) (xy 363.092505 -276.702629) (xy 363.093762 -276.688042)
			(xy 363.095793 -276.661144) (xy 363.106951 -276.608371) (xy 363.125943 -276.557885) (xy 363.152333 -276.510842)
			(xy 363.185517 -276.468318) (xy 363.224737 -276.431287) (xy 363.269094 -276.400596) (xy 363.317574 -276.376948)
			(xy 363.369066 -276.360883) (xy 363.422392 -276.35277) (xy 363.449362 -276.352254) (xy 363.477348 -276.3528)
			(xy 363.532632 -276.36155) (xy 363.585867 -276.378841) (xy 363.635741 -276.404246) (xy 363.681027 -276.437141)
			(xy 363.720609 -276.476715) (xy 363.753514 -276.521994) (xy 363.77893 -276.571863) (xy 363.796232 -276.625094)
			(xy 363.804994 -276.680376) (xy 363.80547 -276.708362) (xy 363.804975 -276.735011) (xy 364.033552 -276.735011)
			(xy 364.033552 -276.681713) (xy 364.041495 -276.629009) (xy 364.057205 -276.578079) (xy 364.080331 -276.530058)
			(xy 364.110355 -276.486021) (xy 364.146607 -276.44695) (xy 364.188278 -276.413719) (xy 364.234436 -276.38707)
			(xy 364.28405 -276.367598) (xy 364.336012 -276.355738) (xy 364.389162 -276.351755) (xy 364.442312 -276.355738)
			(xy 364.494274 -276.367598) (xy 364.543888 -276.38707) (xy 364.590046 -276.413719) (xy 364.631717 -276.44695)
			(xy 364.667969 -276.486021) (xy 364.697993 -276.530058) (xy 364.721119 -276.578079) (xy 364.736829 -276.629009)
			(xy 364.744772 -276.681713) (xy 364.74527 -276.708362) (xy 364.744772 -276.735011) (xy 364.973352 -276.735011)
			(xy 364.973352 -276.681713) (xy 364.981295 -276.629009) (xy 364.997005 -276.578079) (xy 365.020131 -276.530058)
			(xy 365.050155 -276.486021) (xy 365.086407 -276.44695) (xy 365.128078 -276.413719) (xy 365.174236 -276.38707)
			(xy 365.22385 -276.367598) (xy 365.275812 -276.355738) (xy 365.328962 -276.351755) (xy 365.382112 -276.355738)
			(xy 365.434074 -276.367598) (xy 365.483688 -276.38707) (xy 365.529846 -276.413719) (xy 365.571517 -276.44695)
			(xy 365.607769 -276.486021) (xy 365.637793 -276.530058) (xy 365.660919 -276.578079) (xy 365.676629 -276.629009)
			(xy 365.684572 -276.681713) (xy 365.68507 -276.708362) (xy 365.684572 -276.735011) (xy 365.913152 -276.735011)
			(xy 365.913152 -276.681713) (xy 365.921095 -276.629009) (xy 365.936805 -276.578079) (xy 365.959931 -276.530058)
			(xy 365.989955 -276.486021) (xy 366.026207 -276.44695) (xy 366.067878 -276.413719) (xy 366.114036 -276.38707)
			(xy 366.16365 -276.367598) (xy 366.215612 -276.355738) (xy 366.268762 -276.351755) (xy 366.321912 -276.355738)
			(xy 366.373874 -276.367598) (xy 366.423488 -276.38707) (xy 366.469646 -276.413719) (xy 366.511317 -276.44695)
			(xy 366.547569 -276.486021) (xy 366.577593 -276.530058) (xy 366.600719 -276.578079) (xy 366.616429 -276.629009)
			(xy 366.624372 -276.681713) (xy 366.62487 -276.708362) (xy 366.624372 -276.735011) (xy 366.624334 -276.735265)
			(xy 366.852952 -276.735265) (xy 366.852952 -276.681967) (xy 366.860895 -276.629263) (xy 366.876605 -276.578333)
			(xy 366.899731 -276.530312) (xy 366.929755 -276.486275) (xy 366.966007 -276.447204) (xy 367.007678 -276.413973)
			(xy 367.053836 -276.387324) (xy 367.10345 -276.367852) (xy 367.155412 -276.355992) (xy 367.208562 -276.352009)
			(xy 367.261712 -276.355992) (xy 367.313674 -276.367852) (xy 367.363288 -276.387324) (xy 367.409446 -276.413973)
			(xy 367.451117 -276.447204) (xy 367.487369 -276.486275) (xy 367.517393 -276.530312) (xy 367.540519 -276.578333)
			(xy 367.556229 -276.629263) (xy 367.564172 -276.681967) (xy 367.56467 -276.708616) (xy 367.564177 -276.735011)
			(xy 367.792752 -276.735011) (xy 367.792752 -276.681713) (xy 367.800695 -276.629009) (xy 367.816405 -276.578079)
			(xy 367.839531 -276.530058) (xy 367.869555 -276.486021) (xy 367.905807 -276.44695) (xy 367.947478 -276.413719)
			(xy 367.993636 -276.38707) (xy 368.04325 -276.367598) (xy 368.095212 -276.355738) (xy 368.148362 -276.351755)
			(xy 368.201512 -276.355738) (xy 368.253474 -276.367598) (xy 368.303088 -276.38707) (xy 368.349246 -276.413719)
			(xy 368.390917 -276.44695) (xy 368.427169 -276.486021) (xy 368.457193 -276.530058) (xy 368.480319 -276.578079)
			(xy 368.496029 -276.629009) (xy 368.503972 -276.681713) (xy 368.50447 -276.708362) (xy 368.503972 -276.735011)
			(xy 368.503934 -276.735265) (xy 368.732806 -276.735265) (xy 368.732806 -276.681967) (xy 368.740749 -276.629263)
			(xy 368.756459 -276.578333) (xy 368.779585 -276.530312) (xy 368.809609 -276.486275) (xy 368.845861 -276.447204)
			(xy 368.887532 -276.413973) (xy 368.93369 -276.387324) (xy 368.983304 -276.367852) (xy 369.035266 -276.355992)
			(xy 369.088416 -276.352009) (xy 369.141566 -276.355992) (xy 369.193528 -276.367852) (xy 369.243142 -276.387324)
			(xy 369.2893 -276.413973) (xy 369.330971 -276.447204) (xy 369.367223 -276.486275) (xy 369.397247 -276.530312)
			(xy 369.420373 -276.578333) (xy 369.436083 -276.629263) (xy 369.444026 -276.681967) (xy 369.444524 -276.708616)
			(xy 369.444026 -276.735265) (xy 370.612406 -276.735265) (xy 370.612406 -276.681967) (xy 370.620349 -276.629263)
			(xy 370.636059 -276.578333) (xy 370.659185 -276.530312) (xy 370.689209 -276.486275) (xy 370.725461 -276.447204)
			(xy 370.767132 -276.413973) (xy 370.81329 -276.387324) (xy 370.862904 -276.367852) (xy 370.914866 -276.355992)
			(xy 370.968016 -276.352009) (xy 371.021166 -276.355992) (xy 371.073128 -276.367852) (xy 371.122742 -276.387324)
			(xy 371.1689 -276.413973) (xy 371.210571 -276.447204) (xy 371.246823 -276.486275) (xy 371.276847 -276.530312)
			(xy 371.299973 -276.578333) (xy 371.315683 -276.629263) (xy 371.323626 -276.681967) (xy 371.324124 -276.708616)
			(xy 371.323626 -276.735265) (xy 371.552206 -276.735265) (xy 371.552206 -276.681967) (xy 371.560149 -276.629263)
			(xy 371.575859 -276.578333) (xy 371.598985 -276.530312) (xy 371.629009 -276.486275) (xy 371.665261 -276.447204)
			(xy 371.706932 -276.413973) (xy 371.75309 -276.387324) (xy 371.802704 -276.367852) (xy 371.854666 -276.355992)
			(xy 371.907816 -276.352009) (xy 371.960966 -276.355992) (xy 372.012928 -276.367852) (xy 372.062542 -276.387324)
			(xy 372.1087 -276.413973) (xy 372.150371 -276.447204) (xy 372.186623 -276.486275) (xy 372.216647 -276.530312)
			(xy 372.239773 -276.578333) (xy 372.255483 -276.629263) (xy 372.263426 -276.681967) (xy 372.263924 -276.708616)
			(xy 372.263426 -276.735265) (xy 372.492006 -276.735265) (xy 372.492006 -276.681967) (xy 372.499949 -276.629263)
			(xy 372.515659 -276.578333) (xy 372.538785 -276.530312) (xy 372.568809 -276.486275) (xy 372.605061 -276.447204)
			(xy 372.646732 -276.413973) (xy 372.69289 -276.387324) (xy 372.742504 -276.367852) (xy 372.794466 -276.355992)
			(xy 372.847616 -276.352009) (xy 372.900766 -276.355992) (xy 372.952728 -276.367852) (xy 373.002342 -276.387324)
			(xy 373.0485 -276.413973) (xy 373.090171 -276.447204) (xy 373.126423 -276.486275) (xy 373.156447 -276.530312)
			(xy 373.179573 -276.578333) (xy 373.195283 -276.629263) (xy 373.203226 -276.681967) (xy 373.203724 -276.708616)
			(xy 373.203226 -276.735265) (xy 373.431552 -276.735265) (xy 373.431552 -276.681967) (xy 373.439495 -276.629263)
			(xy 373.455205 -276.578333) (xy 373.478331 -276.530312) (xy 373.508355 -276.486275) (xy 373.544607 -276.447204)
			(xy 373.586278 -276.413973) (xy 373.632436 -276.387324) (xy 373.68205 -276.367852) (xy 373.734012 -276.355992)
			(xy 373.787162 -276.352009) (xy 373.840312 -276.355992) (xy 373.892274 -276.367852) (xy 373.941888 -276.387324)
			(xy 373.988046 -276.413973) (xy 374.029717 -276.447204) (xy 374.065969 -276.486275) (xy 374.095993 -276.530312)
			(xy 374.119119 -276.578333) (xy 374.134829 -276.629263) (xy 374.142772 -276.681967) (xy 374.14327 -276.708616)
			(xy 374.142772 -276.735265) (xy 374.371606 -276.735265) (xy 374.371606 -276.681967) (xy 374.379549 -276.629263)
			(xy 374.395259 -276.578333) (xy 374.418385 -276.530312) (xy 374.448409 -276.486275) (xy 374.484661 -276.447204)
			(xy 374.526332 -276.413973) (xy 374.57249 -276.387324) (xy 374.622104 -276.367852) (xy 374.674066 -276.355992)
			(xy 374.727216 -276.352009) (xy 374.780366 -276.355992) (xy 374.832328 -276.367852) (xy 374.881942 -276.387324)
			(xy 374.9281 -276.413973) (xy 374.969771 -276.447204) (xy 375.006023 -276.486275) (xy 375.036047 -276.530312)
			(xy 375.059173 -276.578333) (xy 375.074883 -276.629263) (xy 375.082826 -276.681967) (xy 375.083324 -276.708616)
			(xy 375.082826 -276.735265) (xy 375.311406 -276.735265) (xy 375.311406 -276.681967) (xy 375.319349 -276.629263)
			(xy 375.335059 -276.578333) (xy 375.358185 -276.530312) (xy 375.388209 -276.486275) (xy 375.424461 -276.447204)
			(xy 375.466132 -276.413973) (xy 375.51229 -276.387324) (xy 375.561904 -276.367852) (xy 375.613866 -276.355992)
			(xy 375.667016 -276.352009) (xy 375.720166 -276.355992) (xy 375.772128 -276.367852) (xy 375.821742 -276.387324)
			(xy 375.8679 -276.413973) (xy 375.909571 -276.447204) (xy 375.945823 -276.486275) (xy 375.975847 -276.530312)
			(xy 375.998973 -276.578333) (xy 376.014683 -276.629263) (xy 376.022626 -276.681967) (xy 376.023124 -276.708616)
			(xy 376.022626 -276.735265) (xy 376.251206 -276.735265) (xy 376.251206 -276.681967) (xy 376.259149 -276.629263)
			(xy 376.274859 -276.578333) (xy 376.297985 -276.530312) (xy 376.328009 -276.486275) (xy 376.364261 -276.447204)
			(xy 376.405932 -276.413973) (xy 376.45209 -276.387324) (xy 376.501704 -276.367852) (xy 376.553666 -276.355992)
			(xy 376.606816 -276.352009) (xy 376.659966 -276.355992) (xy 376.711928 -276.367852) (xy 376.761542 -276.387324)
			(xy 376.8077 -276.413973) (xy 376.849371 -276.447204) (xy 376.885623 -276.486275) (xy 376.915647 -276.530312)
			(xy 376.938773 -276.578333) (xy 376.954483 -276.629263) (xy 376.962426 -276.681967) (xy 376.962924 -276.708616)
			(xy 376.962426 -276.735265) (xy 377.191006 -276.735265) (xy 377.191006 -276.681967) (xy 377.198949 -276.629263)
			(xy 377.214659 -276.578333) (xy 377.237785 -276.530312) (xy 377.267809 -276.486275) (xy 377.304061 -276.447204)
			(xy 377.345732 -276.413973) (xy 377.39189 -276.387324) (xy 377.441504 -276.367852) (xy 377.493466 -276.355992)
			(xy 377.546616 -276.352009) (xy 377.599766 -276.355992) (xy 377.651728 -276.367852) (xy 377.701342 -276.387324)
			(xy 377.7475 -276.413973) (xy 377.789171 -276.447204) (xy 377.825423 -276.486275) (xy 377.855447 -276.530312)
			(xy 377.878573 -276.578333) (xy 377.894283 -276.629263) (xy 377.902226 -276.681967) (xy 377.902724 -276.708616)
			(xy 377.902226 -276.735265) (xy 378.130806 -276.735265) (xy 378.130806 -276.681967) (xy 378.138749 -276.629263)
			(xy 378.154459 -276.578333) (xy 378.177585 -276.530312) (xy 378.207609 -276.486275) (xy 378.243861 -276.447204)
			(xy 378.285532 -276.413973) (xy 378.33169 -276.387324) (xy 378.381304 -276.367852) (xy 378.433266 -276.355992)
			(xy 378.486416 -276.352009) (xy 378.539566 -276.355992) (xy 378.591528 -276.367852) (xy 378.641142 -276.387324)
			(xy 378.6873 -276.413973) (xy 378.728971 -276.447204) (xy 378.765223 -276.486275) (xy 378.795247 -276.530312)
			(xy 378.818373 -276.578333) (xy 378.834083 -276.629263) (xy 378.842026 -276.681967) (xy 378.842524 -276.708616)
			(xy 378.842026 -276.735265) (xy 379.070606 -276.735265) (xy 379.070606 -276.681967) (xy 379.078549 -276.629263)
			(xy 379.094259 -276.578333) (xy 379.117385 -276.530312) (xy 379.147409 -276.486275) (xy 379.183661 -276.447204)
			(xy 379.225332 -276.413973) (xy 379.27149 -276.387324) (xy 379.321104 -276.367852) (xy 379.373066 -276.355992)
			(xy 379.426216 -276.352009) (xy 379.479366 -276.355992) (xy 379.531328 -276.367852) (xy 379.580942 -276.387324)
			(xy 379.6271 -276.413973) (xy 379.668771 -276.447204) (xy 379.705023 -276.486275) (xy 379.735047 -276.530312)
			(xy 379.758173 -276.578333) (xy 379.773883 -276.629263) (xy 379.781826 -276.681967) (xy 379.782324 -276.708616)
			(xy 379.781826 -276.735265) (xy 379.773883 -276.787969) (xy 379.758173 -276.838899) (xy 379.735047 -276.88692)
			(xy 379.705023 -276.930957) (xy 379.668771 -276.970028) (xy 379.6271 -277.003259) (xy 379.580942 -277.029908)
			(xy 379.531328 -277.04938) (xy 379.479366 -277.06124) (xy 379.426216 -277.065224) (xy 379.373066 -277.06124)
			(xy 379.321104 -277.04938) (xy 379.27149 -277.029908) (xy 379.225332 -277.003259) (xy 379.183661 -276.970028)
			(xy 379.147409 -276.930957) (xy 379.117385 -276.88692) (xy 379.094259 -276.838899) (xy 379.078549 -276.787969)
			(xy 379.070606 -276.735265) (xy 378.842026 -276.735265) (xy 378.834083 -276.787969) (xy 378.818373 -276.838899)
			(xy 378.795247 -276.88692) (xy 378.765223 -276.930957) (xy 378.728971 -276.970028) (xy 378.6873 -277.003259)
			(xy 378.641142 -277.029908) (xy 378.591528 -277.04938) (xy 378.539566 -277.06124) (xy 378.486416 -277.065224)
			(xy 378.433266 -277.06124) (xy 378.381304 -277.04938) (xy 378.33169 -277.029908) (xy 378.285532 -277.003259)
			(xy 378.243861 -276.970028) (xy 378.207609 -276.930957) (xy 378.177585 -276.88692) (xy 378.154459 -276.838899)
			(xy 378.138749 -276.787969) (xy 378.130806 -276.735265) (xy 377.902226 -276.735265) (xy 377.894283 -276.787969)
			(xy 377.878573 -276.838899) (xy 377.855447 -276.88692) (xy 377.825423 -276.930957) (xy 377.789171 -276.970028)
			(xy 377.7475 -277.003259) (xy 377.701342 -277.029908) (xy 377.651728 -277.04938) (xy 377.599766 -277.06124)
			(xy 377.546616 -277.065224) (xy 377.493466 -277.06124) (xy 377.441504 -277.04938) (xy 377.39189 -277.029908)
			(xy 377.345732 -277.003259) (xy 377.304061 -276.970028) (xy 377.267809 -276.930957) (xy 377.237785 -276.88692)
			(xy 377.214659 -276.838899) (xy 377.198949 -276.787969) (xy 377.191006 -276.735265) (xy 376.962426 -276.735265)
			(xy 376.954483 -276.787969) (xy 376.938773 -276.838899) (xy 376.915647 -276.88692) (xy 376.885623 -276.930957)
			(xy 376.849371 -276.970028) (xy 376.8077 -277.003259) (xy 376.761542 -277.029908) (xy 376.711928 -277.04938)
			(xy 376.659966 -277.06124) (xy 376.606816 -277.065224) (xy 376.553666 -277.06124) (xy 376.501704 -277.04938)
			(xy 376.45209 -277.029908) (xy 376.405932 -277.003259) (xy 376.364261 -276.970028) (xy 376.328009 -276.930957)
			(xy 376.297985 -276.88692) (xy 376.274859 -276.838899) (xy 376.259149 -276.787969) (xy 376.251206 -276.735265)
			(xy 376.022626 -276.735265) (xy 376.014683 -276.787969) (xy 375.998973 -276.838899) (xy 375.975847 -276.88692)
			(xy 375.945823 -276.930957) (xy 375.909571 -276.970028) (xy 375.8679 -277.003259) (xy 375.821742 -277.029908)
			(xy 375.772128 -277.04938) (xy 375.720166 -277.06124) (xy 375.667016 -277.065224) (xy 375.613866 -277.06124)
			(xy 375.561904 -277.04938) (xy 375.51229 -277.029908) (xy 375.466132 -277.003259) (xy 375.424461 -276.970028)
			(xy 375.388209 -276.930957) (xy 375.358185 -276.88692) (xy 375.335059 -276.838899) (xy 375.319349 -276.787969)
			(xy 375.311406 -276.735265) (xy 375.082826 -276.735265) (xy 375.074883 -276.787969) (xy 375.059173 -276.838899)
			(xy 375.036047 -276.88692) (xy 375.006023 -276.930957) (xy 374.969771 -276.970028) (xy 374.9281 -277.003259)
			(xy 374.881942 -277.029908) (xy 374.832328 -277.04938) (xy 374.780366 -277.06124) (xy 374.727216 -277.065224)
			(xy 374.674066 -277.06124) (xy 374.622104 -277.04938) (xy 374.57249 -277.029908) (xy 374.526332 -277.003259)
			(xy 374.484661 -276.970028) (xy 374.448409 -276.930957) (xy 374.418385 -276.88692) (xy 374.395259 -276.838899)
			(xy 374.379549 -276.787969) (xy 374.371606 -276.735265) (xy 374.142772 -276.735265) (xy 374.134829 -276.787969)
			(xy 374.119119 -276.838899) (xy 374.095993 -276.88692) (xy 374.065969 -276.930957) (xy 374.029717 -276.970028)
			(xy 373.988046 -277.003259) (xy 373.941888 -277.029908) (xy 373.892274 -277.04938) (xy 373.840312 -277.06124)
			(xy 373.787162 -277.065224) (xy 373.734012 -277.06124) (xy 373.68205 -277.04938) (xy 373.632436 -277.029908)
			(xy 373.586278 -277.003259) (xy 373.544607 -276.970028) (xy 373.508355 -276.930957) (xy 373.478331 -276.88692)
			(xy 373.455205 -276.838899) (xy 373.439495 -276.787969) (xy 373.431552 -276.735265) (xy 373.203226 -276.735265)
			(xy 373.195283 -276.787969) (xy 373.179573 -276.838899) (xy 373.156447 -276.88692) (xy 373.126423 -276.930957)
			(xy 373.090171 -276.970028) (xy 373.0485 -277.003259) (xy 373.002342 -277.029908) (xy 372.952728 -277.04938)
			(xy 372.900766 -277.06124) (xy 372.847616 -277.065224) (xy 372.794466 -277.06124) (xy 372.742504 -277.04938)
			(xy 372.69289 -277.029908) (xy 372.646732 -277.003259) (xy 372.605061 -276.970028) (xy 372.568809 -276.930957)
			(xy 372.538785 -276.88692) (xy 372.515659 -276.838899) (xy 372.499949 -276.787969) (xy 372.492006 -276.735265)
			(xy 372.263426 -276.735265) (xy 372.255483 -276.787969) (xy 372.239773 -276.838899) (xy 372.216647 -276.88692)
			(xy 372.186623 -276.930957) (xy 372.150371 -276.970028) (xy 372.1087 -277.003259) (xy 372.062542 -277.029908)
			(xy 372.012928 -277.04938) (xy 371.960966 -277.06124) (xy 371.907816 -277.065224) (xy 371.854666 -277.06124)
			(xy 371.802704 -277.04938) (xy 371.75309 -277.029908) (xy 371.706932 -277.003259) (xy 371.665261 -276.970028)
			(xy 371.629009 -276.930957) (xy 371.598985 -276.88692) (xy 371.575859 -276.838899) (xy 371.560149 -276.787969)
			(xy 371.552206 -276.735265) (xy 371.323626 -276.735265) (xy 371.315683 -276.787969) (xy 371.299973 -276.838899)
			(xy 371.276847 -276.88692) (xy 371.246823 -276.930957) (xy 371.210571 -276.970028) (xy 371.1689 -277.003259)
			(xy 371.122742 -277.029908) (xy 371.073128 -277.04938) (xy 371.021166 -277.06124) (xy 370.968016 -277.065224)
			(xy 370.914866 -277.06124) (xy 370.862904 -277.04938) (xy 370.81329 -277.029908) (xy 370.767132 -277.003259)
			(xy 370.725461 -276.970028) (xy 370.689209 -276.930957) (xy 370.659185 -276.88692) (xy 370.636059 -276.838899)
			(xy 370.620349 -276.787969) (xy 370.612406 -276.735265) (xy 369.444026 -276.735265) (xy 369.436083 -276.787969)
			(xy 369.420373 -276.838899) (xy 369.397247 -276.88692) (xy 369.367223 -276.930957) (xy 369.330971 -276.970028)
			(xy 369.2893 -277.003259) (xy 369.243142 -277.029908) (xy 369.193528 -277.04938) (xy 369.141566 -277.06124)
			(xy 369.088416 -277.065224) (xy 369.035266 -277.06124) (xy 368.983304 -277.04938) (xy 368.93369 -277.029908)
			(xy 368.887532 -277.003259) (xy 368.845861 -276.970028) (xy 368.809609 -276.930957) (xy 368.779585 -276.88692)
			(xy 368.756459 -276.838899) (xy 368.740749 -276.787969) (xy 368.732806 -276.735265) (xy 368.503934 -276.735265)
			(xy 368.496029 -276.787715) (xy 368.480319 -276.838645) (xy 368.457193 -276.886666) (xy 368.427169 -276.930703)
			(xy 368.390917 -276.969774) (xy 368.349246 -277.003005) (xy 368.303088 -277.029654) (xy 368.253474 -277.049126)
			(xy 368.201512 -277.060986) (xy 368.148362 -277.06497) (xy 368.095212 -277.060986) (xy 368.04325 -277.049126)
			(xy 367.993636 -277.029654) (xy 367.947478 -277.003005) (xy 367.905807 -276.969774) (xy 367.869555 -276.930703)
			(xy 367.839531 -276.886666) (xy 367.816405 -276.838645) (xy 367.800695 -276.787715) (xy 367.792752 -276.735011)
			(xy 367.564177 -276.735011) (xy 367.564172 -276.735265) (xy 367.556229 -276.787969) (xy 367.540519 -276.838899)
			(xy 367.517393 -276.88692) (xy 367.487369 -276.930957) (xy 367.451117 -276.970028) (xy 367.409446 -277.003259)
			(xy 367.363288 -277.029908) (xy 367.313674 -277.04938) (xy 367.261712 -277.06124) (xy 367.208562 -277.065224)
			(xy 367.155412 -277.06124) (xy 367.10345 -277.04938) (xy 367.053836 -277.029908) (xy 367.007678 -277.003259)
			(xy 366.966007 -276.970028) (xy 366.929755 -276.930957) (xy 366.899731 -276.88692) (xy 366.876605 -276.838899)
			(xy 366.860895 -276.787969) (xy 366.852952 -276.735265) (xy 366.624334 -276.735265) (xy 366.616429 -276.787715)
			(xy 366.600719 -276.838645) (xy 366.577593 -276.886666) (xy 366.547569 -276.930703) (xy 366.511317 -276.969774)
			(xy 366.469646 -277.003005) (xy 366.423488 -277.029654) (xy 366.373874 -277.049126) (xy 366.321912 -277.060986)
			(xy 366.268762 -277.06497) (xy 366.215612 -277.060986) (xy 366.16365 -277.049126) (xy 366.114036 -277.029654)
			(xy 366.067878 -277.003005) (xy 366.026207 -276.969774) (xy 365.989955 -276.930703) (xy 365.959931 -276.886666)
			(xy 365.936805 -276.838645) (xy 365.921095 -276.787715) (xy 365.913152 -276.735011) (xy 365.684572 -276.735011)
			(xy 365.676629 -276.787715) (xy 365.660919 -276.838645) (xy 365.637793 -276.886666) (xy 365.607769 -276.930703)
			(xy 365.571517 -276.969774) (xy 365.529846 -277.003005) (xy 365.483688 -277.029654) (xy 365.434074 -277.049126)
			(xy 365.382112 -277.060986) (xy 365.328962 -277.06497) (xy 365.275812 -277.060986) (xy 365.22385 -277.049126)
			(xy 365.174236 -277.029654) (xy 365.128078 -277.003005) (xy 365.086407 -276.969774) (xy 365.050155 -276.930703)
			(xy 365.020131 -276.886666) (xy 364.997005 -276.838645) (xy 364.981295 -276.787715) (xy 364.973352 -276.735011)
			(xy 364.744772 -276.735011) (xy 364.736829 -276.787715) (xy 364.721119 -276.838645) (xy 364.697993 -276.886666)
			(xy 364.667969 -276.930703) (xy 364.631717 -276.969774) (xy 364.590046 -277.003005) (xy 364.543888 -277.029654)
			(xy 364.494274 -277.049126) (xy 364.442312 -277.060986) (xy 364.389162 -277.06497) (xy 364.336012 -277.060986)
			(xy 364.28405 -277.049126) (xy 364.234436 -277.029654) (xy 364.188278 -277.003005) (xy 364.146607 -276.969774)
			(xy 364.110355 -276.930703) (xy 364.080331 -276.886666) (xy 364.057205 -276.838645) (xy 364.041495 -276.787715)
			(xy 364.033552 -276.735011) (xy 363.804975 -276.735011) (xy 363.804969 -276.735329) (xy 363.79683 -276.788647)
			(xy 363.780747 -276.840128) (xy 363.757088 -276.888597) (xy 363.726394 -276.932946) (xy 363.689365 -276.972161)
			(xy 363.646848 -277.005347) (xy 363.599815 -277.031746) (xy 363.54934 -277.050753) (xy 363.496577 -277.061934)
			(xy 363.469682 -277.063962) (xy 363.455117 -277.06529) (xy 363.427607 -277.075187) (xy 363.404026 -277.092469)
			(xy 363.386304 -277.115722) (xy 363.375892 -277.143041) (xy 363.373641 -277.17219) (xy 363.379737 -277.200783)
			(xy 363.39368 -277.22648) (xy 363.403642 -277.23719) (xy 363.483398 -277.316946) (xy 363.493982 -277.326829)
			(xy 363.519359 -277.340747) (xy 363.547626 -277.346973) (xy 363.576502 -277.345004) (xy 363.603662 -277.335)
			(xy 363.626917 -277.317767) (xy 363.636052 -277.306532) (xy 363.653031 -277.285113) (xy 363.692403 -277.247208)
			(xy 363.737101 -277.215756) (xy 363.786075 -277.191496) (xy 363.838178 -277.174995) (xy 363.892189 -277.16664)
			(xy 363.919516 -277.16607) (xy 363.947499 -277.16662) (xy 364.002775 -277.175377) (xy 364.056002 -277.192673)
			(xy 364.105867 -277.218081) (xy 364.151145 -277.250977) (xy 364.190719 -277.290551) (xy 364.223616 -277.335828)
			(xy 364.249025 -277.385693) (xy 364.266322 -277.438919) (xy 364.275079 -277.494195) (xy 364.275624 -277.522178)
			(xy 364.275135 -277.549081) (xy 364.503452 -277.549081) (xy 364.503452 -277.495783) (xy 364.511395 -277.443079)
			(xy 364.527105 -277.392149) (xy 364.550231 -277.344128) (xy 364.580255 -277.300091) (xy 364.616507 -277.26102)
			(xy 364.658178 -277.227789) (xy 364.704336 -277.20114) (xy 364.75395 -277.181668) (xy 364.805912 -277.169808)
			(xy 364.859062 -277.165825) (xy 364.912212 -277.169808) (xy 364.964174 -277.181668) (xy 365.013788 -277.20114)
			(xy 365.059946 -277.227789) (xy 365.101617 -277.26102) (xy 365.137869 -277.300091) (xy 365.167893 -277.344128)
			(xy 365.191019 -277.392149) (xy 365.206729 -277.443079) (xy 365.214672 -277.495783) (xy 365.21517 -277.522432)
			(xy 365.214677 -277.548827) (xy 365.443506 -277.548827) (xy 365.443506 -277.495529) (xy 365.451449 -277.442825)
			(xy 365.467159 -277.391895) (xy 365.490285 -277.343874) (xy 365.520309 -277.299837) (xy 365.556561 -277.260766)
			(xy 365.598232 -277.227535) (xy 365.64439 -277.200886) (xy 365.694004 -277.181414) (xy 365.745966 -277.169554)
			(xy 365.799116 -277.165571) (xy 365.852266 -277.169554) (xy 365.904228 -277.181414) (xy 365.953842 -277.200886)
			(xy 366 -277.227535) (xy 366.041671 -277.260766) (xy 366.077923 -277.299837) (xy 366.107947 -277.343874)
			(xy 366.131073 -277.391895) (xy 366.146783 -277.442825) (xy 366.154726 -277.495529) (xy 366.155224 -277.522178)
			(xy 366.154726 -277.548827) (xy 366.154688 -277.549081) (xy 366.383306 -277.549081) (xy 366.383306 -277.495783)
			(xy 366.391249 -277.443079) (xy 366.406959 -277.392149) (xy 366.430085 -277.344128) (xy 366.460109 -277.300091)
			(xy 366.496361 -277.26102) (xy 366.538032 -277.227789) (xy 366.58419 -277.20114) (xy 366.633804 -277.181668)
			(xy 366.685766 -277.169808) (xy 366.738916 -277.165825) (xy 366.792066 -277.169808) (xy 366.844028 -277.181668)
			(xy 366.893642 -277.20114) (xy 366.9398 -277.227789) (xy 366.981471 -277.26102) (xy 367.017723 -277.300091)
			(xy 367.047747 -277.344128) (xy 367.070873 -277.392149) (xy 367.086583 -277.443079) (xy 367.094526 -277.495783)
			(xy 367.095024 -277.522432) (xy 367.094531 -277.548827) (xy 367.323106 -277.548827) (xy 367.323106 -277.495529)
			(xy 367.331049 -277.442825) (xy 367.346759 -277.391895) (xy 367.369885 -277.343874) (xy 367.399909 -277.299837)
			(xy 367.436161 -277.260766) (xy 367.477832 -277.227535) (xy 367.52399 -277.200886) (xy 367.573604 -277.181414)
			(xy 367.625566 -277.169554) (xy 367.678716 -277.165571) (xy 367.731866 -277.169554) (xy 367.783828 -277.181414)
			(xy 367.833442 -277.200886) (xy 367.8796 -277.227535) (xy 367.921271 -277.260766) (xy 367.957523 -277.299837)
			(xy 367.987547 -277.343874) (xy 368.010673 -277.391895) (xy 368.026383 -277.442825) (xy 368.034326 -277.495529)
			(xy 368.034824 -277.522178) (xy 368.034326 -277.548827) (xy 368.262906 -277.548827) (xy 368.262906 -277.495529)
			(xy 368.270849 -277.442825) (xy 368.286559 -277.391895) (xy 368.309685 -277.343874) (xy 368.339709 -277.299837)
			(xy 368.375961 -277.260766) (xy 368.417632 -277.227535) (xy 368.46379 -277.200886) (xy 368.513404 -277.181414)
			(xy 368.565366 -277.169554) (xy 368.618516 -277.165571) (xy 368.671666 -277.169554) (xy 368.723628 -277.181414)
			(xy 368.773242 -277.200886) (xy 368.8194 -277.227535) (xy 368.861071 -277.260766) (xy 368.897323 -277.299837)
			(xy 368.927347 -277.343874) (xy 368.950473 -277.391895) (xy 368.966183 -277.442825) (xy 368.974126 -277.495529)
			(xy 368.974624 -277.522178) (xy 368.974126 -277.548827) (xy 369.202706 -277.548827) (xy 369.202706 -277.495529)
			(xy 369.210649 -277.442825) (xy 369.226359 -277.391895) (xy 369.249485 -277.343874) (xy 369.279509 -277.299837)
			(xy 369.315761 -277.260766) (xy 369.357432 -277.227535) (xy 369.40359 -277.200886) (xy 369.453204 -277.181414)
			(xy 369.505166 -277.169554) (xy 369.558316 -277.165571) (xy 369.611466 -277.169554) (xy 369.663428 -277.181414)
			(xy 369.713042 -277.200886) (xy 369.7592 -277.227535) (xy 369.800871 -277.260766) (xy 369.837123 -277.299837)
			(xy 369.867147 -277.343874) (xy 369.890273 -277.391895) (xy 369.905983 -277.442825) (xy 369.913926 -277.495529)
			(xy 369.914424 -277.522178) (xy 369.913926 -277.548827) (xy 370.142506 -277.548827) (xy 370.142506 -277.495529)
			(xy 370.150449 -277.442825) (xy 370.166159 -277.391895) (xy 370.189285 -277.343874) (xy 370.219309 -277.299837)
			(xy 370.255561 -277.260766) (xy 370.297232 -277.227535) (xy 370.34339 -277.200886) (xy 370.393004 -277.181414)
			(xy 370.444966 -277.169554) (xy 370.498116 -277.165571) (xy 370.551266 -277.169554) (xy 370.603228 -277.181414)
			(xy 370.652842 -277.200886) (xy 370.699 -277.227535) (xy 370.740671 -277.260766) (xy 370.776923 -277.299837)
			(xy 370.806947 -277.343874) (xy 370.830073 -277.391895) (xy 370.845783 -277.442825) (xy 370.853726 -277.495529)
			(xy 370.854224 -277.522178) (xy 370.853726 -277.548827) (xy 370.853688 -277.549081) (xy 371.082052 -277.549081)
			(xy 371.082052 -277.495783) (xy 371.089995 -277.443079) (xy 371.105705 -277.392149) (xy 371.128831 -277.344128)
			(xy 371.158855 -277.300091) (xy 371.195107 -277.26102) (xy 371.236778 -277.227789) (xy 371.282936 -277.20114)
			(xy 371.33255 -277.181668) (xy 371.384512 -277.169808) (xy 371.437662 -277.165825) (xy 371.490812 -277.169808)
			(xy 371.542774 -277.181668) (xy 371.592388 -277.20114) (xy 371.638546 -277.227789) (xy 371.680217 -277.26102)
			(xy 371.716469 -277.300091) (xy 371.746493 -277.344128) (xy 371.769619 -277.392149) (xy 371.785329 -277.443079)
			(xy 371.793272 -277.495783) (xy 371.79377 -277.522432) (xy 371.793272 -277.549081) (xy 372.021852 -277.549081)
			(xy 372.021852 -277.495783) (xy 372.029795 -277.443079) (xy 372.045505 -277.392149) (xy 372.068631 -277.344128)
			(xy 372.098655 -277.300091) (xy 372.134907 -277.26102) (xy 372.176578 -277.227789) (xy 372.222736 -277.20114)
			(xy 372.27235 -277.181668) (xy 372.324312 -277.169808) (xy 372.377462 -277.165825) (xy 372.430612 -277.169808)
			(xy 372.482574 -277.181668) (xy 372.532188 -277.20114) (xy 372.578346 -277.227789) (xy 372.620017 -277.26102)
			(xy 372.656269 -277.300091) (xy 372.686293 -277.344128) (xy 372.709419 -277.392149) (xy 372.725129 -277.443079)
			(xy 372.733072 -277.495783) (xy 372.73357 -277.522432) (xy 372.733072 -277.549081) (xy 372.961906 -277.549081)
			(xy 372.961906 -277.495783) (xy 372.969849 -277.443079) (xy 372.985559 -277.392149) (xy 373.008685 -277.344128)
			(xy 373.038709 -277.300091) (xy 373.074961 -277.26102) (xy 373.116632 -277.227789) (xy 373.16279 -277.20114)
			(xy 373.212404 -277.181668) (xy 373.264366 -277.169808) (xy 373.317516 -277.165825) (xy 373.370666 -277.169808)
			(xy 373.422628 -277.181668) (xy 373.472242 -277.20114) (xy 373.5184 -277.227789) (xy 373.560071 -277.26102)
			(xy 373.596323 -277.300091) (xy 373.626347 -277.344128) (xy 373.649473 -277.392149) (xy 373.665183 -277.443079)
			(xy 373.673126 -277.495783) (xy 373.673624 -277.522432) (xy 373.673126 -277.549081) (xy 373.901452 -277.549081)
			(xy 373.901452 -277.495783) (xy 373.909395 -277.443079) (xy 373.925105 -277.392149) (xy 373.948231 -277.344128)
			(xy 373.978255 -277.300091) (xy 374.014507 -277.26102) (xy 374.056178 -277.227789) (xy 374.102336 -277.20114)
			(xy 374.15195 -277.181668) (xy 374.203912 -277.169808) (xy 374.257062 -277.165825) (xy 374.310212 -277.169808)
			(xy 374.362174 -277.181668) (xy 374.411788 -277.20114) (xy 374.457946 -277.227789) (xy 374.499617 -277.26102)
			(xy 374.535869 -277.300091) (xy 374.565893 -277.344128) (xy 374.589019 -277.392149) (xy 374.604729 -277.443079)
			(xy 374.612672 -277.495783) (xy 374.61317 -277.522432) (xy 374.612672 -277.549081) (xy 374.841252 -277.549081)
			(xy 374.841252 -277.495783) (xy 374.849195 -277.443079) (xy 374.864905 -277.392149) (xy 374.888031 -277.344128)
			(xy 374.918055 -277.300091) (xy 374.954307 -277.26102) (xy 374.995978 -277.227789) (xy 375.042136 -277.20114)
			(xy 375.09175 -277.181668) (xy 375.143712 -277.169808) (xy 375.196862 -277.165825) (xy 375.250012 -277.169808)
			(xy 375.301974 -277.181668) (xy 375.351588 -277.20114) (xy 375.397746 -277.227789) (xy 375.439417 -277.26102)
			(xy 375.475669 -277.300091) (xy 375.505693 -277.344128) (xy 375.528819 -277.392149) (xy 375.544529 -277.443079)
			(xy 375.552472 -277.495783) (xy 375.55297 -277.522432) (xy 375.552472 -277.549081) (xy 375.781052 -277.549081)
			(xy 375.781052 -277.495783) (xy 375.788995 -277.443079) (xy 375.804705 -277.392149) (xy 375.827831 -277.344128)
			(xy 375.857855 -277.300091) (xy 375.894107 -277.26102) (xy 375.935778 -277.227789) (xy 375.981936 -277.20114)
			(xy 376.03155 -277.181668) (xy 376.083512 -277.169808) (xy 376.136662 -277.165825) (xy 376.189812 -277.169808)
			(xy 376.241774 -277.181668) (xy 376.291388 -277.20114) (xy 376.337546 -277.227789) (xy 376.379217 -277.26102)
			(xy 376.415469 -277.300091) (xy 376.445493 -277.344128) (xy 376.468619 -277.392149) (xy 376.484329 -277.443079)
			(xy 376.492272 -277.495783) (xy 376.49277 -277.522432) (xy 376.492272 -277.549081) (xy 376.720852 -277.549081)
			(xy 376.720852 -277.495783) (xy 376.728795 -277.443079) (xy 376.744505 -277.392149) (xy 376.767631 -277.344128)
			(xy 376.797655 -277.300091) (xy 376.833907 -277.26102) (xy 376.875578 -277.227789) (xy 376.921736 -277.20114)
			(xy 376.97135 -277.181668) (xy 377.023312 -277.169808) (xy 377.076462 -277.165825) (xy 377.129612 -277.169808)
			(xy 377.181574 -277.181668) (xy 377.231188 -277.20114) (xy 377.277346 -277.227789) (xy 377.319017 -277.26102)
			(xy 377.355269 -277.300091) (xy 377.385293 -277.344128) (xy 377.408419 -277.392149) (xy 377.424129 -277.443079)
			(xy 377.432072 -277.495783) (xy 377.43257 -277.522432) (xy 377.432072 -277.549081) (xy 377.660906 -277.549081)
			(xy 377.660906 -277.495783) (xy 377.668849 -277.443079) (xy 377.684559 -277.392149) (xy 377.707685 -277.344128)
			(xy 377.737709 -277.300091) (xy 377.773961 -277.26102) (xy 377.815632 -277.227789) (xy 377.86179 -277.20114)
			(xy 377.911404 -277.181668) (xy 377.963366 -277.169808) (xy 378.016516 -277.165825) (xy 378.069666 -277.169808)
			(xy 378.121628 -277.181668) (xy 378.171242 -277.20114) (xy 378.2174 -277.227789) (xy 378.259071 -277.26102)
			(xy 378.295323 -277.300091) (xy 378.325347 -277.344128) (xy 378.348473 -277.392149) (xy 378.364183 -277.443079)
			(xy 378.372126 -277.495783) (xy 378.372624 -277.522432) (xy 378.372126 -277.549081) (xy 378.600706 -277.549081)
			(xy 378.600706 -277.495783) (xy 378.608649 -277.443079) (xy 378.624359 -277.392149) (xy 378.647485 -277.344128)
			(xy 378.677509 -277.300091) (xy 378.713761 -277.26102) (xy 378.755432 -277.227789) (xy 378.80159 -277.20114)
			(xy 378.851204 -277.181668) (xy 378.903166 -277.169808) (xy 378.956316 -277.165825) (xy 379.009466 -277.169808)
			(xy 379.061428 -277.181668) (xy 379.111042 -277.20114) (xy 379.1572 -277.227789) (xy 379.198871 -277.26102)
			(xy 379.235123 -277.300091) (xy 379.265147 -277.344128) (xy 379.288273 -277.392149) (xy 379.303983 -277.443079)
			(xy 379.311926 -277.495783) (xy 379.312424 -277.522432) (xy 379.311926 -277.549081) (xy 379.540252 -277.549081)
			(xy 379.540252 -277.495783) (xy 379.548195 -277.443079) (xy 379.563905 -277.392149) (xy 379.587031 -277.344128)
			(xy 379.617055 -277.300091) (xy 379.653307 -277.26102) (xy 379.694978 -277.227789) (xy 379.741136 -277.20114)
			(xy 379.79075 -277.181668) (xy 379.842712 -277.169808) (xy 379.895862 -277.165825) (xy 379.949012 -277.169808)
			(xy 380.000974 -277.181668) (xy 380.050588 -277.20114) (xy 380.096746 -277.227789) (xy 380.138417 -277.26102)
			(xy 380.174669 -277.300091) (xy 380.204693 -277.344128) (xy 380.227819 -277.392149) (xy 380.243529 -277.443079)
			(xy 380.251472 -277.495783) (xy 380.25197 -277.522432) (xy 380.251472 -277.549081) (xy 380.480052 -277.549081)
			(xy 380.480052 -277.495783) (xy 380.487995 -277.443079) (xy 380.503705 -277.392149) (xy 380.526831 -277.344128)
			(xy 380.556855 -277.300091) (xy 380.593107 -277.26102) (xy 380.634778 -277.227789) (xy 380.680936 -277.20114)
			(xy 380.73055 -277.181668) (xy 380.782512 -277.169808) (xy 380.835662 -277.165825) (xy 380.888812 -277.169808)
			(xy 380.940774 -277.181668) (xy 380.990388 -277.20114) (xy 381.036546 -277.227789) (xy 381.078217 -277.26102)
			(xy 381.114469 -277.300091) (xy 381.144493 -277.344128) (xy 381.167619 -277.392149) (xy 381.183329 -277.443079)
			(xy 381.191272 -277.495783) (xy 381.19177 -277.522432) (xy 381.191272 -277.549081) (xy 381.183329 -277.601785)
			(xy 381.167619 -277.652715) (xy 381.144493 -277.700736) (xy 381.114469 -277.744773) (xy 381.078217 -277.783844)
			(xy 381.036546 -277.817075) (xy 380.990388 -277.843724) (xy 380.940774 -277.863196) (xy 380.888812 -277.875056)
			(xy 380.835662 -277.87904) (xy 380.782512 -277.875056) (xy 380.73055 -277.863196) (xy 380.680936 -277.843724)
			(xy 380.634778 -277.817075) (xy 380.593107 -277.783844) (xy 380.556855 -277.744773) (xy 380.526831 -277.700736)
			(xy 380.503705 -277.652715) (xy 380.487995 -277.601785) (xy 380.480052 -277.549081) (xy 380.251472 -277.549081)
			(xy 380.243529 -277.601785) (xy 380.227819 -277.652715) (xy 380.204693 -277.700736) (xy 380.174669 -277.744773)
			(xy 380.138417 -277.783844) (xy 380.096746 -277.817075) (xy 380.050588 -277.843724) (xy 380.000974 -277.863196)
			(xy 379.949012 -277.875056) (xy 379.895862 -277.87904) (xy 379.842712 -277.875056) (xy 379.79075 -277.863196)
			(xy 379.741136 -277.843724) (xy 379.694978 -277.817075) (xy 379.653307 -277.783844) (xy 379.617055 -277.744773)
			(xy 379.587031 -277.700736) (xy 379.563905 -277.652715) (xy 379.548195 -277.601785) (xy 379.540252 -277.549081)
			(xy 379.311926 -277.549081) (xy 379.303983 -277.601785) (xy 379.288273 -277.652715) (xy 379.265147 -277.700736)
			(xy 379.235123 -277.744773) (xy 379.198871 -277.783844) (xy 379.1572 -277.817075) (xy 379.111042 -277.843724)
			(xy 379.061428 -277.863196) (xy 379.009466 -277.875056) (xy 378.956316 -277.87904) (xy 378.903166 -277.875056)
			(xy 378.851204 -277.863196) (xy 378.80159 -277.843724) (xy 378.755432 -277.817075) (xy 378.713761 -277.783844)
			(xy 378.677509 -277.744773) (xy 378.647485 -277.700736) (xy 378.624359 -277.652715) (xy 378.608649 -277.601785)
			(xy 378.600706 -277.549081) (xy 378.372126 -277.549081) (xy 378.364183 -277.601785) (xy 378.348473 -277.652715)
			(xy 378.325347 -277.700736) (xy 378.295323 -277.744773) (xy 378.259071 -277.783844) (xy 378.2174 -277.817075)
			(xy 378.171242 -277.843724) (xy 378.121628 -277.863196) (xy 378.069666 -277.875056) (xy 378.016516 -277.87904)
			(xy 377.963366 -277.875056) (xy 377.911404 -277.863196) (xy 377.86179 -277.843724) (xy 377.815632 -277.817075)
			(xy 377.773961 -277.783844) (xy 377.737709 -277.744773) (xy 377.707685 -277.700736) (xy 377.684559 -277.652715)
			(xy 377.668849 -277.601785) (xy 377.660906 -277.549081) (xy 377.432072 -277.549081) (xy 377.424129 -277.601785)
			(xy 377.408419 -277.652715) (xy 377.385293 -277.700736) (xy 377.355269 -277.744773) (xy 377.319017 -277.783844)
			(xy 377.277346 -277.817075) (xy 377.231188 -277.843724) (xy 377.181574 -277.863196) (xy 377.129612 -277.875056)
			(xy 377.076462 -277.87904) (xy 377.023312 -277.875056) (xy 376.97135 -277.863196) (xy 376.921736 -277.843724)
			(xy 376.875578 -277.817075) (xy 376.833907 -277.783844) (xy 376.797655 -277.744773) (xy 376.767631 -277.700736)
			(xy 376.744505 -277.652715) (xy 376.728795 -277.601785) (xy 376.720852 -277.549081) (xy 376.492272 -277.549081)
			(xy 376.484329 -277.601785) (xy 376.468619 -277.652715) (xy 376.445493 -277.700736) (xy 376.415469 -277.744773)
			(xy 376.379217 -277.783844) (xy 376.337546 -277.817075) (xy 376.291388 -277.843724) (xy 376.241774 -277.863196)
			(xy 376.189812 -277.875056) (xy 376.136662 -277.87904) (xy 376.083512 -277.875056) (xy 376.03155 -277.863196)
			(xy 375.981936 -277.843724) (xy 375.935778 -277.817075) (xy 375.894107 -277.783844) (xy 375.857855 -277.744773)
			(xy 375.827831 -277.700736) (xy 375.804705 -277.652715) (xy 375.788995 -277.601785) (xy 375.781052 -277.549081)
			(xy 375.552472 -277.549081) (xy 375.544529 -277.601785) (xy 375.528819 -277.652715) (xy 375.505693 -277.700736)
			(xy 375.475669 -277.744773) (xy 375.439417 -277.783844) (xy 375.397746 -277.817075) (xy 375.351588 -277.843724)
			(xy 375.301974 -277.863196) (xy 375.250012 -277.875056) (xy 375.196862 -277.87904) (xy 375.143712 -277.875056)
			(xy 375.09175 -277.863196) (xy 375.042136 -277.843724) (xy 374.995978 -277.817075) (xy 374.954307 -277.783844)
			(xy 374.918055 -277.744773) (xy 374.888031 -277.700736) (xy 374.864905 -277.652715) (xy 374.849195 -277.601785)
			(xy 374.841252 -277.549081) (xy 374.612672 -277.549081) (xy 374.604729 -277.601785) (xy 374.589019 -277.652715)
			(xy 374.565893 -277.700736) (xy 374.535869 -277.744773) (xy 374.499617 -277.783844) (xy 374.457946 -277.817075)
			(xy 374.411788 -277.843724) (xy 374.362174 -277.863196) (xy 374.310212 -277.875056) (xy 374.257062 -277.87904)
			(xy 374.203912 -277.875056) (xy 374.15195 -277.863196) (xy 374.102336 -277.843724) (xy 374.056178 -277.817075)
			(xy 374.014507 -277.783844) (xy 373.978255 -277.744773) (xy 373.948231 -277.700736) (xy 373.925105 -277.652715)
			(xy 373.909395 -277.601785) (xy 373.901452 -277.549081) (xy 373.673126 -277.549081) (xy 373.665183 -277.601785)
			(xy 373.649473 -277.652715) (xy 373.626347 -277.700736) (xy 373.596323 -277.744773) (xy 373.560071 -277.783844)
			(xy 373.5184 -277.817075) (xy 373.472242 -277.843724) (xy 373.422628 -277.863196) (xy 373.370666 -277.875056)
			(xy 373.317516 -277.87904) (xy 373.264366 -277.875056) (xy 373.212404 -277.863196) (xy 373.16279 -277.843724)
			(xy 373.116632 -277.817075) (xy 373.074961 -277.783844) (xy 373.038709 -277.744773) (xy 373.008685 -277.700736)
			(xy 372.985559 -277.652715) (xy 372.969849 -277.601785) (xy 372.961906 -277.549081) (xy 372.733072 -277.549081)
			(xy 372.725129 -277.601785) (xy 372.709419 -277.652715) (xy 372.686293 -277.700736) (xy 372.656269 -277.744773)
			(xy 372.620017 -277.783844) (xy 372.578346 -277.817075) (xy 372.532188 -277.843724) (xy 372.482574 -277.863196)
			(xy 372.430612 -277.875056) (xy 372.377462 -277.87904) (xy 372.324312 -277.875056) (xy 372.27235 -277.863196)
			(xy 372.222736 -277.843724) (xy 372.176578 -277.817075) (xy 372.134907 -277.783844) (xy 372.098655 -277.744773)
			(xy 372.068631 -277.700736) (xy 372.045505 -277.652715) (xy 372.029795 -277.601785) (xy 372.021852 -277.549081)
			(xy 371.793272 -277.549081) (xy 371.785329 -277.601785) (xy 371.769619 -277.652715) (xy 371.746493 -277.700736)
			(xy 371.716469 -277.744773) (xy 371.680217 -277.783844) (xy 371.638546 -277.817075) (xy 371.592388 -277.843724)
			(xy 371.542774 -277.863196) (xy 371.490812 -277.875056) (xy 371.437662 -277.87904) (xy 371.384512 -277.875056)
			(xy 371.33255 -277.863196) (xy 371.282936 -277.843724) (xy 371.236778 -277.817075) (xy 371.195107 -277.783844)
			(xy 371.158855 -277.744773) (xy 371.128831 -277.700736) (xy 371.105705 -277.652715) (xy 371.089995 -277.601785)
			(xy 371.082052 -277.549081) (xy 370.853688 -277.549081) (xy 370.845783 -277.601531) (xy 370.830073 -277.652461)
			(xy 370.806947 -277.700482) (xy 370.776923 -277.744519) (xy 370.740671 -277.78359) (xy 370.699 -277.816821)
			(xy 370.652842 -277.84347) (xy 370.603228 -277.862942) (xy 370.551266 -277.874802) (xy 370.498116 -277.878786)
			(xy 370.444966 -277.874802) (xy 370.393004 -277.862942) (xy 370.34339 -277.84347) (xy 370.297232 -277.816821)
			(xy 370.255561 -277.78359) (xy 370.219309 -277.744519) (xy 370.189285 -277.700482) (xy 370.166159 -277.652461)
			(xy 370.150449 -277.601531) (xy 370.142506 -277.548827) (xy 369.913926 -277.548827) (xy 369.905983 -277.601531)
			(xy 369.890273 -277.652461) (xy 369.867147 -277.700482) (xy 369.837123 -277.744519) (xy 369.800871 -277.78359)
			(xy 369.7592 -277.816821) (xy 369.713042 -277.84347) (xy 369.663428 -277.862942) (xy 369.611466 -277.874802)
			(xy 369.558316 -277.878786) (xy 369.505166 -277.874802) (xy 369.453204 -277.862942) (xy 369.40359 -277.84347)
			(xy 369.357432 -277.816821) (xy 369.315761 -277.78359) (xy 369.279509 -277.744519) (xy 369.249485 -277.700482)
			(xy 369.226359 -277.652461) (xy 369.210649 -277.601531) (xy 369.202706 -277.548827) (xy 368.974126 -277.548827)
			(xy 368.966183 -277.601531) (xy 368.950473 -277.652461) (xy 368.927347 -277.700482) (xy 368.897323 -277.744519)
			(xy 368.861071 -277.78359) (xy 368.8194 -277.816821) (xy 368.773242 -277.84347) (xy 368.723628 -277.862942)
			(xy 368.671666 -277.874802) (xy 368.618516 -277.878786) (xy 368.565366 -277.874802) (xy 368.513404 -277.862942)
			(xy 368.46379 -277.84347) (xy 368.417632 -277.816821) (xy 368.375961 -277.78359) (xy 368.339709 -277.744519)
			(xy 368.309685 -277.700482) (xy 368.286559 -277.652461) (xy 368.270849 -277.601531) (xy 368.262906 -277.548827)
			(xy 368.034326 -277.548827) (xy 368.026383 -277.601531) (xy 368.010673 -277.652461) (xy 367.987547 -277.700482)
			(xy 367.957523 -277.744519) (xy 367.921271 -277.78359) (xy 367.8796 -277.816821) (xy 367.833442 -277.84347)
			(xy 367.783828 -277.862942) (xy 367.731866 -277.874802) (xy 367.678716 -277.878786) (xy 367.625566 -277.874802)
			(xy 367.573604 -277.862942) (xy 367.52399 -277.84347) (xy 367.477832 -277.816821) (xy 367.436161 -277.78359)
			(xy 367.399909 -277.744519) (xy 367.369885 -277.700482) (xy 367.346759 -277.652461) (xy 367.331049 -277.601531)
			(xy 367.323106 -277.548827) (xy 367.094531 -277.548827) (xy 367.094526 -277.549081) (xy 367.086583 -277.601785)
			(xy 367.070873 -277.652715) (xy 367.047747 -277.700736) (xy 367.017723 -277.744773) (xy 366.981471 -277.783844)
			(xy 366.9398 -277.817075) (xy 366.893642 -277.843724) (xy 366.844028 -277.863196) (xy 366.792066 -277.875056)
			(xy 366.738916 -277.87904) (xy 366.685766 -277.875056) (xy 366.633804 -277.863196) (xy 366.58419 -277.843724)
			(xy 366.538032 -277.817075) (xy 366.496361 -277.783844) (xy 366.460109 -277.744773) (xy 366.430085 -277.700736)
			(xy 366.406959 -277.652715) (xy 366.391249 -277.601785) (xy 366.383306 -277.549081) (xy 366.154688 -277.549081)
			(xy 366.146783 -277.601531) (xy 366.131073 -277.652461) (xy 366.107947 -277.700482) (xy 366.077923 -277.744519)
			(xy 366.041671 -277.78359) (xy 366 -277.816821) (xy 365.953842 -277.84347) (xy 365.904228 -277.862942)
			(xy 365.852266 -277.874802) (xy 365.799116 -277.878786) (xy 365.745966 -277.874802) (xy 365.694004 -277.862942)
			(xy 365.64439 -277.84347) (xy 365.598232 -277.816821) (xy 365.556561 -277.78359) (xy 365.520309 -277.744519)
			(xy 365.490285 -277.700482) (xy 365.467159 -277.652461) (xy 365.451449 -277.601531) (xy 365.443506 -277.548827)
			(xy 365.214677 -277.548827) (xy 365.214672 -277.549081) (xy 365.206729 -277.601785) (xy 365.191019 -277.652715)
			(xy 365.167893 -277.700736) (xy 365.137869 -277.744773) (xy 365.101617 -277.783844) (xy 365.059946 -277.817075)
			(xy 365.013788 -277.843724) (xy 364.964174 -277.863196) (xy 364.912212 -277.875056) (xy 364.859062 -277.87904)
			(xy 364.805912 -277.875056) (xy 364.75395 -277.863196) (xy 364.704336 -277.843724) (xy 364.658178 -277.817075)
			(xy 364.616507 -277.783844) (xy 364.580255 -277.744773) (xy 364.550231 -277.700736) (xy 364.527105 -277.652715)
			(xy 364.511395 -277.601785) (xy 364.503452 -277.549081) (xy 364.275135 -277.549081) (xy 364.275127 -277.549509)
			(xy 364.266778 -277.60353) (xy 364.250272 -277.655641) (xy 364.225997 -277.704618) (xy 364.194523 -277.74931)
			(xy 364.15659 -277.788668) (xy 364.135162 -277.805642) (xy 364.123981 -277.814812) (xy 364.106835 -277.83808)
			(xy 364.096884 -277.865215) (xy 364.094923 -277.894052) (xy 364.10111 -277.922285) (xy 364.11495 -277.947659)
			(xy 364.124748 -277.958296) (xy 364.19917 -278.032718) (xy 364.231936 -278.016716) (xy 364.256525 -278.005184)
			(xy 364.308329 -277.988881) (xy 364.362008 -277.980639) (xy 364.389162 -277.98014) (xy 364.417148 -277.980658)
			(xy 364.472431 -277.989409) (xy 364.525665 -278.006702) (xy 364.575537 -278.032111) (xy 364.620819 -278.06501)
			(xy 364.660396 -278.104589) (xy 364.693294 -278.149872) (xy 364.718702 -278.199745) (xy 364.735993 -278.252978)
			(xy 364.744743 -278.308262) (xy 364.74527 -278.336248) (xy 364.744766 -278.362897) (xy 364.973352 -278.362897)
			(xy 364.973352 -278.309599) (xy 364.981295 -278.256895) (xy 364.997005 -278.205965) (xy 365.020131 -278.157944)
			(xy 365.050155 -278.113907) (xy 365.086407 -278.074836) (xy 365.128078 -278.041605) (xy 365.174236 -278.014956)
			(xy 365.22385 -277.995484) (xy 365.275812 -277.983624) (xy 365.328962 -277.979641) (xy 365.382112 -277.983624)
			(xy 365.434074 -277.995484) (xy 365.483688 -278.014956) (xy 365.529846 -278.041605) (xy 365.571517 -278.074836)
			(xy 365.607769 -278.113907) (xy 365.637793 -278.157944) (xy 365.660919 -278.205965) (xy 365.676629 -278.256895)
			(xy 365.684572 -278.309599) (xy 365.68507 -278.336248) (xy 365.684572 -278.362897) (xy 365.913152 -278.362897)
			(xy 365.913152 -278.309599) (xy 365.921095 -278.256895) (xy 365.936805 -278.205965) (xy 365.959931 -278.157944)
			(xy 365.989955 -278.113907) (xy 366.026207 -278.074836) (xy 366.067878 -278.041605) (xy 366.114036 -278.014956)
			(xy 366.16365 -277.995484) (xy 366.215612 -277.983624) (xy 366.268762 -277.979641) (xy 366.321912 -277.983624)
			(xy 366.373874 -277.995484) (xy 366.423488 -278.014956) (xy 366.469646 -278.041605) (xy 366.511317 -278.074836)
			(xy 366.547569 -278.113907) (xy 366.577593 -278.157944) (xy 366.600719 -278.205965) (xy 366.616429 -278.256895)
			(xy 366.624372 -278.309599) (xy 366.62487 -278.336248) (xy 366.624372 -278.362897) (xy 366.624334 -278.363151)
			(xy 366.853206 -278.363151) (xy 366.853206 -278.309853) (xy 366.861149 -278.257149) (xy 366.876859 -278.206219)
			(xy 366.899985 -278.158198) (xy 366.930009 -278.114161) (xy 366.966261 -278.07509) (xy 367.007932 -278.041859)
			(xy 367.05409 -278.01521) (xy 367.103704 -277.995738) (xy 367.155666 -277.983878) (xy 367.208816 -277.979895)
			(xy 367.261966 -277.983878) (xy 367.313928 -277.995738) (xy 367.363542 -278.01521) (xy 367.4097 -278.041859)
			(xy 367.451371 -278.07509) (xy 367.487623 -278.114161) (xy 367.517647 -278.158198) (xy 367.540773 -278.206219)
			(xy 367.556483 -278.257149) (xy 367.564426 -278.309853) (xy 367.564924 -278.336502) (xy 367.564431 -278.362897)
			(xy 368.732552 -278.362897) (xy 368.732552 -278.309599) (xy 368.740495 -278.256895) (xy 368.756205 -278.205965)
			(xy 368.779331 -278.157944) (xy 368.809355 -278.113907) (xy 368.845607 -278.074836) (xy 368.887278 -278.041605)
			(xy 368.933436 -278.014956) (xy 368.98305 -277.995484) (xy 369.035012 -277.983624) (xy 369.088162 -277.979641)
			(xy 369.141312 -277.983624) (xy 369.193274 -277.995484) (xy 369.242888 -278.014956) (xy 369.289046 -278.041605)
			(xy 369.330717 -278.074836) (xy 369.366969 -278.113907) (xy 369.396993 -278.157944) (xy 369.420119 -278.205965)
			(xy 369.435829 -278.256895) (xy 369.443772 -278.309599) (xy 369.44427 -278.336248) (xy 369.443772 -278.362897)
			(xy 369.443734 -278.363151) (xy 369.672352 -278.363151) (xy 369.672352 -278.309853) (xy 369.680295 -278.257149)
			(xy 369.696005 -278.206219) (xy 369.719131 -278.158198) (xy 369.749155 -278.114161) (xy 369.785407 -278.07509)
			(xy 369.827078 -278.041859) (xy 369.873236 -278.01521) (xy 369.92285 -277.995738) (xy 369.974812 -277.983878)
			(xy 370.027962 -277.979895) (xy 370.081112 -277.983878) (xy 370.133074 -277.995738) (xy 370.182688 -278.01521)
			(xy 370.228846 -278.041859) (xy 370.270517 -278.07509) (xy 370.306769 -278.114161) (xy 370.336793 -278.158198)
			(xy 370.359919 -278.206219) (xy 370.375629 -278.257149) (xy 370.383572 -278.309853) (xy 370.38407 -278.336502)
			(xy 370.383572 -278.363151) (xy 370.612406 -278.363151) (xy 370.612406 -278.309853) (xy 370.620349 -278.257149)
			(xy 370.636059 -278.206219) (xy 370.659185 -278.158198) (xy 370.689209 -278.114161) (xy 370.725461 -278.07509)
			(xy 370.767132 -278.041859) (xy 370.81329 -278.01521) (xy 370.862904 -277.995738) (xy 370.914866 -277.983878)
			(xy 370.968016 -277.979895) (xy 371.021166 -277.983878) (xy 371.073128 -277.995738) (xy 371.122742 -278.01521)
			(xy 371.1689 -278.041859) (xy 371.210571 -278.07509) (xy 371.246823 -278.114161) (xy 371.276847 -278.158198)
			(xy 371.299973 -278.206219) (xy 371.315683 -278.257149) (xy 371.323626 -278.309853) (xy 371.324124 -278.336502)
			(xy 371.323626 -278.363151) (xy 372.492006 -278.363151) (xy 372.492006 -278.309853) (xy 372.499949 -278.257149)
			(xy 372.515659 -278.206219) (xy 372.538785 -278.158198) (xy 372.568809 -278.114161) (xy 372.605061 -278.07509)
			(xy 372.646732 -278.041859) (xy 372.69289 -278.01521) (xy 372.742504 -277.995738) (xy 372.794466 -277.983878)
			(xy 372.847616 -277.979895) (xy 372.900766 -277.983878) (xy 372.952728 -277.995738) (xy 373.002342 -278.01521)
			(xy 373.0485 -278.041859) (xy 373.090171 -278.07509) (xy 373.126423 -278.114161) (xy 373.156447 -278.158198)
			(xy 373.179573 -278.206219) (xy 373.195283 -278.257149) (xy 373.203226 -278.309853) (xy 373.203724 -278.336502)
			(xy 373.203226 -278.363151) (xy 373.431806 -278.363151) (xy 373.431806 -278.309853) (xy 373.439749 -278.257149)
			(xy 373.455459 -278.206219) (xy 373.478585 -278.158198) (xy 373.508609 -278.114161) (xy 373.544861 -278.07509)
			(xy 373.586532 -278.041859) (xy 373.63269 -278.01521) (xy 373.682304 -277.995738) (xy 373.734266 -277.983878)
			(xy 373.787416 -277.979895) (xy 373.840566 -277.983878) (xy 373.892528 -277.995738) (xy 373.942142 -278.01521)
			(xy 373.9883 -278.041859) (xy 374.029971 -278.07509) (xy 374.066223 -278.114161) (xy 374.096247 -278.158198)
			(xy 374.119373 -278.206219) (xy 374.135083 -278.257149) (xy 374.143026 -278.309853) (xy 374.143524 -278.336502)
			(xy 374.143026 -278.363151) (xy 374.371606 -278.363151) (xy 374.371606 -278.309853) (xy 374.379549 -278.257149)
			(xy 374.395259 -278.206219) (xy 374.418385 -278.158198) (xy 374.448409 -278.114161) (xy 374.484661 -278.07509)
			(xy 374.526332 -278.041859) (xy 374.57249 -278.01521) (xy 374.622104 -277.995738) (xy 374.674066 -277.983878)
			(xy 374.727216 -277.979895) (xy 374.780366 -277.983878) (xy 374.832328 -277.995738) (xy 374.881942 -278.01521)
			(xy 374.9281 -278.041859) (xy 374.969771 -278.07509) (xy 375.006023 -278.114161) (xy 375.036047 -278.158198)
			(xy 375.059173 -278.206219) (xy 375.074883 -278.257149) (xy 375.082826 -278.309853) (xy 375.083324 -278.336502)
			(xy 375.082826 -278.363151) (xy 375.311406 -278.363151) (xy 375.311406 -278.309853) (xy 375.319349 -278.257149)
			(xy 375.335059 -278.206219) (xy 375.358185 -278.158198) (xy 375.388209 -278.114161) (xy 375.424461 -278.07509)
			(xy 375.466132 -278.041859) (xy 375.51229 -278.01521) (xy 375.561904 -277.995738) (xy 375.613866 -277.983878)
			(xy 375.667016 -277.979895) (xy 375.720166 -277.983878) (xy 375.772128 -277.995738) (xy 375.821742 -278.01521)
			(xy 375.8679 -278.041859) (xy 375.909571 -278.07509) (xy 375.945823 -278.114161) (xy 375.975847 -278.158198)
			(xy 375.998973 -278.206219) (xy 376.014683 -278.257149) (xy 376.022626 -278.309853) (xy 376.023124 -278.336502)
			(xy 376.022626 -278.363151) (xy 376.250952 -278.363151) (xy 376.250952 -278.309853) (xy 376.258895 -278.257149)
			(xy 376.274605 -278.206219) (xy 376.297731 -278.158198) (xy 376.327755 -278.114161) (xy 376.364007 -278.07509)
			(xy 376.405678 -278.041859) (xy 376.451836 -278.01521) (xy 376.50145 -277.995738) (xy 376.553412 -277.983878)
			(xy 376.606562 -277.979895) (xy 376.659712 -277.983878) (xy 376.711674 -277.995738) (xy 376.761288 -278.01521)
			(xy 376.807446 -278.041859) (xy 376.849117 -278.07509) (xy 376.885369 -278.114161) (xy 376.915393 -278.158198)
			(xy 376.938519 -278.206219) (xy 376.954229 -278.257149) (xy 376.962172 -278.309853) (xy 376.96267 -278.336502)
			(xy 376.962172 -278.363151) (xy 377.191006 -278.363151) (xy 377.191006 -278.309853) (xy 377.198949 -278.257149)
			(xy 377.214659 -278.206219) (xy 377.237785 -278.158198) (xy 377.267809 -278.114161) (xy 377.304061 -278.07509)
			(xy 377.345732 -278.041859) (xy 377.39189 -278.01521) (xy 377.441504 -277.995738) (xy 377.493466 -277.983878)
			(xy 377.546616 -277.979895) (xy 377.599766 -277.983878) (xy 377.651728 -277.995738) (xy 377.701342 -278.01521)
			(xy 377.7475 -278.041859) (xy 377.789171 -278.07509) (xy 377.825423 -278.114161) (xy 377.855447 -278.158198)
			(xy 377.878573 -278.206219) (xy 377.894283 -278.257149) (xy 377.902226 -278.309853) (xy 377.902724 -278.336502)
			(xy 377.902226 -278.363151) (xy 378.130552 -278.363151) (xy 378.130552 -278.309853) (xy 378.138495 -278.257149)
			(xy 378.154205 -278.206219) (xy 378.177331 -278.158198) (xy 378.207355 -278.114161) (xy 378.243607 -278.07509)
			(xy 378.285278 -278.041859) (xy 378.331436 -278.01521) (xy 378.38105 -277.995738) (xy 378.433012 -277.983878)
			(xy 378.486162 -277.979895) (xy 378.539312 -277.983878) (xy 378.591274 -277.995738) (xy 378.640888 -278.01521)
			(xy 378.687046 -278.041859) (xy 378.728717 -278.07509) (xy 378.764969 -278.114161) (xy 378.794993 -278.158198)
			(xy 378.818119 -278.206219) (xy 378.833829 -278.257149) (xy 378.841772 -278.309853) (xy 378.84227 -278.336502)
			(xy 378.841772 -278.363151) (xy 379.070606 -278.363151) (xy 379.070606 -278.309853) (xy 379.078549 -278.257149)
			(xy 379.094259 -278.206219) (xy 379.117385 -278.158198) (xy 379.147409 -278.114161) (xy 379.183661 -278.07509)
			(xy 379.225332 -278.041859) (xy 379.27149 -278.01521) (xy 379.321104 -277.995738) (xy 379.373066 -277.983878)
			(xy 379.426216 -277.979895) (xy 379.479366 -277.983878) (xy 379.531328 -277.995738) (xy 379.580942 -278.01521)
			(xy 379.6271 -278.041859) (xy 379.668771 -278.07509) (xy 379.705023 -278.114161) (xy 379.735047 -278.158198)
			(xy 379.758173 -278.206219) (xy 379.773883 -278.257149) (xy 379.781826 -278.309853) (xy 379.782324 -278.336502)
			(xy 379.781826 -278.363151) (xy 380.010406 -278.363151) (xy 380.010406 -278.309853) (xy 380.018349 -278.257149)
			(xy 380.034059 -278.206219) (xy 380.057185 -278.158198) (xy 380.087209 -278.114161) (xy 380.123461 -278.07509)
			(xy 380.165132 -278.041859) (xy 380.21129 -278.01521) (xy 380.260904 -277.995738) (xy 380.312866 -277.983878)
			(xy 380.366016 -277.979895) (xy 380.419166 -277.983878) (xy 380.471128 -277.995738) (xy 380.520742 -278.01521)
			(xy 380.5669 -278.041859) (xy 380.608571 -278.07509) (xy 380.644823 -278.114161) (xy 380.674847 -278.158198)
			(xy 380.697973 -278.206219) (xy 380.713683 -278.257149) (xy 380.721626 -278.309853) (xy 380.722124 -278.336502)
			(xy 380.721626 -278.363151) (xy 380.950206 -278.363151) (xy 380.950206 -278.309853) (xy 380.958149 -278.257149)
			(xy 380.973859 -278.206219) (xy 380.996985 -278.158198) (xy 381.027009 -278.114161) (xy 381.063261 -278.07509)
			(xy 381.104932 -278.041859) (xy 381.15109 -278.01521) (xy 381.200704 -277.995738) (xy 381.252666 -277.983878)
			(xy 381.305816 -277.979895) (xy 381.358966 -277.983878) (xy 381.410928 -277.995738) (xy 381.460542 -278.01521)
			(xy 381.5067 -278.041859) (xy 381.548371 -278.07509) (xy 381.584623 -278.114161) (xy 381.614647 -278.158198)
			(xy 381.637773 -278.206219) (xy 381.653483 -278.257149) (xy 381.661426 -278.309853) (xy 381.661924 -278.336502)
			(xy 381.661426 -278.363151) (xy 381.653483 -278.415855) (xy 381.637773 -278.466785) (xy 381.614647 -278.514806)
			(xy 381.584623 -278.558843) (xy 381.548371 -278.597914) (xy 381.5067 -278.631145) (xy 381.460542 -278.657794)
			(xy 381.410928 -278.677266) (xy 381.358966 -278.689126) (xy 381.305816 -278.69311) (xy 381.252666 -278.689126)
			(xy 381.200704 -278.677266) (xy 381.15109 -278.657794) (xy 381.104932 -278.631145) (xy 381.063261 -278.597914)
			(xy 381.027009 -278.558843) (xy 380.996985 -278.514806) (xy 380.973859 -278.466785) (xy 380.958149 -278.415855)
			(xy 380.950206 -278.363151) (xy 380.721626 -278.363151) (xy 380.713683 -278.415855) (xy 380.697973 -278.466785)
			(xy 380.674847 -278.514806) (xy 380.644823 -278.558843) (xy 380.608571 -278.597914) (xy 380.5669 -278.631145)
			(xy 380.520742 -278.657794) (xy 380.471128 -278.677266) (xy 380.419166 -278.689126) (xy 380.366016 -278.69311)
			(xy 380.312866 -278.689126) (xy 380.260904 -278.677266) (xy 380.21129 -278.657794) (xy 380.165132 -278.631145)
			(xy 380.123461 -278.597914) (xy 380.087209 -278.558843) (xy 380.057185 -278.514806) (xy 380.034059 -278.466785)
			(xy 380.018349 -278.415855) (xy 380.010406 -278.363151) (xy 379.781826 -278.363151) (xy 379.773883 -278.415855)
			(xy 379.758173 -278.466785) (xy 379.735047 -278.514806) (xy 379.705023 -278.558843) (xy 379.668771 -278.597914)
			(xy 379.6271 -278.631145) (xy 379.580942 -278.657794) (xy 379.531328 -278.677266) (xy 379.479366 -278.689126)
			(xy 379.426216 -278.69311) (xy 379.373066 -278.689126) (xy 379.321104 -278.677266) (xy 379.27149 -278.657794)
			(xy 379.225332 -278.631145) (xy 379.183661 -278.597914) (xy 379.147409 -278.558843) (xy 379.117385 -278.514806)
			(xy 379.094259 -278.466785) (xy 379.078549 -278.415855) (xy 379.070606 -278.363151) (xy 378.841772 -278.363151)
			(xy 378.833829 -278.415855) (xy 378.818119 -278.466785) (xy 378.794993 -278.514806) (xy 378.764969 -278.558843)
			(xy 378.728717 -278.597914) (xy 378.687046 -278.631145) (xy 378.640888 -278.657794) (xy 378.591274 -278.677266)
			(xy 378.539312 -278.689126) (xy 378.486162 -278.69311) (xy 378.433012 -278.689126) (xy 378.38105 -278.677266)
			(xy 378.331436 -278.657794) (xy 378.285278 -278.631145) (xy 378.243607 -278.597914) (xy 378.207355 -278.558843)
			(xy 378.177331 -278.514806) (xy 378.154205 -278.466785) (xy 378.138495 -278.415855) (xy 378.130552 -278.363151)
			(xy 377.902226 -278.363151) (xy 377.894283 -278.415855) (xy 377.878573 -278.466785) (xy 377.855447 -278.514806)
			(xy 377.825423 -278.558843) (xy 377.789171 -278.597914) (xy 377.7475 -278.631145) (xy 377.701342 -278.657794)
			(xy 377.651728 -278.677266) (xy 377.599766 -278.689126) (xy 377.546616 -278.69311) (xy 377.493466 -278.689126)
			(xy 377.441504 -278.677266) (xy 377.39189 -278.657794) (xy 377.345732 -278.631145) (xy 377.304061 -278.597914)
			(xy 377.267809 -278.558843) (xy 377.237785 -278.514806) (xy 377.214659 -278.466785) (xy 377.198949 -278.415855)
			(xy 377.191006 -278.363151) (xy 376.962172 -278.363151) (xy 376.954229 -278.415855) (xy 376.938519 -278.466785)
			(xy 376.915393 -278.514806) (xy 376.885369 -278.558843) (xy 376.849117 -278.597914) (xy 376.807446 -278.631145)
			(xy 376.761288 -278.657794) (xy 376.711674 -278.677266) (xy 376.659712 -278.689126) (xy 376.606562 -278.69311)
			(xy 376.553412 -278.689126) (xy 376.50145 -278.677266) (xy 376.451836 -278.657794) (xy 376.405678 -278.631145)
			(xy 376.364007 -278.597914) (xy 376.327755 -278.558843) (xy 376.297731 -278.514806) (xy 376.274605 -278.466785)
			(xy 376.258895 -278.415855) (xy 376.250952 -278.363151) (xy 376.022626 -278.363151) (xy 376.014683 -278.415855)
			(xy 375.998973 -278.466785) (xy 375.975847 -278.514806) (xy 375.945823 -278.558843) (xy 375.909571 -278.597914)
			(xy 375.8679 -278.631145) (xy 375.821742 -278.657794) (xy 375.772128 -278.677266) (xy 375.720166 -278.689126)
			(xy 375.667016 -278.69311) (xy 375.613866 -278.689126) (xy 375.561904 -278.677266) (xy 375.51229 -278.657794)
			(xy 375.466132 -278.631145) (xy 375.424461 -278.597914) (xy 375.388209 -278.558843) (xy 375.358185 -278.514806)
			(xy 375.335059 -278.466785) (xy 375.319349 -278.415855) (xy 375.311406 -278.363151) (xy 375.082826 -278.363151)
			(xy 375.074883 -278.415855) (xy 375.059173 -278.466785) (xy 375.036047 -278.514806) (xy 375.006023 -278.558843)
			(xy 374.969771 -278.597914) (xy 374.9281 -278.631145) (xy 374.881942 -278.657794) (xy 374.832328 -278.677266)
			(xy 374.780366 -278.689126) (xy 374.727216 -278.69311) (xy 374.674066 -278.689126) (xy 374.622104 -278.677266)
			(xy 374.57249 -278.657794) (xy 374.526332 -278.631145) (xy 374.484661 -278.597914) (xy 374.448409 -278.558843)
			(xy 374.418385 -278.514806) (xy 374.395259 -278.466785) (xy 374.379549 -278.415855) (xy 374.371606 -278.363151)
			(xy 374.143026 -278.363151) (xy 374.135083 -278.415855) (xy 374.119373 -278.466785) (xy 374.096247 -278.514806)
			(xy 374.066223 -278.558843) (xy 374.029971 -278.597914) (xy 373.9883 -278.631145) (xy 373.942142 -278.657794)
			(xy 373.892528 -278.677266) (xy 373.840566 -278.689126) (xy 373.787416 -278.69311) (xy 373.734266 -278.689126)
			(xy 373.682304 -278.677266) (xy 373.63269 -278.657794) (xy 373.586532 -278.631145) (xy 373.544861 -278.597914)
			(xy 373.508609 -278.558843) (xy 373.478585 -278.514806) (xy 373.455459 -278.466785) (xy 373.439749 -278.415855)
			(xy 373.431806 -278.363151) (xy 373.203226 -278.363151) (xy 373.195283 -278.415855) (xy 373.179573 -278.466785)
			(xy 373.156447 -278.514806) (xy 373.126423 -278.558843) (xy 373.090171 -278.597914) (xy 373.0485 -278.631145)
			(xy 373.002342 -278.657794) (xy 372.952728 -278.677266) (xy 372.900766 -278.689126) (xy 372.847616 -278.69311)
			(xy 372.794466 -278.689126) (xy 372.742504 -278.677266) (xy 372.69289 -278.657794) (xy 372.646732 -278.631145)
			(xy 372.605061 -278.597914) (xy 372.568809 -278.558843) (xy 372.538785 -278.514806) (xy 372.515659 -278.466785)
			(xy 372.499949 -278.415855) (xy 372.492006 -278.363151) (xy 371.323626 -278.363151) (xy 371.315683 -278.415855)
			(xy 371.299973 -278.466785) (xy 371.276847 -278.514806) (xy 371.246823 -278.558843) (xy 371.210571 -278.597914)
			(xy 371.1689 -278.631145) (xy 371.122742 -278.657794) (xy 371.073128 -278.677266) (xy 371.021166 -278.689126)
			(xy 370.968016 -278.69311) (xy 370.914866 -278.689126) (xy 370.862904 -278.677266) (xy 370.81329 -278.657794)
			(xy 370.767132 -278.631145) (xy 370.725461 -278.597914) (xy 370.689209 -278.558843) (xy 370.659185 -278.514806)
			(xy 370.636059 -278.466785) (xy 370.620349 -278.415855) (xy 370.612406 -278.363151) (xy 370.383572 -278.363151)
			(xy 370.375629 -278.415855) (xy 370.359919 -278.466785) (xy 370.336793 -278.514806) (xy 370.306769 -278.558843)
			(xy 370.270517 -278.597914) (xy 370.228846 -278.631145) (xy 370.182688 -278.657794) (xy 370.133074 -278.677266)
			(xy 370.081112 -278.689126) (xy 370.027962 -278.69311) (xy 369.974812 -278.689126) (xy 369.92285 -278.677266)
			(xy 369.873236 -278.657794) (xy 369.827078 -278.631145) (xy 369.785407 -278.597914) (xy 369.749155 -278.558843)
			(xy 369.719131 -278.514806) (xy 369.696005 -278.466785) (xy 369.680295 -278.415855) (xy 369.672352 -278.363151)
			(xy 369.443734 -278.363151) (xy 369.435829 -278.415601) (xy 369.420119 -278.466531) (xy 369.396993 -278.514552)
			(xy 369.366969 -278.558589) (xy 369.330717 -278.59766) (xy 369.289046 -278.630891) (xy 369.242888 -278.65754)
			(xy 369.193274 -278.677012) (xy 369.141312 -278.688872) (xy 369.088162 -278.692856) (xy 369.035012 -278.688872)
			(xy 368.98305 -278.677012) (xy 368.933436 -278.65754) (xy 368.887278 -278.630891) (xy 368.845607 -278.59766)
			(xy 368.809355 -278.558589) (xy 368.779331 -278.514552) (xy 368.756205 -278.466531) (xy 368.740495 -278.415601)
			(xy 368.732552 -278.362897) (xy 367.564431 -278.362897) (xy 367.564426 -278.363151) (xy 367.556483 -278.415855)
			(xy 367.540773 -278.466785) (xy 367.517647 -278.514806) (xy 367.487623 -278.558843) (xy 367.451371 -278.597914)
			(xy 367.4097 -278.631145) (xy 367.363542 -278.657794) (xy 367.313928 -278.677266) (xy 367.261966 -278.689126)
			(xy 367.208816 -278.69311) (xy 367.155666 -278.689126) (xy 367.103704 -278.677266) (xy 367.05409 -278.657794)
			(xy 367.007932 -278.631145) (xy 366.966261 -278.597914) (xy 366.930009 -278.558843) (xy 366.899985 -278.514806)
			(xy 366.876859 -278.466785) (xy 366.861149 -278.415855) (xy 366.853206 -278.363151) (xy 366.624334 -278.363151)
			(xy 366.616429 -278.415601) (xy 366.600719 -278.466531) (xy 366.577593 -278.514552) (xy 366.547569 -278.558589)
			(xy 366.511317 -278.59766) (xy 366.469646 -278.630891) (xy 366.423488 -278.65754) (xy 366.373874 -278.677012)
			(xy 366.321912 -278.688872) (xy 366.268762 -278.692856) (xy 366.215612 -278.688872) (xy 366.16365 -278.677012)
			(xy 366.114036 -278.65754) (xy 366.067878 -278.630891) (xy 366.026207 -278.59766) (xy 365.989955 -278.558589)
			(xy 365.959931 -278.514552) (xy 365.936805 -278.466531) (xy 365.921095 -278.415601) (xy 365.913152 -278.362897)
			(xy 365.684572 -278.362897) (xy 365.676629 -278.415601) (xy 365.660919 -278.466531) (xy 365.637793 -278.514552)
			(xy 365.607769 -278.558589) (xy 365.571517 -278.59766) (xy 365.529846 -278.630891) (xy 365.483688 -278.65754)
			(xy 365.434074 -278.677012) (xy 365.382112 -278.688872) (xy 365.328962 -278.692856) (xy 365.275812 -278.688872)
			(xy 365.22385 -278.677012) (xy 365.174236 -278.65754) (xy 365.128078 -278.630891) (xy 365.086407 -278.59766)
			(xy 365.050155 -278.558589) (xy 365.020131 -278.514552) (xy 364.997005 -278.466531) (xy 364.981295 -278.415601)
			(xy 364.973352 -278.362897) (xy 364.744766 -278.362897) (xy 364.744756 -278.363401) (xy 364.736507 -278.417076)
			(xy 364.720208 -278.468878) (xy 364.708694 -278.493474) (xy 364.692692 -278.52624) (xy 364.950248 -278.783796)
			(xy 364.950248 -278.803862) (xy 364.983268 -278.816308) (xy 365.008456 -278.8262) (xy 365.055748 -278.852499)
			(xy 365.098517 -278.88565) (xy 365.135777 -278.924891) (xy 365.16667 -278.969318) (xy 365.190486 -279.017908)
			(xy 365.206674 -279.069542) (xy 365.214864 -279.123031) (xy 365.214866 -279.176967) (xy 365.443506 -279.176967)
			(xy 365.443506 -279.123669) (xy 365.451449 -279.070965) (xy 365.467159 -279.020035) (xy 365.490285 -278.972014)
			(xy 365.520309 -278.927977) (xy 365.556561 -278.888906) (xy 365.598232 -278.855675) (xy 365.64439 -278.829026)
			(xy 365.694004 -278.809554) (xy 365.745966 -278.797694) (xy 365.799116 -278.793711) (xy 365.852266 -278.797694)
			(xy 365.904228 -278.809554) (xy 365.953842 -278.829026) (xy 366 -278.855675) (xy 366.041671 -278.888906)
			(xy 366.077923 -278.927977) (xy 366.107947 -278.972014) (xy 366.131073 -279.020035) (xy 366.146783 -279.070965)
			(xy 366.154726 -279.123669) (xy 366.155224 -279.150318) (xy 366.154726 -279.176967) (xy 367.322852 -279.176967)
			(xy 367.322852 -279.123669) (xy 367.330795 -279.070965) (xy 367.346505 -279.020035) (xy 367.369631 -278.972014)
			(xy 367.399655 -278.927977) (xy 367.435907 -278.888906) (xy 367.477578 -278.855675) (xy 367.523736 -278.829026)
			(xy 367.57335 -278.809554) (xy 367.625312 -278.797694) (xy 367.678462 -278.793711) (xy 367.731612 -278.797694)
			(xy 367.783574 -278.809554) (xy 367.833188 -278.829026) (xy 367.879346 -278.855675) (xy 367.921017 -278.888906)
			(xy 367.957269 -278.927977) (xy 367.987293 -278.972014) (xy 368.010419 -279.020035) (xy 368.026129 -279.070965)
			(xy 368.034072 -279.123669) (xy 368.03457 -279.150318) (xy 368.034072 -279.176967) (xy 368.262906 -279.176967)
			(xy 368.262906 -279.123669) (xy 368.270849 -279.070965) (xy 368.286559 -279.020035) (xy 368.309685 -278.972014)
			(xy 368.339709 -278.927977) (xy 368.375961 -278.888906) (xy 368.417632 -278.855675) (xy 368.46379 -278.829026)
			(xy 368.513404 -278.809554) (xy 368.565366 -278.797694) (xy 368.618516 -278.793711) (xy 368.671666 -278.797694)
			(xy 368.723628 -278.809554) (xy 368.773242 -278.829026) (xy 368.8194 -278.855675) (xy 368.861071 -278.888906)
			(xy 368.897323 -278.927977) (xy 368.927347 -278.972014) (xy 368.950473 -279.020035) (xy 368.966183 -279.070965)
			(xy 368.974126 -279.123669) (xy 368.974624 -279.150318) (xy 368.974126 -279.176967) (xy 369.202452 -279.176967)
			(xy 369.202452 -279.123669) (xy 369.210395 -279.070965) (xy 369.226105 -279.020035) (xy 369.249231 -278.972014)
			(xy 369.279255 -278.927977) (xy 369.315507 -278.888906) (xy 369.357178 -278.855675) (xy 369.403336 -278.829026)
			(xy 369.45295 -278.809554) (xy 369.504912 -278.797694) (xy 369.558062 -278.793711) (xy 369.611212 -278.797694)
			(xy 369.663174 -278.809554) (xy 369.712788 -278.829026) (xy 369.758946 -278.855675) (xy 369.800617 -278.888906)
			(xy 369.836869 -278.927977) (xy 369.866893 -278.972014) (xy 369.890019 -279.020035) (xy 369.905729 -279.070965)
			(xy 369.913672 -279.123669) (xy 369.91417 -279.150318) (xy 369.913672 -279.176967) (xy 370.142252 -279.176967)
			(xy 370.142252 -279.123669) (xy 370.150195 -279.070965) (xy 370.165905 -279.020035) (xy 370.189031 -278.972014)
			(xy 370.219055 -278.927977) (xy 370.255307 -278.888906) (xy 370.296978 -278.855675) (xy 370.343136 -278.829026)
			(xy 370.39275 -278.809554) (xy 370.444712 -278.797694) (xy 370.497862 -278.793711) (xy 370.551012 -278.797694)
			(xy 370.602974 -278.809554) (xy 370.652588 -278.829026) (xy 370.698746 -278.855675) (xy 370.740417 -278.888906)
			(xy 370.776669 -278.927977) (xy 370.806693 -278.972014) (xy 370.829819 -279.020035) (xy 370.845529 -279.070965)
			(xy 370.853472 -279.123669) (xy 370.85397 -279.150318) (xy 370.853472 -279.176967) (xy 371.082306 -279.176967)
			(xy 371.082306 -279.123669) (xy 371.090249 -279.070965) (xy 371.105959 -279.020035) (xy 371.129085 -278.972014)
			(xy 371.159109 -278.927977) (xy 371.195361 -278.888906) (xy 371.237032 -278.855675) (xy 371.28319 -278.829026)
			(xy 371.332804 -278.809554) (xy 371.384766 -278.797694) (xy 371.437916 -278.793711) (xy 371.491066 -278.797694)
			(xy 371.543028 -278.809554) (xy 371.592642 -278.829026) (xy 371.6388 -278.855675) (xy 371.680471 -278.888906)
			(xy 371.716723 -278.927977) (xy 371.746747 -278.972014) (xy 371.769873 -279.020035) (xy 371.785583 -279.070965)
			(xy 371.793526 -279.123669) (xy 371.794024 -279.150318) (xy 371.793526 -279.176967) (xy 372.021852 -279.176967)
			(xy 372.021852 -279.123669) (xy 372.029795 -279.070965) (xy 372.045505 -279.020035) (xy 372.068631 -278.972014)
			(xy 372.098655 -278.927977) (xy 372.134907 -278.888906) (xy 372.176578 -278.855675) (xy 372.222736 -278.829026)
			(xy 372.27235 -278.809554) (xy 372.324312 -278.797694) (xy 372.377462 -278.793711) (xy 372.430612 -278.797694)
			(xy 372.482574 -278.809554) (xy 372.532188 -278.829026) (xy 372.578346 -278.855675) (xy 372.620017 -278.888906)
			(xy 372.656269 -278.927977) (xy 372.686293 -278.972014) (xy 372.709419 -279.020035) (xy 372.725129 -279.070965)
			(xy 372.733072 -279.123669) (xy 372.73357 -279.150318) (xy 372.733072 -279.176967) (xy 372.961652 -279.176967)
			(xy 372.961652 -279.123669) (xy 372.969595 -279.070965) (xy 372.985305 -279.020035) (xy 373.008431 -278.972014)
			(xy 373.038455 -278.927977) (xy 373.074707 -278.888906) (xy 373.116378 -278.855675) (xy 373.162536 -278.829026)
			(xy 373.21215 -278.809554) (xy 373.264112 -278.797694) (xy 373.317262 -278.793711) (xy 373.370412 -278.797694)
			(xy 373.422374 -278.809554) (xy 373.471988 -278.829026) (xy 373.518146 -278.855675) (xy 373.559817 -278.888906)
			(xy 373.596069 -278.927977) (xy 373.626093 -278.972014) (xy 373.649219 -279.020035) (xy 373.664929 -279.070965)
			(xy 373.672872 -279.123669) (xy 373.67337 -279.150318) (xy 373.672872 -279.176967) (xy 373.901452 -279.176967)
			(xy 373.901452 -279.123669) (xy 373.909395 -279.070965) (xy 373.925105 -279.020035) (xy 373.948231 -278.972014)
			(xy 373.978255 -278.927977) (xy 374.014507 -278.888906) (xy 374.056178 -278.855675) (xy 374.102336 -278.829026)
			(xy 374.15195 -278.809554) (xy 374.203912 -278.797694) (xy 374.257062 -278.793711) (xy 374.310212 -278.797694)
			(xy 374.362174 -278.809554) (xy 374.411788 -278.829026) (xy 374.457946 -278.855675) (xy 374.499617 -278.888906)
			(xy 374.535869 -278.927977) (xy 374.565893 -278.972014) (xy 374.589019 -279.020035) (xy 374.604729 -279.070965)
			(xy 374.612672 -279.123669) (xy 374.61317 -279.150318) (xy 374.612672 -279.176967) (xy 374.841252 -279.176967)
			(xy 374.841252 -279.123669) (xy 374.849195 -279.070965) (xy 374.864905 -279.020035) (xy 374.888031 -278.972014)
			(xy 374.918055 -278.927977) (xy 374.954307 -278.888906) (xy 374.995978 -278.855675) (xy 375.042136 -278.829026)
			(xy 375.09175 -278.809554) (xy 375.143712 -278.797694) (xy 375.196862 -278.793711) (xy 375.250012 -278.797694)
			(xy 375.301974 -278.809554) (xy 375.351588 -278.829026) (xy 375.397746 -278.855675) (xy 375.439417 -278.888906)
			(xy 375.475669 -278.927977) (xy 375.505693 -278.972014) (xy 375.528819 -279.020035) (xy 375.544529 -279.070965)
			(xy 375.552472 -279.123669) (xy 375.55297 -279.150318) (xy 375.552472 -279.176967) (xy 375.781052 -279.176967)
			(xy 375.781052 -279.123669) (xy 375.788995 -279.070965) (xy 375.804705 -279.020035) (xy 375.827831 -278.972014)
			(xy 375.857855 -278.927977) (xy 375.894107 -278.888906) (xy 375.935778 -278.855675) (xy 375.981936 -278.829026)
			(xy 376.03155 -278.809554) (xy 376.083512 -278.797694) (xy 376.136662 -278.793711) (xy 376.189812 -278.797694)
			(xy 376.241774 -278.809554) (xy 376.291388 -278.829026) (xy 376.337546 -278.855675) (xy 376.379217 -278.888906)
			(xy 376.415469 -278.927977) (xy 376.445493 -278.972014) (xy 376.468619 -279.020035) (xy 376.484329 -279.070965)
			(xy 376.492272 -279.123669) (xy 376.49277 -279.150318) (xy 376.492272 -279.176967) (xy 376.720852 -279.176967)
			(xy 376.720852 -279.123669) (xy 376.728795 -279.070965) (xy 376.744505 -279.020035) (xy 376.767631 -278.972014)
			(xy 376.797655 -278.927977) (xy 376.833907 -278.888906) (xy 376.875578 -278.855675) (xy 376.921736 -278.829026)
			(xy 376.97135 -278.809554) (xy 377.023312 -278.797694) (xy 377.076462 -278.793711) (xy 377.129612 -278.797694)
			(xy 377.181574 -278.809554) (xy 377.231188 -278.829026) (xy 377.277346 -278.855675) (xy 377.319017 -278.888906)
			(xy 377.355269 -278.927977) (xy 377.385293 -278.972014) (xy 377.408419 -279.020035) (xy 377.424129 -279.070965)
			(xy 377.432072 -279.123669) (xy 377.43257 -279.150318) (xy 377.432072 -279.176967) (xy 377.660906 -279.176967)
			(xy 377.660906 -279.123669) (xy 377.668849 -279.070965) (xy 377.684559 -279.020035) (xy 377.707685 -278.972014)
			(xy 377.737709 -278.927977) (xy 377.773961 -278.888906) (xy 377.815632 -278.855675) (xy 377.86179 -278.829026)
			(xy 377.911404 -278.809554) (xy 377.963366 -278.797694) (xy 378.016516 -278.793711) (xy 378.069666 -278.797694)
			(xy 378.121628 -278.809554) (xy 378.171242 -278.829026) (xy 378.2174 -278.855675) (xy 378.259071 -278.888906)
			(xy 378.295323 -278.927977) (xy 378.325347 -278.972014) (xy 378.348473 -279.020035) (xy 378.364183 -279.070965)
			(xy 378.372126 -279.123669) (xy 378.372624 -279.150318) (xy 378.372126 -279.176967) (xy 378.600452 -279.176967)
			(xy 378.600452 -279.123669) (xy 378.608395 -279.070965) (xy 378.624105 -279.020035) (xy 378.647231 -278.972014)
			(xy 378.677255 -278.927977) (xy 378.713507 -278.888906) (xy 378.755178 -278.855675) (xy 378.801336 -278.829026)
			(xy 378.85095 -278.809554) (xy 378.902912 -278.797694) (xy 378.956062 -278.793711) (xy 379.009212 -278.797694)
			(xy 379.061174 -278.809554) (xy 379.110788 -278.829026) (xy 379.156946 -278.855675) (xy 379.198617 -278.888906)
			(xy 379.234869 -278.927977) (xy 379.264893 -278.972014) (xy 379.288019 -279.020035) (xy 379.303729 -279.070965)
			(xy 379.311672 -279.123669) (xy 379.31217 -279.150318) (xy 379.311672 -279.176967) (xy 379.540506 -279.176967)
			(xy 379.540506 -279.123669) (xy 379.548449 -279.070965) (xy 379.564159 -279.020035) (xy 379.587285 -278.972014)
			(xy 379.617309 -278.927977) (xy 379.653561 -278.888906) (xy 379.695232 -278.855675) (xy 379.74139 -278.829026)
			(xy 379.791004 -278.809554) (xy 379.842966 -278.797694) (xy 379.896116 -278.793711) (xy 379.949266 -278.797694)
			(xy 380.001228 -278.809554) (xy 380.050842 -278.829026) (xy 380.097 -278.855675) (xy 380.138671 -278.888906)
			(xy 380.174923 -278.927977) (xy 380.204947 -278.972014) (xy 380.228073 -279.020035) (xy 380.243783 -279.070965)
			(xy 380.251726 -279.123669) (xy 380.252224 -279.150318) (xy 380.251726 -279.176967) (xy 381.419852 -279.176967)
			(xy 381.419852 -279.123669) (xy 381.427795 -279.070965) (xy 381.443505 -279.020035) (xy 381.466631 -278.972014)
			(xy 381.496655 -278.927977) (xy 381.532907 -278.888906) (xy 381.574578 -278.855675) (xy 381.620736 -278.829026)
			(xy 381.67035 -278.809554) (xy 381.722312 -278.797694) (xy 381.775462 -278.793711) (xy 381.828612 -278.797694)
			(xy 381.880574 -278.809554) (xy 381.930188 -278.829026) (xy 381.976346 -278.855675) (xy 382.018017 -278.888906)
			(xy 382.054269 -278.927977) (xy 382.084293 -278.972014) (xy 382.107419 -279.020035) (xy 382.123129 -279.070965)
			(xy 382.131072 -279.123669) (xy 382.13157 -279.150318) (xy 382.131072 -279.176967) (xy 382.123129 -279.229671)
			(xy 382.107419 -279.280601) (xy 382.084293 -279.328622) (xy 382.054269 -279.372659) (xy 382.018017 -279.41173)
			(xy 381.976346 -279.444961) (xy 381.930188 -279.47161) (xy 381.880574 -279.491082) (xy 381.828612 -279.502942)
			(xy 381.775462 -279.506926) (xy 381.722312 -279.502942) (xy 381.67035 -279.491082) (xy 381.620736 -279.47161)
			(xy 381.574578 -279.444961) (xy 381.532907 -279.41173) (xy 381.496655 -279.372659) (xy 381.466631 -279.328622)
			(xy 381.443505 -279.280601) (xy 381.427795 -279.229671) (xy 381.419852 -279.176967) (xy 380.251726 -279.176967)
			(xy 380.243783 -279.229671) (xy 380.228073 -279.280601) (xy 380.204947 -279.328622) (xy 380.174923 -279.372659)
			(xy 380.138671 -279.41173) (xy 380.097 -279.444961) (xy 380.050842 -279.47161) (xy 380.001228 -279.491082)
			(xy 379.949266 -279.502942) (xy 379.896116 -279.506926) (xy 379.842966 -279.502942) (xy 379.791004 -279.491082)
			(xy 379.74139 -279.47161) (xy 379.695232 -279.444961) (xy 379.653561 -279.41173) (xy 379.617309 -279.372659)
			(xy 379.587285 -279.328622) (xy 379.564159 -279.280601) (xy 379.548449 -279.229671) (xy 379.540506 -279.176967)
			(xy 379.311672 -279.176967) (xy 379.303729 -279.229671) (xy 379.288019 -279.280601) (xy 379.264893 -279.328622)
			(xy 379.234869 -279.372659) (xy 379.198617 -279.41173) (xy 379.156946 -279.444961) (xy 379.110788 -279.47161)
			(xy 379.061174 -279.491082) (xy 379.009212 -279.502942) (xy 378.956062 -279.506926) (xy 378.902912 -279.502942)
			(xy 378.85095 -279.491082) (xy 378.801336 -279.47161) (xy 378.755178 -279.444961) (xy 378.713507 -279.41173)
			(xy 378.677255 -279.372659) (xy 378.647231 -279.328622) (xy 378.624105 -279.280601) (xy 378.608395 -279.229671)
			(xy 378.600452 -279.176967) (xy 378.372126 -279.176967) (xy 378.364183 -279.229671) (xy 378.348473 -279.280601)
			(xy 378.325347 -279.328622) (xy 378.295323 -279.372659) (xy 378.259071 -279.41173) (xy 378.2174 -279.444961)
			(xy 378.171242 -279.47161) (xy 378.121628 -279.491082) (xy 378.069666 -279.502942) (xy 378.016516 -279.506926)
			(xy 377.963366 -279.502942) (xy 377.911404 -279.491082) (xy 377.86179 -279.47161) (xy 377.815632 -279.444961)
			(xy 377.773961 -279.41173) (xy 377.737709 -279.372659) (xy 377.707685 -279.328622) (xy 377.684559 -279.280601)
			(xy 377.668849 -279.229671) (xy 377.660906 -279.176967) (xy 377.432072 -279.176967) (xy 377.424129 -279.229671)
			(xy 377.408419 -279.280601) (xy 377.385293 -279.328622) (xy 377.355269 -279.372659) (xy 377.319017 -279.41173)
			(xy 377.277346 -279.444961) (xy 377.231188 -279.47161) (xy 377.181574 -279.491082) (xy 377.129612 -279.502942)
			(xy 377.076462 -279.506926) (xy 377.023312 -279.502942) (xy 376.97135 -279.491082) (xy 376.921736 -279.47161)
			(xy 376.875578 -279.444961) (xy 376.833907 -279.41173) (xy 376.797655 -279.372659) (xy 376.767631 -279.328622)
			(xy 376.744505 -279.280601) (xy 376.728795 -279.229671) (xy 376.720852 -279.176967) (xy 376.492272 -279.176967)
			(xy 376.484329 -279.229671) (xy 376.468619 -279.280601) (xy 376.445493 -279.328622) (xy 376.415469 -279.372659)
			(xy 376.379217 -279.41173) (xy 376.337546 -279.444961) (xy 376.291388 -279.47161) (xy 376.241774 -279.491082)
			(xy 376.189812 -279.502942) (xy 376.136662 -279.506926) (xy 376.083512 -279.502942) (xy 376.03155 -279.491082)
			(xy 375.981936 -279.47161) (xy 375.935778 -279.444961) (xy 375.894107 -279.41173) (xy 375.857855 -279.372659)
			(xy 375.827831 -279.328622) (xy 375.804705 -279.280601) (xy 375.788995 -279.229671) (xy 375.781052 -279.176967)
			(xy 375.552472 -279.176967) (xy 375.544529 -279.229671) (xy 375.528819 -279.280601) (xy 375.505693 -279.328622)
			(xy 375.475669 -279.372659) (xy 375.439417 -279.41173) (xy 375.397746 -279.444961) (xy 375.351588 -279.47161)
			(xy 375.301974 -279.491082) (xy 375.250012 -279.502942) (xy 375.196862 -279.506926) (xy 375.143712 -279.502942)
			(xy 375.09175 -279.491082) (xy 375.042136 -279.47161) (xy 374.995978 -279.444961) (xy 374.954307 -279.41173)
			(xy 374.918055 -279.372659) (xy 374.888031 -279.328622) (xy 374.864905 -279.280601) (xy 374.849195 -279.229671)
			(xy 374.841252 -279.176967) (xy 374.612672 -279.176967) (xy 374.604729 -279.229671) (xy 374.589019 -279.280601)
			(xy 374.565893 -279.328622) (xy 374.535869 -279.372659) (xy 374.499617 -279.41173) (xy 374.457946 -279.444961)
			(xy 374.411788 -279.47161) (xy 374.362174 -279.491082) (xy 374.310212 -279.502942) (xy 374.257062 -279.506926)
			(xy 374.203912 -279.502942) (xy 374.15195 -279.491082) (xy 374.102336 -279.47161) (xy 374.056178 -279.444961)
			(xy 374.014507 -279.41173) (xy 373.978255 -279.372659) (xy 373.948231 -279.328622) (xy 373.925105 -279.280601)
			(xy 373.909395 -279.229671) (xy 373.901452 -279.176967) (xy 373.672872 -279.176967) (xy 373.664929 -279.229671)
			(xy 373.649219 -279.280601) (xy 373.626093 -279.328622) (xy 373.596069 -279.372659) (xy 373.559817 -279.41173)
			(xy 373.518146 -279.444961) (xy 373.471988 -279.47161) (xy 373.422374 -279.491082) (xy 373.370412 -279.502942)
			(xy 373.317262 -279.506926) (xy 373.264112 -279.502942) (xy 373.21215 -279.491082) (xy 373.162536 -279.47161)
			(xy 373.116378 -279.444961) (xy 373.074707 -279.41173) (xy 373.038455 -279.372659) (xy 373.008431 -279.328622)
			(xy 372.985305 -279.280601) (xy 372.969595 -279.229671) (xy 372.961652 -279.176967) (xy 372.733072 -279.176967)
			(xy 372.725129 -279.229671) (xy 372.709419 -279.280601) (xy 372.686293 -279.328622) (xy 372.656269 -279.372659)
			(xy 372.620017 -279.41173) (xy 372.578346 -279.444961) (xy 372.532188 -279.47161) (xy 372.482574 -279.491082)
			(xy 372.430612 -279.502942) (xy 372.377462 -279.506926) (xy 372.324312 -279.502942) (xy 372.27235 -279.491082)
			(xy 372.222736 -279.47161) (xy 372.176578 -279.444961) (xy 372.134907 -279.41173) (xy 372.098655 -279.372659)
			(xy 372.068631 -279.328622) (xy 372.045505 -279.280601) (xy 372.029795 -279.229671) (xy 372.021852 -279.176967)
			(xy 371.793526 -279.176967) (xy 371.785583 -279.229671) (xy 371.769873 -279.280601) (xy 371.746747 -279.328622)
			(xy 371.716723 -279.372659) (xy 371.680471 -279.41173) (xy 371.6388 -279.444961) (xy 371.592642 -279.47161)
			(xy 371.543028 -279.491082) (xy 371.491066 -279.502942) (xy 371.437916 -279.506926) (xy 371.384766 -279.502942)
			(xy 371.332804 -279.491082) (xy 371.28319 -279.47161) (xy 371.237032 -279.444961) (xy 371.195361 -279.41173)
			(xy 371.159109 -279.372659) (xy 371.129085 -279.328622) (xy 371.105959 -279.280601) (xy 371.090249 -279.229671)
			(xy 371.082306 -279.176967) (xy 370.853472 -279.176967) (xy 370.845529 -279.229671) (xy 370.829819 -279.280601)
			(xy 370.806693 -279.328622) (xy 370.776669 -279.372659) (xy 370.740417 -279.41173) (xy 370.698746 -279.444961)
			(xy 370.652588 -279.47161) (xy 370.602974 -279.491082) (xy 370.551012 -279.502942) (xy 370.497862 -279.506926)
			(xy 370.444712 -279.502942) (xy 370.39275 -279.491082) (xy 370.343136 -279.47161) (xy 370.296978 -279.444961)
			(xy 370.255307 -279.41173) (xy 370.219055 -279.372659) (xy 370.189031 -279.328622) (xy 370.165905 -279.280601)
			(xy 370.150195 -279.229671) (xy 370.142252 -279.176967) (xy 369.913672 -279.176967) (xy 369.905729 -279.229671)
			(xy 369.890019 -279.280601) (xy 369.866893 -279.328622) (xy 369.836869 -279.372659) (xy 369.800617 -279.41173)
			(xy 369.758946 -279.444961) (xy 369.712788 -279.47161) (xy 369.663174 -279.491082) (xy 369.611212 -279.502942)
			(xy 369.558062 -279.506926) (xy 369.504912 -279.502942) (xy 369.45295 -279.491082) (xy 369.403336 -279.47161)
			(xy 369.357178 -279.444961) (xy 369.315507 -279.41173) (xy 369.279255 -279.372659) (xy 369.249231 -279.328622)
			(xy 369.226105 -279.280601) (xy 369.210395 -279.229671) (xy 369.202452 -279.176967) (xy 368.974126 -279.176967)
			(xy 368.966183 -279.229671) (xy 368.950473 -279.280601) (xy 368.927347 -279.328622) (xy 368.897323 -279.372659)
			(xy 368.861071 -279.41173) (xy 368.8194 -279.444961) (xy 368.773242 -279.47161) (xy 368.723628 -279.491082)
			(xy 368.671666 -279.502942) (xy 368.618516 -279.506926) (xy 368.565366 -279.502942) (xy 368.513404 -279.491082)
			(xy 368.46379 -279.47161) (xy 368.417632 -279.444961) (xy 368.375961 -279.41173) (xy 368.339709 -279.372659)
			(xy 368.309685 -279.328622) (xy 368.286559 -279.280601) (xy 368.270849 -279.229671) (xy 368.262906 -279.176967)
			(xy 368.034072 -279.176967) (xy 368.026129 -279.229671) (xy 368.010419 -279.280601) (xy 367.987293 -279.328622)
			(xy 367.957269 -279.372659) (xy 367.921017 -279.41173) (xy 367.879346 -279.444961) (xy 367.833188 -279.47161)
			(xy 367.783574 -279.491082) (xy 367.731612 -279.502942) (xy 367.678462 -279.506926) (xy 367.625312 -279.502942)
			(xy 367.57335 -279.491082) (xy 367.523736 -279.47161) (xy 367.477578 -279.444961) (xy 367.435907 -279.41173)
			(xy 367.399655 -279.372659) (xy 367.369631 -279.328622) (xy 367.346505 -279.280601) (xy 367.330795 -279.229671)
			(xy 367.322852 -279.176967) (xy 366.154726 -279.176967) (xy 366.146783 -279.229671) (xy 366.131073 -279.280601)
			(xy 366.107947 -279.328622) (xy 366.077923 -279.372659) (xy 366.041671 -279.41173) (xy 366 -279.444961)
			(xy 365.953842 -279.47161) (xy 365.904228 -279.491082) (xy 365.852266 -279.502942) (xy 365.799116 -279.506926)
			(xy 365.745966 -279.502942) (xy 365.694004 -279.491082) (xy 365.64439 -279.47161) (xy 365.598232 -279.444961)
			(xy 365.556561 -279.41173) (xy 365.520309 -279.372659) (xy 365.490285 -279.328622) (xy 365.467159 -279.280601)
			(xy 365.451449 -279.229671) (xy 365.443506 -279.176967) (xy 365.214866 -279.176967) (xy 365.214866 -279.177144)
			(xy 365.20668 -279.230633) (xy 365.190495 -279.282269) (xy 365.166683 -279.33086) (xy 365.135793 -279.37529)
			(xy 365.098536 -279.414533) (xy 365.055769 -279.447688) (xy 365.008479 -279.473989) (xy 364.983268 -279.48382)
			(xy 364.950248 -279.496266) (xy 364.950248 -279.990783) (xy 365.913152 -279.990783) (xy 365.913152 -279.937485)
			(xy 365.921095 -279.884781) (xy 365.936805 -279.833851) (xy 365.959931 -279.78583) (xy 365.989955 -279.741793)
			(xy 366.026207 -279.702722) (xy 366.067878 -279.669491) (xy 366.114036 -279.642842) (xy 366.16365 -279.62337)
			(xy 366.215612 -279.61151) (xy 366.268762 -279.607527) (xy 366.321912 -279.61151) (xy 366.373874 -279.62337)
			(xy 366.423488 -279.642842) (xy 366.469646 -279.669491) (xy 366.511317 -279.702722) (xy 366.547569 -279.741793)
			(xy 366.577593 -279.78583) (xy 366.600719 -279.833851) (xy 366.616429 -279.884781) (xy 366.624372 -279.937485)
			(xy 366.62487 -279.964134) (xy 366.624372 -279.990783) (xy 366.853206 -279.990783) (xy 366.853206 -279.937485)
			(xy 366.861149 -279.884781) (xy 366.876859 -279.833851) (xy 366.899985 -279.78583) (xy 366.930009 -279.741793)
			(xy 366.966261 -279.702722) (xy 367.007932 -279.669491) (xy 367.05409 -279.642842) (xy 367.103704 -279.62337)
			(xy 367.155666 -279.61151) (xy 367.208816 -279.607527) (xy 367.261966 -279.61151) (xy 367.313928 -279.62337)
			(xy 367.363542 -279.642842) (xy 367.4097 -279.669491) (xy 367.451371 -279.702722) (xy 367.487623 -279.741793)
			(xy 367.517647 -279.78583) (xy 367.540773 -279.833851) (xy 367.556483 -279.884781) (xy 367.564426 -279.937485)
			(xy 367.564924 -279.964134) (xy 367.564426 -279.990783) (xy 367.793006 -279.990783) (xy 367.793006 -279.937485)
			(xy 367.800949 -279.884781) (xy 367.816659 -279.833851) (xy 367.839785 -279.78583) (xy 367.869809 -279.741793)
			(xy 367.906061 -279.702722) (xy 367.947732 -279.669491) (xy 367.99389 -279.642842) (xy 368.043504 -279.62337)
			(xy 368.095466 -279.61151) (xy 368.148616 -279.607527) (xy 368.201766 -279.61151) (xy 368.253728 -279.62337)
			(xy 368.303342 -279.642842) (xy 368.3495 -279.669491) (xy 368.391171 -279.702722) (xy 368.427423 -279.741793)
			(xy 368.457447 -279.78583) (xy 368.480573 -279.833851) (xy 368.496283 -279.884781) (xy 368.504226 -279.937485)
			(xy 368.504724 -279.964134) (xy 368.504226 -279.990783) (xy 368.732806 -279.990783) (xy 368.732806 -279.937485)
			(xy 368.740749 -279.884781) (xy 368.756459 -279.833851) (xy 368.779585 -279.78583) (xy 368.809609 -279.741793)
			(xy 368.845861 -279.702722) (xy 368.887532 -279.669491) (xy 368.93369 -279.642842) (xy 368.983304 -279.62337)
			(xy 369.035266 -279.61151) (xy 369.088416 -279.607527) (xy 369.141566 -279.61151) (xy 369.193528 -279.62337)
			(xy 369.243142 -279.642842) (xy 369.2893 -279.669491) (xy 369.330971 -279.702722) (xy 369.367223 -279.741793)
			(xy 369.397247 -279.78583) (xy 369.420373 -279.833851) (xy 369.436083 -279.884781) (xy 369.444026 -279.937485)
			(xy 369.444524 -279.964134) (xy 369.444026 -279.990783) (xy 370.612406 -279.990783) (xy 370.612406 -279.937485)
			(xy 370.620349 -279.884781) (xy 370.636059 -279.833851) (xy 370.659185 -279.78583) (xy 370.689209 -279.741793)
			(xy 370.725461 -279.702722) (xy 370.767132 -279.669491) (xy 370.81329 -279.642842) (xy 370.862904 -279.62337)
			(xy 370.914866 -279.61151) (xy 370.968016 -279.607527) (xy 371.021166 -279.61151) (xy 371.073128 -279.62337)
			(xy 371.122742 -279.642842) (xy 371.1689 -279.669491) (xy 371.210571 -279.702722) (xy 371.246823 -279.741793)
			(xy 371.276847 -279.78583) (xy 371.299973 -279.833851) (xy 371.315683 -279.884781) (xy 371.323626 -279.937485)
			(xy 371.324124 -279.964134) (xy 371.323626 -279.990783) (xy 371.551952 -279.990783) (xy 371.551952 -279.937485)
			(xy 371.559895 -279.884781) (xy 371.575605 -279.833851) (xy 371.598731 -279.78583) (xy 371.628755 -279.741793)
			(xy 371.665007 -279.702722) (xy 371.706678 -279.669491) (xy 371.752836 -279.642842) (xy 371.80245 -279.62337)
			(xy 371.854412 -279.61151) (xy 371.907562 -279.607527) (xy 371.960712 -279.61151) (xy 372.012674 -279.62337)
			(xy 372.062288 -279.642842) (xy 372.108446 -279.669491) (xy 372.150117 -279.702722) (xy 372.186369 -279.741793)
			(xy 372.216393 -279.78583) (xy 372.239519 -279.833851) (xy 372.255229 -279.884781) (xy 372.263172 -279.937485)
			(xy 372.26367 -279.964134) (xy 372.263172 -279.990783) (xy 372.492006 -279.990783) (xy 372.492006 -279.937485)
			(xy 372.499949 -279.884781) (xy 372.515659 -279.833851) (xy 372.538785 -279.78583) (xy 372.568809 -279.741793)
			(xy 372.605061 -279.702722) (xy 372.646732 -279.669491) (xy 372.69289 -279.642842) (xy 372.742504 -279.62337)
			(xy 372.794466 -279.61151) (xy 372.847616 -279.607527) (xy 372.900766 -279.61151) (xy 372.952728 -279.62337)
			(xy 373.002342 -279.642842) (xy 373.0485 -279.669491) (xy 373.090171 -279.702722) (xy 373.126423 -279.741793)
			(xy 373.156447 -279.78583) (xy 373.179573 -279.833851) (xy 373.195283 -279.884781) (xy 373.203226 -279.937485)
			(xy 373.203724 -279.964134) (xy 373.203226 -279.990783) (xy 373.431806 -279.990783) (xy 373.431806 -279.937485)
			(xy 373.439749 -279.884781) (xy 373.455459 -279.833851) (xy 373.478585 -279.78583) (xy 373.508609 -279.741793)
			(xy 373.544861 -279.702722) (xy 373.586532 -279.669491) (xy 373.63269 -279.642842) (xy 373.682304 -279.62337)
			(xy 373.734266 -279.61151) (xy 373.787416 -279.607527) (xy 373.840566 -279.61151) (xy 373.892528 -279.62337)
			(xy 373.942142 -279.642842) (xy 373.9883 -279.669491) (xy 374.029971 -279.702722) (xy 374.066223 -279.741793)
			(xy 374.096247 -279.78583) (xy 374.119373 -279.833851) (xy 374.135083 -279.884781) (xy 374.143026 -279.937485)
			(xy 374.143524 -279.964134) (xy 374.143026 -279.990783) (xy 374.371352 -279.990783) (xy 374.371352 -279.937485)
			(xy 374.379295 -279.884781) (xy 374.395005 -279.833851) (xy 374.418131 -279.78583) (xy 374.448155 -279.741793)
			(xy 374.484407 -279.702722) (xy 374.526078 -279.669491) (xy 374.572236 -279.642842) (xy 374.62185 -279.62337)
			(xy 374.673812 -279.61151) (xy 374.726962 -279.607527) (xy 374.780112 -279.61151) (xy 374.832074 -279.62337)
			(xy 374.881688 -279.642842) (xy 374.927846 -279.669491) (xy 374.969517 -279.702722) (xy 375.005769 -279.741793)
			(xy 375.035793 -279.78583) (xy 375.058919 -279.833851) (xy 375.074629 -279.884781) (xy 375.082572 -279.937485)
			(xy 375.08307 -279.964134) (xy 375.082572 -279.990783) (xy 375.311406 -279.990783) (xy 375.311406 -279.937485)
			(xy 375.319349 -279.884781) (xy 375.335059 -279.833851) (xy 375.358185 -279.78583) (xy 375.388209 -279.741793)
			(xy 375.424461 -279.702722) (xy 375.466132 -279.669491) (xy 375.51229 -279.642842) (xy 375.561904 -279.62337)
			(xy 375.613866 -279.61151) (xy 375.667016 -279.607527) (xy 375.720166 -279.61151) (xy 375.772128 -279.62337)
			(xy 375.821742 -279.642842) (xy 375.8679 -279.669491) (xy 375.909571 -279.702722) (xy 375.945823 -279.741793)
			(xy 375.975847 -279.78583) (xy 375.998973 -279.833851) (xy 376.014683 -279.884781) (xy 376.022626 -279.937485)
			(xy 376.023124 -279.964134) (xy 376.022631 -279.990529) (xy 376.250952 -279.990529) (xy 376.250952 -279.937231)
			(xy 376.258895 -279.884527) (xy 376.274605 -279.833597) (xy 376.297731 -279.785576) (xy 376.327755 -279.741539)
			(xy 376.364007 -279.702468) (xy 376.405678 -279.669237) (xy 376.451836 -279.642588) (xy 376.50145 -279.623116)
			(xy 376.553412 -279.611256) (xy 376.606562 -279.607273) (xy 376.659712 -279.611256) (xy 376.711674 -279.623116)
			(xy 376.761288 -279.642588) (xy 376.807446 -279.669237) (xy 376.849117 -279.702468) (xy 376.885369 -279.741539)
			(xy 376.915393 -279.785576) (xy 376.938519 -279.833597) (xy 376.954229 -279.884527) (xy 376.962172 -279.937231)
			(xy 376.96267 -279.96388) (xy 376.962172 -279.990529) (xy 376.962134 -279.990783) (xy 378.130806 -279.990783)
			(xy 378.130806 -279.937485) (xy 378.138749 -279.884781) (xy 378.154459 -279.833851) (xy 378.177585 -279.78583)
			(xy 378.207609 -279.741793) (xy 378.243861 -279.702722) (xy 378.285532 -279.669491) (xy 378.33169 -279.642842)
			(xy 378.381304 -279.62337) (xy 378.433266 -279.61151) (xy 378.486416 -279.607527) (xy 378.539566 -279.61151)
			(xy 378.591528 -279.62337) (xy 378.641142 -279.642842) (xy 378.6873 -279.669491) (xy 378.728971 -279.702722)
			(xy 378.765223 -279.741793) (xy 378.795247 -279.78583) (xy 378.818373 -279.833851) (xy 378.834083 -279.884781)
			(xy 378.842026 -279.937485) (xy 378.842524 -279.964134) (xy 378.842026 -279.990783) (xy 379.070606 -279.990783)
			(xy 379.070606 -279.937485) (xy 379.078549 -279.884781) (xy 379.094259 -279.833851) (xy 379.117385 -279.78583)
			(xy 379.147409 -279.741793) (xy 379.183661 -279.702722) (xy 379.225332 -279.669491) (xy 379.27149 -279.642842)
			(xy 379.321104 -279.62337) (xy 379.373066 -279.61151) (xy 379.426216 -279.607527) (xy 379.479366 -279.61151)
			(xy 379.531328 -279.62337) (xy 379.580942 -279.642842) (xy 379.6271 -279.669491) (xy 379.668771 -279.702722)
			(xy 379.705023 -279.741793) (xy 379.735047 -279.78583) (xy 379.758173 -279.833851) (xy 379.773883 -279.884781)
			(xy 379.781826 -279.937485) (xy 379.782324 -279.964134) (xy 379.781826 -279.990783) (xy 380.010152 -279.990783)
			(xy 380.010152 -279.937485) (xy 380.018095 -279.884781) (xy 380.033805 -279.833851) (xy 380.056931 -279.78583)
			(xy 380.086955 -279.741793) (xy 380.123207 -279.702722) (xy 380.164878 -279.669491) (xy 380.211036 -279.642842)
			(xy 380.26065 -279.62337) (xy 380.312612 -279.61151) (xy 380.365762 -279.607527) (xy 380.418912 -279.61151)
			(xy 380.470874 -279.62337) (xy 380.520488 -279.642842) (xy 380.566646 -279.669491) (xy 380.608317 -279.702722)
			(xy 380.644569 -279.741793) (xy 380.674593 -279.78583) (xy 380.697719 -279.833851) (xy 380.713429 -279.884781)
			(xy 380.721372 -279.937485) (xy 380.72187 -279.964134) (xy 380.721372 -279.990783) (xy 382.829298 -279.990783)
			(xy 382.829298 -279.937485) (xy 382.837241 -279.884781) (xy 382.852951 -279.833851) (xy 382.876077 -279.78583)
			(xy 382.906101 -279.741793) (xy 382.942353 -279.702722) (xy 382.984024 -279.669491) (xy 383.030182 -279.642842)
			(xy 383.079796 -279.62337) (xy 383.131758 -279.61151) (xy 383.184908 -279.607527) (xy 383.238058 -279.61151)
			(xy 383.29002 -279.62337) (xy 383.339634 -279.642842) (xy 383.385792 -279.669491) (xy 383.427463 -279.702722)
			(xy 383.463715 -279.741793) (xy 383.493739 -279.78583) (xy 383.516865 -279.833851) (xy 383.532575 -279.884781)
			(xy 383.540518 -279.937485) (xy 383.541016 -279.964134) (xy 383.540518 -279.990783) (xy 383.532575 -280.043487)
			(xy 383.516865 -280.094417) (xy 383.493739 -280.142438) (xy 383.463715 -280.186475) (xy 383.427463 -280.225546)
			(xy 383.385792 -280.258777) (xy 383.339634 -280.285426) (xy 383.29002 -280.304898) (xy 383.238058 -280.316758)
			(xy 383.184908 -280.320742) (xy 383.131758 -280.316758) (xy 383.079796 -280.304898) (xy 383.030182 -280.285426)
			(xy 382.984024 -280.258777) (xy 382.942353 -280.225546) (xy 382.906101 -280.186475) (xy 382.876077 -280.142438)
			(xy 382.852951 -280.094417) (xy 382.837241 -280.043487) (xy 382.829298 -279.990783) (xy 380.721372 -279.990783)
			(xy 380.713429 -280.043487) (xy 380.697719 -280.094417) (xy 380.674593 -280.142438) (xy 380.644569 -280.186475)
			(xy 380.608317 -280.225546) (xy 380.566646 -280.258777) (xy 380.520488 -280.285426) (xy 380.470874 -280.304898)
			(xy 380.418912 -280.316758) (xy 380.365762 -280.320742) (xy 380.312612 -280.316758) (xy 380.26065 -280.304898)
			(xy 380.211036 -280.285426) (xy 380.164878 -280.258777) (xy 380.123207 -280.225546) (xy 380.086955 -280.186475)
			(xy 380.056931 -280.142438) (xy 380.033805 -280.094417) (xy 380.018095 -280.043487) (xy 380.010152 -279.990783)
			(xy 379.781826 -279.990783) (xy 379.773883 -280.043487) (xy 379.758173 -280.094417) (xy 379.735047 -280.142438)
			(xy 379.705023 -280.186475) (xy 379.668771 -280.225546) (xy 379.6271 -280.258777) (xy 379.580942 -280.285426)
			(xy 379.531328 -280.304898) (xy 379.479366 -280.316758) (xy 379.426216 -280.320742) (xy 379.373066 -280.316758)
			(xy 379.321104 -280.304898) (xy 379.27149 -280.285426) (xy 379.225332 -280.258777) (xy 379.183661 -280.225546)
			(xy 379.147409 -280.186475) (xy 379.117385 -280.142438) (xy 379.094259 -280.094417) (xy 379.078549 -280.043487)
			(xy 379.070606 -279.990783) (xy 378.842026 -279.990783) (xy 378.834083 -280.043487) (xy 378.818373 -280.094417)
			(xy 378.795247 -280.142438) (xy 378.765223 -280.186475) (xy 378.728971 -280.225546) (xy 378.6873 -280.258777)
			(xy 378.641142 -280.285426) (xy 378.591528 -280.304898) (xy 378.539566 -280.316758) (xy 378.486416 -280.320742)
			(xy 378.433266 -280.316758) (xy 378.381304 -280.304898) (xy 378.33169 -280.285426) (xy 378.285532 -280.258777)
			(xy 378.243861 -280.225546) (xy 378.207609 -280.186475) (xy 378.177585 -280.142438) (xy 378.154459 -280.094417)
			(xy 378.138749 -280.043487) (xy 378.130806 -279.990783) (xy 376.962134 -279.990783) (xy 376.954229 -280.043233)
			(xy 376.938519 -280.094163) (xy 376.915393 -280.142184) (xy 376.885369 -280.186221) (xy 376.849117 -280.225292)
			(xy 376.807446 -280.258523) (xy 376.761288 -280.285172) (xy 376.711674 -280.304644) (xy 376.659712 -280.316504)
			(xy 376.606562 -280.320488) (xy 376.553412 -280.316504) (xy 376.50145 -280.304644) (xy 376.451836 -280.285172)
			(xy 376.405678 -280.258523) (xy 376.364007 -280.225292) (xy 376.327755 -280.186221) (xy 376.297731 -280.142184)
			(xy 376.274605 -280.094163) (xy 376.258895 -280.043233) (xy 376.250952 -279.990529) (xy 376.022631 -279.990529)
			(xy 376.022626 -279.990783) (xy 376.014683 -280.043487) (xy 375.998973 -280.094417) (xy 375.975847 -280.142438)
			(xy 375.945823 -280.186475) (xy 375.909571 -280.225546) (xy 375.8679 -280.258777) (xy 375.821742 -280.285426)
			(xy 375.772128 -280.304898) (xy 375.720166 -280.316758) (xy 375.667016 -280.320742) (xy 375.613866 -280.316758)
			(xy 375.561904 -280.304898) (xy 375.51229 -280.285426) (xy 375.466132 -280.258777) (xy 375.424461 -280.225546)
			(xy 375.388209 -280.186475) (xy 375.358185 -280.142438) (xy 375.335059 -280.094417) (xy 375.319349 -280.043487)
			(xy 375.311406 -279.990783) (xy 375.082572 -279.990783) (xy 375.074629 -280.043487) (xy 375.058919 -280.094417)
			(xy 375.035793 -280.142438) (xy 375.005769 -280.186475) (xy 374.969517 -280.225546) (xy 374.927846 -280.258777)
			(xy 374.881688 -280.285426) (xy 374.832074 -280.304898) (xy 374.780112 -280.316758) (xy 374.726962 -280.320742)
			(xy 374.673812 -280.316758) (xy 374.62185 -280.304898) (xy 374.572236 -280.285426) (xy 374.526078 -280.258777)
			(xy 374.484407 -280.225546) (xy 374.448155 -280.186475) (xy 374.418131 -280.142438) (xy 374.395005 -280.094417)
			(xy 374.379295 -280.043487) (xy 374.371352 -279.990783) (xy 374.143026 -279.990783) (xy 374.135083 -280.043487)
			(xy 374.119373 -280.094417) (xy 374.096247 -280.142438) (xy 374.066223 -280.186475) (xy 374.029971 -280.225546)
			(xy 373.9883 -280.258777) (xy 373.942142 -280.285426) (xy 373.892528 -280.304898) (xy 373.840566 -280.316758)
			(xy 373.787416 -280.320742) (xy 373.734266 -280.316758) (xy 373.682304 -280.304898) (xy 373.63269 -280.285426)
			(xy 373.586532 -280.258777) (xy 373.544861 -280.225546) (xy 373.508609 -280.186475) (xy 373.478585 -280.142438)
			(xy 373.455459 -280.094417) (xy 373.439749 -280.043487) (xy 373.431806 -279.990783) (xy 373.203226 -279.990783)
			(xy 373.195283 -280.043487) (xy 373.179573 -280.094417) (xy 373.156447 -280.142438) (xy 373.126423 -280.186475)
			(xy 373.090171 -280.225546) (xy 373.0485 -280.258777) (xy 373.002342 -280.285426) (xy 372.952728 -280.304898)
			(xy 372.900766 -280.316758) (xy 372.847616 -280.320742) (xy 372.794466 -280.316758) (xy 372.742504 -280.304898)
			(xy 372.69289 -280.285426) (xy 372.646732 -280.258777) (xy 372.605061 -280.225546) (xy 372.568809 -280.186475)
			(xy 372.538785 -280.142438) (xy 372.515659 -280.094417) (xy 372.499949 -280.043487) (xy 372.492006 -279.990783)
			(xy 372.263172 -279.990783) (xy 372.255229 -280.043487) (xy 372.239519 -280.094417) (xy 372.216393 -280.142438)
			(xy 372.186369 -280.186475) (xy 372.150117 -280.225546) (xy 372.108446 -280.258777) (xy 372.062288 -280.285426)
			(xy 372.012674 -280.304898) (xy 371.960712 -280.316758) (xy 371.907562 -280.320742) (xy 371.854412 -280.316758)
			(xy 371.80245 -280.304898) (xy 371.752836 -280.285426) (xy 371.706678 -280.258777) (xy 371.665007 -280.225546)
			(xy 371.628755 -280.186475) (xy 371.598731 -280.142438) (xy 371.575605 -280.094417) (xy 371.559895 -280.043487)
			(xy 371.551952 -279.990783) (xy 371.323626 -279.990783) (xy 371.315683 -280.043487) (xy 371.299973 -280.094417)
			(xy 371.276847 -280.142438) (xy 371.246823 -280.186475) (xy 371.210571 -280.225546) (xy 371.1689 -280.258777)
			(xy 371.122742 -280.285426) (xy 371.073128 -280.304898) (xy 371.021166 -280.316758) (xy 370.968016 -280.320742)
			(xy 370.914866 -280.316758) (xy 370.862904 -280.304898) (xy 370.81329 -280.285426) (xy 370.767132 -280.258777)
			(xy 370.725461 -280.225546) (xy 370.689209 -280.186475) (xy 370.659185 -280.142438) (xy 370.636059 -280.094417)
			(xy 370.620349 -280.043487) (xy 370.612406 -279.990783) (xy 369.444026 -279.990783) (xy 369.436083 -280.043487)
			(xy 369.420373 -280.094417) (xy 369.397247 -280.142438) (xy 369.367223 -280.186475) (xy 369.330971 -280.225546)
			(xy 369.2893 -280.258777) (xy 369.243142 -280.285426) (xy 369.193528 -280.304898) (xy 369.141566 -280.316758)
			(xy 369.088416 -280.320742) (xy 369.035266 -280.316758) (xy 368.983304 -280.304898) (xy 368.93369 -280.285426)
			(xy 368.887532 -280.258777) (xy 368.845861 -280.225546) (xy 368.809609 -280.186475) (xy 368.779585 -280.142438)
			(xy 368.756459 -280.094417) (xy 368.740749 -280.043487) (xy 368.732806 -279.990783) (xy 368.504226 -279.990783)
			(xy 368.496283 -280.043487) (xy 368.480573 -280.094417) (xy 368.457447 -280.142438) (xy 368.427423 -280.186475)
			(xy 368.391171 -280.225546) (xy 368.3495 -280.258777) (xy 368.303342 -280.285426) (xy 368.253728 -280.304898)
			(xy 368.201766 -280.316758) (xy 368.148616 -280.320742) (xy 368.095466 -280.316758) (xy 368.043504 -280.304898)
			(xy 367.99389 -280.285426) (xy 367.947732 -280.258777) (xy 367.906061 -280.225546) (xy 367.869809 -280.186475)
			(xy 367.839785 -280.142438) (xy 367.816659 -280.094417) (xy 367.800949 -280.043487) (xy 367.793006 -279.990783)
			(xy 367.564426 -279.990783) (xy 367.556483 -280.043487) (xy 367.540773 -280.094417) (xy 367.517647 -280.142438)
			(xy 367.487623 -280.186475) (xy 367.451371 -280.225546) (xy 367.4097 -280.258777) (xy 367.363542 -280.285426)
			(xy 367.313928 -280.304898) (xy 367.261966 -280.316758) (xy 367.208816 -280.320742) (xy 367.155666 -280.316758)
			(xy 367.103704 -280.304898) (xy 367.05409 -280.285426) (xy 367.007932 -280.258777) (xy 366.966261 -280.225546)
			(xy 366.930009 -280.186475) (xy 366.899985 -280.142438) (xy 366.876859 -280.094417) (xy 366.861149 -280.043487)
			(xy 366.853206 -279.990783) (xy 366.624372 -279.990783) (xy 366.616429 -280.043487) (xy 366.600719 -280.094417)
			(xy 366.577593 -280.142438) (xy 366.547569 -280.186475) (xy 366.511317 -280.225546) (xy 366.469646 -280.258777)
			(xy 366.423488 -280.285426) (xy 366.373874 -280.304898) (xy 366.321912 -280.316758) (xy 366.268762 -280.320742)
			(xy 366.215612 -280.316758) (xy 366.16365 -280.304898) (xy 366.114036 -280.285426) (xy 366.067878 -280.258777)
			(xy 366.026207 -280.225546) (xy 365.989955 -280.186475) (xy 365.959931 -280.142438) (xy 365.936805 -280.094417)
			(xy 365.921095 -280.043487) (xy 365.913152 -279.990783) (xy 364.950248 -279.990783) (xy 364.950248 -280.432002)
			(xy 364.983268 -280.444448) (xy 365.008455 -280.454342) (xy 365.055747 -280.480642) (xy 365.098518 -280.513792)
			(xy 365.135783 -280.553028) (xy 365.166686 -280.59745) (xy 365.190515 -280.646033) (xy 365.206722 -280.697662)
			(xy 365.214936 -280.751148) (xy 365.215424 -280.778204) (xy 365.214912 -280.804853) (xy 365.443506 -280.804853)
			(xy 365.443506 -280.751555) (xy 365.451449 -280.698851) (xy 365.467159 -280.647921) (xy 365.490285 -280.5999)
			(xy 365.520309 -280.555863) (xy 365.556561 -280.516792) (xy 365.598232 -280.483561) (xy 365.64439 -280.456912)
			(xy 365.694004 -280.43744) (xy 365.745966 -280.42558) (xy 365.799116 -280.421597) (xy 365.852266 -280.42558)
			(xy 365.904228 -280.43744) (xy 365.953842 -280.456912) (xy 366 -280.483561) (xy 366.041671 -280.516792)
			(xy 366.077923 -280.555863) (xy 366.107947 -280.5999) (xy 366.131073 -280.647921) (xy 366.146783 -280.698851)
			(xy 366.154726 -280.751555) (xy 366.155224 -280.778204) (xy 366.154726 -280.804853) (xy 366.383052 -280.804853)
			(xy 366.383052 -280.751555) (xy 366.390995 -280.698851) (xy 366.406705 -280.647921) (xy 366.429831 -280.5999)
			(xy 366.459855 -280.555863) (xy 366.496107 -280.516792) (xy 366.537778 -280.483561) (xy 366.583936 -280.456912)
			(xy 366.63355 -280.43744) (xy 366.685512 -280.42558) (xy 366.738662 -280.421597) (xy 366.791812 -280.42558)
			(xy 366.843774 -280.43744) (xy 366.893388 -280.456912) (xy 366.939546 -280.483561) (xy 366.981217 -280.516792)
			(xy 367.017469 -280.555863) (xy 367.047493 -280.5999) (xy 367.070619 -280.647921) (xy 367.086329 -280.698851)
			(xy 367.094272 -280.751555) (xy 367.09477 -280.778204) (xy 367.094272 -280.804853) (xy 367.322852 -280.804853)
			(xy 367.322852 -280.751555) (xy 367.330795 -280.698851) (xy 367.346505 -280.647921) (xy 367.369631 -280.5999)
			(xy 367.399655 -280.555863) (xy 367.435907 -280.516792) (xy 367.477578 -280.483561) (xy 367.523736 -280.456912)
			(xy 367.57335 -280.43744) (xy 367.625312 -280.42558) (xy 367.678462 -280.421597) (xy 367.731612 -280.42558)
			(xy 367.783574 -280.43744) (xy 367.833188 -280.456912) (xy 367.879346 -280.483561) (xy 367.921017 -280.516792)
			(xy 367.957269 -280.555863) (xy 367.987293 -280.5999) (xy 368.010419 -280.647921) (xy 368.026129 -280.698851)
			(xy 368.034072 -280.751555) (xy 368.03457 -280.778204) (xy 368.034072 -280.804853) (xy 368.262652 -280.804853)
			(xy 368.262652 -280.751555) (xy 368.270595 -280.698851) (xy 368.286305 -280.647921) (xy 368.309431 -280.5999)
			(xy 368.339455 -280.555863) (xy 368.375707 -280.516792) (xy 368.417378 -280.483561) (xy 368.463536 -280.456912)
			(xy 368.51315 -280.43744) (xy 368.565112 -280.42558) (xy 368.618262 -280.421597) (xy 368.671412 -280.42558)
			(xy 368.723374 -280.43744) (xy 368.772988 -280.456912) (xy 368.819146 -280.483561) (xy 368.860817 -280.516792)
			(xy 368.897069 -280.555863) (xy 368.927093 -280.5999) (xy 368.950219 -280.647921) (xy 368.965929 -280.698851)
			(xy 368.973872 -280.751555) (xy 368.97437 -280.778204) (xy 368.973872 -280.804853) (xy 369.202452 -280.804853)
			(xy 369.202452 -280.751555) (xy 369.210395 -280.698851) (xy 369.226105 -280.647921) (xy 369.249231 -280.5999)
			(xy 369.279255 -280.555863) (xy 369.315507 -280.516792) (xy 369.357178 -280.483561) (xy 369.403336 -280.456912)
			(xy 369.45295 -280.43744) (xy 369.504912 -280.42558) (xy 369.558062 -280.421597) (xy 369.611212 -280.42558)
			(xy 369.663174 -280.43744) (xy 369.712788 -280.456912) (xy 369.758946 -280.483561) (xy 369.800617 -280.516792)
			(xy 369.836869 -280.555863) (xy 369.866893 -280.5999) (xy 369.890019 -280.647921) (xy 369.905729 -280.698851)
			(xy 369.913672 -280.751555) (xy 369.91417 -280.778204) (xy 369.913672 -280.804853) (xy 370.142252 -280.804853)
			(xy 370.142252 -280.751555) (xy 370.150195 -280.698851) (xy 370.165905 -280.647921) (xy 370.189031 -280.5999)
			(xy 370.219055 -280.555863) (xy 370.255307 -280.516792) (xy 370.296978 -280.483561) (xy 370.343136 -280.456912)
			(xy 370.39275 -280.43744) (xy 370.444712 -280.42558) (xy 370.497862 -280.421597) (xy 370.551012 -280.42558)
			(xy 370.602974 -280.43744) (xy 370.652588 -280.456912) (xy 370.698746 -280.483561) (xy 370.740417 -280.516792)
			(xy 370.776669 -280.555863) (xy 370.806693 -280.5999) (xy 370.829819 -280.647921) (xy 370.845529 -280.698851)
			(xy 370.853472 -280.751555) (xy 370.85397 -280.778204) (xy 370.853472 -280.804853) (xy 371.082052 -280.804853)
			(xy 371.082052 -280.751555) (xy 371.089995 -280.698851) (xy 371.105705 -280.647921) (xy 371.128831 -280.5999)
			(xy 371.158855 -280.555863) (xy 371.195107 -280.516792) (xy 371.236778 -280.483561) (xy 371.282936 -280.456912)
			(xy 371.33255 -280.43744) (xy 371.384512 -280.42558) (xy 371.437662 -280.421597) (xy 371.490812 -280.42558)
			(xy 371.542774 -280.43744) (xy 371.592388 -280.456912) (xy 371.638546 -280.483561) (xy 371.680217 -280.516792)
			(xy 371.716469 -280.555863) (xy 371.746493 -280.5999) (xy 371.769619 -280.647921) (xy 371.785329 -280.698851)
			(xy 371.793272 -280.751555) (xy 371.79377 -280.778204) (xy 371.793272 -280.804853) (xy 372.021852 -280.804853)
			(xy 372.021852 -280.751555) (xy 372.029795 -280.698851) (xy 372.045505 -280.647921) (xy 372.068631 -280.5999)
			(xy 372.098655 -280.555863) (xy 372.134907 -280.516792) (xy 372.176578 -280.483561) (xy 372.222736 -280.456912)
			(xy 372.27235 -280.43744) (xy 372.324312 -280.42558) (xy 372.377462 -280.421597) (xy 372.430612 -280.42558)
			(xy 372.482574 -280.43744) (xy 372.532188 -280.456912) (xy 372.578346 -280.483561) (xy 372.620017 -280.516792)
			(xy 372.656269 -280.555863) (xy 372.686293 -280.5999) (xy 372.709419 -280.647921) (xy 372.725129 -280.698851)
			(xy 372.733072 -280.751555) (xy 372.73357 -280.778204) (xy 372.733072 -280.804853) (xy 372.961652 -280.804853)
			(xy 372.961652 -280.751555) (xy 372.969595 -280.698851) (xy 372.985305 -280.647921) (xy 373.008431 -280.5999)
			(xy 373.038455 -280.555863) (xy 373.074707 -280.516792) (xy 373.116378 -280.483561) (xy 373.162536 -280.456912)
			(xy 373.21215 -280.43744) (xy 373.264112 -280.42558) (xy 373.317262 -280.421597) (xy 373.370412 -280.42558)
			(xy 373.422374 -280.43744) (xy 373.471988 -280.456912) (xy 373.518146 -280.483561) (xy 373.559817 -280.516792)
			(xy 373.596069 -280.555863) (xy 373.626093 -280.5999) (xy 373.649219 -280.647921) (xy 373.664929 -280.698851)
			(xy 373.672872 -280.751555) (xy 373.67337 -280.778204) (xy 373.672872 -280.804853) (xy 373.901706 -280.804853)
			(xy 373.901706 -280.751555) (xy 373.909649 -280.698851) (xy 373.925359 -280.647921) (xy 373.948485 -280.5999)
			(xy 373.978509 -280.555863) (xy 374.014761 -280.516792) (xy 374.056432 -280.483561) (xy 374.10259 -280.456912)
			(xy 374.152204 -280.43744) (xy 374.204166 -280.42558) (xy 374.257316 -280.421597) (xy 374.310466 -280.42558)
			(xy 374.362428 -280.43744) (xy 374.412042 -280.456912) (xy 374.4582 -280.483561) (xy 374.499871 -280.516792)
			(xy 374.536123 -280.555863) (xy 374.566147 -280.5999) (xy 374.589273 -280.647921) (xy 374.604983 -280.698851)
			(xy 374.612926 -280.751555) (xy 374.613424 -280.778204) (xy 374.612926 -280.804853) (xy 374.841506 -280.804853)
			(xy 374.841506 -280.751555) (xy 374.849449 -280.698851) (xy 374.865159 -280.647921) (xy 374.888285 -280.5999)
			(xy 374.918309 -280.555863) (xy 374.954561 -280.516792) (xy 374.996232 -280.483561) (xy 375.04239 -280.456912)
			(xy 375.092004 -280.43744) (xy 375.143966 -280.42558) (xy 375.197116 -280.421597) (xy 375.250266 -280.42558)
			(xy 375.302228 -280.43744) (xy 375.351842 -280.456912) (xy 375.398 -280.483561) (xy 375.439671 -280.516792)
			(xy 375.475923 -280.555863) (xy 375.505947 -280.5999) (xy 375.529073 -280.647921) (xy 375.544783 -280.698851)
			(xy 375.552726 -280.751555) (xy 375.553224 -280.778204) (xy 375.552726 -280.804853) (xy 375.781306 -280.804853)
			(xy 375.781306 -280.751555) (xy 375.789249 -280.698851) (xy 375.804959 -280.647921) (xy 375.828085 -280.5999)
			(xy 375.858109 -280.555863) (xy 375.894361 -280.516792) (xy 375.936032 -280.483561) (xy 375.98219 -280.456912)
			(xy 376.031804 -280.43744) (xy 376.083766 -280.42558) (xy 376.136916 -280.421597) (xy 376.190066 -280.42558)
			(xy 376.242028 -280.43744) (xy 376.291642 -280.456912) (xy 376.3378 -280.483561) (xy 376.379471 -280.516792)
			(xy 376.415723 -280.555863) (xy 376.445747 -280.5999) (xy 376.468873 -280.647921) (xy 376.484583 -280.698851)
			(xy 376.492526 -280.751555) (xy 376.493024 -280.778204) (xy 376.492526 -280.804853) (xy 376.721106 -280.804853)
			(xy 376.721106 -280.751555) (xy 376.729049 -280.698851) (xy 376.744759 -280.647921) (xy 376.767885 -280.5999)
			(xy 376.797909 -280.555863) (xy 376.834161 -280.516792) (xy 376.875832 -280.483561) (xy 376.92199 -280.456912)
			(xy 376.971604 -280.43744) (xy 377.023566 -280.42558) (xy 377.076716 -280.421597) (xy 377.129866 -280.42558)
			(xy 377.181828 -280.43744) (xy 377.231442 -280.456912) (xy 377.2776 -280.483561) (xy 377.319271 -280.516792)
			(xy 377.355523 -280.555863) (xy 377.385547 -280.5999) (xy 377.408673 -280.647921) (xy 377.424383 -280.698851)
			(xy 377.432326 -280.751555) (xy 377.432824 -280.778204) (xy 377.432326 -280.804853) (xy 377.660906 -280.804853)
			(xy 377.660906 -280.751555) (xy 377.668849 -280.698851) (xy 377.684559 -280.647921) (xy 377.707685 -280.5999)
			(xy 377.737709 -280.555863) (xy 377.773961 -280.516792) (xy 377.815632 -280.483561) (xy 377.86179 -280.456912)
			(xy 377.911404 -280.43744) (xy 377.963366 -280.42558) (xy 378.016516 -280.421597) (xy 378.069666 -280.42558)
			(xy 378.121628 -280.43744) (xy 378.171242 -280.456912) (xy 378.2174 -280.483561) (xy 378.259071 -280.516792)
			(xy 378.295323 -280.555863) (xy 378.325347 -280.5999) (xy 378.348473 -280.647921) (xy 378.364183 -280.698851)
			(xy 378.372126 -280.751555) (xy 378.372624 -280.778204) (xy 378.372126 -280.804853) (xy 378.600452 -280.804853)
			(xy 378.600452 -280.751555) (xy 378.608395 -280.698851) (xy 378.624105 -280.647921) (xy 378.647231 -280.5999)
			(xy 378.677255 -280.555863) (xy 378.713507 -280.516792) (xy 378.755178 -280.483561) (xy 378.801336 -280.456912)
			(xy 378.85095 -280.43744) (xy 378.902912 -280.42558) (xy 378.956062 -280.421597) (xy 379.009212 -280.42558)
			(xy 379.061174 -280.43744) (xy 379.110788 -280.456912) (xy 379.156946 -280.483561) (xy 379.198617 -280.516792)
			(xy 379.234869 -280.555863) (xy 379.264893 -280.5999) (xy 379.288019 -280.647921) (xy 379.303729 -280.698851)
			(xy 379.311672 -280.751555) (xy 379.31217 -280.778204) (xy 379.311672 -280.804853) (xy 379.540252 -280.804853)
			(xy 379.540252 -280.751555) (xy 379.548195 -280.698851) (xy 379.563905 -280.647921) (xy 379.587031 -280.5999)
			(xy 379.617055 -280.555863) (xy 379.653307 -280.516792) (xy 379.694978 -280.483561) (xy 379.741136 -280.456912)
			(xy 379.79075 -280.43744) (xy 379.842712 -280.42558) (xy 379.895862 -280.421597) (xy 379.949012 -280.42558)
			(xy 380.000974 -280.43744) (xy 380.050588 -280.456912) (xy 380.096746 -280.483561) (xy 380.138417 -280.516792)
			(xy 380.174669 -280.555863) (xy 380.204693 -280.5999) (xy 380.227819 -280.647921) (xy 380.243529 -280.698851)
			(xy 380.251472 -280.751555) (xy 380.25197 -280.778204) (xy 380.251472 -280.804853) (xy 380.480052 -280.804853)
			(xy 380.480052 -280.751555) (xy 380.487995 -280.698851) (xy 380.503705 -280.647921) (xy 380.526831 -280.5999)
			(xy 380.556855 -280.555863) (xy 380.593107 -280.516792) (xy 380.634778 -280.483561) (xy 380.680936 -280.456912)
			(xy 380.73055 -280.43744) (xy 380.782512 -280.42558) (xy 380.835662 -280.421597) (xy 380.888812 -280.42558)
			(xy 380.940774 -280.43744) (xy 380.990388 -280.456912) (xy 381.036546 -280.483561) (xy 381.078217 -280.516792)
			(xy 381.114469 -280.555863) (xy 381.144493 -280.5999) (xy 381.167619 -280.647921) (xy 381.183329 -280.698851)
			(xy 381.191272 -280.751555) (xy 381.19177 -280.778204) (xy 381.191272 -280.804853) (xy 381.419852 -280.804853)
			(xy 381.419852 -280.751555) (xy 381.427795 -280.698851) (xy 381.443505 -280.647921) (xy 381.466631 -280.5999)
			(xy 381.496655 -280.555863) (xy 381.532907 -280.516792) (xy 381.574578 -280.483561) (xy 381.620736 -280.456912)
			(xy 381.67035 -280.43744) (xy 381.722312 -280.42558) (xy 381.775462 -280.421597) (xy 381.828612 -280.42558)
			(xy 381.880574 -280.43744) (xy 381.930188 -280.456912) (xy 381.976346 -280.483561) (xy 382.018017 -280.516792)
			(xy 382.054269 -280.555863) (xy 382.084293 -280.5999) (xy 382.107419 -280.647921) (xy 382.123129 -280.698851)
			(xy 382.131072 -280.751555) (xy 382.13157 -280.778204) (xy 382.131072 -280.804853) (xy 383.299452 -280.804853)
			(xy 383.299452 -280.751555) (xy 383.307395 -280.698851) (xy 383.323105 -280.647921) (xy 383.346231 -280.5999)
			(xy 383.376255 -280.555863) (xy 383.412507 -280.516792) (xy 383.454178 -280.483561) (xy 383.500336 -280.456912)
			(xy 383.54995 -280.43744) (xy 383.601912 -280.42558) (xy 383.655062 -280.421597) (xy 383.708212 -280.42558)
			(xy 383.760174 -280.43744) (xy 383.809788 -280.456912) (xy 383.855946 -280.483561) (xy 383.897617 -280.516792)
			(xy 383.933869 -280.555863) (xy 383.963893 -280.5999) (xy 383.987019 -280.647921) (xy 384.002729 -280.698851)
			(xy 384.010672 -280.751555) (xy 384.01117 -280.778204) (xy 384.010672 -280.804853) (xy 384.002729 -280.857557)
			(xy 383.987019 -280.908487) (xy 383.963893 -280.956508) (xy 383.933869 -281.000545) (xy 383.897617 -281.039616)
			(xy 383.855946 -281.072847) (xy 383.809788 -281.099496) (xy 383.760174 -281.118968) (xy 383.708212 -281.130828)
			(xy 383.655062 -281.134812) (xy 383.601912 -281.130828) (xy 383.54995 -281.118968) (xy 383.500336 -281.099496)
			(xy 383.454178 -281.072847) (xy 383.412507 -281.039616) (xy 383.376255 -281.000545) (xy 383.346231 -280.956508)
			(xy 383.323105 -280.908487) (xy 383.307395 -280.857557) (xy 383.299452 -280.804853) (xy 382.131072 -280.804853)
			(xy 382.123129 -280.857557) (xy 382.107419 -280.908487) (xy 382.084293 -280.956508) (xy 382.054269 -281.000545)
			(xy 382.018017 -281.039616) (xy 381.976346 -281.072847) (xy 381.930188 -281.099496) (xy 381.880574 -281.118968)
			(xy 381.828612 -281.130828) (xy 381.775462 -281.134812) (xy 381.722312 -281.130828) (xy 381.67035 -281.118968)
			(xy 381.620736 -281.099496) (xy 381.574578 -281.072847) (xy 381.532907 -281.039616) (xy 381.496655 -281.000545)
			(xy 381.466631 -280.956508) (xy 381.443505 -280.908487) (xy 381.427795 -280.857557) (xy 381.419852 -280.804853)
			(xy 381.191272 -280.804853) (xy 381.183329 -280.857557) (xy 381.167619 -280.908487) (xy 381.144493 -280.956508)
			(xy 381.114469 -281.000545) (xy 381.078217 -281.039616) (xy 381.036546 -281.072847) (xy 380.990388 -281.099496)
			(xy 380.940774 -281.118968) (xy 380.888812 -281.130828) (xy 380.835662 -281.134812) (xy 380.782512 -281.130828)
			(xy 380.73055 -281.118968) (xy 380.680936 -281.099496) (xy 380.634778 -281.072847) (xy 380.593107 -281.039616)
			(xy 380.556855 -281.000545) (xy 380.526831 -280.956508) (xy 380.503705 -280.908487) (xy 380.487995 -280.857557)
			(xy 380.480052 -280.804853) (xy 380.251472 -280.804853) (xy 380.243529 -280.857557) (xy 380.227819 -280.908487)
			(xy 380.204693 -280.956508) (xy 380.174669 -281.000545) (xy 380.138417 -281.039616) (xy 380.096746 -281.072847)
			(xy 380.050588 -281.099496) (xy 380.000974 -281.118968) (xy 379.949012 -281.130828) (xy 379.895862 -281.134812)
			(xy 379.842712 -281.130828) (xy 379.79075 -281.118968) (xy 379.741136 -281.099496) (xy 379.694978 -281.072847)
			(xy 379.653307 -281.039616) (xy 379.617055 -281.000545) (xy 379.587031 -280.956508) (xy 379.563905 -280.908487)
			(xy 379.548195 -280.857557) (xy 379.540252 -280.804853) (xy 379.311672 -280.804853) (xy 379.303729 -280.857557)
			(xy 379.288019 -280.908487) (xy 379.264893 -280.956508) (xy 379.234869 -281.000545) (xy 379.198617 -281.039616)
			(xy 379.156946 -281.072847) (xy 379.110788 -281.099496) (xy 379.061174 -281.118968) (xy 379.009212 -281.130828)
			(xy 378.956062 -281.134812) (xy 378.902912 -281.130828) (xy 378.85095 -281.118968) (xy 378.801336 -281.099496)
			(xy 378.755178 -281.072847) (xy 378.713507 -281.039616) (xy 378.677255 -281.000545) (xy 378.647231 -280.956508)
			(xy 378.624105 -280.908487) (xy 378.608395 -280.857557) (xy 378.600452 -280.804853) (xy 378.372126 -280.804853)
			(xy 378.364183 -280.857557) (xy 378.348473 -280.908487) (xy 378.325347 -280.956508) (xy 378.295323 -281.000545)
			(xy 378.259071 -281.039616) (xy 378.2174 -281.072847) (xy 378.171242 -281.099496) (xy 378.121628 -281.118968)
			(xy 378.069666 -281.130828) (xy 378.016516 -281.134812) (xy 377.963366 -281.130828) (xy 377.911404 -281.118968)
			(xy 377.86179 -281.099496) (xy 377.815632 -281.072847) (xy 377.773961 -281.039616) (xy 377.737709 -281.000545)
			(xy 377.707685 -280.956508) (xy 377.684559 -280.908487) (xy 377.668849 -280.857557) (xy 377.660906 -280.804853)
			(xy 377.432326 -280.804853) (xy 377.424383 -280.857557) (xy 377.408673 -280.908487) (xy 377.385547 -280.956508)
			(xy 377.355523 -281.000545) (xy 377.319271 -281.039616) (xy 377.2776 -281.072847) (xy 377.231442 -281.099496)
			(xy 377.181828 -281.118968) (xy 377.129866 -281.130828) (xy 377.076716 -281.134812) (xy 377.023566 -281.130828)
			(xy 376.971604 -281.118968) (xy 376.92199 -281.099496) (xy 376.875832 -281.072847) (xy 376.834161 -281.039616)
			(xy 376.797909 -281.000545) (xy 376.767885 -280.956508) (xy 376.744759 -280.908487) (xy 376.729049 -280.857557)
			(xy 376.721106 -280.804853) (xy 376.492526 -280.804853) (xy 376.484583 -280.857557) (xy 376.468873 -280.908487)
			(xy 376.445747 -280.956508) (xy 376.415723 -281.000545) (xy 376.379471 -281.039616) (xy 376.3378 -281.072847)
			(xy 376.291642 -281.099496) (xy 376.242028 -281.118968) (xy 376.190066 -281.130828) (xy 376.136916 -281.134812)
			(xy 376.083766 -281.130828) (xy 376.031804 -281.118968) (xy 375.98219 -281.099496) (xy 375.936032 -281.072847)
			(xy 375.894361 -281.039616) (xy 375.858109 -281.000545) (xy 375.828085 -280.956508) (xy 375.804959 -280.908487)
			(xy 375.789249 -280.857557) (xy 375.781306 -280.804853) (xy 375.552726 -280.804853) (xy 375.544783 -280.857557)
			(xy 375.529073 -280.908487) (xy 375.505947 -280.956508) (xy 375.475923 -281.000545) (xy 375.439671 -281.039616)
			(xy 375.398 -281.072847) (xy 375.351842 -281.099496) (xy 375.302228 -281.118968) (xy 375.250266 -281.130828)
			(xy 375.197116 -281.134812) (xy 375.143966 -281.130828) (xy 375.092004 -281.118968) (xy 375.04239 -281.099496)
			(xy 374.996232 -281.072847) (xy 374.954561 -281.039616) (xy 374.918309 -281.000545) (xy 374.888285 -280.956508)
			(xy 374.865159 -280.908487) (xy 374.849449 -280.857557) (xy 374.841506 -280.804853) (xy 374.612926 -280.804853)
			(xy 374.604983 -280.857557) (xy 374.589273 -280.908487) (xy 374.566147 -280.956508) (xy 374.536123 -281.000545)
			(xy 374.499871 -281.039616) (xy 374.4582 -281.072847) (xy 374.412042 -281.099496) (xy 374.362428 -281.118968)
			(xy 374.310466 -281.130828) (xy 374.257316 -281.134812) (xy 374.204166 -281.130828) (xy 374.152204 -281.118968)
			(xy 374.10259 -281.099496) (xy 374.056432 -281.072847) (xy 374.014761 -281.039616) (xy 373.978509 -281.000545)
			(xy 373.948485 -280.956508) (xy 373.925359 -280.908487) (xy 373.909649 -280.857557) (xy 373.901706 -280.804853)
			(xy 373.672872 -280.804853) (xy 373.664929 -280.857557) (xy 373.649219 -280.908487) (xy 373.626093 -280.956508)
			(xy 373.596069 -281.000545) (xy 373.559817 -281.039616) (xy 373.518146 -281.072847) (xy 373.471988 -281.099496)
			(xy 373.422374 -281.118968) (xy 373.370412 -281.130828) (xy 373.317262 -281.134812) (xy 373.264112 -281.130828)
			(xy 373.21215 -281.118968) (xy 373.162536 -281.099496) (xy 373.116378 -281.072847) (xy 373.074707 -281.039616)
			(xy 373.038455 -281.000545) (xy 373.008431 -280.956508) (xy 372.985305 -280.908487) (xy 372.969595 -280.857557)
			(xy 372.961652 -280.804853) (xy 372.733072 -280.804853) (xy 372.725129 -280.857557) (xy 372.709419 -280.908487)
			(xy 372.686293 -280.956508) (xy 372.656269 -281.000545) (xy 372.620017 -281.039616) (xy 372.578346 -281.072847)
			(xy 372.532188 -281.099496) (xy 372.482574 -281.118968) (xy 372.430612 -281.130828) (xy 372.377462 -281.134812)
			(xy 372.324312 -281.130828) (xy 372.27235 -281.118968) (xy 372.222736 -281.099496) (xy 372.176578 -281.072847)
			(xy 372.134907 -281.039616) (xy 372.098655 -281.000545) (xy 372.068631 -280.956508) (xy 372.045505 -280.908487)
			(xy 372.029795 -280.857557) (xy 372.021852 -280.804853) (xy 371.793272 -280.804853) (xy 371.785329 -280.857557)
			(xy 371.769619 -280.908487) (xy 371.746493 -280.956508) (xy 371.716469 -281.000545) (xy 371.680217 -281.039616)
			(xy 371.638546 -281.072847) (xy 371.592388 -281.099496) (xy 371.542774 -281.118968) (xy 371.490812 -281.130828)
			(xy 371.437662 -281.134812) (xy 371.384512 -281.130828) (xy 371.33255 -281.118968) (xy 371.282936 -281.099496)
			(xy 371.236778 -281.072847) (xy 371.195107 -281.039616) (xy 371.158855 -281.000545) (xy 371.128831 -280.956508)
			(xy 371.105705 -280.908487) (xy 371.089995 -280.857557) (xy 371.082052 -280.804853) (xy 370.853472 -280.804853)
			(xy 370.845529 -280.857557) (xy 370.829819 -280.908487) (xy 370.806693 -280.956508) (xy 370.776669 -281.000545)
			(xy 370.740417 -281.039616) (xy 370.698746 -281.072847) (xy 370.652588 -281.099496) (xy 370.602974 -281.118968)
			(xy 370.551012 -281.130828) (xy 370.497862 -281.134812) (xy 370.444712 -281.130828) (xy 370.39275 -281.118968)
			(xy 370.343136 -281.099496) (xy 370.296978 -281.072847) (xy 370.255307 -281.039616) (xy 370.219055 -281.000545)
			(xy 370.189031 -280.956508) (xy 370.165905 -280.908487) (xy 370.150195 -280.857557) (xy 370.142252 -280.804853)
			(xy 369.913672 -280.804853) (xy 369.905729 -280.857557) (xy 369.890019 -280.908487) (xy 369.866893 -280.956508)
			(xy 369.836869 -281.000545) (xy 369.800617 -281.039616) (xy 369.758946 -281.072847) (xy 369.712788 -281.099496)
			(xy 369.663174 -281.118968) (xy 369.611212 -281.130828) (xy 369.558062 -281.134812) (xy 369.504912 -281.130828)
			(xy 369.45295 -281.118968) (xy 369.403336 -281.099496) (xy 369.357178 -281.072847) (xy 369.315507 -281.039616)
			(xy 369.279255 -281.000545) (xy 369.249231 -280.956508) (xy 369.226105 -280.908487) (xy 369.210395 -280.857557)
			(xy 369.202452 -280.804853) (xy 368.973872 -280.804853) (xy 368.965929 -280.857557) (xy 368.950219 -280.908487)
			(xy 368.927093 -280.956508) (xy 368.897069 -281.000545) (xy 368.860817 -281.039616) (xy 368.819146 -281.072847)
			(xy 368.772988 -281.099496) (xy 368.723374 -281.118968) (xy 368.671412 -281.130828) (xy 368.618262 -281.134812)
			(xy 368.565112 -281.130828) (xy 368.51315 -281.118968) (xy 368.463536 -281.099496) (xy 368.417378 -281.072847)
			(xy 368.375707 -281.039616) (xy 368.339455 -281.000545) (xy 368.309431 -280.956508) (xy 368.286305 -280.908487)
			(xy 368.270595 -280.857557) (xy 368.262652 -280.804853) (xy 368.034072 -280.804853) (xy 368.026129 -280.857557)
			(xy 368.010419 -280.908487) (xy 367.987293 -280.956508) (xy 367.957269 -281.000545) (xy 367.921017 -281.039616)
			(xy 367.879346 -281.072847) (xy 367.833188 -281.099496) (xy 367.783574 -281.118968) (xy 367.731612 -281.130828)
			(xy 367.678462 -281.134812) (xy 367.625312 -281.130828) (xy 367.57335 -281.118968) (xy 367.523736 -281.099496)
			(xy 367.477578 -281.072847) (xy 367.435907 -281.039616) (xy 367.399655 -281.000545) (xy 367.369631 -280.956508)
			(xy 367.346505 -280.908487) (xy 367.330795 -280.857557) (xy 367.322852 -280.804853) (xy 367.094272 -280.804853)
			(xy 367.086329 -280.857557) (xy 367.070619 -280.908487) (xy 367.047493 -280.956508) (xy 367.017469 -281.000545)
			(xy 366.981217 -281.039616) (xy 366.939546 -281.072847) (xy 366.893388 -281.099496) (xy 366.843774 -281.118968)
			(xy 366.791812 -281.130828) (xy 366.738662 -281.134812) (xy 366.685512 -281.130828) (xy 366.63355 -281.118968)
			(xy 366.583936 -281.099496) (xy 366.537778 -281.072847) (xy 366.496107 -281.039616) (xy 366.459855 -281.000545)
			(xy 366.429831 -280.956508) (xy 366.406705 -280.908487) (xy 366.390995 -280.857557) (xy 366.383052 -280.804853)
			(xy 366.154726 -280.804853) (xy 366.146783 -280.857557) (xy 366.131073 -280.908487) (xy 366.107947 -280.956508)
			(xy 366.077923 -281.000545) (xy 366.041671 -281.039616) (xy 366 -281.072847) (xy 365.953842 -281.099496)
			(xy 365.904228 -281.118968) (xy 365.852266 -281.130828) (xy 365.799116 -281.134812) (xy 365.745966 -281.130828)
			(xy 365.694004 -281.118968) (xy 365.64439 -281.099496) (xy 365.598232 -281.072847) (xy 365.556561 -281.039616)
			(xy 365.520309 -281.000545) (xy 365.490285 -280.956508) (xy 365.467159 -280.908487) (xy 365.451449 -280.857557)
			(xy 365.443506 -280.804853) (xy 365.214912 -280.804853) (xy 365.21488 -280.806496) (xy 365.205937 -280.862368)
			(xy 365.188276 -280.916125) (xy 365.162341 -280.966415) (xy 365.128784 -281.011975) (xy 365.108998 -281.032204)
			(xy 365.099743 -281.041883) (xy 365.086201 -281.064976) (xy 365.079118 -281.090793) (xy 365.07898 -281.117563)
			(xy 365.085797 -281.143452) (xy 365.099101 -281.166683) (xy 365.108236 -281.176476) (xy 365.193326 -281.261566)
			(xy 365.222536 -281.252168) (xy 365.248545 -281.244553) (xy 365.302119 -281.236388) (xy 365.329216 -281.235912)
			(xy 365.3572 -281.236434) (xy 365.412478 -281.245192) (xy 365.465706 -281.262489) (xy 365.515573 -281.2879)
			(xy 365.56085 -281.3208) (xy 365.600424 -281.360377) (xy 365.633318 -281.405658) (xy 365.658725 -281.455527)
			(xy 365.676017 -281.508757) (xy 365.684769 -281.564036) (xy 365.685324 -281.59202) (xy 365.684842 -281.618669)
			(xy 365.913152 -281.618669) (xy 365.913152 -281.565371) (xy 365.921095 -281.512667) (xy 365.936805 -281.461737)
			(xy 365.959931 -281.413716) (xy 365.989955 -281.369679) (xy 366.026207 -281.330608) (xy 366.067878 -281.297377)
			(xy 366.114036 -281.270728) (xy 366.16365 -281.251256) (xy 366.215612 -281.239396) (xy 366.268762 -281.235413)
			(xy 366.321912 -281.239396) (xy 366.373874 -281.251256) (xy 366.423488 -281.270728) (xy 366.469646 -281.297377)
			(xy 366.511317 -281.330608) (xy 366.547569 -281.369679) (xy 366.577593 -281.413716) (xy 366.600719 -281.461737)
			(xy 366.616429 -281.512667) (xy 366.624372 -281.565371) (xy 366.62487 -281.59202) (xy 366.624372 -281.618669)
			(xy 366.853206 -281.618669) (xy 366.853206 -281.565371) (xy 366.861149 -281.512667) (xy 366.876859 -281.461737)
			(xy 366.899985 -281.413716) (xy 366.930009 -281.369679) (xy 366.966261 -281.330608) (xy 367.007932 -281.297377)
			(xy 367.05409 -281.270728) (xy 367.103704 -281.251256) (xy 367.155666 -281.239396) (xy 367.208816 -281.235413)
			(xy 367.261966 -281.239396) (xy 367.313928 -281.251256) (xy 367.363542 -281.270728) (xy 367.4097 -281.297377)
			(xy 367.451371 -281.330608) (xy 367.487623 -281.369679) (xy 367.517647 -281.413716) (xy 367.540773 -281.461737)
			(xy 367.556483 -281.512667) (xy 367.564426 -281.565371) (xy 367.564924 -281.59202) (xy 367.564426 -281.618669)
			(xy 367.793006 -281.618669) (xy 367.793006 -281.565371) (xy 367.800949 -281.512667) (xy 367.816659 -281.461737)
			(xy 367.839785 -281.413716) (xy 367.869809 -281.369679) (xy 367.906061 -281.330608) (xy 367.947732 -281.297377)
			(xy 367.99389 -281.270728) (xy 368.043504 -281.251256) (xy 368.095466 -281.239396) (xy 368.148616 -281.235413)
			(xy 368.201766 -281.239396) (xy 368.253728 -281.251256) (xy 368.303342 -281.270728) (xy 368.3495 -281.297377)
			(xy 368.391171 -281.330608) (xy 368.427423 -281.369679) (xy 368.457447 -281.413716) (xy 368.480573 -281.461737)
			(xy 368.496283 -281.512667) (xy 368.504226 -281.565371) (xy 368.504724 -281.59202) (xy 368.504226 -281.618669)
			(xy 368.732806 -281.618669) (xy 368.732806 -281.565371) (xy 368.740749 -281.512667) (xy 368.756459 -281.461737)
			(xy 368.779585 -281.413716) (xy 368.809609 -281.369679) (xy 368.845861 -281.330608) (xy 368.887532 -281.297377)
			(xy 368.93369 -281.270728) (xy 368.983304 -281.251256) (xy 369.035266 -281.239396) (xy 369.088416 -281.235413)
			(xy 369.141566 -281.239396) (xy 369.193528 -281.251256) (xy 369.243142 -281.270728) (xy 369.2893 -281.297377)
			(xy 369.330971 -281.330608) (xy 369.367223 -281.369679) (xy 369.397247 -281.413716) (xy 369.420373 -281.461737)
			(xy 369.436083 -281.512667) (xy 369.444026 -281.565371) (xy 369.444524 -281.59202) (xy 369.444026 -281.618669)
			(xy 369.672606 -281.618669) (xy 369.672606 -281.565371) (xy 369.680549 -281.512667) (xy 369.696259 -281.461737)
			(xy 369.719385 -281.413716) (xy 369.749409 -281.369679) (xy 369.785661 -281.330608) (xy 369.827332 -281.297377)
			(xy 369.87349 -281.270728) (xy 369.923104 -281.251256) (xy 369.975066 -281.239396) (xy 370.028216 -281.235413)
			(xy 370.081366 -281.239396) (xy 370.133328 -281.251256) (xy 370.182942 -281.270728) (xy 370.2291 -281.297377)
			(xy 370.270771 -281.330608) (xy 370.307023 -281.369679) (xy 370.337047 -281.413716) (xy 370.360173 -281.461737)
			(xy 370.375883 -281.512667) (xy 370.383826 -281.565371) (xy 370.384324 -281.59202) (xy 370.383826 -281.618669)
			(xy 370.612406 -281.618669) (xy 370.612406 -281.565371) (xy 370.620349 -281.512667) (xy 370.636059 -281.461737)
			(xy 370.659185 -281.413716) (xy 370.689209 -281.369679) (xy 370.725461 -281.330608) (xy 370.767132 -281.297377)
			(xy 370.81329 -281.270728) (xy 370.862904 -281.251256) (xy 370.914866 -281.239396) (xy 370.968016 -281.235413)
			(xy 371.021166 -281.239396) (xy 371.073128 -281.251256) (xy 371.122742 -281.270728) (xy 371.1689 -281.297377)
			(xy 371.210571 -281.330608) (xy 371.246823 -281.369679) (xy 371.276847 -281.413716) (xy 371.299973 -281.461737)
			(xy 371.315683 -281.512667) (xy 371.323626 -281.565371) (xy 371.324124 -281.59202) (xy 371.323626 -281.618669)
			(xy 371.552206 -281.618669) (xy 371.552206 -281.565371) (xy 371.560149 -281.512667) (xy 371.575859 -281.461737)
			(xy 371.598985 -281.413716) (xy 371.629009 -281.369679) (xy 371.665261 -281.330608) (xy 371.706932 -281.297377)
			(xy 371.75309 -281.270728) (xy 371.802704 -281.251256) (xy 371.854666 -281.239396) (xy 371.907816 -281.235413)
			(xy 371.960966 -281.239396) (xy 372.012928 -281.251256) (xy 372.062542 -281.270728) (xy 372.1087 -281.297377)
			(xy 372.150371 -281.330608) (xy 372.186623 -281.369679) (xy 372.216647 -281.413716) (xy 372.239773 -281.461737)
			(xy 372.255483 -281.512667) (xy 372.263426 -281.565371) (xy 372.263924 -281.59202) (xy 372.263426 -281.618669)
			(xy 372.492006 -281.618669) (xy 372.492006 -281.565371) (xy 372.499949 -281.512667) (xy 372.515659 -281.461737)
			(xy 372.538785 -281.413716) (xy 372.568809 -281.369679) (xy 372.605061 -281.330608) (xy 372.646732 -281.297377)
			(xy 372.69289 -281.270728) (xy 372.742504 -281.251256) (xy 372.794466 -281.239396) (xy 372.847616 -281.235413)
			(xy 372.900766 -281.239396) (xy 372.952728 -281.251256) (xy 373.002342 -281.270728) (xy 373.0485 -281.297377)
			(xy 373.090171 -281.330608) (xy 373.126423 -281.369679) (xy 373.156447 -281.413716) (xy 373.179573 -281.461737)
			(xy 373.195283 -281.512667) (xy 373.203226 -281.565371) (xy 373.203724 -281.59202) (xy 373.203226 -281.618669)
			(xy 373.431806 -281.618669) (xy 373.431806 -281.565371) (xy 373.439749 -281.512667) (xy 373.455459 -281.461737)
			(xy 373.478585 -281.413716) (xy 373.508609 -281.369679) (xy 373.544861 -281.330608) (xy 373.586532 -281.297377)
			(xy 373.63269 -281.270728) (xy 373.682304 -281.251256) (xy 373.734266 -281.239396) (xy 373.787416 -281.235413)
			(xy 373.840566 -281.239396) (xy 373.892528 -281.251256) (xy 373.942142 -281.270728) (xy 373.9883 -281.297377)
			(xy 374.029971 -281.330608) (xy 374.066223 -281.369679) (xy 374.096247 -281.413716) (xy 374.119373 -281.461737)
			(xy 374.135083 -281.512667) (xy 374.143026 -281.565371) (xy 374.143524 -281.59202) (xy 374.143026 -281.618669)
			(xy 374.371352 -281.618669) (xy 374.371352 -281.565371) (xy 374.379295 -281.512667) (xy 374.395005 -281.461737)
			(xy 374.418131 -281.413716) (xy 374.448155 -281.369679) (xy 374.484407 -281.330608) (xy 374.526078 -281.297377)
			(xy 374.572236 -281.270728) (xy 374.62185 -281.251256) (xy 374.673812 -281.239396) (xy 374.726962 -281.235413)
			(xy 374.780112 -281.239396) (xy 374.832074 -281.251256) (xy 374.881688 -281.270728) (xy 374.927846 -281.297377)
			(xy 374.969517 -281.330608) (xy 375.005769 -281.369679) (xy 375.035793 -281.413716) (xy 375.058919 -281.461737)
			(xy 375.074629 -281.512667) (xy 375.082572 -281.565371) (xy 375.08307 -281.59202) (xy 375.082577 -281.618415)
			(xy 375.311152 -281.618415) (xy 375.311152 -281.565117) (xy 375.319095 -281.512413) (xy 375.334805 -281.461483)
			(xy 375.357931 -281.413462) (xy 375.387955 -281.369425) (xy 375.424207 -281.330354) (xy 375.465878 -281.297123)
			(xy 375.512036 -281.270474) (xy 375.56165 -281.251002) (xy 375.613612 -281.239142) (xy 375.666762 -281.235159)
			(xy 375.719912 -281.239142) (xy 375.771874 -281.251002) (xy 375.821488 -281.270474) (xy 375.867646 -281.297123)
			(xy 375.909317 -281.330354) (xy 375.945569 -281.369425) (xy 375.975593 -281.413462) (xy 375.998719 -281.461483)
			(xy 376.014429 -281.512413) (xy 376.022372 -281.565117) (xy 376.02287 -281.591766) (xy 376.022372 -281.618415)
			(xy 376.022334 -281.618669) (xy 376.251206 -281.618669) (xy 376.251206 -281.565371) (xy 376.259149 -281.512667)
			(xy 376.274859 -281.461737) (xy 376.297985 -281.413716) (xy 376.328009 -281.369679) (xy 376.364261 -281.330608)
			(xy 376.405932 -281.297377) (xy 376.45209 -281.270728) (xy 376.501704 -281.251256) (xy 376.553666 -281.239396)
			(xy 376.606816 -281.235413) (xy 376.659966 -281.239396) (xy 376.711928 -281.251256) (xy 376.761542 -281.270728)
			(xy 376.8077 -281.297377) (xy 376.849371 -281.330608) (xy 376.885623 -281.369679) (xy 376.915647 -281.413716)
			(xy 376.938773 -281.461737) (xy 376.954483 -281.512667) (xy 376.962426 -281.565371) (xy 376.962924 -281.59202)
			(xy 376.962426 -281.618669) (xy 377.190752 -281.618669) (xy 377.190752 -281.565371) (xy 377.198695 -281.512667)
			(xy 377.214405 -281.461737) (xy 377.237531 -281.413716) (xy 377.267555 -281.369679) (xy 377.303807 -281.330608)
			(xy 377.345478 -281.297377) (xy 377.391636 -281.270728) (xy 377.44125 -281.251256) (xy 377.493212 -281.239396)
			(xy 377.546362 -281.235413) (xy 377.599512 -281.239396) (xy 377.651474 -281.251256) (xy 377.701088 -281.270728)
			(xy 377.747246 -281.297377) (xy 377.788917 -281.330608) (xy 377.825169 -281.369679) (xy 377.855193 -281.413716)
			(xy 377.878319 -281.461737) (xy 377.894029 -281.512667) (xy 377.901972 -281.565371) (xy 377.90247 -281.59202)
			(xy 377.901972 -281.618669) (xy 378.130806 -281.618669) (xy 378.130806 -281.565371) (xy 378.138749 -281.512667)
			(xy 378.154459 -281.461737) (xy 378.177585 -281.413716) (xy 378.207609 -281.369679) (xy 378.243861 -281.330608)
			(xy 378.285532 -281.297377) (xy 378.33169 -281.270728) (xy 378.381304 -281.251256) (xy 378.433266 -281.239396)
			(xy 378.486416 -281.235413) (xy 378.539566 -281.239396) (xy 378.591528 -281.251256) (xy 378.641142 -281.270728)
			(xy 378.6873 -281.297377) (xy 378.728971 -281.330608) (xy 378.765223 -281.369679) (xy 378.795247 -281.413716)
			(xy 378.818373 -281.461737) (xy 378.834083 -281.512667) (xy 378.842026 -281.565371) (xy 378.842524 -281.59202)
			(xy 378.842026 -281.618669) (xy 379.070606 -281.618669) (xy 379.070606 -281.565371) (xy 379.078549 -281.512667)
			(xy 379.094259 -281.461737) (xy 379.117385 -281.413716) (xy 379.147409 -281.369679) (xy 379.183661 -281.330608)
			(xy 379.225332 -281.297377) (xy 379.27149 -281.270728) (xy 379.321104 -281.251256) (xy 379.373066 -281.239396)
			(xy 379.426216 -281.235413) (xy 379.479366 -281.239396) (xy 379.531328 -281.251256) (xy 379.580942 -281.270728)
			(xy 379.6271 -281.297377) (xy 379.668771 -281.330608) (xy 379.705023 -281.369679) (xy 379.735047 -281.413716)
			(xy 379.758173 -281.461737) (xy 379.773883 -281.512667) (xy 379.781826 -281.565371) (xy 379.782324 -281.59202)
			(xy 379.781826 -281.618669) (xy 380.010406 -281.618669) (xy 380.010406 -281.565371) (xy 380.018349 -281.512667)
			(xy 380.034059 -281.461737) (xy 380.057185 -281.413716) (xy 380.087209 -281.369679) (xy 380.123461 -281.330608)
			(xy 380.165132 -281.297377) (xy 380.21129 -281.270728) (xy 380.260904 -281.251256) (xy 380.312866 -281.239396)
			(xy 380.366016 -281.235413) (xy 380.419166 -281.239396) (xy 380.471128 -281.251256) (xy 380.520742 -281.270728)
			(xy 380.5669 -281.297377) (xy 380.608571 -281.330608) (xy 380.644823 -281.369679) (xy 380.674847 -281.413716)
			(xy 380.697973 -281.461737) (xy 380.713683 -281.512667) (xy 380.721626 -281.565371) (xy 380.722124 -281.59202)
			(xy 380.721626 -281.618669) (xy 380.950206 -281.618669) (xy 380.950206 -281.565371) (xy 380.958149 -281.512667)
			(xy 380.973859 -281.461737) (xy 380.996985 -281.413716) (xy 381.027009 -281.369679) (xy 381.063261 -281.330608)
			(xy 381.104932 -281.297377) (xy 381.15109 -281.270728) (xy 381.200704 -281.251256) (xy 381.252666 -281.239396)
			(xy 381.305816 -281.235413) (xy 381.358966 -281.239396) (xy 381.410928 -281.251256) (xy 381.460542 -281.270728)
			(xy 381.5067 -281.297377) (xy 381.548371 -281.330608) (xy 381.584623 -281.369679) (xy 381.614647 -281.413716)
			(xy 381.637773 -281.461737) (xy 381.653483 -281.512667) (xy 381.661426 -281.565371) (xy 381.661924 -281.59202)
			(xy 381.661426 -281.618669) (xy 381.890006 -281.618669) (xy 381.890006 -281.565371) (xy 381.897949 -281.512667)
			(xy 381.913659 -281.461737) (xy 381.936785 -281.413716) (xy 381.966809 -281.369679) (xy 382.003061 -281.330608)
			(xy 382.044732 -281.297377) (xy 382.09089 -281.270728) (xy 382.140504 -281.251256) (xy 382.192466 -281.239396)
			(xy 382.245616 -281.235413) (xy 382.298766 -281.239396) (xy 382.350728 -281.251256) (xy 382.400342 -281.270728)
			(xy 382.4465 -281.297377) (xy 382.488171 -281.330608) (xy 382.524423 -281.369679) (xy 382.554447 -281.413716)
			(xy 382.577573 -281.461737) (xy 382.593283 -281.512667) (xy 382.601226 -281.565371) (xy 382.601724 -281.59202)
			(xy 382.601226 -281.618669) (xy 382.829552 -281.618669) (xy 382.829552 -281.565371) (xy 382.837495 -281.512667)
			(xy 382.853205 -281.461737) (xy 382.876331 -281.413716) (xy 382.906355 -281.369679) (xy 382.942607 -281.330608)
			(xy 382.984278 -281.297377) (xy 383.030436 -281.270728) (xy 383.08005 -281.251256) (xy 383.132012 -281.239396)
			(xy 383.185162 -281.235413) (xy 383.238312 -281.239396) (xy 383.290274 -281.251256) (xy 383.339888 -281.270728)
			(xy 383.386046 -281.297377) (xy 383.427717 -281.330608) (xy 383.463969 -281.369679) (xy 383.493993 -281.413716)
			(xy 383.517119 -281.461737) (xy 383.532829 -281.512667) (xy 383.540772 -281.565371) (xy 383.54127 -281.59202)
			(xy 383.540772 -281.618669) (xy 383.769352 -281.618669) (xy 383.769352 -281.565371) (xy 383.777295 -281.512667)
			(xy 383.793005 -281.461737) (xy 383.816131 -281.413716) (xy 383.846155 -281.369679) (xy 383.882407 -281.330608)
			(xy 383.924078 -281.297377) (xy 383.970236 -281.270728) (xy 384.01985 -281.251256) (xy 384.071812 -281.239396)
			(xy 384.124962 -281.235413) (xy 384.178112 -281.239396) (xy 384.230074 -281.251256) (xy 384.279688 -281.270728)
			(xy 384.325846 -281.297377) (xy 384.367517 -281.330608) (xy 384.403769 -281.369679) (xy 384.433793 -281.413716)
			(xy 384.456919 -281.461737) (xy 384.472629 -281.512667) (xy 384.480572 -281.565371) (xy 384.48107 -281.59202)
			(xy 384.480572 -281.618669) (xy 384.709152 -281.618669) (xy 384.709152 -281.565371) (xy 384.717095 -281.512667)
			(xy 384.732805 -281.461737) (xy 384.755931 -281.413716) (xy 384.785955 -281.369679) (xy 384.822207 -281.330608)
			(xy 384.863878 -281.297377) (xy 384.910036 -281.270728) (xy 384.95965 -281.251256) (xy 385.011612 -281.239396)
			(xy 385.064762 -281.235413) (xy 385.117912 -281.239396) (xy 385.169874 -281.251256) (xy 385.219488 -281.270728)
			(xy 385.265646 -281.297377) (xy 385.307317 -281.330608) (xy 385.343569 -281.369679) (xy 385.373593 -281.413716)
			(xy 385.396719 -281.461737) (xy 385.412429 -281.512667) (xy 385.420372 -281.565371) (xy 385.42087 -281.59202)
			(xy 385.420372 -281.618669) (xy 385.412429 -281.671373) (xy 385.396719 -281.722303) (xy 385.373593 -281.770324)
			(xy 385.343569 -281.814361) (xy 385.307317 -281.853432) (xy 385.265646 -281.886663) (xy 385.219488 -281.913312)
			(xy 385.169874 -281.932784) (xy 385.117912 -281.944644) (xy 385.064762 -281.948628) (xy 385.011612 -281.944644)
			(xy 384.95965 -281.932784) (xy 384.910036 -281.913312) (xy 384.863878 -281.886663) (xy 384.822207 -281.853432)
			(xy 384.785955 -281.814361) (xy 384.755931 -281.770324) (xy 384.732805 -281.722303) (xy 384.717095 -281.671373)
			(xy 384.709152 -281.618669) (xy 384.480572 -281.618669) (xy 384.472629 -281.671373) (xy 384.456919 -281.722303)
			(xy 384.433793 -281.770324) (xy 384.403769 -281.814361) (xy 384.367517 -281.853432) (xy 384.325846 -281.886663)
			(xy 384.279688 -281.913312) (xy 384.230074 -281.932784) (xy 384.178112 -281.944644) (xy 384.124962 -281.948628)
			(xy 384.071812 -281.944644) (xy 384.01985 -281.932784) (xy 383.970236 -281.913312) (xy 383.924078 -281.886663)
			(xy 383.882407 -281.853432) (xy 383.846155 -281.814361) (xy 383.816131 -281.770324) (xy 383.793005 -281.722303)
			(xy 383.777295 -281.671373) (xy 383.769352 -281.618669) (xy 383.540772 -281.618669) (xy 383.532829 -281.671373)
			(xy 383.517119 -281.722303) (xy 383.493993 -281.770324) (xy 383.463969 -281.814361) (xy 383.427717 -281.853432)
			(xy 383.386046 -281.886663) (xy 383.339888 -281.913312) (xy 383.290274 -281.932784) (xy 383.238312 -281.944644)
			(xy 383.185162 -281.948628) (xy 383.132012 -281.944644) (xy 383.08005 -281.932784) (xy 383.030436 -281.913312)
			(xy 382.984278 -281.886663) (xy 382.942607 -281.853432) (xy 382.906355 -281.814361) (xy 382.876331 -281.770324)
			(xy 382.853205 -281.722303) (xy 382.837495 -281.671373) (xy 382.829552 -281.618669) (xy 382.601226 -281.618669)
			(xy 382.593283 -281.671373) (xy 382.577573 -281.722303) (xy 382.554447 -281.770324) (xy 382.524423 -281.814361)
			(xy 382.488171 -281.853432) (xy 382.4465 -281.886663) (xy 382.400342 -281.913312) (xy 382.350728 -281.932784)
			(xy 382.298766 -281.944644) (xy 382.245616 -281.948628) (xy 382.192466 -281.944644) (xy 382.140504 -281.932784)
			(xy 382.09089 -281.913312) (xy 382.044732 -281.886663) (xy 382.003061 -281.853432) (xy 381.966809 -281.814361)
			(xy 381.936785 -281.770324) (xy 381.913659 -281.722303) (xy 381.897949 -281.671373) (xy 381.890006 -281.618669)
			(xy 381.661426 -281.618669) (xy 381.653483 -281.671373) (xy 381.637773 -281.722303) (xy 381.614647 -281.770324)
			(xy 381.584623 -281.814361) (xy 381.548371 -281.853432) (xy 381.5067 -281.886663) (xy 381.460542 -281.913312)
			(xy 381.410928 -281.932784) (xy 381.358966 -281.944644) (xy 381.305816 -281.948628) (xy 381.252666 -281.944644)
			(xy 381.200704 -281.932784) (xy 381.15109 -281.913312) (xy 381.104932 -281.886663) (xy 381.063261 -281.853432)
			(xy 381.027009 -281.814361) (xy 380.996985 -281.770324) (xy 380.973859 -281.722303) (xy 380.958149 -281.671373)
			(xy 380.950206 -281.618669) (xy 380.721626 -281.618669) (xy 380.713683 -281.671373) (xy 380.697973 -281.722303)
			(xy 380.674847 -281.770324) (xy 380.644823 -281.814361) (xy 380.608571 -281.853432) (xy 380.5669 -281.886663)
			(xy 380.520742 -281.913312) (xy 380.471128 -281.932784) (xy 380.419166 -281.944644) (xy 380.366016 -281.948628)
			(xy 380.312866 -281.944644) (xy 380.260904 -281.932784) (xy 380.21129 -281.913312) (xy 380.165132 -281.886663)
			(xy 380.123461 -281.853432) (xy 380.087209 -281.814361) (xy 380.057185 -281.770324) (xy 380.034059 -281.722303)
			(xy 380.018349 -281.671373) (xy 380.010406 -281.618669) (xy 379.781826 -281.618669) (xy 379.773883 -281.671373)
			(xy 379.758173 -281.722303) (xy 379.735047 -281.770324) (xy 379.705023 -281.814361) (xy 379.668771 -281.853432)
			(xy 379.6271 -281.886663) (xy 379.580942 -281.913312) (xy 379.531328 -281.932784) (xy 379.479366 -281.944644)
			(xy 379.426216 -281.948628) (xy 379.373066 -281.944644) (xy 379.321104 -281.932784) (xy 379.27149 -281.913312)
			(xy 379.225332 -281.886663) (xy 379.183661 -281.853432) (xy 379.147409 -281.814361) (xy 379.117385 -281.770324)
			(xy 379.094259 -281.722303) (xy 379.078549 -281.671373) (xy 379.070606 -281.618669) (xy 378.842026 -281.618669)
			(xy 378.834083 -281.671373) (xy 378.818373 -281.722303) (xy 378.795247 -281.770324) (xy 378.765223 -281.814361)
			(xy 378.728971 -281.853432) (xy 378.6873 -281.886663) (xy 378.641142 -281.913312) (xy 378.591528 -281.932784)
			(xy 378.539566 -281.944644) (xy 378.486416 -281.948628) (xy 378.433266 -281.944644) (xy 378.381304 -281.932784)
			(xy 378.33169 -281.913312) (xy 378.285532 -281.886663) (xy 378.243861 -281.853432) (xy 378.207609 -281.814361)
			(xy 378.177585 -281.770324) (xy 378.154459 -281.722303) (xy 378.138749 -281.671373) (xy 378.130806 -281.618669)
			(xy 377.901972 -281.618669) (xy 377.894029 -281.671373) (xy 377.878319 -281.722303) (xy 377.855193 -281.770324)
			(xy 377.825169 -281.814361) (xy 377.788917 -281.853432) (xy 377.747246 -281.886663) (xy 377.701088 -281.913312)
			(xy 377.651474 -281.932784) (xy 377.599512 -281.944644) (xy 377.546362 -281.948628) (xy 377.493212 -281.944644)
			(xy 377.44125 -281.932784) (xy 377.391636 -281.913312) (xy 377.345478 -281.886663) (xy 377.303807 -281.853432)
			(xy 377.267555 -281.814361) (xy 377.237531 -281.770324) (xy 377.214405 -281.722303) (xy 377.198695 -281.671373)
			(xy 377.190752 -281.618669) (xy 376.962426 -281.618669) (xy 376.954483 -281.671373) (xy 376.938773 -281.722303)
			(xy 376.915647 -281.770324) (xy 376.885623 -281.814361) (xy 376.849371 -281.853432) (xy 376.8077 -281.886663)
			(xy 376.761542 -281.913312) (xy 376.711928 -281.932784) (xy 376.659966 -281.944644) (xy 376.606816 -281.948628)
			(xy 376.553666 -281.944644) (xy 376.501704 -281.932784) (xy 376.45209 -281.913312) (xy 376.405932 -281.886663)
			(xy 376.364261 -281.853432) (xy 376.328009 -281.814361) (xy 376.297985 -281.770324) (xy 376.274859 -281.722303)
			(xy 376.259149 -281.671373) (xy 376.251206 -281.618669) (xy 376.022334 -281.618669) (xy 376.014429 -281.671119)
			(xy 375.998719 -281.722049) (xy 375.975593 -281.77007) (xy 375.945569 -281.814107) (xy 375.909317 -281.853178)
			(xy 375.867646 -281.886409) (xy 375.821488 -281.913058) (xy 375.771874 -281.93253) (xy 375.719912 -281.94439)
			(xy 375.666762 -281.948374) (xy 375.613612 -281.94439) (xy 375.56165 -281.93253) (xy 375.512036 -281.913058)
			(xy 375.465878 -281.886409) (xy 375.424207 -281.853178) (xy 375.387955 -281.814107) (xy 375.357931 -281.77007)
			(xy 375.334805 -281.722049) (xy 375.319095 -281.671119) (xy 375.311152 -281.618415) (xy 375.082577 -281.618415)
			(xy 375.082572 -281.618669) (xy 375.074629 -281.671373) (xy 375.058919 -281.722303) (xy 375.035793 -281.770324)
			(xy 375.005769 -281.814361) (xy 374.969517 -281.853432) (xy 374.927846 -281.886663) (xy 374.881688 -281.913312)
			(xy 374.832074 -281.932784) (xy 374.780112 -281.944644) (xy 374.726962 -281.948628) (xy 374.673812 -281.944644)
			(xy 374.62185 -281.932784) (xy 374.572236 -281.913312) (xy 374.526078 -281.886663) (xy 374.484407 -281.853432)
			(xy 374.448155 -281.814361) (xy 374.418131 -281.770324) (xy 374.395005 -281.722303) (xy 374.379295 -281.671373)
			(xy 374.371352 -281.618669) (xy 374.143026 -281.618669) (xy 374.135083 -281.671373) (xy 374.119373 -281.722303)
			(xy 374.096247 -281.770324) (xy 374.066223 -281.814361) (xy 374.029971 -281.853432) (xy 373.9883 -281.886663)
			(xy 373.942142 -281.913312) (xy 373.892528 -281.932784) (xy 373.840566 -281.944644) (xy 373.787416 -281.948628)
			(xy 373.734266 -281.944644) (xy 373.682304 -281.932784) (xy 373.63269 -281.913312) (xy 373.586532 -281.886663)
			(xy 373.544861 -281.853432) (xy 373.508609 -281.814361) (xy 373.478585 -281.770324) (xy 373.455459 -281.722303)
			(xy 373.439749 -281.671373) (xy 373.431806 -281.618669) (xy 373.203226 -281.618669) (xy 373.195283 -281.671373)
			(xy 373.179573 -281.722303) (xy 373.156447 -281.770324) (xy 373.126423 -281.814361) (xy 373.090171 -281.853432)
			(xy 373.0485 -281.886663) (xy 373.002342 -281.913312) (xy 372.952728 -281.932784) (xy 372.900766 -281.944644)
			(xy 372.847616 -281.948628) (xy 372.794466 -281.944644) (xy 372.742504 -281.932784) (xy 372.69289 -281.913312)
			(xy 372.646732 -281.886663) (xy 372.605061 -281.853432) (xy 372.568809 -281.814361) (xy 372.538785 -281.770324)
			(xy 372.515659 -281.722303) (xy 372.499949 -281.671373) (xy 372.492006 -281.618669) (xy 372.263426 -281.618669)
			(xy 372.255483 -281.671373) (xy 372.239773 -281.722303) (xy 372.216647 -281.770324) (xy 372.186623 -281.814361)
			(xy 372.150371 -281.853432) (xy 372.1087 -281.886663) (xy 372.062542 -281.913312) (xy 372.012928 -281.932784)
			(xy 371.960966 -281.944644) (xy 371.907816 -281.948628) (xy 371.854666 -281.944644) (xy 371.802704 -281.932784)
			(xy 371.75309 -281.913312) (xy 371.706932 -281.886663) (xy 371.665261 -281.853432) (xy 371.629009 -281.814361)
			(xy 371.598985 -281.770324) (xy 371.575859 -281.722303) (xy 371.560149 -281.671373) (xy 371.552206 -281.618669)
			(xy 371.323626 -281.618669) (xy 371.315683 -281.671373) (xy 371.299973 -281.722303) (xy 371.276847 -281.770324)
			(xy 371.246823 -281.814361) (xy 371.210571 -281.853432) (xy 371.1689 -281.886663) (xy 371.122742 -281.913312)
			(xy 371.073128 -281.932784) (xy 371.021166 -281.944644) (xy 370.968016 -281.948628) (xy 370.914866 -281.944644)
			(xy 370.862904 -281.932784) (xy 370.81329 -281.913312) (xy 370.767132 -281.886663) (xy 370.725461 -281.853432)
			(xy 370.689209 -281.814361) (xy 370.659185 -281.770324) (xy 370.636059 -281.722303) (xy 370.620349 -281.671373)
			(xy 370.612406 -281.618669) (xy 370.383826 -281.618669) (xy 370.375883 -281.671373) (xy 370.360173 -281.722303)
			(xy 370.337047 -281.770324) (xy 370.307023 -281.814361) (xy 370.270771 -281.853432) (xy 370.2291 -281.886663)
			(xy 370.182942 -281.913312) (xy 370.133328 -281.932784) (xy 370.081366 -281.944644) (xy 370.028216 -281.948628)
			(xy 369.975066 -281.944644) (xy 369.923104 -281.932784) (xy 369.87349 -281.913312) (xy 369.827332 -281.886663)
			(xy 369.785661 -281.853432) (xy 369.749409 -281.814361) (xy 369.719385 -281.770324) (xy 369.696259 -281.722303)
			(xy 369.680549 -281.671373) (xy 369.672606 -281.618669) (xy 369.444026 -281.618669) (xy 369.436083 -281.671373)
			(xy 369.420373 -281.722303) (xy 369.397247 -281.770324) (xy 369.367223 -281.814361) (xy 369.330971 -281.853432)
			(xy 369.2893 -281.886663) (xy 369.243142 -281.913312) (xy 369.193528 -281.932784) (xy 369.141566 -281.944644)
			(xy 369.088416 -281.948628) (xy 369.035266 -281.944644) (xy 368.983304 -281.932784) (xy 368.93369 -281.913312)
			(xy 368.887532 -281.886663) (xy 368.845861 -281.853432) (xy 368.809609 -281.814361) (xy 368.779585 -281.770324)
			(xy 368.756459 -281.722303) (xy 368.740749 -281.671373) (xy 368.732806 -281.618669) (xy 368.504226 -281.618669)
			(xy 368.496283 -281.671373) (xy 368.480573 -281.722303) (xy 368.457447 -281.770324) (xy 368.427423 -281.814361)
			(xy 368.391171 -281.853432) (xy 368.3495 -281.886663) (xy 368.303342 -281.913312) (xy 368.253728 -281.932784)
			(xy 368.201766 -281.944644) (xy 368.148616 -281.948628) (xy 368.095466 -281.944644) (xy 368.043504 -281.932784)
			(xy 367.99389 -281.913312) (xy 367.947732 -281.886663) (xy 367.906061 -281.853432) (xy 367.869809 -281.814361)
			(xy 367.839785 -281.770324) (xy 367.816659 -281.722303) (xy 367.800949 -281.671373) (xy 367.793006 -281.618669)
			(xy 367.564426 -281.618669) (xy 367.556483 -281.671373) (xy 367.540773 -281.722303) (xy 367.517647 -281.770324)
			(xy 367.487623 -281.814361) (xy 367.451371 -281.853432) (xy 367.4097 -281.886663) (xy 367.363542 -281.913312)
			(xy 367.313928 -281.932784) (xy 367.261966 -281.944644) (xy 367.208816 -281.948628) (xy 367.155666 -281.944644)
			(xy 367.103704 -281.932784) (xy 367.05409 -281.913312) (xy 367.007932 -281.886663) (xy 366.966261 -281.853432)
			(xy 366.930009 -281.814361) (xy 366.899985 -281.770324) (xy 366.876859 -281.722303) (xy 366.861149 -281.671373)
			(xy 366.853206 -281.618669) (xy 366.624372 -281.618669) (xy 366.616429 -281.671373) (xy 366.600719 -281.722303)
			(xy 366.577593 -281.770324) (xy 366.547569 -281.814361) (xy 366.511317 -281.853432) (xy 366.469646 -281.886663)
			(xy 366.423488 -281.913312) (xy 366.373874 -281.932784) (xy 366.321912 -281.944644) (xy 366.268762 -281.948628)
			(xy 366.215612 -281.944644) (xy 366.16365 -281.932784) (xy 366.114036 -281.913312) (xy 366.067878 -281.886663)
			(xy 366.026207 -281.853432) (xy 365.989955 -281.814361) (xy 365.959931 -281.770324) (xy 365.936805 -281.722303)
			(xy 365.921095 -281.671373) (xy 365.913152 -281.618669) (xy 365.684842 -281.618669) (xy 365.684834 -281.619116)
			(xy 365.676669 -281.672688) (xy 365.669068 -281.6987) (xy 365.65967 -281.72791) (xy 366.241076 -282.309316)
			(xy 366.251596 -282.319149) (xy 366.276807 -282.333036) (xy 366.304891 -282.33934) (xy 366.333619 -282.33756)
			(xy 366.36071 -282.327837) (xy 366.384014 -282.310944) (xy 366.401682 -282.288221) (xy 366.407446 -282.275026)
			(xy 366.417675 -282.250462) (xy 366.444359 -282.204428) (xy 366.477596 -282.162877) (xy 366.516644 -282.126733)
			(xy 366.560636 -282.096801) (xy 366.608591 -282.073748) (xy 366.659442 -282.058086) (xy 366.712058 -282.050164)
			(xy 366.738662 -282.049728) (xy 366.766648 -282.050246) (xy 366.821932 -282.058997) (xy 366.875166 -282.07629)
			(xy 366.925039 -282.101699) (xy 366.970323 -282.134597) (xy 367.009901 -282.174176) (xy 367.0428 -282.219459)
			(xy 367.068209 -282.269332) (xy 367.085503 -282.322566) (xy 367.094254 -282.37785) (xy 367.09477 -282.405836)
			(xy 367.094273 -282.432437) (xy 367.094266 -282.432485) (xy 367.322852 -282.432485) (xy 367.322852 -282.379187)
			(xy 367.330795 -282.326483) (xy 367.346505 -282.275553) (xy 367.369631 -282.227532) (xy 367.399655 -282.183495)
			(xy 367.435907 -282.144424) (xy 367.477578 -282.111193) (xy 367.523736 -282.084544) (xy 367.57335 -282.065072)
			(xy 367.625312 -282.053212) (xy 367.678462 -282.049229) (xy 367.731612 -282.053212) (xy 367.783574 -282.065072)
			(xy 367.833188 -282.084544) (xy 367.879346 -282.111193) (xy 367.921017 -282.144424) (xy 367.957269 -282.183495)
			(xy 367.987293 -282.227532) (xy 368.010419 -282.275553) (xy 368.026129 -282.326483) (xy 368.034072 -282.379187)
			(xy 368.03457 -282.405836) (xy 368.034072 -282.432485) (xy 368.262652 -282.432485) (xy 368.262652 -282.379187)
			(xy 368.270595 -282.326483) (xy 368.286305 -282.275553) (xy 368.309431 -282.227532) (xy 368.339455 -282.183495)
			(xy 368.375707 -282.144424) (xy 368.417378 -282.111193) (xy 368.463536 -282.084544) (xy 368.51315 -282.065072)
			(xy 368.565112 -282.053212) (xy 368.618262 -282.049229) (xy 368.671412 -282.053212) (xy 368.723374 -282.065072)
			(xy 368.772988 -282.084544) (xy 368.819146 -282.111193) (xy 368.860817 -282.144424) (xy 368.897069 -282.183495)
			(xy 368.927093 -282.227532) (xy 368.950219 -282.275553) (xy 368.965929 -282.326483) (xy 368.973872 -282.379187)
			(xy 368.97437 -282.405836) (xy 368.973872 -282.432485) (xy 369.202452 -282.432485) (xy 369.202452 -282.379187)
			(xy 369.210395 -282.326483) (xy 369.226105 -282.275553) (xy 369.249231 -282.227532) (xy 369.279255 -282.183495)
			(xy 369.315507 -282.144424) (xy 369.357178 -282.111193) (xy 369.403336 -282.084544) (xy 369.45295 -282.065072)
			(xy 369.504912 -282.053212) (xy 369.558062 -282.049229) (xy 369.611212 -282.053212) (xy 369.663174 -282.065072)
			(xy 369.712788 -282.084544) (xy 369.758946 -282.111193) (xy 369.800617 -282.144424) (xy 369.836869 -282.183495)
			(xy 369.866893 -282.227532) (xy 369.890019 -282.275553) (xy 369.905729 -282.326483) (xy 369.913672 -282.379187)
			(xy 369.91417 -282.405836) (xy 369.913672 -282.432485) (xy 370.142252 -282.432485) (xy 370.142252 -282.379187)
			(xy 370.150195 -282.326483) (xy 370.165905 -282.275553) (xy 370.189031 -282.227532) (xy 370.219055 -282.183495)
			(xy 370.255307 -282.144424) (xy 370.296978 -282.111193) (xy 370.343136 -282.084544) (xy 370.39275 -282.065072)
			(xy 370.444712 -282.053212) (xy 370.497862 -282.049229) (xy 370.551012 -282.053212) (xy 370.602974 -282.065072)
			(xy 370.652588 -282.084544) (xy 370.698746 -282.111193) (xy 370.740417 -282.144424) (xy 370.776669 -282.183495)
			(xy 370.806693 -282.227532) (xy 370.829819 -282.275553) (xy 370.845529 -282.326483) (xy 370.853472 -282.379187)
			(xy 370.85397 -282.405836) (xy 370.853472 -282.432485) (xy 371.082052 -282.432485) (xy 371.082052 -282.379187)
			(xy 371.089995 -282.326483) (xy 371.105705 -282.275553) (xy 371.128831 -282.227532) (xy 371.158855 -282.183495)
			(xy 371.195107 -282.144424) (xy 371.236778 -282.111193) (xy 371.282936 -282.084544) (xy 371.33255 -282.065072)
			(xy 371.384512 -282.053212) (xy 371.437662 -282.049229) (xy 371.490812 -282.053212) (xy 371.542774 -282.065072)
			(xy 371.592388 -282.084544) (xy 371.638546 -282.111193) (xy 371.680217 -282.144424) (xy 371.716469 -282.183495)
			(xy 371.746493 -282.227532) (xy 371.769619 -282.275553) (xy 371.785329 -282.326483) (xy 371.793272 -282.379187)
			(xy 371.79377 -282.405836) (xy 371.793272 -282.432485) (xy 372.021852 -282.432485) (xy 372.021852 -282.379187)
			(xy 372.029795 -282.326483) (xy 372.045505 -282.275553) (xy 372.068631 -282.227532) (xy 372.098655 -282.183495)
			(xy 372.134907 -282.144424) (xy 372.176578 -282.111193) (xy 372.222736 -282.084544) (xy 372.27235 -282.065072)
			(xy 372.324312 -282.053212) (xy 372.377462 -282.049229) (xy 372.430612 -282.053212) (xy 372.482574 -282.065072)
			(xy 372.532188 -282.084544) (xy 372.578346 -282.111193) (xy 372.620017 -282.144424) (xy 372.656269 -282.183495)
			(xy 372.686293 -282.227532) (xy 372.709419 -282.275553) (xy 372.725129 -282.326483) (xy 372.733072 -282.379187)
			(xy 372.73357 -282.405836) (xy 372.733072 -282.432485) (xy 372.961652 -282.432485) (xy 372.961652 -282.379187)
			(xy 372.969595 -282.326483) (xy 372.985305 -282.275553) (xy 373.008431 -282.227532) (xy 373.038455 -282.183495)
			(xy 373.074707 -282.144424) (xy 373.116378 -282.111193) (xy 373.162536 -282.084544) (xy 373.21215 -282.065072)
			(xy 373.264112 -282.053212) (xy 373.317262 -282.049229) (xy 373.370412 -282.053212) (xy 373.422374 -282.065072)
			(xy 373.471988 -282.084544) (xy 373.518146 -282.111193) (xy 373.559817 -282.144424) (xy 373.596069 -282.183495)
			(xy 373.626093 -282.227532) (xy 373.649219 -282.275553) (xy 373.664929 -282.326483) (xy 373.672872 -282.379187)
			(xy 373.67337 -282.405836) (xy 373.672872 -282.432485) (xy 373.901706 -282.432485) (xy 373.901706 -282.379187)
			(xy 373.909649 -282.326483) (xy 373.925359 -282.275553) (xy 373.948485 -282.227532) (xy 373.978509 -282.183495)
			(xy 374.014761 -282.144424) (xy 374.056432 -282.111193) (xy 374.10259 -282.084544) (xy 374.152204 -282.065072)
			(xy 374.204166 -282.053212) (xy 374.257316 -282.049229) (xy 374.310466 -282.053212) (xy 374.362428 -282.065072)
			(xy 374.412042 -282.084544) (xy 374.4582 -282.111193) (xy 374.499871 -282.144424) (xy 374.536123 -282.183495)
			(xy 374.566147 -282.227532) (xy 374.589273 -282.275553) (xy 374.604983 -282.326483) (xy 374.612926 -282.379187)
			(xy 374.613424 -282.405836) (xy 374.612931 -282.432231) (xy 374.841506 -282.432231) (xy 374.841506 -282.378933)
			(xy 374.849449 -282.326229) (xy 374.865159 -282.275299) (xy 374.888285 -282.227278) (xy 374.918309 -282.183241)
			(xy 374.954561 -282.14417) (xy 374.996232 -282.110939) (xy 375.04239 -282.08429) (xy 375.092004 -282.064818)
			(xy 375.143966 -282.052958) (xy 375.197116 -282.048975) (xy 375.250266 -282.052958) (xy 375.302228 -282.064818)
			(xy 375.351842 -282.08429) (xy 375.398 -282.110939) (xy 375.439671 -282.14417) (xy 375.475923 -282.183241)
			(xy 375.505947 -282.227278) (xy 375.529073 -282.275299) (xy 375.544783 -282.326229) (xy 375.552726 -282.378933)
			(xy 375.553224 -282.405582) (xy 375.552726 -282.432231) (xy 375.781306 -282.432231) (xy 375.781306 -282.378933)
			(xy 375.789249 -282.326229) (xy 375.804959 -282.275299) (xy 375.828085 -282.227278) (xy 375.858109 -282.183241)
			(xy 375.894361 -282.14417) (xy 375.936032 -282.110939) (xy 375.98219 -282.08429) (xy 376.031804 -282.064818)
			(xy 376.083766 -282.052958) (xy 376.136916 -282.048975) (xy 376.190066 -282.052958) (xy 376.242028 -282.064818)
			(xy 376.291642 -282.08429) (xy 376.3378 -282.110939) (xy 376.379471 -282.14417) (xy 376.415723 -282.183241)
			(xy 376.445747 -282.227278) (xy 376.468873 -282.275299) (xy 376.484583 -282.326229) (xy 376.492526 -282.378933)
			(xy 376.493024 -282.405582) (xy 376.492526 -282.432231) (xy 376.721106 -282.432231) (xy 376.721106 -282.378933)
			(xy 376.729049 -282.326229) (xy 376.744759 -282.275299) (xy 376.767885 -282.227278) (xy 376.797909 -282.183241)
			(xy 376.834161 -282.14417) (xy 376.875832 -282.110939) (xy 376.92199 -282.08429) (xy 376.971604 -282.064818)
			(xy 377.023566 -282.052958) (xy 377.076716 -282.048975) (xy 377.129866 -282.052958) (xy 377.181828 -282.064818)
			(xy 377.231442 -282.08429) (xy 377.2776 -282.110939) (xy 377.319271 -282.14417) (xy 377.355523 -282.183241)
			(xy 377.385547 -282.227278) (xy 377.408673 -282.275299) (xy 377.424383 -282.326229) (xy 377.432326 -282.378933)
			(xy 377.432824 -282.405582) (xy 377.432326 -282.432231) (xy 377.660906 -282.432231) (xy 377.660906 -282.378933)
			(xy 377.668849 -282.326229) (xy 377.684559 -282.275299) (xy 377.707685 -282.227278) (xy 377.737709 -282.183241)
			(xy 377.773961 -282.14417) (xy 377.815632 -282.110939) (xy 377.86179 -282.08429) (xy 377.911404 -282.064818)
			(xy 377.963366 -282.052958) (xy 378.016516 -282.048975) (xy 378.069666 -282.052958) (xy 378.121628 -282.064818)
			(xy 378.171242 -282.08429) (xy 378.2174 -282.110939) (xy 378.259071 -282.14417) (xy 378.295323 -282.183241)
			(xy 378.325347 -282.227278) (xy 378.348473 -282.275299) (xy 378.364183 -282.326229) (xy 378.372126 -282.378933)
			(xy 378.372624 -282.405582) (xy 378.372126 -282.432231) (xy 378.372088 -282.432485) (xy 378.600452 -282.432485)
			(xy 378.600452 -282.379187) (xy 378.608395 -282.326483) (xy 378.624105 -282.275553) (xy 378.647231 -282.227532)
			(xy 378.677255 -282.183495) (xy 378.713507 -282.144424) (xy 378.755178 -282.111193) (xy 378.801336 -282.084544)
			(xy 378.85095 -282.065072) (xy 378.902912 -282.053212) (xy 378.956062 -282.049229) (xy 379.009212 -282.053212)
			(xy 379.061174 -282.065072) (xy 379.110788 -282.084544) (xy 379.156946 -282.111193) (xy 379.198617 -282.144424)
			(xy 379.234869 -282.183495) (xy 379.264893 -282.227532) (xy 379.288019 -282.275553) (xy 379.303729 -282.326483)
			(xy 379.311672 -282.379187) (xy 379.31217 -282.405836) (xy 379.311672 -282.432485) (xy 379.540252 -282.432485)
			(xy 379.540252 -282.379187) (xy 379.548195 -282.326483) (xy 379.563905 -282.275553) (xy 379.587031 -282.227532)
			(xy 379.617055 -282.183495) (xy 379.653307 -282.144424) (xy 379.694978 -282.111193) (xy 379.741136 -282.084544)
			(xy 379.79075 -282.065072) (xy 379.842712 -282.053212) (xy 379.895862 -282.049229) (xy 379.949012 -282.053212)
			(xy 380.000974 -282.065072) (xy 380.050588 -282.084544) (xy 380.096746 -282.111193) (xy 380.138417 -282.144424)
			(xy 380.174669 -282.183495) (xy 380.204693 -282.227532) (xy 380.227819 -282.275553) (xy 380.243529 -282.326483)
			(xy 380.251472 -282.379187) (xy 380.25197 -282.405836) (xy 380.251472 -282.432485) (xy 380.480052 -282.432485)
			(xy 380.480052 -282.379187) (xy 380.487995 -282.326483) (xy 380.503705 -282.275553) (xy 380.526831 -282.227532)
			(xy 380.556855 -282.183495) (xy 380.593107 -282.144424) (xy 380.634778 -282.111193) (xy 380.680936 -282.084544)
			(xy 380.73055 -282.065072) (xy 380.782512 -282.053212) (xy 380.835662 -282.049229) (xy 380.888812 -282.053212)
			(xy 380.940774 -282.065072) (xy 380.990388 -282.084544) (xy 381.036546 -282.111193) (xy 381.078217 -282.144424)
			(xy 381.114469 -282.183495) (xy 381.144493 -282.227532) (xy 381.167619 -282.275553) (xy 381.183329 -282.326483)
			(xy 381.191272 -282.379187) (xy 381.19177 -282.405836) (xy 381.191272 -282.432485) (xy 381.419852 -282.432485)
			(xy 381.419852 -282.379187) (xy 381.427795 -282.326483) (xy 381.443505 -282.275553) (xy 381.466631 -282.227532)
			(xy 381.496655 -282.183495) (xy 381.532907 -282.144424) (xy 381.574578 -282.111193) (xy 381.620736 -282.084544)
			(xy 381.67035 -282.065072) (xy 381.722312 -282.053212) (xy 381.775462 -282.049229) (xy 381.828612 -282.053212)
			(xy 381.880574 -282.065072) (xy 381.930188 -282.084544) (xy 381.976346 -282.111193) (xy 382.018017 -282.144424)
			(xy 382.054269 -282.183495) (xy 382.084293 -282.227532) (xy 382.107419 -282.275553) (xy 382.123129 -282.326483)
			(xy 382.131072 -282.379187) (xy 382.13157 -282.405836) (xy 382.131072 -282.432485) (xy 382.359906 -282.432485)
			(xy 382.359906 -282.379187) (xy 382.367849 -282.326483) (xy 382.383559 -282.275553) (xy 382.406685 -282.227532)
			(xy 382.436709 -282.183495) (xy 382.472961 -282.144424) (xy 382.514632 -282.111193) (xy 382.56079 -282.084544)
			(xy 382.610404 -282.065072) (xy 382.662366 -282.053212) (xy 382.715516 -282.049229) (xy 382.768666 -282.053212)
			(xy 382.820628 -282.065072) (xy 382.870242 -282.084544) (xy 382.9164 -282.111193) (xy 382.958071 -282.144424)
			(xy 382.994323 -282.183495) (xy 383.024347 -282.227532) (xy 383.047473 -282.275553) (xy 383.063183 -282.326483)
			(xy 383.071126 -282.379187) (xy 383.071624 -282.405836) (xy 383.071126 -282.432485) (xy 383.299452 -282.432485)
			(xy 383.299452 -282.379187) (xy 383.307395 -282.326483) (xy 383.323105 -282.275553) (xy 383.346231 -282.227532)
			(xy 383.376255 -282.183495) (xy 383.412507 -282.144424) (xy 383.454178 -282.111193) (xy 383.500336 -282.084544)
			(xy 383.54995 -282.065072) (xy 383.601912 -282.053212) (xy 383.655062 -282.049229) (xy 383.708212 -282.053212)
			(xy 383.760174 -282.065072) (xy 383.809788 -282.084544) (xy 383.855946 -282.111193) (xy 383.897617 -282.144424)
			(xy 383.933869 -282.183495) (xy 383.963893 -282.227532) (xy 383.987019 -282.275553) (xy 384.002729 -282.326483)
			(xy 384.010672 -282.379187) (xy 384.01117 -282.405836) (xy 384.010672 -282.432485) (xy 384.239252 -282.432485)
			(xy 384.239252 -282.379187) (xy 384.247195 -282.326483) (xy 384.262905 -282.275553) (xy 384.286031 -282.227532)
			(xy 384.316055 -282.183495) (xy 384.352307 -282.144424) (xy 384.393978 -282.111193) (xy 384.440136 -282.084544)
			(xy 384.48975 -282.065072) (xy 384.541712 -282.053212) (xy 384.594862 -282.049229) (xy 384.648012 -282.053212)
			(xy 384.699974 -282.065072) (xy 384.749588 -282.084544) (xy 384.795746 -282.111193) (xy 384.837417 -282.144424)
			(xy 384.873669 -282.183495) (xy 384.903693 -282.227532) (xy 384.926819 -282.275553) (xy 384.942529 -282.326483)
			(xy 384.950472 -282.379187) (xy 384.95097 -282.405836) (xy 384.950472 -282.432485) (xy 385.179052 -282.432485)
			(xy 385.179052 -282.379187) (xy 385.186995 -282.326483) (xy 385.202705 -282.275553) (xy 385.225831 -282.227532)
			(xy 385.255855 -282.183495) (xy 385.292107 -282.144424) (xy 385.333778 -282.111193) (xy 385.379936 -282.084544)
			(xy 385.42955 -282.065072) (xy 385.481512 -282.053212) (xy 385.534662 -282.049229) (xy 385.587812 -282.053212)
			(xy 385.639774 -282.065072) (xy 385.689388 -282.084544) (xy 385.735546 -282.111193) (xy 385.777217 -282.144424)
			(xy 385.813469 -282.183495) (xy 385.843493 -282.227532) (xy 385.866619 -282.275553) (xy 385.882329 -282.326483)
			(xy 385.890272 -282.379187) (xy 385.89077 -282.405836) (xy 385.890272 -282.432485) (xy 385.882329 -282.485189)
			(xy 385.866619 -282.536119) (xy 385.843493 -282.58414) (xy 385.813469 -282.628177) (xy 385.777217 -282.667248)
			(xy 385.735546 -282.700479) (xy 385.689388 -282.727128) (xy 385.639774 -282.7466) (xy 385.587812 -282.75846)
			(xy 385.534662 -282.762444) (xy 385.481512 -282.75846) (xy 385.42955 -282.7466) (xy 385.379936 -282.727128)
			(xy 385.333778 -282.700479) (xy 385.292107 -282.667248) (xy 385.255855 -282.628177) (xy 385.225831 -282.58414)
			(xy 385.202705 -282.536119) (xy 385.186995 -282.485189) (xy 385.179052 -282.432485) (xy 384.950472 -282.432485)
			(xy 384.942529 -282.485189) (xy 384.926819 -282.536119) (xy 384.903693 -282.58414) (xy 384.873669 -282.628177)
			(xy 384.837417 -282.667248) (xy 384.795746 -282.700479) (xy 384.749588 -282.727128) (xy 384.699974 -282.7466)
			(xy 384.648012 -282.75846) (xy 384.594862 -282.762444) (xy 384.541712 -282.75846) (xy 384.48975 -282.7466)
			(xy 384.440136 -282.727128) (xy 384.393978 -282.700479) (xy 384.352307 -282.667248) (xy 384.316055 -282.628177)
			(xy 384.286031 -282.58414) (xy 384.262905 -282.536119) (xy 384.247195 -282.485189) (xy 384.239252 -282.432485)
			(xy 384.010672 -282.432485) (xy 384.002729 -282.485189) (xy 383.987019 -282.536119) (xy 383.963893 -282.58414)
			(xy 383.933869 -282.628177) (xy 383.897617 -282.667248) (xy 383.855946 -282.700479) (xy 383.809788 -282.727128)
			(xy 383.760174 -282.7466) (xy 383.708212 -282.75846) (xy 383.655062 -282.762444) (xy 383.601912 -282.75846)
			(xy 383.54995 -282.7466) (xy 383.500336 -282.727128) (xy 383.454178 -282.700479) (xy 383.412507 -282.667248)
			(xy 383.376255 -282.628177) (xy 383.346231 -282.58414) (xy 383.323105 -282.536119) (xy 383.307395 -282.485189)
			(xy 383.299452 -282.432485) (xy 383.071126 -282.432485) (xy 383.063183 -282.485189) (xy 383.047473 -282.536119)
			(xy 383.024347 -282.58414) (xy 382.994323 -282.628177) (xy 382.958071 -282.667248) (xy 382.9164 -282.700479)
			(xy 382.870242 -282.727128) (xy 382.820628 -282.7466) (xy 382.768666 -282.75846) (xy 382.715516 -282.762444)
			(xy 382.662366 -282.75846) (xy 382.610404 -282.7466) (xy 382.56079 -282.727128) (xy 382.514632 -282.700479)
			(xy 382.472961 -282.667248) (xy 382.436709 -282.628177) (xy 382.406685 -282.58414) (xy 382.383559 -282.536119)
			(xy 382.367849 -282.485189) (xy 382.359906 -282.432485) (xy 382.131072 -282.432485) (xy 382.123129 -282.485189)
			(xy 382.107419 -282.536119) (xy 382.084293 -282.58414) (xy 382.054269 -282.628177) (xy 382.018017 -282.667248)
			(xy 381.976346 -282.700479) (xy 381.930188 -282.727128) (xy 381.880574 -282.7466) (xy 381.828612 -282.75846)
			(xy 381.775462 -282.762444) (xy 381.722312 -282.75846) (xy 381.67035 -282.7466) (xy 381.620736 -282.727128)
			(xy 381.574578 -282.700479) (xy 381.532907 -282.667248) (xy 381.496655 -282.628177) (xy 381.466631 -282.58414)
			(xy 381.443505 -282.536119) (xy 381.427795 -282.485189) (xy 381.419852 -282.432485) (xy 381.191272 -282.432485)
			(xy 381.183329 -282.485189) (xy 381.167619 -282.536119) (xy 381.144493 -282.58414) (xy 381.114469 -282.628177)
			(xy 381.078217 -282.667248) (xy 381.036546 -282.700479) (xy 380.990388 -282.727128) (xy 380.940774 -282.7466)
			(xy 380.888812 -282.75846) (xy 380.835662 -282.762444) (xy 380.782512 -282.75846) (xy 380.73055 -282.7466)
			(xy 380.680936 -282.727128) (xy 380.634778 -282.700479) (xy 380.593107 -282.667248) (xy 380.556855 -282.628177)
			(xy 380.526831 -282.58414) (xy 380.503705 -282.536119) (xy 380.487995 -282.485189) (xy 380.480052 -282.432485)
			(xy 380.251472 -282.432485) (xy 380.243529 -282.485189) (xy 380.227819 -282.536119) (xy 380.204693 -282.58414)
			(xy 380.174669 -282.628177) (xy 380.138417 -282.667248) (xy 380.096746 -282.700479) (xy 380.050588 -282.727128)
			(xy 380.000974 -282.7466) (xy 379.949012 -282.75846) (xy 379.895862 -282.762444) (xy 379.842712 -282.75846)
			(xy 379.79075 -282.7466) (xy 379.741136 -282.727128) (xy 379.694978 -282.700479) (xy 379.653307 -282.667248)
			(xy 379.617055 -282.628177) (xy 379.587031 -282.58414) (xy 379.563905 -282.536119) (xy 379.548195 -282.485189)
			(xy 379.540252 -282.432485) (xy 379.311672 -282.432485) (xy 379.303729 -282.485189) (xy 379.288019 -282.536119)
			(xy 379.264893 -282.58414) (xy 379.234869 -282.628177) (xy 379.198617 -282.667248) (xy 379.156946 -282.700479)
			(xy 379.110788 -282.727128) (xy 379.061174 -282.7466) (xy 379.009212 -282.75846) (xy 378.956062 -282.762444)
			(xy 378.902912 -282.75846) (xy 378.85095 -282.7466) (xy 378.801336 -282.727128) (xy 378.755178 -282.700479)
			(xy 378.713507 -282.667248) (xy 378.677255 -282.628177) (xy 378.647231 -282.58414) (xy 378.624105 -282.536119)
			(xy 378.608395 -282.485189) (xy 378.600452 -282.432485) (xy 378.372088 -282.432485) (xy 378.364183 -282.484935)
			(xy 378.348473 -282.535865) (xy 378.325347 -282.583886) (xy 378.295323 -282.627923) (xy 378.259071 -282.666994)
			(xy 378.2174 -282.700225) (xy 378.171242 -282.726874) (xy 378.121628 -282.746346) (xy 378.069666 -282.758206)
			(xy 378.016516 -282.76219) (xy 377.963366 -282.758206) (xy 377.911404 -282.746346) (xy 377.86179 -282.726874)
			(xy 377.815632 -282.700225) (xy 377.773961 -282.666994) (xy 377.737709 -282.627923) (xy 377.707685 -282.583886)
			(xy 377.684559 -282.535865) (xy 377.668849 -282.484935) (xy 377.660906 -282.432231) (xy 377.432326 -282.432231)
			(xy 377.424383 -282.484935) (xy 377.408673 -282.535865) (xy 377.385547 -282.583886) (xy 377.355523 -282.627923)
			(xy 377.319271 -282.666994) (xy 377.2776 -282.700225) (xy 377.231442 -282.726874) (xy 377.181828 -282.746346)
			(xy 377.129866 -282.758206) (xy 377.076716 -282.76219) (xy 377.023566 -282.758206) (xy 376.971604 -282.746346)
			(xy 376.92199 -282.726874) (xy 376.875832 -282.700225) (xy 376.834161 -282.666994) (xy 376.797909 -282.627923)
			(xy 376.767885 -282.583886) (xy 376.744759 -282.535865) (xy 376.729049 -282.484935) (xy 376.721106 -282.432231)
			(xy 376.492526 -282.432231) (xy 376.484583 -282.484935) (xy 376.468873 -282.535865) (xy 376.445747 -282.583886)
			(xy 376.415723 -282.627923) (xy 376.379471 -282.666994) (xy 376.3378 -282.700225) (xy 376.291642 -282.726874)
			(xy 376.242028 -282.746346) (xy 376.190066 -282.758206) (xy 376.136916 -282.76219) (xy 376.083766 -282.758206)
			(xy 376.031804 -282.746346) (xy 375.98219 -282.726874) (xy 375.936032 -282.700225) (xy 375.894361 -282.666994)
			(xy 375.858109 -282.627923) (xy 375.828085 -282.583886) (xy 375.804959 -282.535865) (xy 375.789249 -282.484935)
			(xy 375.781306 -282.432231) (xy 375.552726 -282.432231) (xy 375.544783 -282.484935) (xy 375.529073 -282.535865)
			(xy 375.505947 -282.583886) (xy 375.475923 -282.627923) (xy 375.439671 -282.666994) (xy 375.398 -282.700225)
			(xy 375.351842 -282.726874) (xy 375.302228 -282.746346) (xy 375.250266 -282.758206) (xy 375.197116 -282.76219)
			(xy 375.143966 -282.758206) (xy 375.092004 -282.746346) (xy 375.04239 -282.726874) (xy 374.996232 -282.700225)
			(xy 374.954561 -282.666994) (xy 374.918309 -282.627923) (xy 374.888285 -282.583886) (xy 374.865159 -282.535865)
			(xy 374.849449 -282.484935) (xy 374.841506 -282.432231) (xy 374.612931 -282.432231) (xy 374.612926 -282.432485)
			(xy 374.604983 -282.485189) (xy 374.589273 -282.536119) (xy 374.566147 -282.58414) (xy 374.536123 -282.628177)
			(xy 374.499871 -282.667248) (xy 374.4582 -282.700479) (xy 374.412042 -282.727128) (xy 374.362428 -282.7466)
			(xy 374.310466 -282.75846) (xy 374.257316 -282.762444) (xy 374.204166 -282.75846) (xy 374.152204 -282.7466)
			(xy 374.10259 -282.727128) (xy 374.056432 -282.700479) (xy 374.014761 -282.667248) (xy 373.978509 -282.628177)
			(xy 373.948485 -282.58414) (xy 373.925359 -282.536119) (xy 373.909649 -282.485189) (xy 373.901706 -282.432485)
			(xy 373.672872 -282.432485) (xy 373.664929 -282.485189) (xy 373.649219 -282.536119) (xy 373.626093 -282.58414)
			(xy 373.596069 -282.628177) (xy 373.559817 -282.667248) (xy 373.518146 -282.700479) (xy 373.471988 -282.727128)
			(xy 373.422374 -282.7466) (xy 373.370412 -282.75846) (xy 373.317262 -282.762444) (xy 373.264112 -282.75846)
			(xy 373.21215 -282.7466) (xy 373.162536 -282.727128) (xy 373.116378 -282.700479) (xy 373.074707 -282.667248)
			(xy 373.038455 -282.628177) (xy 373.008431 -282.58414) (xy 372.985305 -282.536119) (xy 372.969595 -282.485189)
			(xy 372.961652 -282.432485) (xy 372.733072 -282.432485) (xy 372.725129 -282.485189) (xy 372.709419 -282.536119)
			(xy 372.686293 -282.58414) (xy 372.656269 -282.628177) (xy 372.620017 -282.667248) (xy 372.578346 -282.700479)
			(xy 372.532188 -282.727128) (xy 372.482574 -282.7466) (xy 372.430612 -282.75846) (xy 372.377462 -282.762444)
			(xy 372.324312 -282.75846) (xy 372.27235 -282.7466) (xy 372.222736 -282.727128) (xy 372.176578 -282.700479)
			(xy 372.134907 -282.667248) (xy 372.098655 -282.628177) (xy 372.068631 -282.58414) (xy 372.045505 -282.536119)
			(xy 372.029795 -282.485189) (xy 372.021852 -282.432485) (xy 371.793272 -282.432485) (xy 371.785329 -282.485189)
			(xy 371.769619 -282.536119) (xy 371.746493 -282.58414) (xy 371.716469 -282.628177) (xy 371.680217 -282.667248)
			(xy 371.638546 -282.700479) (xy 371.592388 -282.727128) (xy 371.542774 -282.7466) (xy 371.490812 -282.75846)
			(xy 371.437662 -282.762444) (xy 371.384512 -282.75846) (xy 371.33255 -282.7466) (xy 371.282936 -282.727128)
			(xy 371.236778 -282.700479) (xy 371.195107 -282.667248) (xy 371.158855 -282.628177) (xy 371.128831 -282.58414)
			(xy 371.105705 -282.536119) (xy 371.089995 -282.485189) (xy 371.082052 -282.432485) (xy 370.853472 -282.432485)
			(xy 370.845529 -282.485189) (xy 370.829819 -282.536119) (xy 370.806693 -282.58414) (xy 370.776669 -282.628177)
			(xy 370.740417 -282.667248) (xy 370.698746 -282.700479) (xy 370.652588 -282.727128) (xy 370.602974 -282.7466)
			(xy 370.551012 -282.75846) (xy 370.497862 -282.762444) (xy 370.444712 -282.75846) (xy 370.39275 -282.7466)
			(xy 370.343136 -282.727128) (xy 370.296978 -282.700479) (xy 370.255307 -282.667248) (xy 370.219055 -282.628177)
			(xy 370.189031 -282.58414) (xy 370.165905 -282.536119) (xy 370.150195 -282.485189) (xy 370.142252 -282.432485)
			(xy 369.913672 -282.432485) (xy 369.905729 -282.485189) (xy 369.890019 -282.536119) (xy 369.866893 -282.58414)
			(xy 369.836869 -282.628177) (xy 369.800617 -282.667248) (xy 369.758946 -282.700479) (xy 369.712788 -282.727128)
			(xy 369.663174 -282.7466) (xy 369.611212 -282.75846) (xy 369.558062 -282.762444) (xy 369.504912 -282.75846)
			(xy 369.45295 -282.7466) (xy 369.403336 -282.727128) (xy 369.357178 -282.700479) (xy 369.315507 -282.667248)
			(xy 369.279255 -282.628177) (xy 369.249231 -282.58414) (xy 369.226105 -282.536119) (xy 369.210395 -282.485189)
			(xy 369.202452 -282.432485) (xy 368.973872 -282.432485) (xy 368.965929 -282.485189) (xy 368.950219 -282.536119)
			(xy 368.927093 -282.58414) (xy 368.897069 -282.628177) (xy 368.860817 -282.667248) (xy 368.819146 -282.700479)
			(xy 368.772988 -282.727128) (xy 368.723374 -282.7466) (xy 368.671412 -282.75846) (xy 368.618262 -282.762444)
			(xy 368.565112 -282.75846) (xy 368.51315 -282.7466) (xy 368.463536 -282.727128) (xy 368.417378 -282.700479)
			(xy 368.375707 -282.667248) (xy 368.339455 -282.628177) (xy 368.309431 -282.58414) (xy 368.286305 -282.536119)
			(xy 368.270595 -282.485189) (xy 368.262652 -282.432485) (xy 368.034072 -282.432485) (xy 368.026129 -282.485189)
			(xy 368.010419 -282.536119) (xy 367.987293 -282.58414) (xy 367.957269 -282.628177) (xy 367.921017 -282.667248)
			(xy 367.879346 -282.700479) (xy 367.833188 -282.727128) (xy 367.783574 -282.7466) (xy 367.731612 -282.75846)
			(xy 367.678462 -282.762444) (xy 367.625312 -282.75846) (xy 367.57335 -282.7466) (xy 367.523736 -282.727128)
			(xy 367.477578 -282.700479) (xy 367.435907 -282.667248) (xy 367.399655 -282.628177) (xy 367.369631 -282.58414)
			(xy 367.346505 -282.536119) (xy 367.330795 -282.485189) (xy 367.322852 -282.432485) (xy 367.094266 -282.432485)
			(xy 367.086354 -282.485048) (xy 367.070697 -282.535894) (xy 367.047651 -282.583847) (xy 367.017728 -282.627837)
			(xy 366.981595 -282.666887) (xy 366.940055 -282.700128) (xy 366.894032 -282.72682) (xy 366.869472 -282.737052)
			(xy 366.856262 -282.742802) (xy 366.8335 -282.760441) (xy 366.816577 -282.783741) (xy 366.806845 -282.810843)
			(xy 366.805081 -282.839586) (xy 366.811423 -282.867675) (xy 366.825368 -282.892871) (xy 366.835182 -282.903422)
			(xy 366.927384 -282.995624) (xy 366.963452 -282.961588) (xy 366.98342 -282.943338) (xy 367.027844 -282.91247)
			(xy 367.076423 -282.888674) (xy 367.128043 -282.872497) (xy 367.181515 -282.864312) (xy 367.208562 -282.863798)
			(xy 367.236549 -282.864316) (xy 367.291835 -282.873067) (xy 367.345071 -282.890359) (xy 367.394946 -282.915768)
			(xy 367.440232 -282.948666) (xy 367.479813 -282.988244) (xy 367.512716 -283.033527) (xy 367.538128 -283.083399)
			(xy 367.555426 -283.136634) (xy 367.564182 -283.191919) (xy 367.56467 -283.219906) (xy 367.564173 -283.246555)
			(xy 367.793006 -283.246555) (xy 367.793006 -283.193257) (xy 367.800949 -283.140553) (xy 367.816659 -283.089623)
			(xy 367.839785 -283.041602) (xy 367.869809 -282.997565) (xy 367.906061 -282.958494) (xy 367.947732 -282.925263)
			(xy 367.99389 -282.898614) (xy 368.043504 -282.879142) (xy 368.095466 -282.867282) (xy 368.148616 -282.863299)
			(xy 368.201766 -282.867282) (xy 368.253728 -282.879142) (xy 368.303342 -282.898614) (xy 368.3495 -282.925263)
			(xy 368.391171 -282.958494) (xy 368.427423 -282.997565) (xy 368.457447 -283.041602) (xy 368.480573 -283.089623)
			(xy 368.496283 -283.140553) (xy 368.504226 -283.193257) (xy 368.504724 -283.219906) (xy 368.504226 -283.246555)
			(xy 368.732552 -283.246555) (xy 368.732552 -283.193257) (xy 368.740495 -283.140553) (xy 368.756205 -283.089623)
			(xy 368.779331 -283.041602) (xy 368.809355 -282.997565) (xy 368.845607 -282.958494) (xy 368.887278 -282.925263)
			(xy 368.933436 -282.898614) (xy 368.98305 -282.879142) (xy 369.035012 -282.867282) (xy 369.088162 -282.863299)
			(xy 369.141312 -282.867282) (xy 369.193274 -282.879142) (xy 369.242888 -282.898614) (xy 369.289046 -282.925263)
			(xy 369.330717 -282.958494) (xy 369.366969 -282.997565) (xy 369.396993 -283.041602) (xy 369.420119 -283.089623)
			(xy 369.435829 -283.140553) (xy 369.443772 -283.193257) (xy 369.44427 -283.219906) (xy 369.443772 -283.246555)
			(xy 369.672352 -283.246555) (xy 369.672352 -283.193257) (xy 369.680295 -283.140553) (xy 369.696005 -283.089623)
			(xy 369.719131 -283.041602) (xy 369.749155 -282.997565) (xy 369.785407 -282.958494) (xy 369.827078 -282.925263)
			(xy 369.873236 -282.898614) (xy 369.92285 -282.879142) (xy 369.974812 -282.867282) (xy 370.027962 -282.863299)
			(xy 370.081112 -282.867282) (xy 370.133074 -282.879142) (xy 370.182688 -282.898614) (xy 370.228846 -282.925263)
			(xy 370.270517 -282.958494) (xy 370.306769 -282.997565) (xy 370.336793 -283.041602) (xy 370.359919 -283.089623)
			(xy 370.375629 -283.140553) (xy 370.383572 -283.193257) (xy 370.38407 -283.219906) (xy 370.383572 -283.246555)
			(xy 370.612406 -283.246555) (xy 370.612406 -283.193257) (xy 370.620349 -283.140553) (xy 370.636059 -283.089623)
			(xy 370.659185 -283.041602) (xy 370.689209 -282.997565) (xy 370.725461 -282.958494) (xy 370.767132 -282.925263)
			(xy 370.81329 -282.898614) (xy 370.862904 -282.879142) (xy 370.914866 -282.867282) (xy 370.968016 -282.863299)
			(xy 371.021166 -282.867282) (xy 371.073128 -282.879142) (xy 371.122742 -282.898614) (xy 371.1689 -282.925263)
			(xy 371.210571 -282.958494) (xy 371.246823 -282.997565) (xy 371.276847 -283.041602) (xy 371.299973 -283.089623)
			(xy 371.315683 -283.140553) (xy 371.323626 -283.193257) (xy 371.324124 -283.219906) (xy 371.323626 -283.246555)
			(xy 372.492006 -283.246555) (xy 372.492006 -283.193257) (xy 372.499949 -283.140553) (xy 372.515659 -283.089623)
			(xy 372.538785 -283.041602) (xy 372.568809 -282.997565) (xy 372.605061 -282.958494) (xy 372.646732 -282.925263)
			(xy 372.69289 -282.898614) (xy 372.742504 -282.879142) (xy 372.794466 -282.867282) (xy 372.847616 -282.863299)
			(xy 372.900766 -282.867282) (xy 372.952728 -282.879142) (xy 373.002342 -282.898614) (xy 373.0485 -282.925263)
			(xy 373.090171 -282.958494) (xy 373.126423 -282.997565) (xy 373.156447 -283.041602) (xy 373.179573 -283.089623)
			(xy 373.195283 -283.140553) (xy 373.203226 -283.193257) (xy 373.203724 -283.219906) (xy 373.203226 -283.246555)
			(xy 373.431806 -283.246555) (xy 373.431806 -283.193257) (xy 373.439749 -283.140553) (xy 373.455459 -283.089623)
			(xy 373.478585 -283.041602) (xy 373.508609 -282.997565) (xy 373.544861 -282.958494) (xy 373.586532 -282.925263)
			(xy 373.63269 -282.898614) (xy 373.682304 -282.879142) (xy 373.734266 -282.867282) (xy 373.787416 -282.863299)
			(xy 373.840566 -282.867282) (xy 373.892528 -282.879142) (xy 373.942142 -282.898614) (xy 373.9883 -282.925263)
			(xy 374.029971 -282.958494) (xy 374.066223 -282.997565) (xy 374.096247 -283.041602) (xy 374.119373 -283.089623)
			(xy 374.135083 -283.140553) (xy 374.143026 -283.193257) (xy 374.143524 -283.219906) (xy 374.143026 -283.246555)
			(xy 374.371352 -283.246555) (xy 374.371352 -283.193257) (xy 374.379295 -283.140553) (xy 374.395005 -283.089623)
			(xy 374.418131 -283.041602) (xy 374.448155 -282.997565) (xy 374.484407 -282.958494) (xy 374.526078 -282.925263)
			(xy 374.572236 -282.898614) (xy 374.62185 -282.879142) (xy 374.673812 -282.867282) (xy 374.726962 -282.863299)
			(xy 374.780112 -282.867282) (xy 374.832074 -282.879142) (xy 374.881688 -282.898614) (xy 374.927846 -282.925263)
			(xy 374.969517 -282.958494) (xy 375.005769 -282.997565) (xy 375.035793 -283.041602) (xy 375.058919 -283.089623)
			(xy 375.074629 -283.140553) (xy 375.082572 -283.193257) (xy 375.08307 -283.219906) (xy 375.082577 -283.246301)
			(xy 376.250952 -283.246301) (xy 376.250952 -283.193003) (xy 376.258895 -283.140299) (xy 376.274605 -283.089369)
			(xy 376.297731 -283.041348) (xy 376.327755 -282.997311) (xy 376.364007 -282.95824) (xy 376.405678 -282.925009)
			(xy 376.451836 -282.89836) (xy 376.50145 -282.878888) (xy 376.553412 -282.867028) (xy 376.606562 -282.863045)
			(xy 376.659712 -282.867028) (xy 376.711674 -282.878888) (xy 376.761288 -282.89836) (xy 376.807446 -282.925009)
			(xy 376.849117 -282.95824) (xy 376.885369 -282.997311) (xy 376.915393 -283.041348) (xy 376.938519 -283.089369)
			(xy 376.954229 -283.140299) (xy 376.962172 -283.193003) (xy 376.96267 -283.219652) (xy 376.962172 -283.246301)
			(xy 376.962134 -283.246555) (xy 377.190752 -283.246555) (xy 377.190752 -283.193257) (xy 377.198695 -283.140553)
			(xy 377.214405 -283.089623) (xy 377.237531 -283.041602) (xy 377.267555 -282.997565) (xy 377.303807 -282.958494)
			(xy 377.345478 -282.925263) (xy 377.391636 -282.898614) (xy 377.44125 -282.879142) (xy 377.493212 -282.867282)
			(xy 377.546362 -282.863299) (xy 377.599512 -282.867282) (xy 377.651474 -282.879142) (xy 377.701088 -282.898614)
			(xy 377.747246 -282.925263) (xy 377.788917 -282.958494) (xy 377.825169 -282.997565) (xy 377.855193 -283.041602)
			(xy 377.878319 -283.089623) (xy 377.894029 -283.140553) (xy 377.901972 -283.193257) (xy 377.90247 -283.219906)
			(xy 377.901972 -283.246555) (xy 378.130552 -283.246555) (xy 378.130552 -283.193257) (xy 378.138495 -283.140553)
			(xy 378.154205 -283.089623) (xy 378.177331 -283.041602) (xy 378.207355 -282.997565) (xy 378.243607 -282.958494)
			(xy 378.285278 -282.925263) (xy 378.331436 -282.898614) (xy 378.38105 -282.879142) (xy 378.433012 -282.867282)
			(xy 378.486162 -282.863299) (xy 378.539312 -282.867282) (xy 378.591274 -282.879142) (xy 378.640888 -282.898614)
			(xy 378.687046 -282.925263) (xy 378.728717 -282.958494) (xy 378.764969 -282.997565) (xy 378.794993 -283.041602)
			(xy 378.818119 -283.089623) (xy 378.833829 -283.140553) (xy 378.841772 -283.193257) (xy 378.84227 -283.219906)
			(xy 378.841772 -283.246555) (xy 379.070606 -283.246555) (xy 379.070606 -283.193257) (xy 379.078549 -283.140553)
			(xy 379.094259 -283.089623) (xy 379.117385 -283.041602) (xy 379.147409 -282.997565) (xy 379.183661 -282.958494)
			(xy 379.225332 -282.925263) (xy 379.27149 -282.898614) (xy 379.321104 -282.879142) (xy 379.373066 -282.867282)
			(xy 379.426216 -282.863299) (xy 379.479366 -282.867282) (xy 379.531328 -282.879142) (xy 379.580942 -282.898614)
			(xy 379.6271 -282.925263) (xy 379.668771 -282.958494) (xy 379.705023 -282.997565) (xy 379.735047 -283.041602)
			(xy 379.758173 -283.089623) (xy 379.773883 -283.140553) (xy 379.781826 -283.193257) (xy 379.782324 -283.219906)
			(xy 379.781826 -283.246555) (xy 380.010152 -283.246555) (xy 380.010152 -283.193257) (xy 380.018095 -283.140553)
			(xy 380.033805 -283.089623) (xy 380.056931 -283.041602) (xy 380.086955 -282.997565) (xy 380.123207 -282.958494)
			(xy 380.164878 -282.925263) (xy 380.211036 -282.898614) (xy 380.26065 -282.879142) (xy 380.312612 -282.867282)
			(xy 380.365762 -282.863299) (xy 380.418912 -282.867282) (xy 380.470874 -282.879142) (xy 380.520488 -282.898614)
			(xy 380.566646 -282.925263) (xy 380.608317 -282.958494) (xy 380.644569 -282.997565) (xy 380.674593 -283.041602)
			(xy 380.697719 -283.089623) (xy 380.713429 -283.140553) (xy 380.721372 -283.193257) (xy 380.72187 -283.219906)
			(xy 380.721372 -283.246555) (xy 380.950206 -283.246555) (xy 380.950206 -283.193257) (xy 380.958149 -283.140553)
			(xy 380.973859 -283.089623) (xy 380.996985 -283.041602) (xy 381.027009 -282.997565) (xy 381.063261 -282.958494)
			(xy 381.104932 -282.925263) (xy 381.15109 -282.898614) (xy 381.200704 -282.879142) (xy 381.252666 -282.867282)
			(xy 381.305816 -282.863299) (xy 381.358966 -282.867282) (xy 381.410928 -282.879142) (xy 381.460542 -282.898614)
			(xy 381.5067 -282.925263) (xy 381.548371 -282.958494) (xy 381.584623 -282.997565) (xy 381.614647 -283.041602)
			(xy 381.637773 -283.089623) (xy 381.653483 -283.140553) (xy 381.661426 -283.193257) (xy 381.661924 -283.219906)
			(xy 381.661426 -283.246555) (xy 381.890006 -283.246555) (xy 381.890006 -283.193257) (xy 381.897949 -283.140553)
			(xy 381.913659 -283.089623) (xy 381.936785 -283.041602) (xy 381.966809 -282.997565) (xy 382.003061 -282.958494)
			(xy 382.044732 -282.925263) (xy 382.09089 -282.898614) (xy 382.140504 -282.879142) (xy 382.192466 -282.867282)
			(xy 382.245616 -282.863299) (xy 382.298766 -282.867282) (xy 382.350728 -282.879142) (xy 382.400342 -282.898614)
			(xy 382.4465 -282.925263) (xy 382.488171 -282.958494) (xy 382.524423 -282.997565) (xy 382.554447 -283.041602)
			(xy 382.577573 -283.089623) (xy 382.593283 -283.140553) (xy 382.601226 -283.193257) (xy 382.601724 -283.219906)
			(xy 382.601226 -283.246555) (xy 382.829552 -283.246555) (xy 382.829552 -283.193257) (xy 382.837495 -283.140553)
			(xy 382.853205 -283.089623) (xy 382.876331 -283.041602) (xy 382.906355 -282.997565) (xy 382.942607 -282.958494)
			(xy 382.984278 -282.925263) (xy 383.030436 -282.898614) (xy 383.08005 -282.879142) (xy 383.132012 -282.867282)
			(xy 383.185162 -282.863299) (xy 383.238312 -282.867282) (xy 383.290274 -282.879142) (xy 383.339888 -282.898614)
			(xy 383.386046 -282.925263) (xy 383.427717 -282.958494) (xy 383.463969 -282.997565) (xy 383.493993 -283.041602)
			(xy 383.517119 -283.089623) (xy 383.532829 -283.140553) (xy 383.540772 -283.193257) (xy 383.54127 -283.219906)
			(xy 383.540772 -283.246555) (xy 383.769352 -283.246555) (xy 383.769352 -283.193257) (xy 383.777295 -283.140553)
			(xy 383.793005 -283.089623) (xy 383.816131 -283.041602) (xy 383.846155 -282.997565) (xy 383.882407 -282.958494)
			(xy 383.924078 -282.925263) (xy 383.970236 -282.898614) (xy 384.01985 -282.879142) (xy 384.071812 -282.867282)
			(xy 384.124962 -282.863299) (xy 384.178112 -282.867282) (xy 384.230074 -282.879142) (xy 384.279688 -282.898614)
			(xy 384.325846 -282.925263) (xy 384.367517 -282.958494) (xy 384.403769 -282.997565) (xy 384.433793 -283.041602)
			(xy 384.456919 -283.089623) (xy 384.472629 -283.140553) (xy 384.480572 -283.193257) (xy 384.48107 -283.219906)
			(xy 384.480572 -283.246555) (xy 384.709406 -283.246555) (xy 384.709406 -283.193257) (xy 384.717349 -283.140553)
			(xy 384.733059 -283.089623) (xy 384.756185 -283.041602) (xy 384.786209 -282.997565) (xy 384.822461 -282.958494)
			(xy 384.864132 -282.925263) (xy 384.91029 -282.898614) (xy 384.959904 -282.879142) (xy 385.011866 -282.867282)
			(xy 385.065016 -282.863299) (xy 385.118166 -282.867282) (xy 385.170128 -282.879142) (xy 385.219742 -282.898614)
			(xy 385.2659 -282.925263) (xy 385.307571 -282.958494) (xy 385.343823 -282.997565) (xy 385.373847 -283.041602)
			(xy 385.396973 -283.089623) (xy 385.412683 -283.140553) (xy 385.420626 -283.193257) (xy 385.421124 -283.219906)
			(xy 385.420626 -283.246555) (xy 385.649206 -283.246555) (xy 385.649206 -283.193257) (xy 385.657149 -283.140553)
			(xy 385.672859 -283.089623) (xy 385.695985 -283.041602) (xy 385.726009 -282.997565) (xy 385.762261 -282.958494)
			(xy 385.803932 -282.925263) (xy 385.85009 -282.898614) (xy 385.899704 -282.879142) (xy 385.951666 -282.867282)
			(xy 386.004816 -282.863299) (xy 386.057966 -282.867282) (xy 386.109928 -282.879142) (xy 386.159542 -282.898614)
			(xy 386.2057 -282.925263) (xy 386.247371 -282.958494) (xy 386.283623 -282.997565) (xy 386.313647 -283.041602)
			(xy 386.336773 -283.089623) (xy 386.352483 -283.140553) (xy 386.360426 -283.193257) (xy 386.360924 -283.219906)
			(xy 386.360426 -283.246555) (xy 386.352483 -283.299259) (xy 386.336773 -283.350189) (xy 386.313647 -283.39821)
			(xy 386.283623 -283.442247) (xy 386.247371 -283.481318) (xy 386.2057 -283.514549) (xy 386.159542 -283.541198)
			(xy 386.109928 -283.56067) (xy 386.057966 -283.57253) (xy 386.004816 -283.576514) (xy 385.951666 -283.57253)
			(xy 385.899704 -283.56067) (xy 385.85009 -283.541198) (xy 385.803932 -283.514549) (xy 385.762261 -283.481318)
			(xy 385.726009 -283.442247) (xy 385.695985 -283.39821) (xy 385.672859 -283.350189) (xy 385.657149 -283.299259)
			(xy 385.649206 -283.246555) (xy 385.420626 -283.246555) (xy 385.412683 -283.299259) (xy 385.396973 -283.350189)
			(xy 385.373847 -283.39821) (xy 385.343823 -283.442247) (xy 385.307571 -283.481318) (xy 385.2659 -283.514549)
			(xy 385.219742 -283.541198) (xy 385.170128 -283.56067) (xy 385.118166 -283.57253) (xy 385.065016 -283.576514)
			(xy 385.011866 -283.57253) (xy 384.959904 -283.56067) (xy 384.91029 -283.541198) (xy 384.864132 -283.514549)
			(xy 384.822461 -283.481318) (xy 384.786209 -283.442247) (xy 384.756185 -283.39821) (xy 384.733059 -283.350189)
			(xy 384.717349 -283.299259) (xy 384.709406 -283.246555) (xy 384.480572 -283.246555) (xy 384.472629 -283.299259)
			(xy 384.456919 -283.350189) (xy 384.433793 -283.39821) (xy 384.403769 -283.442247) (xy 384.367517 -283.481318)
			(xy 384.325846 -283.514549) (xy 384.279688 -283.541198) (xy 384.230074 -283.56067) (xy 384.178112 -283.57253)
			(xy 384.124962 -283.576514) (xy 384.071812 -283.57253) (xy 384.01985 -283.56067) (xy 383.970236 -283.541198)
			(xy 383.924078 -283.514549) (xy 383.882407 -283.481318) (xy 383.846155 -283.442247) (xy 383.816131 -283.39821)
			(xy 383.793005 -283.350189) (xy 383.777295 -283.299259) (xy 383.769352 -283.246555) (xy 383.540772 -283.246555)
			(xy 383.532829 -283.299259) (xy 383.517119 -283.350189) (xy 383.493993 -283.39821) (xy 383.463969 -283.442247)
			(xy 383.427717 -283.481318) (xy 383.386046 -283.514549) (xy 383.339888 -283.541198) (xy 383.290274 -283.56067)
			(xy 383.238312 -283.57253) (xy 383.185162 -283.576514) (xy 383.132012 -283.57253) (xy 383.08005 -283.56067)
			(xy 383.030436 -283.541198) (xy 382.984278 -283.514549) (xy 382.942607 -283.481318) (xy 382.906355 -283.442247)
			(xy 382.876331 -283.39821) (xy 382.853205 -283.350189) (xy 382.837495 -283.299259) (xy 382.829552 -283.246555)
			(xy 382.601226 -283.246555) (xy 382.593283 -283.299259) (xy 382.577573 -283.350189) (xy 382.554447 -283.39821)
			(xy 382.524423 -283.442247) (xy 382.488171 -283.481318) (xy 382.4465 -283.514549) (xy 382.400342 -283.541198)
			(xy 382.350728 -283.56067) (xy 382.298766 -283.57253) (xy 382.245616 -283.576514) (xy 382.192466 -283.57253)
			(xy 382.140504 -283.56067) (xy 382.09089 -283.541198) (xy 382.044732 -283.514549) (xy 382.003061 -283.481318)
			(xy 381.966809 -283.442247) (xy 381.936785 -283.39821) (xy 381.913659 -283.350189) (xy 381.897949 -283.299259)
			(xy 381.890006 -283.246555) (xy 381.661426 -283.246555) (xy 381.653483 -283.299259) (xy 381.637773 -283.350189)
			(xy 381.614647 -283.39821) (xy 381.584623 -283.442247) (xy 381.548371 -283.481318) (xy 381.5067 -283.514549)
			(xy 381.460542 -283.541198) (xy 381.410928 -283.56067) (xy 381.358966 -283.57253) (xy 381.305816 -283.576514)
			(xy 381.252666 -283.57253) (xy 381.200704 -283.56067) (xy 381.15109 -283.541198) (xy 381.104932 -283.514549)
			(xy 381.063261 -283.481318) (xy 381.027009 -283.442247) (xy 380.996985 -283.39821) (xy 380.973859 -283.350189)
			(xy 380.958149 -283.299259) (xy 380.950206 -283.246555) (xy 380.721372 -283.246555) (xy 380.713429 -283.299259)
			(xy 380.697719 -283.350189) (xy 380.674593 -283.39821) (xy 380.644569 -283.442247) (xy 380.608317 -283.481318)
			(xy 380.566646 -283.514549) (xy 380.520488 -283.541198) (xy 380.470874 -283.56067) (xy 380.418912 -283.57253)
			(xy 380.365762 -283.576514) (xy 380.312612 -283.57253) (xy 380.26065 -283.56067) (xy 380.211036 -283.541198)
			(xy 380.164878 -283.514549) (xy 380.123207 -283.481318) (xy 380.086955 -283.442247) (xy 380.056931 -283.39821)
			(xy 380.033805 -283.350189) (xy 380.018095 -283.299259) (xy 380.010152 -283.246555) (xy 379.781826 -283.246555)
			(xy 379.773883 -283.299259) (xy 379.758173 -283.350189) (xy 379.735047 -283.39821) (xy 379.705023 -283.442247)
			(xy 379.668771 -283.481318) (xy 379.6271 -283.514549) (xy 379.580942 -283.541198) (xy 379.531328 -283.56067)
			(xy 379.479366 -283.57253) (xy 379.426216 -283.576514) (xy 379.373066 -283.57253) (xy 379.321104 -283.56067)
			(xy 379.27149 -283.541198) (xy 379.225332 -283.514549) (xy 379.183661 -283.481318) (xy 379.147409 -283.442247)
			(xy 379.117385 -283.39821) (xy 379.094259 -283.350189) (xy 379.078549 -283.299259) (xy 379.070606 -283.246555)
			(xy 378.841772 -283.246555) (xy 378.833829 -283.299259) (xy 378.818119 -283.350189) (xy 378.794993 -283.39821)
			(xy 378.764969 -283.442247) (xy 378.728717 -283.481318) (xy 378.687046 -283.514549) (xy 378.640888 -283.541198)
			(xy 378.591274 -283.56067) (xy 378.539312 -283.57253) (xy 378.486162 -283.576514) (xy 378.433012 -283.57253)
			(xy 378.38105 -283.56067) (xy 378.331436 -283.541198) (xy 378.285278 -283.514549) (xy 378.243607 -283.481318)
			(xy 378.207355 -283.442247) (xy 378.177331 -283.39821) (xy 378.154205 -283.350189) (xy 378.138495 -283.299259)
			(xy 378.130552 -283.246555) (xy 377.901972 -283.246555) (xy 377.894029 -283.299259) (xy 377.878319 -283.350189)
			(xy 377.855193 -283.39821) (xy 377.825169 -283.442247) (xy 377.788917 -283.481318) (xy 377.747246 -283.514549)
			(xy 377.701088 -283.541198) (xy 377.651474 -283.56067) (xy 377.599512 -283.57253) (xy 377.546362 -283.576514)
			(xy 377.493212 -283.57253) (xy 377.44125 -283.56067) (xy 377.391636 -283.541198) (xy 377.345478 -283.514549)
			(xy 377.303807 -283.481318) (xy 377.267555 -283.442247) (xy 377.237531 -283.39821) (xy 377.214405 -283.350189)
			(xy 377.198695 -283.299259) (xy 377.190752 -283.246555) (xy 376.962134 -283.246555) (xy 376.954229 -283.299005)
			(xy 376.938519 -283.349935) (xy 376.915393 -283.397956) (xy 376.885369 -283.441993) (xy 376.849117 -283.481064)
			(xy 376.807446 -283.514295) (xy 376.761288 -283.540944) (xy 376.711674 -283.560416) (xy 376.659712 -283.572276)
			(xy 376.606562 -283.57626) (xy 376.553412 -283.572276) (xy 376.50145 -283.560416) (xy 376.451836 -283.540944)
			(xy 376.405678 -283.514295) (xy 376.364007 -283.481064) (xy 376.327755 -283.441993) (xy 376.297731 -283.397956)
			(xy 376.274605 -283.349935) (xy 376.258895 -283.299005) (xy 376.250952 -283.246301) (xy 375.082577 -283.246301)
			(xy 375.082572 -283.246555) (xy 375.074629 -283.299259) (xy 375.058919 -283.350189) (xy 375.035793 -283.39821)
			(xy 375.005769 -283.442247) (xy 374.969517 -283.481318) (xy 374.927846 -283.514549) (xy 374.881688 -283.541198)
			(xy 374.832074 -283.56067) (xy 374.780112 -283.57253) (xy 374.726962 -283.576514) (xy 374.673812 -283.57253)
			(xy 374.62185 -283.56067) (xy 374.572236 -283.541198) (xy 374.526078 -283.514549) (xy 374.484407 -283.481318)
			(xy 374.448155 -283.442247) (xy 374.418131 -283.39821) (xy 374.395005 -283.350189) (xy 374.379295 -283.299259)
			(xy 374.371352 -283.246555) (xy 374.143026 -283.246555) (xy 374.135083 -283.299259) (xy 374.119373 -283.350189)
			(xy 374.096247 -283.39821) (xy 374.066223 -283.442247) (xy 374.029971 -283.481318) (xy 373.9883 -283.514549)
			(xy 373.942142 -283.541198) (xy 373.892528 -283.56067) (xy 373.840566 -283.57253) (xy 373.787416 -283.576514)
			(xy 373.734266 -283.57253) (xy 373.682304 -283.56067) (xy 373.63269 -283.541198) (xy 373.586532 -283.514549)
			(xy 373.544861 -283.481318) (xy 373.508609 -283.442247) (xy 373.478585 -283.39821) (xy 373.455459 -283.350189)
			(xy 373.439749 -283.299259) (xy 373.431806 -283.246555) (xy 373.203226 -283.246555) (xy 373.195283 -283.299259)
			(xy 373.179573 -283.350189) (xy 373.156447 -283.39821) (xy 373.126423 -283.442247) (xy 373.090171 -283.481318)
			(xy 373.0485 -283.514549) (xy 373.002342 -283.541198) (xy 372.952728 -283.56067) (xy 372.900766 -283.57253)
			(xy 372.847616 -283.576514) (xy 372.794466 -283.57253) (xy 372.742504 -283.56067) (xy 372.69289 -283.541198)
			(xy 372.646732 -283.514549) (xy 372.605061 -283.481318) (xy 372.568809 -283.442247) (xy 372.538785 -283.39821)
			(xy 372.515659 -283.350189) (xy 372.499949 -283.299259) (xy 372.492006 -283.246555) (xy 371.323626 -283.246555)
			(xy 371.315683 -283.299259) (xy 371.299973 -283.350189) (xy 371.276847 -283.39821) (xy 371.246823 -283.442247)
			(xy 371.210571 -283.481318) (xy 371.1689 -283.514549) (xy 371.122742 -283.541198) (xy 371.073128 -283.56067)
			(xy 371.021166 -283.57253) (xy 370.968016 -283.576514) (xy 370.914866 -283.57253) (xy 370.862904 -283.56067)
			(xy 370.81329 -283.541198) (xy 370.767132 -283.514549) (xy 370.725461 -283.481318) (xy 370.689209 -283.442247)
			(xy 370.659185 -283.39821) (xy 370.636059 -283.350189) (xy 370.620349 -283.299259) (xy 370.612406 -283.246555)
			(xy 370.383572 -283.246555) (xy 370.375629 -283.299259) (xy 370.359919 -283.350189) (xy 370.336793 -283.39821)
			(xy 370.306769 -283.442247) (xy 370.270517 -283.481318) (xy 370.228846 -283.514549) (xy 370.182688 -283.541198)
			(xy 370.133074 -283.56067) (xy 370.081112 -283.57253) (xy 370.027962 -283.576514) (xy 369.974812 -283.57253)
			(xy 369.92285 -283.56067) (xy 369.873236 -283.541198) (xy 369.827078 -283.514549) (xy 369.785407 -283.481318)
			(xy 369.749155 -283.442247) (xy 369.719131 -283.39821) (xy 369.696005 -283.350189) (xy 369.680295 -283.299259)
			(xy 369.672352 -283.246555) (xy 369.443772 -283.246555) (xy 369.435829 -283.299259) (xy 369.420119 -283.350189)
			(xy 369.396993 -283.39821) (xy 369.366969 -283.442247) (xy 369.330717 -283.481318) (xy 369.289046 -283.514549)
			(xy 369.242888 -283.541198) (xy 369.193274 -283.56067) (xy 369.141312 -283.57253) (xy 369.088162 -283.576514)
			(xy 369.035012 -283.57253) (xy 368.98305 -283.56067) (xy 368.933436 -283.541198) (xy 368.887278 -283.514549)
			(xy 368.845607 -283.481318) (xy 368.809355 -283.442247) (xy 368.779331 -283.39821) (xy 368.756205 -283.350189)
			(xy 368.740495 -283.299259) (xy 368.732552 -283.246555) (xy 368.504226 -283.246555) (xy 368.496283 -283.299259)
			(xy 368.480573 -283.350189) (xy 368.457447 -283.39821) (xy 368.427423 -283.442247) (xy 368.391171 -283.481318)
			(xy 368.3495 -283.514549) (xy 368.303342 -283.541198) (xy 368.253728 -283.56067) (xy 368.201766 -283.57253)
			(xy 368.148616 -283.576514) (xy 368.095466 -283.57253) (xy 368.043504 -283.56067) (xy 367.99389 -283.541198)
			(xy 367.947732 -283.514549) (xy 367.906061 -283.481318) (xy 367.869809 -283.442247) (xy 367.839785 -283.39821)
			(xy 367.816659 -283.350189) (xy 367.800949 -283.299259) (xy 367.793006 -283.246555) (xy 367.564173 -283.246555)
			(xy 367.564166 -283.246954) (xy 367.555983 -283.300427) (xy 367.539804 -283.352047) (xy 367.516004 -283.400626)
			(xy 367.48513 -283.445046) (xy 367.46688 -283.465016) (xy 367.432844 -283.501084) (xy 367.614454 -283.682694)
			(xy 367.638584 -283.6799) (xy 367.648519 -283.678833) (xy 367.66847 -283.677687) (xy 367.678462 -283.677614)
			(xy 367.706449 -283.678132) (xy 367.761734 -283.686883) (xy 367.814969 -283.704176) (xy 367.864842 -283.729584)
			(xy 367.910127 -283.762483) (xy 367.949707 -283.802061) (xy 367.982607 -283.847344) (xy 368.008018 -283.897217)
			(xy 368.025313 -283.950451) (xy 368.034067 -284.005735) (xy 368.03457 -284.033722) (xy 368.034091 -284.060371)
			(xy 368.262652 -284.060371) (xy 368.262652 -284.007073) (xy 368.270595 -283.954369) (xy 368.286305 -283.903439)
			(xy 368.309431 -283.855418) (xy 368.339455 -283.811381) (xy 368.375707 -283.77231) (xy 368.417378 -283.739079)
			(xy 368.463536 -283.71243) (xy 368.51315 -283.692958) (xy 368.565112 -283.681098) (xy 368.618262 -283.677115)
			(xy 368.671412 -283.681098) (xy 368.723374 -283.692958) (xy 368.772988 -283.71243) (xy 368.819146 -283.739079)
			(xy 368.860817 -283.77231) (xy 368.897069 -283.811381) (xy 368.927093 -283.855418) (xy 368.950219 -283.903439)
			(xy 368.965929 -283.954369) (xy 368.973872 -284.007073) (xy 368.97437 -284.033722) (xy 368.973872 -284.060371)
			(xy 369.202452 -284.060371) (xy 369.202452 -284.007073) (xy 369.210395 -283.954369) (xy 369.226105 -283.903439)
			(xy 369.249231 -283.855418) (xy 369.279255 -283.811381) (xy 369.315507 -283.77231) (xy 369.357178 -283.739079)
			(xy 369.403336 -283.71243) (xy 369.45295 -283.692958) (xy 369.504912 -283.681098) (xy 369.558062 -283.677115)
			(xy 369.611212 -283.681098) (xy 369.663174 -283.692958) (xy 369.712788 -283.71243) (xy 369.758946 -283.739079)
			(xy 369.800617 -283.77231) (xy 369.836869 -283.811381) (xy 369.866893 -283.855418) (xy 369.890019 -283.903439)
			(xy 369.905729 -283.954369) (xy 369.913672 -284.007073) (xy 369.91417 -284.033722) (xy 369.913672 -284.060371)
			(xy 370.142252 -284.060371) (xy 370.142252 -284.007073) (xy 370.150195 -283.954369) (xy 370.165905 -283.903439)
			(xy 370.189031 -283.855418) (xy 370.219055 -283.811381) (xy 370.255307 -283.77231) (xy 370.296978 -283.739079)
			(xy 370.343136 -283.71243) (xy 370.39275 -283.692958) (xy 370.444712 -283.681098) (xy 370.497862 -283.677115)
			(xy 370.551012 -283.681098) (xy 370.602974 -283.692958) (xy 370.652588 -283.71243) (xy 370.698746 -283.739079)
			(xy 370.740417 -283.77231) (xy 370.776669 -283.811381) (xy 370.806693 -283.855418) (xy 370.829819 -283.903439)
			(xy 370.845529 -283.954369) (xy 370.853472 -284.007073) (xy 370.85397 -284.033722) (xy 370.853472 -284.060371)
			(xy 371.082052 -284.060371) (xy 371.082052 -284.007073) (xy 371.089995 -283.954369) (xy 371.105705 -283.903439)
			(xy 371.128831 -283.855418) (xy 371.158855 -283.811381) (xy 371.195107 -283.77231) (xy 371.236778 -283.739079)
			(xy 371.282936 -283.71243) (xy 371.33255 -283.692958) (xy 371.384512 -283.681098) (xy 371.437662 -283.677115)
			(xy 371.490812 -283.681098) (xy 371.542774 -283.692958) (xy 371.592388 -283.71243) (xy 371.638546 -283.739079)
			(xy 371.680217 -283.77231) (xy 371.716469 -283.811381) (xy 371.746493 -283.855418) (xy 371.769619 -283.903439)
			(xy 371.785329 -283.954369) (xy 371.793272 -284.007073) (xy 371.79377 -284.033722) (xy 371.793272 -284.060371)
			(xy 372.021852 -284.060371) (xy 372.021852 -284.007073) (xy 372.029795 -283.954369) (xy 372.045505 -283.903439)
			(xy 372.068631 -283.855418) (xy 372.098655 -283.811381) (xy 372.134907 -283.77231) (xy 372.176578 -283.739079)
			(xy 372.222736 -283.71243) (xy 372.27235 -283.692958) (xy 372.324312 -283.681098) (xy 372.377462 -283.677115)
			(xy 372.430612 -283.681098) (xy 372.482574 -283.692958) (xy 372.532188 -283.71243) (xy 372.578346 -283.739079)
			(xy 372.620017 -283.77231) (xy 372.656269 -283.811381) (xy 372.686293 -283.855418) (xy 372.709419 -283.903439)
			(xy 372.725129 -283.954369) (xy 372.733072 -284.007073) (xy 372.73357 -284.033722) (xy 372.733072 -284.060371)
			(xy 372.961906 -284.060371) (xy 372.961906 -284.007073) (xy 372.969849 -283.954369) (xy 372.985559 -283.903439)
			(xy 373.008685 -283.855418) (xy 373.038709 -283.811381) (xy 373.074961 -283.77231) (xy 373.116632 -283.739079)
			(xy 373.16279 -283.71243) (xy 373.212404 -283.692958) (xy 373.264366 -283.681098) (xy 373.317516 -283.677115)
			(xy 373.370666 -283.681098) (xy 373.422628 -283.692958) (xy 373.472242 -283.71243) (xy 373.5184 -283.739079)
			(xy 373.560071 -283.77231) (xy 373.596323 -283.811381) (xy 373.626347 -283.855418) (xy 373.649473 -283.903439)
			(xy 373.665183 -283.954369) (xy 373.673126 -284.007073) (xy 373.673624 -284.033722) (xy 373.673126 -284.060371)
			(xy 373.901452 -284.060371) (xy 373.901452 -284.007073) (xy 373.909395 -283.954369) (xy 373.925105 -283.903439)
			(xy 373.948231 -283.855418) (xy 373.978255 -283.811381) (xy 374.014507 -283.77231) (xy 374.056178 -283.739079)
			(xy 374.102336 -283.71243) (xy 374.15195 -283.692958) (xy 374.203912 -283.681098) (xy 374.257062 -283.677115)
			(xy 374.310212 -283.681098) (xy 374.362174 -283.692958) (xy 374.411788 -283.71243) (xy 374.457946 -283.739079)
			(xy 374.499617 -283.77231) (xy 374.535869 -283.811381) (xy 374.565893 -283.855418) (xy 374.589019 -283.903439)
			(xy 374.604729 -283.954369) (xy 374.612672 -284.007073) (xy 374.61317 -284.033722) (xy 374.612672 -284.060371)
			(xy 374.841252 -284.060371) (xy 374.841252 -284.007073) (xy 374.849195 -283.954369) (xy 374.864905 -283.903439)
			(xy 374.888031 -283.855418) (xy 374.918055 -283.811381) (xy 374.954307 -283.77231) (xy 374.995978 -283.739079)
			(xy 375.042136 -283.71243) (xy 375.09175 -283.692958) (xy 375.143712 -283.681098) (xy 375.196862 -283.677115)
			(xy 375.250012 -283.681098) (xy 375.301974 -283.692958) (xy 375.351588 -283.71243) (xy 375.397746 -283.739079)
			(xy 375.439417 -283.77231) (xy 375.475669 -283.811381) (xy 375.505693 -283.855418) (xy 375.528819 -283.903439)
			(xy 375.544529 -283.954369) (xy 375.552472 -284.007073) (xy 375.55297 -284.033722) (xy 375.552472 -284.060371)
			(xy 375.781052 -284.060371) (xy 375.781052 -284.007073) (xy 375.788995 -283.954369) (xy 375.804705 -283.903439)
			(xy 375.827831 -283.855418) (xy 375.857855 -283.811381) (xy 375.894107 -283.77231) (xy 375.935778 -283.739079)
			(xy 375.981936 -283.71243) (xy 376.03155 -283.692958) (xy 376.083512 -283.681098) (xy 376.136662 -283.677115)
			(xy 376.189812 -283.681098) (xy 376.241774 -283.692958) (xy 376.291388 -283.71243) (xy 376.337546 -283.739079)
			(xy 376.379217 -283.77231) (xy 376.415469 -283.811381) (xy 376.445493 -283.855418) (xy 376.468619 -283.903439)
			(xy 376.484329 -283.954369) (xy 376.492272 -284.007073) (xy 376.49277 -284.033722) (xy 376.492272 -284.060371)
			(xy 376.720852 -284.060371) (xy 376.720852 -284.007073) (xy 376.728795 -283.954369) (xy 376.744505 -283.903439)
			(xy 376.767631 -283.855418) (xy 376.797655 -283.811381) (xy 376.833907 -283.77231) (xy 376.875578 -283.739079)
			(xy 376.921736 -283.71243) (xy 376.97135 -283.692958) (xy 377.023312 -283.681098) (xy 377.076462 -283.677115)
			(xy 377.129612 -283.681098) (xy 377.181574 -283.692958) (xy 377.231188 -283.71243) (xy 377.277346 -283.739079)
			(xy 377.319017 -283.77231) (xy 377.355269 -283.811381) (xy 377.385293 -283.855418) (xy 377.408419 -283.903439)
			(xy 377.424129 -283.954369) (xy 377.432072 -284.007073) (xy 377.43257 -284.033722) (xy 377.432072 -284.060371)
			(xy 377.660652 -284.060371) (xy 377.660652 -284.007073) (xy 377.668595 -283.954369) (xy 377.684305 -283.903439)
			(xy 377.707431 -283.855418) (xy 377.737455 -283.811381) (xy 377.773707 -283.77231) (xy 377.815378 -283.739079)
			(xy 377.861536 -283.71243) (xy 377.91115 -283.692958) (xy 377.963112 -283.681098) (xy 378.016262 -283.677115)
			(xy 378.069412 -283.681098) (xy 378.121374 -283.692958) (xy 378.170988 -283.71243) (xy 378.217146 -283.739079)
			(xy 378.258817 -283.77231) (xy 378.295069 -283.811381) (xy 378.325093 -283.855418) (xy 378.348219 -283.903439)
			(xy 378.363929 -283.954369) (xy 378.371872 -284.007073) (xy 378.37237 -284.033722) (xy 378.371872 -284.060371)
			(xy 378.600452 -284.060371) (xy 378.600452 -284.007073) (xy 378.608395 -283.954369) (xy 378.624105 -283.903439)
			(xy 378.647231 -283.855418) (xy 378.677255 -283.811381) (xy 378.713507 -283.77231) (xy 378.755178 -283.739079)
			(xy 378.801336 -283.71243) (xy 378.85095 -283.692958) (xy 378.902912 -283.681098) (xy 378.956062 -283.677115)
			(xy 379.009212 -283.681098) (xy 379.061174 -283.692958) (xy 379.110788 -283.71243) (xy 379.156946 -283.739079)
			(xy 379.198617 -283.77231) (xy 379.234869 -283.811381) (xy 379.264893 -283.855418) (xy 379.288019 -283.903439)
			(xy 379.303729 -283.954369) (xy 379.311672 -284.007073) (xy 379.31217 -284.033722) (xy 379.311672 -284.060371)
			(xy 379.540252 -284.060371) (xy 379.540252 -284.007073) (xy 379.548195 -283.954369) (xy 379.563905 -283.903439)
			(xy 379.587031 -283.855418) (xy 379.617055 -283.811381) (xy 379.653307 -283.77231) (xy 379.694978 -283.739079)
			(xy 379.741136 -283.71243) (xy 379.79075 -283.692958) (xy 379.842712 -283.681098) (xy 379.895862 -283.677115)
			(xy 379.949012 -283.681098) (xy 380.000974 -283.692958) (xy 380.050588 -283.71243) (xy 380.096746 -283.739079)
			(xy 380.138417 -283.77231) (xy 380.174669 -283.811381) (xy 380.204693 -283.855418) (xy 380.227819 -283.903439)
			(xy 380.243529 -283.954369) (xy 380.251472 -284.007073) (xy 380.25197 -284.033722) (xy 380.251472 -284.060371)
			(xy 380.480052 -284.060371) (xy 380.480052 -284.007073) (xy 380.487995 -283.954369) (xy 380.503705 -283.903439)
			(xy 380.526831 -283.855418) (xy 380.556855 -283.811381) (xy 380.593107 -283.77231) (xy 380.634778 -283.739079)
			(xy 380.680936 -283.71243) (xy 380.73055 -283.692958) (xy 380.782512 -283.681098) (xy 380.835662 -283.677115)
			(xy 380.888812 -283.681098) (xy 380.940774 -283.692958) (xy 380.990388 -283.71243) (xy 381.036546 -283.739079)
			(xy 381.078217 -283.77231) (xy 381.114469 -283.811381) (xy 381.144493 -283.855418) (xy 381.167619 -283.903439)
			(xy 381.183329 -283.954369) (xy 381.191272 -284.007073) (xy 381.19177 -284.033722) (xy 381.191272 -284.060371)
			(xy 382.359652 -284.060371) (xy 382.359652 -284.007073) (xy 382.367595 -283.954369) (xy 382.383305 -283.903439)
			(xy 382.406431 -283.855418) (xy 382.436455 -283.811381) (xy 382.472707 -283.77231) (xy 382.514378 -283.739079)
			(xy 382.560536 -283.71243) (xy 382.61015 -283.692958) (xy 382.662112 -283.681098) (xy 382.715262 -283.677115)
			(xy 382.768412 -283.681098) (xy 382.820374 -283.692958) (xy 382.869988 -283.71243) (xy 382.916146 -283.739079)
			(xy 382.957817 -283.77231) (xy 382.994069 -283.811381) (xy 383.024093 -283.855418) (xy 383.047219 -283.903439)
			(xy 383.062929 -283.954369) (xy 383.070872 -284.007073) (xy 383.07137 -284.033722) (xy 383.070872 -284.060371)
			(xy 383.062929 -284.113075) (xy 383.047219 -284.164005) (xy 383.024093 -284.212026) (xy 382.994069 -284.256063)
			(xy 382.957817 -284.295134) (xy 382.916146 -284.328365) (xy 382.869988 -284.355014) (xy 382.820374 -284.374486)
			(xy 382.768412 -284.386346) (xy 382.715262 -284.39033) (xy 382.662112 -284.386346) (xy 382.61015 -284.374486)
			(xy 382.560536 -284.355014) (xy 382.514378 -284.328365) (xy 382.472707 -284.295134) (xy 382.436455 -284.256063)
			(xy 382.406431 -284.212026) (xy 382.383305 -284.164005) (xy 382.367595 -284.113075) (xy 382.359652 -284.060371)
			(xy 381.191272 -284.060371) (xy 381.183329 -284.113075) (xy 381.167619 -284.164005) (xy 381.144493 -284.212026)
			(xy 381.114469 -284.256063) (xy 381.078217 -284.295134) (xy 381.036546 -284.328365) (xy 380.990388 -284.355014)
			(xy 380.940774 -284.374486) (xy 380.888812 -284.386346) (xy 380.835662 -284.39033) (xy 380.782512 -284.386346)
			(xy 380.73055 -284.374486) (xy 380.680936 -284.355014) (xy 380.634778 -284.328365) (xy 380.593107 -284.295134)
			(xy 380.556855 -284.256063) (xy 380.526831 -284.212026) (xy 380.503705 -284.164005) (xy 380.487995 -284.113075)
			(xy 380.480052 -284.060371) (xy 380.251472 -284.060371) (xy 380.243529 -284.113075) (xy 380.227819 -284.164005)
			(xy 380.204693 -284.212026) (xy 380.174669 -284.256063) (xy 380.138417 -284.295134) (xy 380.096746 -284.328365)
			(xy 380.050588 -284.355014) (xy 380.000974 -284.374486) (xy 379.949012 -284.386346) (xy 379.895862 -284.39033)
			(xy 379.842712 -284.386346) (xy 379.79075 -284.374486) (xy 379.741136 -284.355014) (xy 379.694978 -284.328365)
			(xy 379.653307 -284.295134) (xy 379.617055 -284.256063) (xy 379.587031 -284.212026) (xy 379.563905 -284.164005)
			(xy 379.548195 -284.113075) (xy 379.540252 -284.060371) (xy 379.311672 -284.060371) (xy 379.303729 -284.113075)
			(xy 379.288019 -284.164005) (xy 379.264893 -284.212026) (xy 379.234869 -284.256063) (xy 379.198617 -284.295134)
			(xy 379.156946 -284.328365) (xy 379.110788 -284.355014) (xy 379.061174 -284.374486) (xy 379.009212 -284.386346)
			(xy 378.956062 -284.39033) (xy 378.902912 -284.386346) (xy 378.85095 -284.374486) (xy 378.801336 -284.355014)
			(xy 378.755178 -284.328365) (xy 378.713507 -284.295134) (xy 378.677255 -284.256063) (xy 378.647231 -284.212026)
			(xy 378.624105 -284.164005) (xy 378.608395 -284.113075) (xy 378.600452 -284.060371) (xy 378.371872 -284.060371)
			(xy 378.363929 -284.113075) (xy 378.348219 -284.164005) (xy 378.325093 -284.212026) (xy 378.295069 -284.256063)
			(xy 378.258817 -284.295134) (xy 378.217146 -284.328365) (xy 378.170988 -284.355014) (xy 378.121374 -284.374486)
			(xy 378.069412 -284.386346) (xy 378.016262 -284.39033) (xy 377.963112 -284.386346) (xy 377.91115 -284.374486)
			(xy 377.861536 -284.355014) (xy 377.815378 -284.328365) (xy 377.773707 -284.295134) (xy 377.737455 -284.256063)
			(xy 377.707431 -284.212026) (xy 377.684305 -284.164005) (xy 377.668595 -284.113075) (xy 377.660652 -284.060371)
			(xy 377.432072 -284.060371) (xy 377.424129 -284.113075) (xy 377.408419 -284.164005) (xy 377.385293 -284.212026)
			(xy 377.355269 -284.256063) (xy 377.319017 -284.295134) (xy 377.277346 -284.328365) (xy 377.231188 -284.355014)
			(xy 377.181574 -284.374486) (xy 377.129612 -284.386346) (xy 377.076462 -284.39033) (xy 377.023312 -284.386346)
			(xy 376.97135 -284.374486) (xy 376.921736 -284.355014) (xy 376.875578 -284.328365) (xy 376.833907 -284.295134)
			(xy 376.797655 -284.256063) (xy 376.767631 -284.212026) (xy 376.744505 -284.164005) (xy 376.728795 -284.113075)
			(xy 376.720852 -284.060371) (xy 376.492272 -284.060371) (xy 376.484329 -284.113075) (xy 376.468619 -284.164005)
			(xy 376.445493 -284.212026) (xy 376.415469 -284.256063) (xy 376.379217 -284.295134) (xy 376.337546 -284.328365)
			(xy 376.291388 -284.355014) (xy 376.241774 -284.374486) (xy 376.189812 -284.386346) (xy 376.136662 -284.39033)
			(xy 376.083512 -284.386346) (xy 376.03155 -284.374486) (xy 375.981936 -284.355014) (xy 375.935778 -284.328365)
			(xy 375.894107 -284.295134) (xy 375.857855 -284.256063) (xy 375.827831 -284.212026) (xy 375.804705 -284.164005)
			(xy 375.788995 -284.113075) (xy 375.781052 -284.060371) (xy 375.552472 -284.060371) (xy 375.544529 -284.113075)
			(xy 375.528819 -284.164005) (xy 375.505693 -284.212026) (xy 375.475669 -284.256063) (xy 375.439417 -284.295134)
			(xy 375.397746 -284.328365) (xy 375.351588 -284.355014) (xy 375.301974 -284.374486) (xy 375.250012 -284.386346)
			(xy 375.196862 -284.39033) (xy 375.143712 -284.386346) (xy 375.09175 -284.374486) (xy 375.042136 -284.355014)
			(xy 374.995978 -284.328365) (xy 374.954307 -284.295134) (xy 374.918055 -284.256063) (xy 374.888031 -284.212026)
			(xy 374.864905 -284.164005) (xy 374.849195 -284.113075) (xy 374.841252 -284.060371) (xy 374.612672 -284.060371)
			(xy 374.604729 -284.113075) (xy 374.589019 -284.164005) (xy 374.565893 -284.212026) (xy 374.535869 -284.256063)
			(xy 374.499617 -284.295134) (xy 374.457946 -284.328365) (xy 374.411788 -284.355014) (xy 374.362174 -284.374486)
			(xy 374.310212 -284.386346) (xy 374.257062 -284.39033) (xy 374.203912 -284.386346) (xy 374.15195 -284.374486)
			(xy 374.102336 -284.355014) (xy 374.056178 -284.328365) (xy 374.014507 -284.295134) (xy 373.978255 -284.256063)
			(xy 373.948231 -284.212026) (xy 373.925105 -284.164005) (xy 373.909395 -284.113075) (xy 373.901452 -284.060371)
			(xy 373.673126 -284.060371) (xy 373.665183 -284.113075) (xy 373.649473 -284.164005) (xy 373.626347 -284.212026)
			(xy 373.596323 -284.256063) (xy 373.560071 -284.295134) (xy 373.5184 -284.328365) (xy 373.472242 -284.355014)
			(xy 373.422628 -284.374486) (xy 373.370666 -284.386346) (xy 373.317516 -284.39033) (xy 373.264366 -284.386346)
			(xy 373.212404 -284.374486) (xy 373.16279 -284.355014) (xy 373.116632 -284.328365) (xy 373.074961 -284.295134)
			(xy 373.038709 -284.256063) (xy 373.008685 -284.212026) (xy 372.985559 -284.164005) (xy 372.969849 -284.113075)
			(xy 372.961906 -284.060371) (xy 372.733072 -284.060371) (xy 372.725129 -284.113075) (xy 372.709419 -284.164005)
			(xy 372.686293 -284.212026) (xy 372.656269 -284.256063) (xy 372.620017 -284.295134) (xy 372.578346 -284.328365)
			(xy 372.532188 -284.355014) (xy 372.482574 -284.374486) (xy 372.430612 -284.386346) (xy 372.377462 -284.39033)
			(xy 372.324312 -284.386346) (xy 372.27235 -284.374486) (xy 372.222736 -284.355014) (xy 372.176578 -284.328365)
			(xy 372.134907 -284.295134) (xy 372.098655 -284.256063) (xy 372.068631 -284.212026) (xy 372.045505 -284.164005)
			(xy 372.029795 -284.113075) (xy 372.021852 -284.060371) (xy 371.793272 -284.060371) (xy 371.785329 -284.113075)
			(xy 371.769619 -284.164005) (xy 371.746493 -284.212026) (xy 371.716469 -284.256063) (xy 371.680217 -284.295134)
			(xy 371.638546 -284.328365) (xy 371.592388 -284.355014) (xy 371.542774 -284.374486) (xy 371.490812 -284.386346)
			(xy 371.437662 -284.39033) (xy 371.384512 -284.386346) (xy 371.33255 -284.374486) (xy 371.282936 -284.355014)
			(xy 371.236778 -284.328365) (xy 371.195107 -284.295134) (xy 371.158855 -284.256063) (xy 371.128831 -284.212026)
			(xy 371.105705 -284.164005) (xy 371.089995 -284.113075) (xy 371.082052 -284.060371) (xy 370.853472 -284.060371)
			(xy 370.845529 -284.113075) (xy 370.829819 -284.164005) (xy 370.806693 -284.212026) (xy 370.776669 -284.256063)
			(xy 370.740417 -284.295134) (xy 370.698746 -284.328365) (xy 370.652588 -284.355014) (xy 370.602974 -284.374486)
			(xy 370.551012 -284.386346) (xy 370.497862 -284.39033) (xy 370.444712 -284.386346) (xy 370.39275 -284.374486)
			(xy 370.343136 -284.355014) (xy 370.296978 -284.328365) (xy 370.255307 -284.295134) (xy 370.219055 -284.256063)
			(xy 370.189031 -284.212026) (xy 370.165905 -284.164005) (xy 370.150195 -284.113075) (xy 370.142252 -284.060371)
			(xy 369.913672 -284.060371) (xy 369.905729 -284.113075) (xy 369.890019 -284.164005) (xy 369.866893 -284.212026)
			(xy 369.836869 -284.256063) (xy 369.800617 -284.295134) (xy 369.758946 -284.328365) (xy 369.712788 -284.355014)
			(xy 369.663174 -284.374486) (xy 369.611212 -284.386346) (xy 369.558062 -284.39033) (xy 369.504912 -284.386346)
			(xy 369.45295 -284.374486) (xy 369.403336 -284.355014) (xy 369.357178 -284.328365) (xy 369.315507 -284.295134)
			(xy 369.279255 -284.256063) (xy 369.249231 -284.212026) (xy 369.226105 -284.164005) (xy 369.210395 -284.113075)
			(xy 369.202452 -284.060371) (xy 368.973872 -284.060371) (xy 368.965929 -284.113075) (xy 368.950219 -284.164005)
			(xy 368.927093 -284.212026) (xy 368.897069 -284.256063) (xy 368.860817 -284.295134) (xy 368.819146 -284.328365)
			(xy 368.772988 -284.355014) (xy 368.723374 -284.374486) (xy 368.671412 -284.386346) (xy 368.618262 -284.39033)
			(xy 368.565112 -284.386346) (xy 368.51315 -284.374486) (xy 368.463536 -284.355014) (xy 368.417378 -284.328365)
			(xy 368.375707 -284.295134) (xy 368.339455 -284.256063) (xy 368.309431 -284.212026) (xy 368.286305 -284.164005)
			(xy 368.270595 -284.113075) (xy 368.262652 -284.060371) (xy 368.034091 -284.060371) (xy 368.034089 -284.06046)
			(xy 368.026089 -284.113333) (xy 368.010272 -284.164416) (xy 367.986995 -284.212559) (xy 367.95678 -284.256679)
			(xy 367.920306 -284.295786) (xy 367.878396 -284.328998) (xy 367.831989 -284.35557) (xy 367.80724 -284.3657)
			(xy 367.774728 -284.3784) (xy 367.774728 -284.847538) (xy 368.732308 -284.847538) (xy 368.732806 -284.820889)
			(xy 368.740749 -284.768185) (xy 368.756459 -284.717255) (xy 368.779585 -284.669234) (xy 368.809609 -284.625197)
			(xy 368.845861 -284.586126) (xy 368.887532 -284.552895) (xy 368.93369 -284.526246) (xy 368.983304 -284.506774)
			(xy 369.035266 -284.494914) (xy 369.088416 -284.490931) (xy 369.141566 -284.494914) (xy 369.193528 -284.506774)
			(xy 369.243142 -284.526246) (xy 369.2893 -284.552895) (xy 369.330971 -284.586126) (xy 369.367223 -284.625197)
			(xy 369.397247 -284.669234) (xy 369.420373 -284.717255) (xy 369.436083 -284.768185) (xy 369.444026 -284.820889)
			(xy 369.444524 -284.847538) (xy 370.611908 -284.847538) (xy 370.612406 -284.820889) (xy 370.620349 -284.768185)
			(xy 370.636059 -284.717255) (xy 370.659185 -284.669234) (xy 370.689209 -284.625197) (xy 370.725461 -284.586126)
			(xy 370.767132 -284.552895) (xy 370.81329 -284.526246) (xy 370.862904 -284.506774) (xy 370.914866 -284.494914)
			(xy 370.968016 -284.490931) (xy 371.021166 -284.494914) (xy 371.073128 -284.506774) (xy 371.122742 -284.526246)
			(xy 371.1689 -284.552895) (xy 371.210571 -284.586126) (xy 371.246823 -284.625197) (xy 371.276847 -284.669234)
			(xy 371.299973 -284.717255) (xy 371.315683 -284.768185) (xy 371.323626 -284.820889) (xy 371.324124 -284.847538)
			(xy 372.491508 -284.847538) (xy 372.492006 -284.820889) (xy 372.499949 -284.768185) (xy 372.515659 -284.717255)
			(xy 372.538785 -284.669234) (xy 372.568809 -284.625197) (xy 372.605061 -284.586126) (xy 372.646732 -284.552895)
			(xy 372.69289 -284.526246) (xy 372.742504 -284.506774) (xy 372.794466 -284.494914) (xy 372.847616 -284.490931)
			(xy 372.900766 -284.494914) (xy 372.952728 -284.506774) (xy 373.002342 -284.526246) (xy 373.0485 -284.552895)
			(xy 373.090171 -284.586126) (xy 373.126423 -284.625197) (xy 373.156447 -284.669234) (xy 373.179573 -284.717255)
			(xy 373.195283 -284.768185) (xy 373.203226 -284.820889) (xy 373.203724 -284.847538) (xy 373.203334 -284.870782)
			(xy 373.202888 -284.874187) (xy 373.431806 -284.874187) (xy 373.431806 -284.820889) (xy 373.439749 -284.768185)
			(xy 373.455459 -284.717255) (xy 373.478585 -284.669234) (xy 373.508609 -284.625197) (xy 373.544861 -284.586126)
			(xy 373.586532 -284.552895) (xy 373.63269 -284.526246) (xy 373.682304 -284.506774) (xy 373.734266 -284.494914)
			(xy 373.787416 -284.490931) (xy 373.840566 -284.494914) (xy 373.892528 -284.506774) (xy 373.942142 -284.526246)
			(xy 373.9883 -284.552895) (xy 374.029971 -284.586126) (xy 374.066223 -284.625197) (xy 374.096247 -284.669234)
			(xy 374.119373 -284.717255) (xy 374.135083 -284.768185) (xy 374.143026 -284.820889) (xy 374.143524 -284.847538)
			(xy 374.371108 -284.847538) (xy 374.371606 -284.820889) (xy 374.379549 -284.768185) (xy 374.395259 -284.717255)
			(xy 374.418385 -284.669234) (xy 374.448409 -284.625197) (xy 374.484661 -284.586126) (xy 374.526332 -284.552895)
			(xy 374.57249 -284.526246) (xy 374.622104 -284.506774) (xy 374.674066 -284.494914) (xy 374.727216 -284.490931)
			(xy 374.780366 -284.494914) (xy 374.832328 -284.506774) (xy 374.881942 -284.526246) (xy 374.9281 -284.552895)
			(xy 374.969771 -284.586126) (xy 375.006023 -284.625197) (xy 375.036047 -284.669234) (xy 375.059173 -284.717255)
			(xy 375.074883 -284.768185) (xy 375.082826 -284.820889) (xy 375.083324 -284.847538) (xy 376.250708 -284.847538)
			(xy 376.251206 -284.820889) (xy 376.259149 -284.768185) (xy 376.274859 -284.717255) (xy 376.297985 -284.669234)
			(xy 376.328009 -284.625197) (xy 376.364261 -284.586126) (xy 376.405932 -284.552895) (xy 376.45209 -284.526246)
			(xy 376.501704 -284.506774) (xy 376.553666 -284.494914) (xy 376.606816 -284.490931) (xy 376.659966 -284.494914)
			(xy 376.711928 -284.506774) (xy 376.761542 -284.526246) (xy 376.8077 -284.552895) (xy 376.849371 -284.586126)
			(xy 376.885623 -284.625197) (xy 376.915647 -284.669234) (xy 376.938773 -284.717255) (xy 376.954483 -284.768185)
			(xy 376.962426 -284.820889) (xy 376.962924 -284.847538) (xy 378.130308 -284.847538) (xy 378.130806 -284.820889)
			(xy 378.138749 -284.768185) (xy 378.154459 -284.717255) (xy 378.177585 -284.669234) (xy 378.207609 -284.625197)
			(xy 378.243861 -284.586126) (xy 378.285532 -284.552895) (xy 378.33169 -284.526246) (xy 378.381304 -284.506774)
			(xy 378.433266 -284.494914) (xy 378.486416 -284.490931) (xy 378.539566 -284.494914) (xy 378.591528 -284.506774)
			(xy 378.641142 -284.526246) (xy 378.6873 -284.552895) (xy 378.728971 -284.586126) (xy 378.765223 -284.625197)
			(xy 378.795247 -284.669234) (xy 378.818373 -284.717255) (xy 378.834083 -284.768185) (xy 378.842026 -284.820889)
			(xy 378.842524 -284.847538) (xy 380.009908 -284.847538) (xy 380.010406 -284.820889) (xy 380.018349 -284.768185)
			(xy 380.034059 -284.717255) (xy 380.057185 -284.669234) (xy 380.087209 -284.625197) (xy 380.123461 -284.586126)
			(xy 380.165132 -284.552895) (xy 380.21129 -284.526246) (xy 380.260904 -284.506774) (xy 380.312866 -284.494914)
			(xy 380.366016 -284.490931) (xy 380.419166 -284.494914) (xy 380.471128 -284.506774) (xy 380.520742 -284.526246)
			(xy 380.5669 -284.552895) (xy 380.608571 -284.586126) (xy 380.644823 -284.625197) (xy 380.674847 -284.669234)
			(xy 380.697973 -284.717255) (xy 380.713683 -284.768185) (xy 380.721626 -284.820889) (xy 380.722124 -284.847538)
			(xy 380.721734 -284.870782) (xy 380.721288 -284.874187) (xy 381.890006 -284.874187) (xy 381.890006 -284.820889)
			(xy 381.897949 -284.768185) (xy 381.913659 -284.717255) (xy 381.936785 -284.669234) (xy 381.966809 -284.625197)
			(xy 382.003061 -284.586126) (xy 382.044732 -284.552895) (xy 382.09089 -284.526246) (xy 382.140504 -284.506774)
			(xy 382.192466 -284.494914) (xy 382.245616 -284.490931) (xy 382.298766 -284.494914) (xy 382.350728 -284.506774)
			(xy 382.400342 -284.526246) (xy 382.4465 -284.552895) (xy 382.488171 -284.586126) (xy 382.524423 -284.625197)
			(xy 382.554447 -284.669234) (xy 382.577573 -284.717255) (xy 382.593283 -284.768185) (xy 382.601226 -284.820889)
			(xy 382.601724 -284.847538) (xy 382.601231 -284.873933) (xy 382.829552 -284.873933) (xy 382.829552 -284.820635)
			(xy 382.837495 -284.767931) (xy 382.853205 -284.717001) (xy 382.876331 -284.66898) (xy 382.906355 -284.624943)
			(xy 382.942607 -284.585872) (xy 382.984278 -284.552641) (xy 383.030436 -284.525992) (xy 383.08005 -284.50652)
			(xy 383.132012 -284.49466) (xy 383.185162 -284.490677) (xy 383.238312 -284.49466) (xy 383.290274 -284.50652)
			(xy 383.339888 -284.525992) (xy 383.386046 -284.552641) (xy 383.427717 -284.585872) (xy 383.463969 -284.624943)
			(xy 383.493993 -284.66898) (xy 383.517119 -284.717001) (xy 383.532829 -284.767931) (xy 383.540772 -284.820635)
			(xy 383.54127 -284.847284) (xy 383.540772 -284.873933) (xy 383.769352 -284.873933) (xy 383.769352 -284.820635)
			(xy 383.777295 -284.767931) (xy 383.793005 -284.717001) (xy 383.816131 -284.66898) (xy 383.846155 -284.624943)
			(xy 383.882407 -284.585872) (xy 383.924078 -284.552641) (xy 383.970236 -284.525992) (xy 384.01985 -284.50652)
			(xy 384.071812 -284.49466) (xy 384.124962 -284.490677) (xy 384.178112 -284.49466) (xy 384.230074 -284.50652)
			(xy 384.279688 -284.525992) (xy 384.325846 -284.552641) (xy 384.367517 -284.585872) (xy 384.403769 -284.624943)
			(xy 384.433793 -284.66898) (xy 384.456919 -284.717001) (xy 384.472629 -284.767931) (xy 384.480572 -284.820635)
			(xy 384.48107 -284.847284) (xy 384.480572 -284.873933) (xy 384.709152 -284.873933) (xy 384.709152 -284.820635)
			(xy 384.717095 -284.767931) (xy 384.732805 -284.717001) (xy 384.755931 -284.66898) (xy 384.785955 -284.624943)
			(xy 384.822207 -284.585872) (xy 384.863878 -284.552641) (xy 384.910036 -284.525992) (xy 384.95965 -284.50652)
			(xy 385.011612 -284.49466) (xy 385.064762 -284.490677) (xy 385.117912 -284.49466) (xy 385.169874 -284.50652)
			(xy 385.219488 -284.525992) (xy 385.265646 -284.552641) (xy 385.307317 -284.585872) (xy 385.343569 -284.624943)
			(xy 385.373593 -284.66898) (xy 385.396719 -284.717001) (xy 385.412429 -284.767931) (xy 385.420372 -284.820635)
			(xy 385.42087 -284.847284) (xy 385.420372 -284.873933) (xy 385.648952 -284.873933) (xy 385.648952 -284.820635)
			(xy 385.656895 -284.767931) (xy 385.672605 -284.717001) (xy 385.695731 -284.66898) (xy 385.725755 -284.624943)
			(xy 385.762007 -284.585872) (xy 385.803678 -284.552641) (xy 385.849836 -284.525992) (xy 385.89945 -284.50652)
			(xy 385.951412 -284.49466) (xy 386.004562 -284.490677) (xy 386.057712 -284.49466) (xy 386.109674 -284.50652)
			(xy 386.159288 -284.525992) (xy 386.205446 -284.552641) (xy 386.247117 -284.585872) (xy 386.283369 -284.624943)
			(xy 386.313393 -284.66898) (xy 386.336519 -284.717001) (xy 386.352229 -284.767931) (xy 386.360172 -284.820635)
			(xy 386.36067 -284.847284) (xy 386.360172 -284.873933) (xy 386.352229 -284.926637) (xy 386.336519 -284.977567)
			(xy 386.313393 -285.025588) (xy 386.283369 -285.069625) (xy 386.247117 -285.108696) (xy 386.205446 -285.141927)
			(xy 386.159288 -285.168576) (xy 386.109674 -285.188048) (xy 386.057712 -285.199908) (xy 386.004562 -285.203892)
			(xy 385.951412 -285.199908) (xy 385.89945 -285.188048) (xy 385.849836 -285.168576) (xy 385.803678 -285.141927)
			(xy 385.762007 -285.108696) (xy 385.725755 -285.069625) (xy 385.695731 -285.025588) (xy 385.672605 -284.977567)
			(xy 385.656895 -284.926637) (xy 385.648952 -284.873933) (xy 385.420372 -284.873933) (xy 385.412429 -284.926637)
			(xy 385.396719 -284.977567) (xy 385.373593 -285.025588) (xy 385.343569 -285.069625) (xy 385.307317 -285.108696)
			(xy 385.265646 -285.141927) (xy 385.219488 -285.168576) (xy 385.169874 -285.188048) (xy 385.117912 -285.199908)
			(xy 385.064762 -285.203892) (xy 385.011612 -285.199908) (xy 384.95965 -285.188048) (xy 384.910036 -285.168576)
			(xy 384.863878 -285.141927) (xy 384.822207 -285.108696) (xy 384.785955 -285.069625) (xy 384.755931 -285.025588)
			(xy 384.732805 -284.977567) (xy 384.717095 -284.926637) (xy 384.709152 -284.873933) (xy 384.480572 -284.873933)
			(xy 384.472629 -284.926637) (xy 384.456919 -284.977567) (xy 384.433793 -285.025588) (xy 384.403769 -285.069625)
			(xy 384.367517 -285.108696) (xy 384.325846 -285.141927) (xy 384.279688 -285.168576) (xy 384.230074 -285.188048)
			(xy 384.178112 -285.199908) (xy 384.124962 -285.203892) (xy 384.071812 -285.199908) (xy 384.01985 -285.188048)
			(xy 383.970236 -285.168576) (xy 383.924078 -285.141927) (xy 383.882407 -285.108696) (xy 383.846155 -285.069625)
			(xy 383.816131 -285.025588) (xy 383.793005 -284.977567) (xy 383.777295 -284.926637) (xy 383.769352 -284.873933)
			(xy 383.540772 -284.873933) (xy 383.532829 -284.926637) (xy 383.517119 -284.977567) (xy 383.493993 -285.025588)
			(xy 383.463969 -285.069625) (xy 383.427717 -285.108696) (xy 383.386046 -285.141927) (xy 383.339888 -285.168576)
			(xy 383.290274 -285.188048) (xy 383.238312 -285.199908) (xy 383.185162 -285.203892) (xy 383.132012 -285.199908)
			(xy 383.08005 -285.188048) (xy 383.030436 -285.168576) (xy 382.984278 -285.141927) (xy 382.942607 -285.108696)
			(xy 382.906355 -285.069625) (xy 382.876331 -285.025588) (xy 382.853205 -284.977567) (xy 382.837495 -284.926637)
			(xy 382.829552 -284.873933) (xy 382.601231 -284.873933) (xy 382.601226 -284.874187) (xy 382.593283 -284.926891)
			(xy 382.577573 -284.977821) (xy 382.554447 -285.025842) (xy 382.524423 -285.069879) (xy 382.488171 -285.10895)
			(xy 382.4465 -285.142181) (xy 382.400342 -285.16883) (xy 382.350728 -285.188302) (xy 382.298766 -285.200162)
			(xy 382.245616 -285.204146) (xy 382.192466 -285.200162) (xy 382.140504 -285.188302) (xy 382.09089 -285.16883)
			(xy 382.044732 -285.142181) (xy 382.003061 -285.10895) (xy 381.966809 -285.069879) (xy 381.936785 -285.025842)
			(xy 381.913659 -284.977821) (xy 381.897949 -284.926891) (xy 381.890006 -284.874187) (xy 380.721288 -284.874187)
			(xy 380.715696 -284.916877) (xy 380.703714 -284.961796) (xy 380.6952 -284.983428) (xy 380.685548 -285.006542)
			(xy 380.858014 -285.304992) (xy 380.882652 -285.308294) (xy 380.907998 -285.312098) (xy 380.957304 -285.326091)
			(xy 381.004095 -285.347006) (xy 381.047407 -285.37441) (xy 381.086345 -285.407737) (xy 381.120105 -285.4463)
			(xy 381.147991 -285.489303) (xy 381.169427 -285.535858) (xy 381.183971 -285.585004) (xy 381.191322 -285.635728)
			(xy 381.19177 -285.661354) (xy 381.191272 -285.688003) (xy 381.183329 -285.740707) (xy 381.167619 -285.791637)
			(xy 381.144493 -285.839658) (xy 381.114469 -285.883695) (xy 381.078217 -285.922766) (xy 381.036546 -285.955997)
			(xy 380.990388 -285.982646) (xy 380.940774 -286.002118) (xy 380.888812 -286.013978) (xy 380.835662 -286.017962)
			(xy 380.782512 -286.013978) (xy 380.73055 -286.002118) (xy 380.680936 -285.982646) (xy 380.634778 -285.955997)
			(xy 380.593107 -285.922766) (xy 380.556855 -285.883695) (xy 380.526831 -285.839658) (xy 380.503705 -285.791637)
			(xy 380.487995 -285.740707) (xy 380.480052 -285.688003) (xy 380.479554 -285.661354) (xy 380.479943 -285.63811)
			(xy 380.485982 -285.592015) (xy 380.497964 -285.547096) (xy 380.506478 -285.525464) (xy 380.51613 -285.50235)
			(xy 380.343664 -285.2039) (xy 380.319026 -285.200598) (xy 380.293688 -285.196741) (xy 380.244383 -285.182757)
			(xy 380.19759 -285.161852) (xy 380.154277 -285.134455) (xy 380.115337 -285.101134) (xy 380.081575 -285.062577)
			(xy 380.053688 -285.019578) (xy 380.032251 -284.973027) (xy 380.017707 -284.923883) (xy 380.010356 -284.873163)
			(xy 380.009908 -284.847538) (xy 378.842524 -284.847538) (xy 378.842134 -284.870782) (xy 378.836096 -284.916877)
			(xy 378.824114 -284.961796) (xy 378.8156 -284.983428) (xy 378.805948 -285.006542) (xy 378.978414 -285.304992)
			(xy 379.003052 -285.308294) (xy 379.028398 -285.312098) (xy 379.077704 -285.326091) (xy 379.124495 -285.347006)
			(xy 379.167807 -285.37441) (xy 379.206745 -285.407737) (xy 379.240505 -285.4463) (xy 379.268391 -285.489303)
			(xy 379.289827 -285.535858) (xy 379.304371 -285.585004) (xy 379.311722 -285.635728) (xy 379.31217 -285.661354)
			(xy 379.311672 -285.688003) (xy 379.303729 -285.740707) (xy 379.288019 -285.791637) (xy 379.264893 -285.839658)
			(xy 379.234869 -285.883695) (xy 379.198617 -285.922766) (xy 379.156946 -285.955997) (xy 379.110788 -285.982646)
			(xy 379.061174 -286.002118) (xy 379.009212 -286.013978) (xy 378.956062 -286.017962) (xy 378.902912 -286.013978)
			(xy 378.85095 -286.002118) (xy 378.801336 -285.982646) (xy 378.755178 -285.955997) (xy 378.713507 -285.922766)
			(xy 378.677255 -285.883695) (xy 378.647231 -285.839658) (xy 378.624105 -285.791637) (xy 378.608395 -285.740707)
			(xy 378.600452 -285.688003) (xy 378.599954 -285.661354) (xy 378.600343 -285.63811) (xy 378.606382 -285.592015)
			(xy 378.618364 -285.547096) (xy 378.626878 -285.525464) (xy 378.63653 -285.50235) (xy 378.464064 -285.2039)
			(xy 378.439426 -285.200598) (xy 378.414088 -285.196741) (xy 378.364783 -285.182757) (xy 378.31799 -285.161852)
			(xy 378.274677 -285.134455) (xy 378.235737 -285.101134) (xy 378.201975 -285.062577) (xy 378.174088 -285.019578)
			(xy 378.152651 -284.973027) (xy 378.138107 -284.923883) (xy 378.130756 -284.873163) (xy 378.130308 -284.847538)
			(xy 376.962924 -284.847538) (xy 376.962534 -284.870782) (xy 376.956496 -284.916877) (xy 376.944514 -284.961796)
			(xy 376.936 -284.983428) (xy 376.926348 -285.006542) (xy 377.098814 -285.304992) (xy 377.123452 -285.308294)
			(xy 377.148798 -285.312098) (xy 377.198104 -285.326091) (xy 377.244895 -285.347006) (xy 377.288207 -285.37441)
			(xy 377.327145 -285.407737) (xy 377.360905 -285.4463) (xy 377.388791 -285.489303) (xy 377.410227 -285.535858)
			(xy 377.424771 -285.585004) (xy 377.432122 -285.635728) (xy 377.43257 -285.661354) (xy 377.432072 -285.688003)
			(xy 377.424129 -285.740707) (xy 377.408419 -285.791637) (xy 377.385293 -285.839658) (xy 377.355269 -285.883695)
			(xy 377.319017 -285.922766) (xy 377.277346 -285.955997) (xy 377.231188 -285.982646) (xy 377.181574 -286.002118)
			(xy 377.129612 -286.013978) (xy 377.076462 -286.017962) (xy 377.023312 -286.013978) (xy 376.97135 -286.002118)
			(xy 376.921736 -285.982646) (xy 376.875578 -285.955997) (xy 376.833907 -285.922766) (xy 376.797655 -285.883695)
			(xy 376.767631 -285.839658) (xy 376.744505 -285.791637) (xy 376.728795 -285.740707) (xy 376.720852 -285.688003)
			(xy 376.720354 -285.661354) (xy 376.720743 -285.63811) (xy 376.726782 -285.592015) (xy 376.738764 -285.547096)
			(xy 376.747278 -285.525464) (xy 376.75693 -285.50235) (xy 376.584464 -285.2039) (xy 376.559826 -285.200598)
			(xy 376.534488 -285.196741) (xy 376.485183 -285.182757) (xy 376.43839 -285.161852) (xy 376.395077 -285.134455)
			(xy 376.356137 -285.101134) (xy 376.322375 -285.062577) (xy 376.294488 -285.019578) (xy 376.273051 -284.973027)
			(xy 376.258507 -284.923883) (xy 376.251156 -284.873163) (xy 376.250708 -284.847538) (xy 375.083324 -284.847538)
			(xy 375.082934 -284.870782) (xy 375.076896 -284.916877) (xy 375.064914 -284.961796) (xy 375.0564 -284.983428)
			(xy 375.046748 -285.006542) (xy 375.219214 -285.304992) (xy 375.243852 -285.308294) (xy 375.269198 -285.312098)
			(xy 375.318504 -285.326091) (xy 375.365295 -285.347006) (xy 375.408607 -285.37441) (xy 375.447545 -285.407737)
			(xy 375.481305 -285.4463) (xy 375.509191 -285.489303) (xy 375.530627 -285.535858) (xy 375.545171 -285.585004)
			(xy 375.552522 -285.635728) (xy 375.55297 -285.661354) (xy 375.552472 -285.688003) (xy 375.544529 -285.740707)
			(xy 375.528819 -285.791637) (xy 375.505693 -285.839658) (xy 375.475669 -285.883695) (xy 375.439417 -285.922766)
			(xy 375.397746 -285.955997) (xy 375.351588 -285.982646) (xy 375.301974 -286.002118) (xy 375.250012 -286.013978)
			(xy 375.196862 -286.017962) (xy 375.143712 -286.013978) (xy 375.09175 -286.002118) (xy 375.042136 -285.982646)
			(xy 374.995978 -285.955997) (xy 374.954307 -285.922766) (xy 374.918055 -285.883695) (xy 374.888031 -285.839658)
			(xy 374.864905 -285.791637) (xy 374.849195 -285.740707) (xy 374.841252 -285.688003) (xy 374.840754 -285.661354)
			(xy 374.841143 -285.63811) (xy 374.847182 -285.592015) (xy 374.859164 -285.547096) (xy 374.867678 -285.525464)
			(xy 374.87733 -285.50235) (xy 374.704864 -285.2039) (xy 374.680226 -285.200598) (xy 374.654888 -285.196741)
			(xy 374.605583 -285.182757) (xy 374.55879 -285.161852) (xy 374.515477 -285.134455) (xy 374.476537 -285.101134)
			(xy 374.442775 -285.062577) (xy 374.414888 -285.019578) (xy 374.393451 -284.973027) (xy 374.378907 -284.923883)
			(xy 374.371556 -284.873163) (xy 374.371108 -284.847538) (xy 374.143524 -284.847538) (xy 374.143026 -284.874187)
			(xy 374.135083 -284.926891) (xy 374.119373 -284.977821) (xy 374.096247 -285.025842) (xy 374.066223 -285.069879)
			(xy 374.029971 -285.10895) (xy 373.9883 -285.142181) (xy 373.942142 -285.16883) (xy 373.892528 -285.188302)
			(xy 373.840566 -285.200162) (xy 373.787416 -285.204146) (xy 373.734266 -285.200162) (xy 373.682304 -285.188302)
			(xy 373.63269 -285.16883) (xy 373.586532 -285.142181) (xy 373.544861 -285.10895) (xy 373.508609 -285.069879)
			(xy 373.478585 -285.025842) (xy 373.455459 -284.977821) (xy 373.439749 -284.926891) (xy 373.431806 -284.874187)
			(xy 373.202888 -284.874187) (xy 373.197296 -284.916877) (xy 373.185314 -284.961796) (xy 373.1768 -284.983428)
			(xy 373.167148 -285.006542) (xy 373.339614 -285.304992) (xy 373.364252 -285.308294) (xy 373.389598 -285.312098)
			(xy 373.438904 -285.326091) (xy 373.485695 -285.347006) (xy 373.529007 -285.37441) (xy 373.567945 -285.407737)
			(xy 373.601705 -285.4463) (xy 373.629591 -285.489303) (xy 373.651027 -285.535858) (xy 373.665571 -285.585004)
			(xy 373.672922 -285.635728) (xy 373.67337 -285.661354) (xy 373.672872 -285.688003) (xy 373.664929 -285.740707)
			(xy 373.649219 -285.791637) (xy 373.626093 -285.839658) (xy 373.596069 -285.883695) (xy 373.559817 -285.922766)
			(xy 373.518146 -285.955997) (xy 373.471988 -285.982646) (xy 373.422374 -286.002118) (xy 373.370412 -286.013978)
			(xy 373.317262 -286.017962) (xy 373.264112 -286.013978) (xy 373.21215 -286.002118) (xy 373.162536 -285.982646)
			(xy 373.116378 -285.955997) (xy 373.074707 -285.922766) (xy 373.038455 -285.883695) (xy 373.008431 -285.839658)
			(xy 372.985305 -285.791637) (xy 372.969595 -285.740707) (xy 372.961652 -285.688003) (xy 372.961154 -285.661354)
			(xy 372.961543 -285.63811) (xy 372.967582 -285.592015) (xy 372.979564 -285.547096) (xy 372.988078 -285.525464)
			(xy 372.99773 -285.50235) (xy 372.825264 -285.2039) (xy 372.800626 -285.200598) (xy 372.775288 -285.196741)
			(xy 372.725983 -285.182757) (xy 372.67919 -285.161852) (xy 372.635877 -285.134455) (xy 372.596937 -285.101134)
			(xy 372.563175 -285.062577) (xy 372.535288 -285.019578) (xy 372.513851 -284.973027) (xy 372.499307 -284.923883)
			(xy 372.491956 -284.873163) (xy 372.491508 -284.847538) (xy 371.324124 -284.847538) (xy 371.323734 -284.870782)
			(xy 371.317696 -284.916877) (xy 371.305714 -284.961796) (xy 371.2972 -284.983428) (xy 371.287548 -285.006542)
			(xy 371.460014 -285.304992) (xy 371.484652 -285.308294) (xy 371.509998 -285.312098) (xy 371.559304 -285.326091)
			(xy 371.606095 -285.347006) (xy 371.649407 -285.37441) (xy 371.688345 -285.407737) (xy 371.722105 -285.4463)
			(xy 371.749991 -285.489303) (xy 371.771427 -285.535858) (xy 371.785971 -285.585004) (xy 371.793322 -285.635728)
			(xy 371.79377 -285.661354) (xy 371.793272 -285.688003) (xy 371.785329 -285.740707) (xy 371.769619 -285.791637)
			(xy 371.746493 -285.839658) (xy 371.716469 -285.883695) (xy 371.680217 -285.922766) (xy 371.638546 -285.955997)
			(xy 371.592388 -285.982646) (xy 371.542774 -286.002118) (xy 371.490812 -286.013978) (xy 371.437662 -286.017962)
			(xy 371.384512 -286.013978) (xy 371.33255 -286.002118) (xy 371.282936 -285.982646) (xy 371.236778 -285.955997)
			(xy 371.195107 -285.922766) (xy 371.158855 -285.883695) (xy 371.128831 -285.839658) (xy 371.105705 -285.791637)
			(xy 371.089995 -285.740707) (xy 371.082052 -285.688003) (xy 371.081554 -285.661354) (xy 371.081943 -285.63811)
			(xy 371.087982 -285.592015) (xy 371.099964 -285.547096) (xy 371.108478 -285.525464) (xy 371.11813 -285.50235)
			(xy 370.945664 -285.2039) (xy 370.921026 -285.200598) (xy 370.895688 -285.196741) (xy 370.846383 -285.182757)
			(xy 370.79959 -285.161852) (xy 370.756277 -285.134455) (xy 370.717337 -285.101134) (xy 370.683575 -285.062577)
			(xy 370.655688 -285.019578) (xy 370.634251 -284.973027) (xy 370.619707 -284.923883) (xy 370.612356 -284.873163)
			(xy 370.611908 -284.847538) (xy 369.444524 -284.847538) (xy 369.444134 -284.870782) (xy 369.438096 -284.916877)
			(xy 369.426114 -284.961796) (xy 369.4176 -284.983428) (xy 369.407948 -285.006542) (xy 369.580414 -285.304992)
			(xy 369.605052 -285.308294) (xy 369.630398 -285.312098) (xy 369.679704 -285.326091) (xy 369.726495 -285.347006)
			(xy 369.769807 -285.37441) (xy 369.808745 -285.407737) (xy 369.842505 -285.4463) (xy 369.870391 -285.489303)
			(xy 369.891827 -285.535858) (xy 369.906371 -285.585004) (xy 369.913722 -285.635728) (xy 369.91417 -285.661354)
			(xy 369.913672 -285.688003) (xy 369.905729 -285.740707) (xy 369.890019 -285.791637) (xy 369.866893 -285.839658)
			(xy 369.836869 -285.883695) (xy 369.800617 -285.922766) (xy 369.758946 -285.955997) (xy 369.712788 -285.982646)
			(xy 369.663174 -286.002118) (xy 369.611212 -286.013978) (xy 369.558062 -286.017962) (xy 369.504912 -286.013978)
			(xy 369.45295 -286.002118) (xy 369.403336 -285.982646) (xy 369.357178 -285.955997) (xy 369.315507 -285.922766)
			(xy 369.279255 -285.883695) (xy 369.249231 -285.839658) (xy 369.226105 -285.791637) (xy 369.210395 -285.740707)
			(xy 369.202452 -285.688003) (xy 369.201954 -285.661354) (xy 369.202343 -285.63811) (xy 369.208382 -285.592015)
			(xy 369.220364 -285.547096) (xy 369.228878 -285.525464) (xy 369.23853 -285.50235) (xy 369.066064 -285.2039)
			(xy 369.041426 -285.200598) (xy 369.016088 -285.196741) (xy 368.966783 -285.182757) (xy 368.91999 -285.161852)
			(xy 368.876677 -285.134455) (xy 368.837737 -285.101134) (xy 368.803975 -285.062577) (xy 368.776088 -285.019578)
			(xy 368.754651 -284.973027) (xy 368.740107 -284.923883) (xy 368.732756 -284.873163) (xy 368.732308 -284.847538)
			(xy 367.774728 -284.847538) (xy 367.774728 -285.316676) (xy 367.80724 -285.329376) (xy 367.831999 -285.339491)
			(xy 367.878413 -285.366066) (xy 367.92033 -285.399282) (xy 367.956809 -285.438394) (xy 367.987028 -285.482521)
			(xy 368.010309 -285.530671) (xy 368.026128 -285.581761) (xy 368.034128 -285.634642) (xy 368.034131 -285.688125)
			(xy 368.026135 -285.741007) (xy 368.010321 -285.792098) (xy 367.987045 -285.84025) (xy 367.95683 -285.88438)
			(xy 367.920354 -285.923495) (xy 367.87844 -285.956716) (xy 367.832029 -285.983295) (xy 367.80724 -285.993332)
			(xy 367.774728 -286.006032) (xy 367.774728 -286.107632) (xy 367.775169 -286.121681) (xy 367.782818 -286.148717)
			(xy 367.797553 -286.172641) (xy 367.818256 -286.191636) (xy 367.843357 -286.204261) (xy 367.870951 -286.209558)
			(xy 367.898942 -286.207126) (xy 367.925208 -286.197148) (xy 367.93678 -286.189166) (xy 367.961247 -286.17183)
			(xy 368.014731 -286.144727) (xy 368.071991 -286.126938) (xy 368.101626 -286.122364) (xy 368.126264 -286.119062)
			(xy 368.29873 -285.820358) (xy 368.289078 -285.797244) (xy 368.280564 -285.775612) (xy 368.268581 -285.730694)
			(xy 368.262541 -285.684599) (xy 368.262154 -285.661354) (xy 368.262652 -285.634705) (xy 368.270595 -285.582001)
			(xy 368.286305 -285.531071) (xy 368.309431 -285.48305) (xy 368.339455 -285.439013) (xy 368.375707 -285.399942)
			(xy 368.417378 -285.366711) (xy 368.463536 -285.340062) (xy 368.51315 -285.32059) (xy 368.565112 -285.30873)
			(xy 368.618262 -285.304747) (xy 368.671412 -285.30873) (xy 368.723374 -285.32059) (xy 368.772988 -285.340062)
			(xy 368.819146 -285.366711) (xy 368.860817 -285.399942) (xy 368.897069 -285.439013) (xy 368.927093 -285.48305)
			(xy 368.950219 -285.531071) (xy 368.965929 -285.582001) (xy 368.973872 -285.634705) (xy 368.97437 -285.661354)
			(xy 368.973921 -285.68698) (xy 368.966569 -285.737702) (xy 368.952025 -285.786848) (xy 368.930588 -285.833402)
			(xy 368.902702 -285.876404) (xy 368.868942 -285.914966) (xy 368.830004 -285.948292) (xy 368.786693 -285.975695)
			(xy 368.739902 -285.996609) (xy 368.690597 -286.010603) (xy 368.665252 -286.014414) (xy 368.640614 -286.017716)
			(xy 368.468148 -286.31642) (xy 368.4778 -286.339534) (xy 368.486316 -286.361166) (xy 368.498303 -286.406084)
			(xy 368.504346 -286.452179) (xy 368.504724 -286.475424) (xy 368.504226 -286.502073) (xy 368.732552 -286.502073)
			(xy 368.732552 -286.448775) (xy 368.740495 -286.396071) (xy 368.756205 -286.345141) (xy 368.779331 -286.29712)
			(xy 368.809355 -286.253083) (xy 368.845607 -286.214012) (xy 368.887278 -286.180781) (xy 368.933436 -286.154132)
			(xy 368.98305 -286.13466) (xy 369.035012 -286.1228) (xy 369.088162 -286.118817) (xy 369.141312 -286.1228)
			(xy 369.193274 -286.13466) (xy 369.242888 -286.154132) (xy 369.289046 -286.180781) (xy 369.330717 -286.214012)
			(xy 369.366969 -286.253083) (xy 369.396993 -286.29712) (xy 369.420119 -286.345141) (xy 369.435829 -286.396071)
			(xy 369.443772 -286.448775) (xy 369.44427 -286.475424) (xy 369.672108 -286.475424) (xy 369.672589 -286.449797)
			(xy 369.67992 -286.399071) (xy 369.69445 -286.34992) (xy 369.715876 -286.30336) (xy 369.743757 -286.260354)
			(xy 369.777517 -286.221789) (xy 369.816458 -286.188464) (xy 369.859774 -286.161067) (xy 369.906571 -286.140164)
			(xy 369.955882 -286.126187) (xy 369.981226 -286.122364) (xy 370.005864 -286.119062) (xy 370.17833 -285.820358)
			(xy 370.168678 -285.797244) (xy 370.160146 -285.775618) (xy 370.148165 -285.730697) (xy 370.142126 -285.6846)
			(xy 370.141754 -285.661354) (xy 370.142252 -285.634705) (xy 370.150195 -285.582001) (xy 370.165905 -285.531071)
			(xy 370.189031 -285.48305) (xy 370.219055 -285.439013) (xy 370.255307 -285.399942) (xy 370.296978 -285.366711)
			(xy 370.343136 -285.340062) (xy 370.39275 -285.32059) (xy 370.444712 -285.30873) (xy 370.497862 -285.304747)
			(xy 370.551012 -285.30873) (xy 370.602974 -285.32059) (xy 370.652588 -285.340062) (xy 370.698746 -285.366711)
			(xy 370.740417 -285.399942) (xy 370.776669 -285.439013) (xy 370.806693 -285.48305) (xy 370.829819 -285.531071)
			(xy 370.845529 -285.582001) (xy 370.853472 -285.634705) (xy 370.85397 -285.661354) (xy 370.853488 -285.686981)
			(xy 370.846159 -285.737708) (xy 370.831631 -285.786861) (xy 370.810206 -285.833421) (xy 370.782325 -285.876429)
			(xy 370.748565 -285.914993) (xy 370.709624 -285.948319) (xy 370.666307 -285.975715) (xy 370.619508 -285.996617)
			(xy 370.570196 -286.010592) (xy 370.544852 -286.014414) (xy 370.520214 -286.017716) (xy 370.347748 -286.31642)
			(xy 370.3574 -286.339534) (xy 370.365925 -286.361163) (xy 370.377908 -286.406082) (xy 370.38395 -286.452179)
			(xy 370.384324 -286.475424) (xy 370.383826 -286.502073) (xy 370.612152 -286.502073) (xy 370.612152 -286.448775)
			(xy 370.620095 -286.396071) (xy 370.635805 -286.345141) (xy 370.658931 -286.29712) (xy 370.688955 -286.253083)
			(xy 370.725207 -286.214012) (xy 370.766878 -286.180781) (xy 370.813036 -286.154132) (xy 370.86265 -286.13466)
			(xy 370.914612 -286.1228) (xy 370.967762 -286.118817) (xy 371.020912 -286.1228) (xy 371.072874 -286.13466)
			(xy 371.122488 -286.154132) (xy 371.168646 -286.180781) (xy 371.210317 -286.214012) (xy 371.246569 -286.253083)
			(xy 371.276593 -286.29712) (xy 371.299719 -286.345141) (xy 371.315429 -286.396071) (xy 371.323372 -286.448775)
			(xy 371.32387 -286.475424) (xy 371.551708 -286.475424) (xy 371.552189 -286.449797) (xy 371.55952 -286.399071)
			(xy 371.57405 -286.34992) (xy 371.595476 -286.30336) (xy 371.623357 -286.260354) (xy 371.657117 -286.221789)
			(xy 371.696058 -286.188464) (xy 371.739374 -286.161067) (xy 371.786171 -286.140164) (xy 371.835482 -286.126187)
			(xy 371.860826 -286.122364) (xy 371.885464 -286.119062) (xy 372.05793 -285.820358) (xy 372.048278 -285.797244)
			(xy 372.039746 -285.775618) (xy 372.027765 -285.730697) (xy 372.021726 -285.6846) (xy 372.021354 -285.661354)
			(xy 372.021852 -285.634705) (xy 372.029795 -285.582001) (xy 372.045505 -285.531071) (xy 372.068631 -285.48305)
			(xy 372.098655 -285.439013) (xy 372.134907 -285.399942) (xy 372.176578 -285.366711) (xy 372.222736 -285.340062)
			(xy 372.27235 -285.32059) (xy 372.324312 -285.30873) (xy 372.377462 -285.304747) (xy 372.430612 -285.30873)
			(xy 372.482574 -285.32059) (xy 372.532188 -285.340062) (xy 372.578346 -285.366711) (xy 372.620017 -285.399942)
			(xy 372.656269 -285.439013) (xy 372.686293 -285.48305) (xy 372.709419 -285.531071) (xy 372.725129 -285.582001)
			(xy 372.733072 -285.634705) (xy 372.73357 -285.661354) (xy 372.733088 -285.686981) (xy 372.725759 -285.737708)
			(xy 372.711231 -285.786861) (xy 372.689806 -285.833421) (xy 372.661925 -285.876429) (xy 372.628165 -285.914993)
			(xy 372.589224 -285.948319) (xy 372.545907 -285.975715) (xy 372.499108 -285.996617) (xy 372.449796 -286.010592)
			(xy 372.424452 -286.014414) (xy 372.399814 -286.017716) (xy 372.227348 -286.31642) (xy 372.237 -286.339534)
			(xy 372.245525 -286.361163) (xy 372.257508 -286.406082) (xy 372.26355 -286.452179) (xy 372.263924 -286.475424)
			(xy 372.263426 -286.502073) (xy 372.491752 -286.502073) (xy 372.491752 -286.448775) (xy 372.499695 -286.396071)
			(xy 372.515405 -286.345141) (xy 372.538531 -286.29712) (xy 372.568555 -286.253083) (xy 372.604807 -286.214012)
			(xy 372.646478 -286.180781) (xy 372.692636 -286.154132) (xy 372.74225 -286.13466) (xy 372.794212 -286.1228)
			(xy 372.847362 -286.118817) (xy 372.900512 -286.1228) (xy 372.952474 -286.13466) (xy 373.002088 -286.154132)
			(xy 373.048246 -286.180781) (xy 373.089917 -286.214012) (xy 373.126169 -286.253083) (xy 373.156193 -286.29712)
			(xy 373.179319 -286.345141) (xy 373.195029 -286.396071) (xy 373.202972 -286.448775) (xy 373.20347 -286.475424)
			(xy 373.431308 -286.475424) (xy 373.431789 -286.449797) (xy 373.43912 -286.399071) (xy 373.45365 -286.34992)
			(xy 373.475076 -286.30336) (xy 373.502957 -286.260354) (xy 373.536717 -286.221789) (xy 373.575658 -286.188464)
			(xy 373.618974 -286.161067) (xy 373.665771 -286.140164) (xy 373.715082 -286.126187) (xy 373.740426 -286.122364)
			(xy 373.765064 -286.119062) (xy 373.93753 -285.820358) (xy 373.927878 -285.797244) (xy 373.919346 -285.775618)
			(xy 373.907365 -285.730697) (xy 373.901326 -285.6846) (xy 373.900954 -285.661354) (xy 373.901452 -285.634705)
			(xy 373.909395 -285.582001) (xy 373.925105 -285.531071) (xy 373.948231 -285.48305) (xy 373.978255 -285.439013)
			(xy 374.014507 -285.399942) (xy 374.056178 -285.366711) (xy 374.102336 -285.340062) (xy 374.15195 -285.32059)
			(xy 374.203912 -285.30873) (xy 374.257062 -285.304747) (xy 374.310212 -285.30873) (xy 374.362174 -285.32059)
			(xy 374.411788 -285.340062) (xy 374.457946 -285.366711) (xy 374.499617 -285.399942) (xy 374.535869 -285.439013)
			(xy 374.565893 -285.48305) (xy 374.589019 -285.531071) (xy 374.604729 -285.582001) (xy 374.612672 -285.634705)
			(xy 374.61317 -285.661354) (xy 374.612688 -285.686981) (xy 374.605359 -285.737708) (xy 374.590831 -285.786861)
			(xy 374.569406 -285.833421) (xy 374.541525 -285.876429) (xy 374.507765 -285.914993) (xy 374.468824 -285.948319)
			(xy 374.425507 -285.975715) (xy 374.378708 -285.996617) (xy 374.329396 -286.010592) (xy 374.304052 -286.014414)
			(xy 374.279414 -286.017716) (xy 374.106948 -286.31642) (xy 374.1166 -286.339534) (xy 374.125125 -286.361163)
			(xy 374.137108 -286.406082) (xy 374.14315 -286.452179) (xy 374.143524 -286.475424) (xy 374.143026 -286.502073)
			(xy 374.371352 -286.502073) (xy 374.371352 -286.448775) (xy 374.379295 -286.396071) (xy 374.395005 -286.345141)
			(xy 374.418131 -286.29712) (xy 374.448155 -286.253083) (xy 374.484407 -286.214012) (xy 374.526078 -286.180781)
			(xy 374.572236 -286.154132) (xy 374.62185 -286.13466) (xy 374.673812 -286.1228) (xy 374.726962 -286.118817)
			(xy 374.780112 -286.1228) (xy 374.832074 -286.13466) (xy 374.881688 -286.154132) (xy 374.927846 -286.180781)
			(xy 374.969517 -286.214012) (xy 375.005769 -286.253083) (xy 375.035793 -286.29712) (xy 375.058919 -286.345141)
			(xy 375.074629 -286.396071) (xy 375.082572 -286.448775) (xy 375.08307 -286.475424) (xy 375.310908 -286.475424)
			(xy 375.311389 -286.449797) (xy 375.31872 -286.399071) (xy 375.33325 -286.34992) (xy 375.354676 -286.30336)
			(xy 375.382557 -286.260354) (xy 375.416317 -286.221789) (xy 375.455258 -286.188464) (xy 375.498574 -286.161067)
			(xy 375.545371 -286.140164) (xy 375.594682 -286.126187) (xy 375.620026 -286.122364) (xy 375.644664 -286.119062)
			(xy 375.81713 -285.820358) (xy 375.807478 -285.797244) (xy 375.798946 -285.775618) (xy 375.786965 -285.730697)
			(xy 375.780926 -285.6846) (xy 375.780554 -285.661354) (xy 375.781052 -285.634705) (xy 375.788995 -285.582001)
			(xy 375.804705 -285.531071) (xy 375.827831 -285.48305) (xy 375.857855 -285.439013) (xy 375.894107 -285.399942)
			(xy 375.935778 -285.366711) (xy 375.981936 -285.340062) (xy 376.03155 -285.32059) (xy 376.083512 -285.30873)
			(xy 376.136662 -285.304747) (xy 376.189812 -285.30873) (xy 376.241774 -285.32059) (xy 376.291388 -285.340062)
			(xy 376.337546 -285.366711) (xy 376.379217 -285.399942) (xy 376.415469 -285.439013) (xy 376.445493 -285.48305)
			(xy 376.468619 -285.531071) (xy 376.484329 -285.582001) (xy 376.492272 -285.634705) (xy 376.49277 -285.661354)
			(xy 376.492288 -285.686981) (xy 376.484959 -285.737708) (xy 376.470431 -285.786861) (xy 376.449006 -285.833421)
			(xy 376.421125 -285.876429) (xy 376.387365 -285.914993) (xy 376.348424 -285.948319) (xy 376.305107 -285.975715)
			(xy 376.258308 -285.996617) (xy 376.208996 -286.010592) (xy 376.183652 -286.014414) (xy 376.159014 -286.017716)
			(xy 375.986548 -286.31642) (xy 375.9962 -286.339534) (xy 376.004725 -286.361163) (xy 376.016708 -286.406082)
			(xy 376.02275 -286.452179) (xy 376.023124 -286.475424) (xy 376.022626 -286.502073) (xy 376.250952 -286.502073)
			(xy 376.250952 -286.448775) (xy 376.258895 -286.396071) (xy 376.274605 -286.345141) (xy 376.297731 -286.29712)
			(xy 376.327755 -286.253083) (xy 376.364007 -286.214012) (xy 376.405678 -286.180781) (xy 376.451836 -286.154132)
			(xy 376.50145 -286.13466) (xy 376.553412 -286.1228) (xy 376.606562 -286.118817) (xy 376.659712 -286.1228)
			(xy 376.711674 -286.13466) (xy 376.761288 -286.154132) (xy 376.807446 -286.180781) (xy 376.849117 -286.214012)
			(xy 376.885369 -286.253083) (xy 376.915393 -286.29712) (xy 376.938519 -286.345141) (xy 376.954229 -286.396071)
			(xy 376.962172 -286.448775) (xy 376.96267 -286.475424) (xy 377.190508 -286.475424) (xy 377.190989 -286.449797)
			(xy 377.19832 -286.399071) (xy 377.21285 -286.34992) (xy 377.234276 -286.30336) (xy 377.262157 -286.260354)
			(xy 377.295917 -286.221789) (xy 377.334858 -286.188464) (xy 377.378174 -286.161067) (xy 377.424971 -286.140164)
			(xy 377.474282 -286.126187) (xy 377.499626 -286.122364) (xy 377.524264 -286.119062) (xy 377.69673 -285.820358)
			(xy 377.687078 -285.797244) (xy 377.678546 -285.775618) (xy 377.666565 -285.730697) (xy 377.660526 -285.6846)
			(xy 377.660154 -285.661354) (xy 377.660652 -285.634705) (xy 377.668595 -285.582001) (xy 377.684305 -285.531071)
			(xy 377.707431 -285.48305) (xy 377.737455 -285.439013) (xy 377.773707 -285.399942) (xy 377.815378 -285.366711)
			(xy 377.861536 -285.340062) (xy 377.91115 -285.32059) (xy 377.963112 -285.30873) (xy 378.016262 -285.304747)
			(xy 378.069412 -285.30873) (xy 378.121374 -285.32059) (xy 378.170988 -285.340062) (xy 378.217146 -285.366711)
			(xy 378.258817 -285.399942) (xy 378.295069 -285.439013) (xy 378.325093 -285.48305) (xy 378.348219 -285.531071)
			(xy 378.363929 -285.582001) (xy 378.371872 -285.634705) (xy 378.37237 -285.661354) (xy 378.371888 -285.686981)
			(xy 378.364559 -285.737708) (xy 378.350031 -285.786861) (xy 378.328606 -285.833421) (xy 378.300725 -285.876429)
			(xy 378.266965 -285.914993) (xy 378.228024 -285.948319) (xy 378.184707 -285.975715) (xy 378.137908 -285.996617)
			(xy 378.088596 -286.010592) (xy 378.063252 -286.014414) (xy 378.038614 -286.017716) (xy 377.866148 -286.31642)
			(xy 377.8758 -286.339534) (xy 377.884325 -286.361163) (xy 377.896308 -286.406082) (xy 377.90235 -286.452179)
			(xy 377.902724 -286.475424) (xy 377.902226 -286.502073) (xy 378.130552 -286.502073) (xy 378.130552 -286.448775)
			(xy 378.138495 -286.396071) (xy 378.154205 -286.345141) (xy 378.177331 -286.29712) (xy 378.207355 -286.253083)
			(xy 378.243607 -286.214012) (xy 378.285278 -286.180781) (xy 378.331436 -286.154132) (xy 378.38105 -286.13466)
			(xy 378.433012 -286.1228) (xy 378.486162 -286.118817) (xy 378.539312 -286.1228) (xy 378.591274 -286.13466)
			(xy 378.640888 -286.154132) (xy 378.687046 -286.180781) (xy 378.728717 -286.214012) (xy 378.764969 -286.253083)
			(xy 378.794993 -286.29712) (xy 378.818119 -286.345141) (xy 378.833829 -286.396071) (xy 378.841772 -286.448775)
			(xy 378.84227 -286.475424) (xy 379.070108 -286.475424) (xy 379.070589 -286.449797) (xy 379.07792 -286.399071)
			(xy 379.09245 -286.34992) (xy 379.113876 -286.30336) (xy 379.141757 -286.260354) (xy 379.175517 -286.221789)
			(xy 379.214458 -286.188464) (xy 379.257774 -286.161067) (xy 379.304571 -286.140164) (xy 379.353882 -286.126187)
			(xy 379.379226 -286.122364) (xy 379.403864 -286.119062) (xy 379.57633 -285.820358) (xy 379.566678 -285.797244)
			(xy 379.558146 -285.775618) (xy 379.546165 -285.730697) (xy 379.540126 -285.6846) (xy 379.539754 -285.661354)
			(xy 379.540252 -285.634705) (xy 379.548195 -285.582001) (xy 379.563905 -285.531071) (xy 379.587031 -285.48305)
			(xy 379.617055 -285.439013) (xy 379.653307 -285.399942) (xy 379.694978 -285.366711) (xy 379.741136 -285.340062)
			(xy 379.79075 -285.32059) (xy 379.842712 -285.30873) (xy 379.895862 -285.304747) (xy 379.949012 -285.30873)
			(xy 380.000974 -285.32059) (xy 380.050588 -285.340062) (xy 380.096746 -285.366711) (xy 380.138417 -285.399942)
			(xy 380.174669 -285.439013) (xy 380.204693 -285.48305) (xy 380.227819 -285.531071) (xy 380.243529 -285.582001)
			(xy 380.251472 -285.634705) (xy 380.25197 -285.661354) (xy 380.251488 -285.686981) (xy 380.244159 -285.737708)
			(xy 380.229631 -285.786861) (xy 380.208206 -285.833421) (xy 380.180325 -285.876429) (xy 380.146565 -285.914993)
			(xy 380.107624 -285.948319) (xy 380.064307 -285.975715) (xy 380.017508 -285.996617) (xy 379.968196 -286.010592)
			(xy 379.942852 -286.014414) (xy 379.918214 -286.017716) (xy 379.745748 -286.31642) (xy 379.7554 -286.339534)
			(xy 379.763925 -286.361163) (xy 379.775908 -286.406082) (xy 379.78195 -286.452179) (xy 379.782324 -286.475424)
			(xy 379.781826 -286.502073) (xy 380.010152 -286.502073) (xy 380.010152 -286.448775) (xy 380.018095 -286.396071)
			(xy 380.033805 -286.345141) (xy 380.056931 -286.29712) (xy 380.086955 -286.253083) (xy 380.123207 -286.214012)
			(xy 380.164878 -286.180781) (xy 380.211036 -286.154132) (xy 380.26065 -286.13466) (xy 380.312612 -286.1228)
			(xy 380.365762 -286.118817) (xy 380.418912 -286.1228) (xy 380.470874 -286.13466) (xy 380.520488 -286.154132)
			(xy 380.566646 -286.180781) (xy 380.608317 -286.214012) (xy 380.644569 -286.253083) (xy 380.674593 -286.29712)
			(xy 380.697719 -286.345141) (xy 380.713429 -286.396071) (xy 380.721372 -286.448775) (xy 380.72187 -286.475424)
			(xy 380.949708 -286.475424) (xy 380.950189 -286.449797) (xy 380.95752 -286.399071) (xy 380.97205 -286.34992)
			(xy 380.993476 -286.30336) (xy 381.021357 -286.260354) (xy 381.055117 -286.221789) (xy 381.094058 -286.188464)
			(xy 381.137374 -286.161067) (xy 381.184171 -286.140164) (xy 381.233482 -286.126187) (xy 381.258826 -286.122364)
			(xy 381.283464 -286.119062) (xy 381.45593 -285.820358) (xy 381.446278 -285.797244) (xy 381.437746 -285.775618)
			(xy 381.425765 -285.730697) (xy 381.419726 -285.6846) (xy 381.419354 -285.661354) (xy 381.419852 -285.634705)
			(xy 381.427795 -285.582001) (xy 381.443505 -285.531071) (xy 381.466631 -285.48305) (xy 381.496655 -285.439013)
			(xy 381.532907 -285.399942) (xy 381.574578 -285.366711) (xy 381.620736 -285.340062) (xy 381.67035 -285.32059)
			(xy 381.722312 -285.30873) (xy 381.775462 -285.304747) (xy 381.828612 -285.30873) (xy 381.880574 -285.32059)
			(xy 381.930188 -285.340062) (xy 381.976346 -285.366711) (xy 382.018017 -285.399942) (xy 382.054269 -285.439013)
			(xy 382.084293 -285.48305) (xy 382.107419 -285.531071) (xy 382.123129 -285.582001) (xy 382.131072 -285.634705)
			(xy 382.13157 -285.661354) (xy 382.131088 -285.686981) (xy 382.13094 -285.688003) (xy 382.359652 -285.688003)
			(xy 382.359652 -285.634705) (xy 382.367595 -285.582001) (xy 382.383305 -285.531071) (xy 382.406431 -285.48305)
			(xy 382.436455 -285.439013) (xy 382.472707 -285.399942) (xy 382.514378 -285.366711) (xy 382.560536 -285.340062)
			(xy 382.61015 -285.32059) (xy 382.662112 -285.30873) (xy 382.715262 -285.304747) (xy 382.768412 -285.30873)
			(xy 382.820374 -285.32059) (xy 382.869988 -285.340062) (xy 382.916146 -285.366711) (xy 382.957817 -285.399942)
			(xy 382.994069 -285.439013) (xy 383.024093 -285.48305) (xy 383.047219 -285.531071) (xy 383.062929 -285.582001)
			(xy 383.070872 -285.634705) (xy 383.07137 -285.661354) (xy 383.070877 -285.687749) (xy 383.299452 -285.687749)
			(xy 383.299452 -285.634451) (xy 383.307395 -285.581747) (xy 383.323105 -285.530817) (xy 383.346231 -285.482796)
			(xy 383.376255 -285.438759) (xy 383.412507 -285.399688) (xy 383.454178 -285.366457) (xy 383.500336 -285.339808)
			(xy 383.54995 -285.320336) (xy 383.601912 -285.308476) (xy 383.655062 -285.304493) (xy 383.708212 -285.308476)
			(xy 383.760174 -285.320336) (xy 383.809788 -285.339808) (xy 383.855946 -285.366457) (xy 383.897617 -285.399688)
			(xy 383.933869 -285.438759) (xy 383.963893 -285.482796) (xy 383.987019 -285.530817) (xy 384.002729 -285.581747)
			(xy 384.010672 -285.634451) (xy 384.01117 -285.6611) (xy 384.010672 -285.687749) (xy 384.010634 -285.688003)
			(xy 384.239252 -285.688003) (xy 384.239252 -285.634705) (xy 384.247195 -285.582001) (xy 384.262905 -285.531071)
			(xy 384.286031 -285.48305) (xy 384.316055 -285.439013) (xy 384.352307 -285.399942) (xy 384.393978 -285.366711)
			(xy 384.440136 -285.340062) (xy 384.48975 -285.32059) (xy 384.541712 -285.30873) (xy 384.594862 -285.304747)
			(xy 384.648012 -285.30873) (xy 384.699974 -285.32059) (xy 384.749588 -285.340062) (xy 384.795746 -285.366711)
			(xy 384.837417 -285.399942) (xy 384.873669 -285.439013) (xy 384.903693 -285.48305) (xy 384.926819 -285.531071)
			(xy 384.942529 -285.582001) (xy 384.950472 -285.634705) (xy 384.95097 -285.661354) (xy 384.950477 -285.687749)
			(xy 385.179052 -285.687749) (xy 385.179052 -285.634451) (xy 385.186995 -285.581747) (xy 385.202705 -285.530817)
			(xy 385.225831 -285.482796) (xy 385.255855 -285.438759) (xy 385.292107 -285.399688) (xy 385.333778 -285.366457)
			(xy 385.379936 -285.339808) (xy 385.42955 -285.320336) (xy 385.481512 -285.308476) (xy 385.534662 -285.304493)
			(xy 385.587812 -285.308476) (xy 385.639774 -285.320336) (xy 385.689388 -285.339808) (xy 385.735546 -285.366457)
			(xy 385.777217 -285.399688) (xy 385.813469 -285.438759) (xy 385.843493 -285.482796) (xy 385.866619 -285.530817)
			(xy 385.882329 -285.581747) (xy 385.890272 -285.634451) (xy 385.89077 -285.6611) (xy 385.890272 -285.687749)
			(xy 385.882329 -285.740453) (xy 385.866619 -285.791383) (xy 385.843493 -285.839404) (xy 385.813469 -285.883441)
			(xy 385.777217 -285.922512) (xy 385.735546 -285.955743) (xy 385.689388 -285.982392) (xy 385.639774 -286.001864)
			(xy 385.587812 -286.013724) (xy 385.534662 -286.017708) (xy 385.481512 -286.013724) (xy 385.42955 -286.001864)
			(xy 385.379936 -285.982392) (xy 385.333778 -285.955743) (xy 385.292107 -285.922512) (xy 385.255855 -285.883441)
			(xy 385.225831 -285.839404) (xy 385.202705 -285.791383) (xy 385.186995 -285.740453) (xy 385.179052 -285.687749)
			(xy 384.950477 -285.687749) (xy 384.950472 -285.688003) (xy 384.942529 -285.740707) (xy 384.926819 -285.791637)
			(xy 384.903693 -285.839658) (xy 384.873669 -285.883695) (xy 384.837417 -285.922766) (xy 384.795746 -285.955997)
			(xy 384.749588 -285.982646) (xy 384.699974 -286.002118) (xy 384.648012 -286.013978) (xy 384.594862 -286.017962)
			(xy 384.541712 -286.013978) (xy 384.48975 -286.002118) (xy 384.440136 -285.982646) (xy 384.393978 -285.955997)
			(xy 384.352307 -285.922766) (xy 384.316055 -285.883695) (xy 384.286031 -285.839658) (xy 384.262905 -285.791637)
			(xy 384.247195 -285.740707) (xy 384.239252 -285.688003) (xy 384.010634 -285.688003) (xy 384.002729 -285.740453)
			(xy 383.987019 -285.791383) (xy 383.963893 -285.839404) (xy 383.933869 -285.883441) (xy 383.897617 -285.922512)
			(xy 383.855946 -285.955743) (xy 383.809788 -285.982392) (xy 383.760174 -286.001864) (xy 383.708212 -286.013724)
			(xy 383.655062 -286.017708) (xy 383.601912 -286.013724) (xy 383.54995 -286.001864) (xy 383.500336 -285.982392)
			(xy 383.454178 -285.955743) (xy 383.412507 -285.922512) (xy 383.376255 -285.883441) (xy 383.346231 -285.839404)
			(xy 383.323105 -285.791383) (xy 383.307395 -285.740453) (xy 383.299452 -285.687749) (xy 383.070877 -285.687749)
			(xy 383.070872 -285.688003) (xy 383.062929 -285.740707) (xy 383.047219 -285.791637) (xy 383.024093 -285.839658)
			(xy 382.994069 -285.883695) (xy 382.957817 -285.922766) (xy 382.916146 -285.955997) (xy 382.869988 -285.982646)
			(xy 382.820374 -286.002118) (xy 382.768412 -286.013978) (xy 382.715262 -286.017962) (xy 382.662112 -286.013978)
			(xy 382.61015 -286.002118) (xy 382.560536 -285.982646) (xy 382.514378 -285.955997) (xy 382.472707 -285.922766)
			(xy 382.436455 -285.883695) (xy 382.406431 -285.839658) (xy 382.383305 -285.791637) (xy 382.367595 -285.740707)
			(xy 382.359652 -285.688003) (xy 382.13094 -285.688003) (xy 382.123759 -285.737708) (xy 382.109231 -285.786861)
			(xy 382.087806 -285.833421) (xy 382.059925 -285.876429) (xy 382.026165 -285.914993) (xy 381.987224 -285.948319)
			(xy 381.943907 -285.975715) (xy 381.897108 -285.996617) (xy 381.847796 -286.010592) (xy 381.822452 -286.014414)
			(xy 381.797814 -286.017716) (xy 381.625348 -286.31642) (xy 381.635 -286.339534) (xy 381.643525 -286.361163)
			(xy 381.655508 -286.406082) (xy 381.66155 -286.452179) (xy 381.661924 -286.475424) (xy 381.661426 -286.502073)
			(xy 381.890006 -286.502073) (xy 381.890006 -286.448775) (xy 381.897949 -286.396071) (xy 381.913659 -286.345141)
			(xy 381.936785 -286.29712) (xy 381.966809 -286.253083) (xy 382.003061 -286.214012) (xy 382.044732 -286.180781)
			(xy 382.09089 -286.154132) (xy 382.140504 -286.13466) (xy 382.192466 -286.1228) (xy 382.245616 -286.118817)
			(xy 382.298766 -286.1228) (xy 382.350728 -286.13466) (xy 382.400342 -286.154132) (xy 382.4465 -286.180781)
			(xy 382.488171 -286.214012) (xy 382.524423 -286.253083) (xy 382.554447 -286.29712) (xy 382.577573 -286.345141)
			(xy 382.593283 -286.396071) (xy 382.601226 -286.448775) (xy 382.601724 -286.475424) (xy 382.601231 -286.501819)
			(xy 382.829552 -286.501819) (xy 382.829552 -286.448521) (xy 382.837495 -286.395817) (xy 382.853205 -286.344887)
			(xy 382.876331 -286.296866) (xy 382.906355 -286.252829) (xy 382.942607 -286.213758) (xy 382.984278 -286.180527)
			(xy 383.030436 -286.153878) (xy 383.08005 -286.134406) (xy 383.132012 -286.122546) (xy 383.185162 -286.118563)
			(xy 383.238312 -286.122546) (xy 383.290274 -286.134406) (xy 383.339888 -286.153878) (xy 383.386046 -286.180527)
			(xy 383.427717 -286.213758) (xy 383.463969 -286.252829) (xy 383.493993 -286.296866) (xy 383.517119 -286.344887)
			(xy 383.532829 -286.395817) (xy 383.540772 -286.448521) (xy 383.54127 -286.47517) (xy 383.540772 -286.501819)
			(xy 383.769352 -286.501819) (xy 383.769352 -286.448521) (xy 383.777295 -286.395817) (xy 383.793005 -286.344887)
			(xy 383.816131 -286.296866) (xy 383.846155 -286.252829) (xy 383.882407 -286.213758) (xy 383.924078 -286.180527)
			(xy 383.970236 -286.153878) (xy 384.01985 -286.134406) (xy 384.071812 -286.122546) (xy 384.124962 -286.118563)
			(xy 384.178112 -286.122546) (xy 384.230074 -286.134406) (xy 384.279688 -286.153878) (xy 384.325846 -286.180527)
			(xy 384.367517 -286.213758) (xy 384.403769 -286.252829) (xy 384.433793 -286.296866) (xy 384.456919 -286.344887)
			(xy 384.472629 -286.395817) (xy 384.480572 -286.448521) (xy 384.48107 -286.47517) (xy 384.480572 -286.501819)
			(xy 384.709152 -286.501819) (xy 384.709152 -286.448521) (xy 384.717095 -286.395817) (xy 384.732805 -286.344887)
			(xy 384.755931 -286.296866) (xy 384.785955 -286.252829) (xy 384.822207 -286.213758) (xy 384.863878 -286.180527)
			(xy 384.910036 -286.153878) (xy 384.95965 -286.134406) (xy 385.011612 -286.122546) (xy 385.064762 -286.118563)
			(xy 385.117912 -286.122546) (xy 385.169874 -286.134406) (xy 385.219488 -286.153878) (xy 385.265646 -286.180527)
			(xy 385.307317 -286.213758) (xy 385.343569 -286.252829) (xy 385.373593 -286.296866) (xy 385.396719 -286.344887)
			(xy 385.412429 -286.395817) (xy 385.420372 -286.448521) (xy 385.42087 -286.47517) (xy 385.420372 -286.501819)
			(xy 385.412429 -286.554523) (xy 385.396719 -286.605453) (xy 385.373593 -286.653474) (xy 385.343569 -286.697511)
			(xy 385.307317 -286.736582) (xy 385.265646 -286.769813) (xy 385.219488 -286.796462) (xy 385.169874 -286.815934)
			(xy 385.117912 -286.827794) (xy 385.064762 -286.831778) (xy 385.011612 -286.827794) (xy 384.95965 -286.815934)
			(xy 384.910036 -286.796462) (xy 384.863878 -286.769813) (xy 384.822207 -286.736582) (xy 384.785955 -286.697511)
			(xy 384.755931 -286.653474) (xy 384.732805 -286.605453) (xy 384.717095 -286.554523) (xy 384.709152 -286.501819)
			(xy 384.480572 -286.501819) (xy 384.472629 -286.554523) (xy 384.456919 -286.605453) (xy 384.433793 -286.653474)
			(xy 384.403769 -286.697511) (xy 384.367517 -286.736582) (xy 384.325846 -286.769813) (xy 384.279688 -286.796462)
			(xy 384.230074 -286.815934) (xy 384.178112 -286.827794) (xy 384.124962 -286.831778) (xy 384.071812 -286.827794)
			(xy 384.01985 -286.815934) (xy 383.970236 -286.796462) (xy 383.924078 -286.769813) (xy 383.882407 -286.736582)
			(xy 383.846155 -286.697511) (xy 383.816131 -286.653474) (xy 383.793005 -286.605453) (xy 383.777295 -286.554523)
			(xy 383.769352 -286.501819) (xy 383.540772 -286.501819) (xy 383.532829 -286.554523) (xy 383.517119 -286.605453)
			(xy 383.493993 -286.653474) (xy 383.463969 -286.697511) (xy 383.427717 -286.736582) (xy 383.386046 -286.769813)
			(xy 383.339888 -286.796462) (xy 383.290274 -286.815934) (xy 383.238312 -286.827794) (xy 383.185162 -286.831778)
			(xy 383.132012 -286.827794) (xy 383.08005 -286.815934) (xy 383.030436 -286.796462) (xy 382.984278 -286.769813)
			(xy 382.942607 -286.736582) (xy 382.906355 -286.697511) (xy 382.876331 -286.653474) (xy 382.853205 -286.605453)
			(xy 382.837495 -286.554523) (xy 382.829552 -286.501819) (xy 382.601231 -286.501819) (xy 382.601226 -286.502073)
			(xy 382.593283 -286.554777) (xy 382.577573 -286.605707) (xy 382.554447 -286.653728) (xy 382.524423 -286.697765)
			(xy 382.488171 -286.736836) (xy 382.4465 -286.770067) (xy 382.400342 -286.796716) (xy 382.350728 -286.816188)
			(xy 382.298766 -286.828048) (xy 382.245616 -286.832032) (xy 382.192466 -286.828048) (xy 382.140504 -286.816188)
			(xy 382.09089 -286.796716) (xy 382.044732 -286.770067) (xy 382.003061 -286.736836) (xy 381.966809 -286.697765)
			(xy 381.936785 -286.653728) (xy 381.913659 -286.605707) (xy 381.897949 -286.554777) (xy 381.890006 -286.502073)
			(xy 381.661426 -286.502073) (xy 381.653483 -286.554777) (xy 381.637773 -286.605707) (xy 381.614647 -286.653728)
			(xy 381.584623 -286.697765) (xy 381.548371 -286.736836) (xy 381.5067 -286.770067) (xy 381.460542 -286.796716)
			(xy 381.410928 -286.816188) (xy 381.358966 -286.828048) (xy 381.305816 -286.832032) (xy 381.252666 -286.828048)
			(xy 381.200704 -286.816188) (xy 381.15109 -286.796716) (xy 381.104932 -286.770067) (xy 381.063261 -286.736836)
			(xy 381.027009 -286.697765) (xy 380.996985 -286.653728) (xy 380.973859 -286.605707) (xy 380.958149 -286.554777)
			(xy 380.950206 -286.502073) (xy 380.949708 -286.475424) (xy 380.72187 -286.475424) (xy 380.721372 -286.502073)
			(xy 380.713429 -286.554777) (xy 380.697719 -286.605707) (xy 380.674593 -286.653728) (xy 380.644569 -286.697765)
			(xy 380.608317 -286.736836) (xy 380.566646 -286.770067) (xy 380.520488 -286.796716) (xy 380.470874 -286.816188)
			(xy 380.418912 -286.828048) (xy 380.365762 -286.832032) (xy 380.312612 -286.828048) (xy 380.26065 -286.816188)
			(xy 380.211036 -286.796716) (xy 380.164878 -286.770067) (xy 380.123207 -286.736836) (xy 380.086955 -286.697765)
			(xy 380.056931 -286.653728) (xy 380.033805 -286.605707) (xy 380.018095 -286.554777) (xy 380.010152 -286.502073)
			(xy 379.781826 -286.502073) (xy 379.773883 -286.554777) (xy 379.758173 -286.605707) (xy 379.735047 -286.653728)
			(xy 379.705023 -286.697765) (xy 379.668771 -286.736836) (xy 379.6271 -286.770067) (xy 379.580942 -286.796716)
			(xy 379.531328 -286.816188) (xy 379.479366 -286.828048) (xy 379.426216 -286.832032) (xy 379.373066 -286.828048)
			(xy 379.321104 -286.816188) (xy 379.27149 -286.796716) (xy 379.225332 -286.770067) (xy 379.183661 -286.736836)
			(xy 379.147409 -286.697765) (xy 379.117385 -286.653728) (xy 379.094259 -286.605707) (xy 379.078549 -286.554777)
			(xy 379.070606 -286.502073) (xy 379.070108 -286.475424) (xy 378.84227 -286.475424) (xy 378.841772 -286.502073)
			(xy 378.833829 -286.554777) (xy 378.818119 -286.605707) (xy 378.794993 -286.653728) (xy 378.764969 -286.697765)
			(xy 378.728717 -286.736836) (xy 378.687046 -286.770067) (xy 378.640888 -286.796716) (xy 378.591274 -286.816188)
			(xy 378.539312 -286.828048) (xy 378.486162 -286.832032) (xy 378.433012 -286.828048) (xy 378.38105 -286.816188)
			(xy 378.331436 -286.796716) (xy 378.285278 -286.770067) (xy 378.243607 -286.736836) (xy 378.207355 -286.697765)
			(xy 378.177331 -286.653728) (xy 378.154205 -286.605707) (xy 378.138495 -286.554777) (xy 378.130552 -286.502073)
			(xy 377.902226 -286.502073) (xy 377.894283 -286.554777) (xy 377.878573 -286.605707) (xy 377.855447 -286.653728)
			(xy 377.825423 -286.697765) (xy 377.789171 -286.736836) (xy 377.7475 -286.770067) (xy 377.701342 -286.796716)
			(xy 377.651728 -286.816188) (xy 377.599766 -286.828048) (xy 377.546616 -286.832032) (xy 377.493466 -286.828048)
			(xy 377.441504 -286.816188) (xy 377.39189 -286.796716) (xy 377.345732 -286.770067) (xy 377.304061 -286.736836)
			(xy 377.267809 -286.697765) (xy 377.237785 -286.653728) (xy 377.214659 -286.605707) (xy 377.198949 -286.554777)
			(xy 377.191006 -286.502073) (xy 377.190508 -286.475424) (xy 376.96267 -286.475424) (xy 376.962172 -286.502073)
			(xy 376.954229 -286.554777) (xy 376.938519 -286.605707) (xy 376.915393 -286.653728) (xy 376.885369 -286.697765)
			(xy 376.849117 -286.736836) (xy 376.807446 -286.770067) (xy 376.761288 -286.796716) (xy 376.711674 -286.816188)
			(xy 376.659712 -286.828048) (xy 376.606562 -286.832032) (xy 376.553412 -286.828048) (xy 376.50145 -286.816188)
			(xy 376.451836 -286.796716) (xy 376.405678 -286.770067) (xy 376.364007 -286.736836) (xy 376.327755 -286.697765)
			(xy 376.297731 -286.653728) (xy 376.274605 -286.605707) (xy 376.258895 -286.554777) (xy 376.250952 -286.502073)
			(xy 376.022626 -286.502073) (xy 376.014683 -286.554777) (xy 375.998973 -286.605707) (xy 375.975847 -286.653728)
			(xy 375.945823 -286.697765) (xy 375.909571 -286.736836) (xy 375.8679 -286.770067) (xy 375.821742 -286.796716)
			(xy 375.772128 -286.816188) (xy 375.720166 -286.828048) (xy 375.667016 -286.832032) (xy 375.613866 -286.828048)
			(xy 375.561904 -286.816188) (xy 375.51229 -286.796716) (xy 375.466132 -286.770067) (xy 375.424461 -286.736836)
			(xy 375.388209 -286.697765) (xy 375.358185 -286.653728) (xy 375.335059 -286.605707) (xy 375.319349 -286.554777)
			(xy 375.311406 -286.502073) (xy 375.310908 -286.475424) (xy 375.08307 -286.475424) (xy 375.082572 -286.502073)
			(xy 375.074629 -286.554777) (xy 375.058919 -286.605707) (xy 375.035793 -286.653728) (xy 375.005769 -286.697765)
			(xy 374.969517 -286.736836) (xy 374.927846 -286.770067) (xy 374.881688 -286.796716) (xy 374.832074 -286.816188)
			(xy 374.780112 -286.828048) (xy 374.726962 -286.832032) (xy 374.673812 -286.828048) (xy 374.62185 -286.816188)
			(xy 374.572236 -286.796716) (xy 374.526078 -286.770067) (xy 374.484407 -286.736836) (xy 374.448155 -286.697765)
			(xy 374.418131 -286.653728) (xy 374.395005 -286.605707) (xy 374.379295 -286.554777) (xy 374.371352 -286.502073)
			(xy 374.143026 -286.502073) (xy 374.135083 -286.554777) (xy 374.119373 -286.605707) (xy 374.096247 -286.653728)
			(xy 374.066223 -286.697765) (xy 374.029971 -286.736836) (xy 373.9883 -286.770067) (xy 373.942142 -286.796716)
			(xy 373.892528 -286.816188) (xy 373.840566 -286.828048) (xy 373.787416 -286.832032) (xy 373.734266 -286.828048)
			(xy 373.682304 -286.816188) (xy 373.63269 -286.796716) (xy 373.586532 -286.770067) (xy 373.544861 -286.736836)
			(xy 373.508609 -286.697765) (xy 373.478585 -286.653728) (xy 373.455459 -286.605707) (xy 373.439749 -286.554777)
			(xy 373.431806 -286.502073) (xy 373.431308 -286.475424) (xy 373.20347 -286.475424) (xy 373.202972 -286.502073)
			(xy 373.195029 -286.554777) (xy 373.179319 -286.605707) (xy 373.156193 -286.653728) (xy 373.126169 -286.697765)
			(xy 373.089917 -286.736836) (xy 373.048246 -286.770067) (xy 373.002088 -286.796716) (xy 372.952474 -286.816188)
			(xy 372.900512 -286.828048) (xy 372.847362 -286.832032) (xy 372.794212 -286.828048) (xy 372.74225 -286.816188)
			(xy 372.692636 -286.796716) (xy 372.646478 -286.770067) (xy 372.604807 -286.736836) (xy 372.568555 -286.697765)
			(xy 372.538531 -286.653728) (xy 372.515405 -286.605707) (xy 372.499695 -286.554777) (xy 372.491752 -286.502073)
			(xy 372.263426 -286.502073) (xy 372.255483 -286.554777) (xy 372.239773 -286.605707) (xy 372.216647 -286.653728)
			(xy 372.186623 -286.697765) (xy 372.150371 -286.736836) (xy 372.1087 -286.770067) (xy 372.062542 -286.796716)
			(xy 372.012928 -286.816188) (xy 371.960966 -286.828048) (xy 371.907816 -286.832032) (xy 371.854666 -286.828048)
			(xy 371.802704 -286.816188) (xy 371.75309 -286.796716) (xy 371.706932 -286.770067) (xy 371.665261 -286.736836)
			(xy 371.629009 -286.697765) (xy 371.598985 -286.653728) (xy 371.575859 -286.605707) (xy 371.560149 -286.554777)
			(xy 371.552206 -286.502073) (xy 371.551708 -286.475424) (xy 371.32387 -286.475424) (xy 371.323372 -286.502073)
			(xy 371.315429 -286.554777) (xy 371.299719 -286.605707) (xy 371.276593 -286.653728) (xy 371.246569 -286.697765)
			(xy 371.210317 -286.736836) (xy 371.168646 -286.770067) (xy 371.122488 -286.796716) (xy 371.072874 -286.816188)
			(xy 371.020912 -286.828048) (xy 370.967762 -286.832032) (xy 370.914612 -286.828048) (xy 370.86265 -286.816188)
			(xy 370.813036 -286.796716) (xy 370.766878 -286.770067) (xy 370.725207 -286.736836) (xy 370.688955 -286.697765)
			(xy 370.658931 -286.653728) (xy 370.635805 -286.605707) (xy 370.620095 -286.554777) (xy 370.612152 -286.502073)
			(xy 370.383826 -286.502073) (xy 370.375883 -286.554777) (xy 370.360173 -286.605707) (xy 370.337047 -286.653728)
			(xy 370.307023 -286.697765) (xy 370.270771 -286.736836) (xy 370.2291 -286.770067) (xy 370.182942 -286.796716)
			(xy 370.133328 -286.816188) (xy 370.081366 -286.828048) (xy 370.028216 -286.832032) (xy 369.975066 -286.828048)
			(xy 369.923104 -286.816188) (xy 369.87349 -286.796716) (xy 369.827332 -286.770067) (xy 369.785661 -286.736836)
			(xy 369.749409 -286.697765) (xy 369.719385 -286.653728) (xy 369.696259 -286.605707) (xy 369.680549 -286.554777)
			(xy 369.672606 -286.502073) (xy 369.672108 -286.475424) (xy 369.44427 -286.475424) (xy 369.443772 -286.502073)
			(xy 369.435829 -286.554777) (xy 369.420119 -286.605707) (xy 369.396993 -286.653728) (xy 369.366969 -286.697765)
			(xy 369.330717 -286.736836) (xy 369.289046 -286.770067) (xy 369.242888 -286.796716) (xy 369.193274 -286.816188)
			(xy 369.141312 -286.828048) (xy 369.088162 -286.832032) (xy 369.035012 -286.828048) (xy 368.98305 -286.816188)
			(xy 368.933436 -286.796716) (xy 368.887278 -286.770067) (xy 368.845607 -286.736836) (xy 368.809355 -286.697765)
			(xy 368.779331 -286.653728) (xy 368.756205 -286.605707) (xy 368.740495 -286.554777) (xy 368.732552 -286.502073)
			(xy 368.504226 -286.502073) (xy 368.504199 -286.503544) (xy 368.495369 -286.559085) (xy 368.477917 -286.612547)
			(xy 368.452277 -286.662601) (xy 368.419086 -286.708002) (xy 368.379171 -286.747619) (xy 368.333523 -286.780469)
			(xy 368.283279 -286.805734) (xy 368.229687 -286.822785) (xy 368.201956 -286.827468) (xy 368.188103 -286.829973)
			(xy 368.162446 -286.841536) (xy 368.140923 -286.859666) (xy 368.125171 -286.882986) (xy 368.116387 -286.909722)
			(xy 368.11524 -286.937841) (xy 368.121817 -286.965203) (xy 368.135618 -286.989728) (xy 368.145314 -286.999934)
			(xy 368.20348 -287.0581) (xy 368.213583 -287.067571) (xy 368.23768 -287.08119) (xy 368.264553 -287.087822)
			(xy 368.29222 -287.086975) (xy 368.318638 -287.078714) (xy 368.341858 -287.063647) (xy 368.351308 -287.053528)
			(xy 368.368288 -287.034955) (xy 368.406575 -287.002301) (xy 368.449078 -286.975362) (xy 368.494951 -286.954676)
			(xy 368.54328 -286.940655) (xy 368.593101 -286.933579) (xy 368.618262 -286.933132) (xy 368.646248 -286.93365)
			(xy 368.701532 -286.942401) (xy 368.754766 -286.959694) (xy 368.804638 -286.985103) (xy 368.849921 -287.018002)
			(xy 368.8895 -287.05758) (xy 368.922398 -287.102863) (xy 368.947807 -287.152736) (xy 368.965099 -287.20597)
			(xy 368.97385 -287.261254) (xy 368.97437 -287.28924) (xy 368.973934 -287.3144) (xy 368.973722 -287.315889)
			(xy 369.202452 -287.315889) (xy 369.202452 -287.262591) (xy 369.210395 -287.209887) (xy 369.226105 -287.158957)
			(xy 369.249231 -287.110936) (xy 369.279255 -287.066899) (xy 369.315507 -287.027828) (xy 369.357178 -286.994597)
			(xy 369.403336 -286.967948) (xy 369.45295 -286.948476) (xy 369.504912 -286.936616) (xy 369.558062 -286.932633)
			(xy 369.611212 -286.936616) (xy 369.663174 -286.948476) (xy 369.712788 -286.967948) (xy 369.758946 -286.994597)
			(xy 369.800617 -287.027828) (xy 369.836869 -287.066899) (xy 369.866893 -287.110936) (xy 369.890019 -287.158957)
			(xy 369.905729 -287.209887) (xy 369.913672 -287.262591) (xy 369.91417 -287.28924) (xy 369.913672 -287.315889)
			(xy 370.142252 -287.315889) (xy 370.142252 -287.262591) (xy 370.150195 -287.209887) (xy 370.165905 -287.158957)
			(xy 370.189031 -287.110936) (xy 370.219055 -287.066899) (xy 370.255307 -287.027828) (xy 370.296978 -286.994597)
			(xy 370.343136 -286.967948) (xy 370.39275 -286.948476) (xy 370.444712 -286.936616) (xy 370.497862 -286.932633)
			(xy 370.551012 -286.936616) (xy 370.602974 -286.948476) (xy 370.652588 -286.967948) (xy 370.698746 -286.994597)
			(xy 370.740417 -287.027828) (xy 370.776669 -287.066899) (xy 370.806693 -287.110936) (xy 370.829819 -287.158957)
			(xy 370.845529 -287.209887) (xy 370.853472 -287.262591) (xy 370.85397 -287.28924) (xy 370.853472 -287.315889)
			(xy 371.082052 -287.315889) (xy 371.082052 -287.262591) (xy 371.089995 -287.209887) (xy 371.105705 -287.158957)
			(xy 371.128831 -287.110936) (xy 371.158855 -287.066899) (xy 371.195107 -287.027828) (xy 371.236778 -286.994597)
			(xy 371.282936 -286.967948) (xy 371.33255 -286.948476) (xy 371.384512 -286.936616) (xy 371.437662 -286.932633)
			(xy 371.490812 -286.936616) (xy 371.542774 -286.948476) (xy 371.592388 -286.967948) (xy 371.638546 -286.994597)
			(xy 371.680217 -287.027828) (xy 371.716469 -287.066899) (xy 371.746493 -287.110936) (xy 371.769619 -287.158957)
			(xy 371.785329 -287.209887) (xy 371.793272 -287.262591) (xy 371.79377 -287.28924) (xy 371.793272 -287.315889)
			(xy 372.021852 -287.315889) (xy 372.021852 -287.262591) (xy 372.029795 -287.209887) (xy 372.045505 -287.158957)
			(xy 372.068631 -287.110936) (xy 372.098655 -287.066899) (xy 372.134907 -287.027828) (xy 372.176578 -286.994597)
			(xy 372.222736 -286.967948) (xy 372.27235 -286.948476) (xy 372.324312 -286.936616) (xy 372.377462 -286.932633)
			(xy 372.430612 -286.936616) (xy 372.482574 -286.948476) (xy 372.532188 -286.967948) (xy 372.578346 -286.994597)
			(xy 372.620017 -287.027828) (xy 372.656269 -287.066899) (xy 372.686293 -287.110936) (xy 372.709419 -287.158957)
			(xy 372.725129 -287.209887) (xy 372.733072 -287.262591) (xy 372.73357 -287.28924) (xy 372.733072 -287.315889)
			(xy 372.961652 -287.315889) (xy 372.961652 -287.262591) (xy 372.969595 -287.209887) (xy 372.985305 -287.158957)
			(xy 373.008431 -287.110936) (xy 373.038455 -287.066899) (xy 373.074707 -287.027828) (xy 373.116378 -286.994597)
			(xy 373.162536 -286.967948) (xy 373.21215 -286.948476) (xy 373.264112 -286.936616) (xy 373.317262 -286.932633)
			(xy 373.370412 -286.936616) (xy 373.422374 -286.948476) (xy 373.471988 -286.967948) (xy 373.518146 -286.994597)
			(xy 373.559817 -287.027828) (xy 373.596069 -287.066899) (xy 373.626093 -287.110936) (xy 373.649219 -287.158957)
			(xy 373.664929 -287.209887) (xy 373.672872 -287.262591) (xy 373.67337 -287.28924) (xy 373.672872 -287.315889)
			(xy 373.901452 -287.315889) (xy 373.901452 -287.262591) (xy 373.909395 -287.209887) (xy 373.925105 -287.158957)
			(xy 373.948231 -287.110936) (xy 373.978255 -287.066899) (xy 374.014507 -287.027828) (xy 374.056178 -286.994597)
			(xy 374.102336 -286.967948) (xy 374.15195 -286.948476) (xy 374.203912 -286.936616) (xy 374.257062 -286.932633)
			(xy 374.310212 -286.936616) (xy 374.362174 -286.948476) (xy 374.411788 -286.967948) (xy 374.457946 -286.994597)
			(xy 374.499617 -287.027828) (xy 374.535869 -287.066899) (xy 374.565893 -287.110936) (xy 374.589019 -287.158957)
			(xy 374.604729 -287.209887) (xy 374.612672 -287.262591) (xy 374.61317 -287.28924) (xy 374.612672 -287.315889)
			(xy 374.841252 -287.315889) (xy 374.841252 -287.262591) (xy 374.849195 -287.209887) (xy 374.864905 -287.158957)
			(xy 374.888031 -287.110936) (xy 374.918055 -287.066899) (xy 374.954307 -287.027828) (xy 374.995978 -286.994597)
			(xy 375.042136 -286.967948) (xy 375.09175 -286.948476) (xy 375.143712 -286.936616) (xy 375.196862 -286.932633)
			(xy 375.250012 -286.936616) (xy 375.301974 -286.948476) (xy 375.351588 -286.967948) (xy 375.397746 -286.994597)
			(xy 375.439417 -287.027828) (xy 375.475669 -287.066899) (xy 375.505693 -287.110936) (xy 375.528819 -287.158957)
			(xy 375.544529 -287.209887) (xy 375.552472 -287.262591) (xy 375.55297 -287.28924) (xy 375.552472 -287.315889)
			(xy 375.781052 -287.315889) (xy 375.781052 -287.262591) (xy 375.788995 -287.209887) (xy 375.804705 -287.158957)
			(xy 375.827831 -287.110936) (xy 375.857855 -287.066899) (xy 375.894107 -287.027828) (xy 375.935778 -286.994597)
			(xy 375.981936 -286.967948) (xy 376.03155 -286.948476) (xy 376.083512 -286.936616) (xy 376.136662 -286.932633)
			(xy 376.189812 -286.936616) (xy 376.241774 -286.948476) (xy 376.291388 -286.967948) (xy 376.337546 -286.994597)
			(xy 376.379217 -287.027828) (xy 376.415469 -287.066899) (xy 376.445493 -287.110936) (xy 376.468619 -287.158957)
			(xy 376.484329 -287.209887) (xy 376.492272 -287.262591) (xy 376.49277 -287.28924) (xy 376.492272 -287.315889)
			(xy 376.720852 -287.315889) (xy 376.720852 -287.262591) (xy 376.728795 -287.209887) (xy 376.744505 -287.158957)
			(xy 376.767631 -287.110936) (xy 376.797655 -287.066899) (xy 376.833907 -287.027828) (xy 376.875578 -286.994597)
			(xy 376.921736 -286.967948) (xy 376.97135 -286.948476) (xy 377.023312 -286.936616) (xy 377.076462 -286.932633)
			(xy 377.129612 -286.936616) (xy 377.181574 -286.948476) (xy 377.231188 -286.967948) (xy 377.277346 -286.994597)
			(xy 377.319017 -287.027828) (xy 377.355269 -287.066899) (xy 377.385293 -287.110936) (xy 377.408419 -287.158957)
			(xy 377.424129 -287.209887) (xy 377.432072 -287.262591) (xy 377.43257 -287.28924) (xy 377.432072 -287.315889)
			(xy 377.660652 -287.315889) (xy 377.660652 -287.262591) (xy 377.668595 -287.209887) (xy 377.684305 -287.158957)
			(xy 377.707431 -287.110936) (xy 377.737455 -287.066899) (xy 377.773707 -287.027828) (xy 377.815378 -286.994597)
			(xy 377.861536 -286.967948) (xy 377.91115 -286.948476) (xy 377.963112 -286.936616) (xy 378.016262 -286.932633)
			(xy 378.069412 -286.936616) (xy 378.121374 -286.948476) (xy 378.170988 -286.967948) (xy 378.217146 -286.994597)
			(xy 378.258817 -287.027828) (xy 378.295069 -287.066899) (xy 378.325093 -287.110936) (xy 378.348219 -287.158957)
			(xy 378.363929 -287.209887) (xy 378.371872 -287.262591) (xy 378.37237 -287.28924) (xy 378.371872 -287.315889)
			(xy 378.600452 -287.315889) (xy 378.600452 -287.262591) (xy 378.608395 -287.209887) (xy 378.624105 -287.158957)
			(xy 378.647231 -287.110936) (xy 378.677255 -287.066899) (xy 378.713507 -287.027828) (xy 378.755178 -286.994597)
			(xy 378.801336 -286.967948) (xy 378.85095 -286.948476) (xy 378.902912 -286.936616) (xy 378.956062 -286.932633)
			(xy 379.009212 -286.936616) (xy 379.061174 -286.948476) (xy 379.110788 -286.967948) (xy 379.156946 -286.994597)
			(xy 379.198617 -287.027828) (xy 379.234869 -287.066899) (xy 379.264893 -287.110936) (xy 379.288019 -287.158957)
			(xy 379.303729 -287.209887) (xy 379.311672 -287.262591) (xy 379.31217 -287.28924) (xy 379.311672 -287.315889)
			(xy 379.540252 -287.315889) (xy 379.540252 -287.262591) (xy 379.548195 -287.209887) (xy 379.563905 -287.158957)
			(xy 379.587031 -287.110936) (xy 379.617055 -287.066899) (xy 379.653307 -287.027828) (xy 379.694978 -286.994597)
			(xy 379.741136 -286.967948) (xy 379.79075 -286.948476) (xy 379.842712 -286.936616) (xy 379.895862 -286.932633)
			(xy 379.949012 -286.936616) (xy 380.000974 -286.948476) (xy 380.050588 -286.967948) (xy 380.096746 -286.994597)
			(xy 380.138417 -287.027828) (xy 380.174669 -287.066899) (xy 380.204693 -287.110936) (xy 380.227819 -287.158957)
			(xy 380.243529 -287.209887) (xy 380.251472 -287.262591) (xy 380.25197 -287.28924) (xy 380.251472 -287.315889)
			(xy 380.480052 -287.315889) (xy 380.480052 -287.262591) (xy 380.487995 -287.209887) (xy 380.503705 -287.158957)
			(xy 380.526831 -287.110936) (xy 380.556855 -287.066899) (xy 380.593107 -287.027828) (xy 380.634778 -286.994597)
			(xy 380.680936 -286.967948) (xy 380.73055 -286.948476) (xy 380.782512 -286.936616) (xy 380.835662 -286.932633)
			(xy 380.888812 -286.936616) (xy 380.940774 -286.948476) (xy 380.990388 -286.967948) (xy 381.036546 -286.994597)
			(xy 381.078217 -287.027828) (xy 381.114469 -287.066899) (xy 381.144493 -287.110936) (xy 381.167619 -287.158957)
			(xy 381.183329 -287.209887) (xy 381.191272 -287.262591) (xy 381.19177 -287.28924) (xy 381.191272 -287.315889)
			(xy 381.419852 -287.315889) (xy 381.419852 -287.262591) (xy 381.427795 -287.209887) (xy 381.443505 -287.158957)
			(xy 381.466631 -287.110936) (xy 381.496655 -287.066899) (xy 381.532907 -287.027828) (xy 381.574578 -286.994597)
			(xy 381.620736 -286.967948) (xy 381.67035 -286.948476) (xy 381.722312 -286.936616) (xy 381.775462 -286.932633)
			(xy 381.828612 -286.936616) (xy 381.880574 -286.948476) (xy 381.930188 -286.967948) (xy 381.976346 -286.994597)
			(xy 382.018017 -287.027828) (xy 382.054269 -287.066899) (xy 382.084293 -287.110936) (xy 382.107419 -287.158957)
			(xy 382.123129 -287.209887) (xy 382.131072 -287.262591) (xy 382.13157 -287.28924) (xy 382.131072 -287.315889)
			(xy 382.359652 -287.315889) (xy 382.359652 -287.262591) (xy 382.367595 -287.209887) (xy 382.383305 -287.158957)
			(xy 382.406431 -287.110936) (xy 382.436455 -287.066899) (xy 382.472707 -287.027828) (xy 382.514378 -286.994597)
			(xy 382.560536 -286.967948) (xy 382.61015 -286.948476) (xy 382.662112 -286.936616) (xy 382.715262 -286.932633)
			(xy 382.768412 -286.936616) (xy 382.820374 -286.948476) (xy 382.869988 -286.967948) (xy 382.916146 -286.994597)
			(xy 382.957817 -287.027828) (xy 382.994069 -287.066899) (xy 383.024093 -287.110936) (xy 383.047219 -287.158957)
			(xy 383.062929 -287.209887) (xy 383.070872 -287.262591) (xy 383.07137 -287.28924) (xy 383.070872 -287.315889)
			(xy 383.299452 -287.315889) (xy 383.299452 -287.262591) (xy 383.307395 -287.209887) (xy 383.323105 -287.158957)
			(xy 383.346231 -287.110936) (xy 383.376255 -287.066899) (xy 383.412507 -287.027828) (xy 383.454178 -286.994597)
			(xy 383.500336 -286.967948) (xy 383.54995 -286.948476) (xy 383.601912 -286.936616) (xy 383.655062 -286.932633)
			(xy 383.708212 -286.936616) (xy 383.760174 -286.948476) (xy 383.809788 -286.967948) (xy 383.855946 -286.994597)
			(xy 383.897617 -287.027828) (xy 383.933869 -287.066899) (xy 383.963893 -287.110936) (xy 383.987019 -287.158957)
			(xy 384.002729 -287.209887) (xy 384.010672 -287.262591) (xy 384.01117 -287.28924) (xy 384.010677 -287.315635)
			(xy 384.239506 -287.315635) (xy 384.239506 -287.262337) (xy 384.247449 -287.209633) (xy 384.263159 -287.158703)
			(xy 384.286285 -287.110682) (xy 384.316309 -287.066645) (xy 384.352561 -287.027574) (xy 384.394232 -286.994343)
			(xy 384.44039 -286.967694) (xy 384.490004 -286.948222) (xy 384.541966 -286.936362) (xy 384.595116 -286.932379)
			(xy 384.648266 -286.936362) (xy 384.700228 -286.948222) (xy 384.749842 -286.967694) (xy 384.796 -286.994343)
			(xy 384.837671 -287.027574) (xy 384.873923 -287.066645) (xy 384.903947 -287.110682) (xy 384.927073 -287.158703)
			(xy 384.942783 -287.209633) (xy 384.950726 -287.262337) (xy 384.951224 -287.288986) (xy 384.950726 -287.315635)
			(xy 384.942783 -287.368339) (xy 384.927073 -287.419269) (xy 384.915698 -287.442889) (xy 385.179306 -287.442889)
			(xy 385.179306 -287.389591) (xy 385.187249 -287.336887) (xy 385.202959 -287.285957) (xy 385.226085 -287.237936)
			(xy 385.256109 -287.193899) (xy 385.292361 -287.154828) (xy 385.334032 -287.121597) (xy 385.38019 -287.094948)
			(xy 385.429804 -287.075476) (xy 385.481766 -287.063616) (xy 385.534916 -287.059633) (xy 385.588066 -287.063616)
			(xy 385.640028 -287.075476) (xy 385.689642 -287.094948) (xy 385.7358 -287.121597) (xy 385.777471 -287.154828)
			(xy 385.813723 -287.193899) (xy 385.843747 -287.237936) (xy 385.866873 -287.285957) (xy 385.882583 -287.336887)
			(xy 385.890526 -287.389591) (xy 385.891024 -287.41624) (xy 385.890526 -287.442889) (xy 385.882583 -287.495593)
			(xy 385.866873 -287.546523) (xy 385.843747 -287.594544) (xy 385.813723 -287.638581) (xy 385.777471 -287.677652)
			(xy 385.7358 -287.710883) (xy 385.689642 -287.737532) (xy 385.640028 -287.757004) (xy 385.588066 -287.768864)
			(xy 385.534916 -287.772848) (xy 385.481766 -287.768864) (xy 385.429804 -287.757004) (xy 385.38019 -287.737532)
			(xy 385.334032 -287.710883) (xy 385.292361 -287.677652) (xy 385.256109 -287.638581) (xy 385.226085 -287.594544)
			(xy 385.202959 -287.546523) (xy 385.187249 -287.495593) (xy 385.179306 -287.442889) (xy 384.915698 -287.442889)
			(xy 384.903947 -287.46729) (xy 384.873923 -287.511327) (xy 384.837671 -287.550398) (xy 384.796 -287.583629)
			(xy 384.749842 -287.610278) (xy 384.700228 -287.62975) (xy 384.648266 -287.64161) (xy 384.595116 -287.645594)
			(xy 384.541966 -287.64161) (xy 384.490004 -287.62975) (xy 384.44039 -287.610278) (xy 384.394232 -287.583629)
			(xy 384.352561 -287.550398) (xy 384.316309 -287.511327) (xy 384.286285 -287.46729) (xy 384.263159 -287.419269)
			(xy 384.247449 -287.368339) (xy 384.239506 -287.315635) (xy 384.010677 -287.315635) (xy 384.010672 -287.315889)
			(xy 384.002729 -287.368593) (xy 383.987019 -287.419523) (xy 383.963893 -287.467544) (xy 383.933869 -287.511581)
			(xy 383.897617 -287.550652) (xy 383.855946 -287.583883) (xy 383.809788 -287.610532) (xy 383.760174 -287.630004)
			(xy 383.708212 -287.641864) (xy 383.655062 -287.645848) (xy 383.601912 -287.641864) (xy 383.54995 -287.630004)
			(xy 383.500336 -287.610532) (xy 383.454178 -287.583883) (xy 383.412507 -287.550652) (xy 383.376255 -287.511581)
			(xy 383.346231 -287.467544) (xy 383.323105 -287.419523) (xy 383.307395 -287.368593) (xy 383.299452 -287.315889)
			(xy 383.070872 -287.315889) (xy 383.062929 -287.368593) (xy 383.047219 -287.419523) (xy 383.024093 -287.467544)
			(xy 382.994069 -287.511581) (xy 382.957817 -287.550652) (xy 382.916146 -287.583883) (xy 382.869988 -287.610532)
			(xy 382.820374 -287.630004) (xy 382.768412 -287.641864) (xy 382.715262 -287.645848) (xy 382.662112 -287.641864)
			(xy 382.61015 -287.630004) (xy 382.560536 -287.610532) (xy 382.514378 -287.583883) (xy 382.472707 -287.550652)
			(xy 382.436455 -287.511581) (xy 382.406431 -287.467544) (xy 382.383305 -287.419523) (xy 382.367595 -287.368593)
			(xy 382.359652 -287.315889) (xy 382.131072 -287.315889) (xy 382.123129 -287.368593) (xy 382.107419 -287.419523)
			(xy 382.084293 -287.467544) (xy 382.054269 -287.511581) (xy 382.018017 -287.550652) (xy 381.976346 -287.583883)
			(xy 381.930188 -287.610532) (xy 381.880574 -287.630004) (xy 381.828612 -287.641864) (xy 381.775462 -287.645848)
			(xy 381.722312 -287.641864) (xy 381.67035 -287.630004) (xy 381.620736 -287.610532) (xy 381.574578 -287.583883)
			(xy 381.532907 -287.550652) (xy 381.496655 -287.511581) (xy 381.466631 -287.467544) (xy 381.443505 -287.419523)
			(xy 381.427795 -287.368593) (xy 381.419852 -287.315889) (xy 381.191272 -287.315889) (xy 381.183329 -287.368593)
			(xy 381.167619 -287.419523) (xy 381.144493 -287.467544) (xy 381.114469 -287.511581) (xy 381.078217 -287.550652)
			(xy 381.036546 -287.583883) (xy 380.990388 -287.610532) (xy 380.940774 -287.630004) (xy 380.888812 -287.641864)
			(xy 380.835662 -287.645848) (xy 380.782512 -287.641864) (xy 380.73055 -287.630004) (xy 380.680936 -287.610532)
			(xy 380.634778 -287.583883) (xy 380.593107 -287.550652) (xy 380.556855 -287.511581) (xy 380.526831 -287.467544)
			(xy 380.503705 -287.419523) (xy 380.487995 -287.368593) (xy 380.480052 -287.315889) (xy 380.251472 -287.315889)
			(xy 380.243529 -287.368593) (xy 380.227819 -287.419523) (xy 380.204693 -287.467544) (xy 380.174669 -287.511581)
			(xy 380.138417 -287.550652) (xy 380.096746 -287.583883) (xy 380.050588 -287.610532) (xy 380.000974 -287.630004)
			(xy 379.949012 -287.641864) (xy 379.895862 -287.645848) (xy 379.842712 -287.641864) (xy 379.79075 -287.630004)
			(xy 379.741136 -287.610532) (xy 379.694978 -287.583883) (xy 379.653307 -287.550652) (xy 379.617055 -287.511581)
			(xy 379.587031 -287.467544) (xy 379.563905 -287.419523) (xy 379.548195 -287.368593) (xy 379.540252 -287.315889)
			(xy 379.311672 -287.315889) (xy 379.303729 -287.368593) (xy 379.288019 -287.419523) (xy 379.264893 -287.467544)
			(xy 379.234869 -287.511581) (xy 379.198617 -287.550652) (xy 379.156946 -287.583883) (xy 379.110788 -287.610532)
			(xy 379.061174 -287.630004) (xy 379.009212 -287.641864) (xy 378.956062 -287.645848) (xy 378.902912 -287.641864)
			(xy 378.85095 -287.630004) (xy 378.801336 -287.610532) (xy 378.755178 -287.583883) (xy 378.713507 -287.550652)
			(xy 378.677255 -287.511581) (xy 378.647231 -287.467544) (xy 378.624105 -287.419523) (xy 378.608395 -287.368593)
			(xy 378.600452 -287.315889) (xy 378.371872 -287.315889) (xy 378.363929 -287.368593) (xy 378.348219 -287.419523)
			(xy 378.325093 -287.467544) (xy 378.295069 -287.511581) (xy 378.258817 -287.550652) (xy 378.217146 -287.583883)
			(xy 378.170988 -287.610532) (xy 378.121374 -287.630004) (xy 378.069412 -287.641864) (xy 378.016262 -287.645848)
			(xy 377.963112 -287.641864) (xy 377.91115 -287.630004) (xy 377.861536 -287.610532) (xy 377.815378 -287.583883)
			(xy 377.773707 -287.550652) (xy 377.737455 -287.511581) (xy 377.707431 -287.467544) (xy 377.684305 -287.419523)
			(xy 377.668595 -287.368593) (xy 377.660652 -287.315889) (xy 377.432072 -287.315889) (xy 377.424129 -287.368593)
			(xy 377.408419 -287.419523) (xy 377.385293 -287.467544) (xy 377.355269 -287.511581) (xy 377.319017 -287.550652)
			(xy 377.277346 -287.583883) (xy 377.231188 -287.610532) (xy 377.181574 -287.630004) (xy 377.129612 -287.641864)
			(xy 377.076462 -287.645848) (xy 377.023312 -287.641864) (xy 376.97135 -287.630004) (xy 376.921736 -287.610532)
			(xy 376.875578 -287.583883) (xy 376.833907 -287.550652) (xy 376.797655 -287.511581) (xy 376.767631 -287.467544)
			(xy 376.744505 -287.419523) (xy 376.728795 -287.368593) (xy 376.720852 -287.315889) (xy 376.492272 -287.315889)
			(xy 376.484329 -287.368593) (xy 376.468619 -287.419523) (xy 376.445493 -287.467544) (xy 376.415469 -287.511581)
			(xy 376.379217 -287.550652) (xy 376.337546 -287.583883) (xy 376.291388 -287.610532) (xy 376.241774 -287.630004)
			(xy 376.189812 -287.641864) (xy 376.136662 -287.645848) (xy 376.083512 -287.641864) (xy 376.03155 -287.630004)
			(xy 375.981936 -287.610532) (xy 375.935778 -287.583883) (xy 375.894107 -287.550652) (xy 375.857855 -287.511581)
			(xy 375.827831 -287.467544) (xy 375.804705 -287.419523) (xy 375.788995 -287.368593) (xy 375.781052 -287.315889)
			(xy 375.552472 -287.315889) (xy 375.544529 -287.368593) (xy 375.528819 -287.419523) (xy 375.505693 -287.467544)
			(xy 375.475669 -287.511581) (xy 375.439417 -287.550652) (xy 375.397746 -287.583883) (xy 375.351588 -287.610532)
			(xy 375.301974 -287.630004) (xy 375.250012 -287.641864) (xy 375.196862 -287.645848) (xy 375.143712 -287.641864)
			(xy 375.09175 -287.630004) (xy 375.042136 -287.610532) (xy 374.995978 -287.583883) (xy 374.954307 -287.550652)
			(xy 374.918055 -287.511581) (xy 374.888031 -287.467544) (xy 374.864905 -287.419523) (xy 374.849195 -287.368593)
			(xy 374.841252 -287.315889) (xy 374.612672 -287.315889) (xy 374.604729 -287.368593) (xy 374.589019 -287.419523)
			(xy 374.565893 -287.467544) (xy 374.535869 -287.511581) (xy 374.499617 -287.550652) (xy 374.457946 -287.583883)
			(xy 374.411788 -287.610532) (xy 374.362174 -287.630004) (xy 374.310212 -287.641864) (xy 374.257062 -287.645848)
			(xy 374.203912 -287.641864) (xy 374.15195 -287.630004) (xy 374.102336 -287.610532) (xy 374.056178 -287.583883)
			(xy 374.014507 -287.550652) (xy 373.978255 -287.511581) (xy 373.948231 -287.467544) (xy 373.925105 -287.419523)
			(xy 373.909395 -287.368593) (xy 373.901452 -287.315889) (xy 373.672872 -287.315889) (xy 373.664929 -287.368593)
			(xy 373.649219 -287.419523) (xy 373.626093 -287.467544) (xy 373.596069 -287.511581) (xy 373.559817 -287.550652)
			(xy 373.518146 -287.583883) (xy 373.471988 -287.610532) (xy 373.422374 -287.630004) (xy 373.370412 -287.641864)
			(xy 373.317262 -287.645848) (xy 373.264112 -287.641864) (xy 373.21215 -287.630004) (xy 373.162536 -287.610532)
			(xy 373.116378 -287.583883) (xy 373.074707 -287.550652) (xy 373.038455 -287.511581) (xy 373.008431 -287.467544)
			(xy 372.985305 -287.419523) (xy 372.969595 -287.368593) (xy 372.961652 -287.315889) (xy 372.733072 -287.315889)
			(xy 372.725129 -287.368593) (xy 372.709419 -287.419523) (xy 372.686293 -287.467544) (xy 372.656269 -287.511581)
			(xy 372.620017 -287.550652) (xy 372.578346 -287.583883) (xy 372.532188 -287.610532) (xy 372.482574 -287.630004)
			(xy 372.430612 -287.641864) (xy 372.377462 -287.645848) (xy 372.324312 -287.641864) (xy 372.27235 -287.630004)
			(xy 372.222736 -287.610532) (xy 372.176578 -287.583883) (xy 372.134907 -287.550652) (xy 372.098655 -287.511581)
			(xy 372.068631 -287.467544) (xy 372.045505 -287.419523) (xy 372.029795 -287.368593) (xy 372.021852 -287.315889)
			(xy 371.793272 -287.315889) (xy 371.785329 -287.368593) (xy 371.769619 -287.419523) (xy 371.746493 -287.467544)
			(xy 371.716469 -287.511581) (xy 371.680217 -287.550652) (xy 371.638546 -287.583883) (xy 371.592388 -287.610532)
			(xy 371.542774 -287.630004) (xy 371.490812 -287.641864) (xy 371.437662 -287.645848) (xy 371.384512 -287.641864)
			(xy 371.33255 -287.630004) (xy 371.282936 -287.610532) (xy 371.236778 -287.583883) (xy 371.195107 -287.550652)
			(xy 371.158855 -287.511581) (xy 371.128831 -287.467544) (xy 371.105705 -287.419523) (xy 371.089995 -287.368593)
			(xy 371.082052 -287.315889) (xy 370.853472 -287.315889) (xy 370.845529 -287.368593) (xy 370.829819 -287.419523)
			(xy 370.806693 -287.467544) (xy 370.776669 -287.511581) (xy 370.740417 -287.550652) (xy 370.698746 -287.583883)
			(xy 370.652588 -287.610532) (xy 370.602974 -287.630004) (xy 370.551012 -287.641864) (xy 370.497862 -287.645848)
			(xy 370.444712 -287.641864) (xy 370.39275 -287.630004) (xy 370.343136 -287.610532) (xy 370.296978 -287.583883)
			(xy 370.255307 -287.550652) (xy 370.219055 -287.511581) (xy 370.189031 -287.467544) (xy 370.165905 -287.419523)
			(xy 370.150195 -287.368593) (xy 370.142252 -287.315889) (xy 369.913672 -287.315889) (xy 369.905729 -287.368593)
			(xy 369.890019 -287.419523) (xy 369.866893 -287.467544) (xy 369.836869 -287.511581) (xy 369.800617 -287.550652)
			(xy 369.758946 -287.583883) (xy 369.712788 -287.610532) (xy 369.663174 -287.630004) (xy 369.611212 -287.641864)
			(xy 369.558062 -287.645848) (xy 369.504912 -287.641864) (xy 369.45295 -287.630004) (xy 369.403336 -287.610532)
			(xy 369.357178 -287.583883) (xy 369.315507 -287.550652) (xy 369.279255 -287.511581) (xy 369.249231 -287.467544)
			(xy 369.226105 -287.419523) (xy 369.210395 -287.368593) (xy 369.202452 -287.315889) (xy 368.973722 -287.315889)
			(xy 368.966846 -287.364218) (xy 368.952816 -287.412542) (xy 368.932125 -287.458411) (xy 368.905184 -287.500911)
			(xy 368.872529 -287.539196) (xy 368.853974 -287.556194) (xy 368.843947 -287.565718) (xy 368.828955 -287.588942)
			(xy 368.820728 -287.615332) (xy 368.819868 -287.642961) (xy 368.826437 -287.669812) (xy 368.839957 -287.693923)
			(xy 368.849402 -287.704022) (xy 368.92865 -287.783016) (xy 368.959384 -287.771078) (xy 368.990443 -287.759806)
			(xy 369.055383 -287.747662) (xy 369.088416 -287.746948) (xy 369.1164 -287.747498) (xy 369.171677 -287.756255)
			(xy 369.224905 -287.77355) (xy 369.274772 -287.798959) (xy 369.320051 -287.831854) (xy 369.359628 -287.871427)
			(xy 369.392527 -287.916704) (xy 369.417939 -287.966569) (xy 369.435239 -288.019795) (xy 369.444 -288.075073)
			(xy 369.444524 -288.103056) (xy 369.443829 -288.136091) (xy 369.431687 -288.201035) (xy 369.420394 -288.232088)
			(xy 369.408456 -288.263076) (xy 369.903248 -288.757868)
		)
		(stroke
			(width 0)
			(type solid)
		)
		(fill yes)
		(layer "In15.Cu")
		(net "PVCCFA_EHV_FIVRA_CPU0")
	)
	(gr_poly
		(pts
			(xy 87.448136 -288.802318) (xy 87.45696 -288.777816) (xy 87.480752 -288.731493) (xy 87.511038 -288.689129)
			(xy 87.547171 -288.651628) (xy 87.588381 -288.619789) (xy 87.63379 -288.594293) (xy 87.682427 -288.575683)
			(xy 87.733257 -288.564356) (xy 87.785194 -288.560553) (xy 87.837131 -288.564356) (xy 87.887961 -288.575683)
			(xy 87.936598 -288.594293) (xy 87.982007 -288.619789) (xy 88.023217 -288.651628) (xy 88.05935 -288.689129)
			(xy 88.089636 -288.731493) (xy 88.113428 -288.777816) (xy 88.122252 -288.802318) (xy 88.133936 -288.836608)
			(xy 88.376506 -288.836608) (xy 88.38819 -288.802318) (xy 88.397818 -288.77575) (xy 88.424262 -288.725811)
			(xy 88.458256 -288.680672) (xy 88.498947 -288.641463) (xy 88.545316 -288.609167) (xy 88.596201 -288.584593)
			(xy 88.650326 -288.568357) (xy 88.678258 -288.564066) (xy 88.702896 -288.560764) (xy 88.875362 -288.26206)
			(xy 88.86571 -288.238946) (xy 88.857195 -288.217314) (xy 88.84521 -288.172396) (xy 88.83917 -288.126301)
			(xy 88.838786 -288.103056) (xy 88.839284 -288.076407) (xy 88.847227 -288.023703) (xy 88.862937 -287.972773)
			(xy 88.886063 -287.924752) (xy 88.916087 -287.880715) (xy 88.952339 -287.841644) (xy 88.99401 -287.808413)
			(xy 89.040168 -287.781764) (xy 89.089782 -287.762292) (xy 89.141744 -287.750432) (xy 89.194894 -287.746449)
			(xy 89.248044 -287.750432) (xy 89.300006 -287.762292) (xy 89.34962 -287.781764) (xy 89.395778 -287.808413)
			(xy 89.437449 -287.841644) (xy 89.473701 -287.880715) (xy 89.503725 -287.924752) (xy 89.526851 -287.972773)
			(xy 89.542561 -288.023703) (xy 89.550504 -288.076407) (xy 89.551002 -288.103056) (xy 89.550553 -288.12868)
			(xy 89.5432 -288.179399) (xy 89.528655 -288.228541) (xy 89.507217 -288.275091) (xy 89.479329 -288.318088)
			(xy 89.445567 -288.356644) (xy 89.406628 -288.389964) (xy 89.363316 -288.41736) (xy 89.316524 -288.438265)
			(xy 89.26722 -288.452249) (xy 89.241884 -288.456116) (xy 89.217246 -288.459418) (xy 89.04478 -288.758122)
			(xy 89.054432 -288.781236) (xy 89.062306 -288.802318) (xy 89.07399 -288.836608) (xy 89.316052 -288.836608)
			(xy 89.327736 -288.802318) (xy 89.33656 -288.777816) (xy 89.360352 -288.731493) (xy 89.390638 -288.689129)
			(xy 89.426771 -288.651628) (xy 89.467981 -288.619789) (xy 89.51339 -288.594293) (xy 89.562027 -288.575683)
			(xy 89.612857 -288.564356) (xy 89.664794 -288.560553) (xy 89.716731 -288.564356) (xy 89.767561 -288.575683)
			(xy 89.816198 -288.594293) (xy 89.861607 -288.619789) (xy 89.902817 -288.651628) (xy 89.93895 -288.689129)
			(xy 89.969236 -288.731493) (xy 89.993028 -288.777816) (xy 90.001852 -288.802318) (xy 90.013536 -288.836608)
			(xy 90.256106 -288.836608) (xy 90.26779 -288.802318) (xy 90.277418 -288.77575) (xy 90.303862 -288.725811)
			(xy 90.337856 -288.680672) (xy 90.378547 -288.641463) (xy 90.424916 -288.609167) (xy 90.475801 -288.584593)
			(xy 90.529926 -288.568357) (xy 90.557858 -288.564066) (xy 90.582496 -288.560764) (xy 90.754962 -288.26206)
			(xy 90.74531 -288.238946) (xy 90.736795 -288.217314) (xy 90.72481 -288.172396) (xy 90.71877 -288.126301)
			(xy 90.718386 -288.103056) (xy 90.718884 -288.076407) (xy 90.726827 -288.023703) (xy 90.742537 -287.972773)
			(xy 90.765663 -287.924752) (xy 90.795687 -287.880715) (xy 90.831939 -287.841644) (xy 90.87361 -287.808413)
			(xy 90.919768 -287.781764) (xy 90.969382 -287.762292) (xy 91.021344 -287.750432) (xy 91.074494 -287.746449)
			(xy 91.127644 -287.750432) (xy 91.179606 -287.762292) (xy 91.22922 -287.781764) (xy 91.275378 -287.808413)
			(xy 91.317049 -287.841644) (xy 91.353301 -287.880715) (xy 91.383325 -287.924752) (xy 91.406451 -287.972773)
			(xy 91.422161 -288.023703) (xy 91.430104 -288.076407) (xy 91.430602 -288.103056) (xy 91.430153 -288.12868)
			(xy 91.4228 -288.179399) (xy 91.408255 -288.228541) (xy 91.386817 -288.275091) (xy 91.358929 -288.318088)
			(xy 91.325167 -288.356644) (xy 91.286228 -288.389964) (xy 91.242916 -288.41736) (xy 91.196124 -288.438265)
			(xy 91.14682 -288.452249) (xy 91.121484 -288.456116) (xy 91.096846 -288.459418) (xy 90.92438 -288.758122)
			(xy 90.934032 -288.781236) (xy 90.941906 -288.802318) (xy 90.95359 -288.836608) (xy 91.195906 -288.836608)
			(xy 91.20759 -288.802318) (xy 91.216414 -288.777816) (xy 91.240206 -288.731493) (xy 91.270492 -288.689129)
			(xy 91.306625 -288.651628) (xy 91.347835 -288.619789) (xy 91.393244 -288.594293) (xy 91.441881 -288.575683)
			(xy 91.492711 -288.564356) (xy 91.544648 -288.560553) (xy 91.596585 -288.564356) (xy 91.647415 -288.575683)
			(xy 91.696052 -288.594293) (xy 91.741461 -288.619789) (xy 91.782671 -288.651628) (xy 91.818804 -288.689129)
			(xy 91.84909 -288.731493) (xy 91.872882 -288.777816) (xy 91.881706 -288.802318) (xy 91.89339 -288.836608)
			(xy 92.135706 -288.836608) (xy 92.14739 -288.802318) (xy 92.157018 -288.77575) (xy 92.183462 -288.725811)
			(xy 92.217456 -288.680672) (xy 92.258147 -288.641463) (xy 92.304516 -288.609167) (xy 92.355401 -288.584593)
			(xy 92.409526 -288.568357) (xy 92.437458 -288.564066) (xy 92.462096 -288.560764) (xy 92.634816 -288.26206)
			(xy 92.625164 -288.238946) (xy 92.616648 -288.217314) (xy 92.604662 -288.172396) (xy 92.59862 -288.126301)
			(xy 92.59824 -288.103056) (xy 92.598738 -288.076407) (xy 92.606681 -288.023703) (xy 92.622391 -287.972773)
			(xy 92.645517 -287.924752) (xy 92.675541 -287.880715) (xy 92.711793 -287.841644) (xy 92.753464 -287.808413)
			(xy 92.799622 -287.781764) (xy 92.849236 -287.762292) (xy 92.901198 -287.750432) (xy 92.954348 -287.746449)
			(xy 93.007498 -287.750432) (xy 93.05946 -287.762292) (xy 93.109074 -287.781764) (xy 93.155232 -287.808413)
			(xy 93.196903 -287.841644) (xy 93.233155 -287.880715) (xy 93.263179 -287.924752) (xy 93.286305 -287.972773)
			(xy 93.302015 -288.023703) (xy 93.309958 -288.076407) (xy 93.310456 -288.103056) (xy 93.310007 -288.128682)
			(xy 93.302655 -288.179403) (xy 93.28811 -288.228548) (xy 93.266673 -288.275101) (xy 93.238787 -288.318101)
			(xy 93.205026 -288.356662) (xy 93.166088 -288.389987) (xy 93.122776 -288.417388) (xy 93.075985 -288.4383)
			(xy 93.026681 -288.452292) (xy 93.001338 -288.456116) (xy 92.9767 -288.459418) (xy 92.80398 -288.758122)
			(xy 92.813632 -288.781236) (xy 92.821506 -288.802318) (xy 92.83319 -288.836608) (xy 93.075506 -288.836608)
			(xy 93.08719 -288.802318) (xy 93.096014 -288.777816) (xy 93.119806 -288.731493) (xy 93.150092 -288.689129)
			(xy 93.186225 -288.651628) (xy 93.227435 -288.619789) (xy 93.272844 -288.594293) (xy 93.321481 -288.575683)
			(xy 93.372311 -288.564356) (xy 93.424248 -288.560553) (xy 93.476185 -288.564356) (xy 93.527015 -288.575683)
			(xy 93.575652 -288.594293) (xy 93.621061 -288.619789) (xy 93.662271 -288.651628) (xy 93.698404 -288.689129)
			(xy 93.72869 -288.731493) (xy 93.752482 -288.777816) (xy 93.761306 -288.802318) (xy 93.77299 -288.836608)
			(xy 94.015306 -288.836608) (xy 94.02699 -288.802318) (xy 94.036618 -288.77575) (xy 94.063062 -288.725811)
			(xy 94.097056 -288.680672) (xy 94.137747 -288.641463) (xy 94.184116 -288.609167) (xy 94.235001 -288.584593)
			(xy 94.289126 -288.568357) (xy 94.317058 -288.564066) (xy 94.341696 -288.560764) (xy 94.514416 -288.26206)
			(xy 94.504764 -288.238946) (xy 94.496248 -288.217314) (xy 94.484262 -288.172396) (xy 94.47822 -288.126301)
			(xy 94.47784 -288.103056) (xy 94.478338 -288.076407) (xy 94.486281 -288.023703) (xy 94.501991 -287.972773)
			(xy 94.525117 -287.924752) (xy 94.555141 -287.880715) (xy 94.591393 -287.841644) (xy 94.633064 -287.808413)
			(xy 94.679222 -287.781764) (xy 94.728836 -287.762292) (xy 94.780798 -287.750432) (xy 94.833948 -287.746449)
			(xy 94.887098 -287.750432) (xy 94.93906 -287.762292) (xy 94.988674 -287.781764) (xy 95.034832 -287.808413)
			(xy 95.076503 -287.841644) (xy 95.112755 -287.880715) (xy 95.142779 -287.924752) (xy 95.165905 -287.972773)
			(xy 95.181615 -288.023703) (xy 95.189558 -288.076407) (xy 95.190056 -288.103056) (xy 95.189607 -288.128682)
			(xy 95.182255 -288.179403) (xy 95.16771 -288.228548) (xy 95.146273 -288.275101) (xy 95.118387 -288.318101)
			(xy 95.084626 -288.356662) (xy 95.045688 -288.389987) (xy 95.002376 -288.417388) (xy 94.955585 -288.4383)
			(xy 94.906281 -288.452292) (xy 94.880938 -288.456116) (xy 94.8563 -288.459418) (xy 94.68358 -288.758122)
			(xy 94.693232 -288.781236) (xy 94.701106 -288.802318) (xy 94.71279 -288.836608) (xy 94.955106 -288.836608)
			(xy 94.96679 -288.802318) (xy 94.975614 -288.777816) (xy 94.999406 -288.731493) (xy 95.029692 -288.689129)
			(xy 95.065825 -288.651628) (xy 95.107035 -288.619789) (xy 95.152444 -288.594293) (xy 95.201081 -288.575683)
			(xy 95.251911 -288.564356) (xy 95.303848 -288.560553) (xy 95.355785 -288.564356) (xy 95.406615 -288.575683)
			(xy 95.455252 -288.594293) (xy 95.500661 -288.619789) (xy 95.541871 -288.651628) (xy 95.578004 -288.689129)
			(xy 95.60829 -288.731493) (xy 95.632082 -288.777816) (xy 95.640906 -288.802318) (xy 95.65259 -288.836608)
			(xy 95.894906 -288.836608) (xy 95.90659 -288.802318) (xy 95.916218 -288.77575) (xy 95.942662 -288.725811)
			(xy 95.976656 -288.680672) (xy 96.017347 -288.641463) (xy 96.063716 -288.609167) (xy 96.114601 -288.584593)
			(xy 96.168726 -288.568357) (xy 96.196658 -288.564066) (xy 96.221296 -288.560764) (xy 96.394016 -288.26206)
			(xy 96.384364 -288.238946) (xy 96.375848 -288.217314) (xy 96.363862 -288.172396) (xy 96.35782 -288.126301)
			(xy 96.35744 -288.103056) (xy 96.357938 -288.076407) (xy 96.365881 -288.023703) (xy 96.381591 -287.972773)
			(xy 96.404717 -287.924752) (xy 96.434741 -287.880715) (xy 96.470993 -287.841644) (xy 96.512664 -287.808413)
			(xy 96.558822 -287.781764) (xy 96.608436 -287.762292) (xy 96.660398 -287.750432) (xy 96.713548 -287.746449)
			(xy 96.766698 -287.750432) (xy 96.81866 -287.762292) (xy 96.868274 -287.781764) (xy 96.914432 -287.808413)
			(xy 96.956103 -287.841644) (xy 96.992355 -287.880715) (xy 97.022379 -287.924752) (xy 97.045505 -287.972773)
			(xy 97.061215 -288.023703) (xy 97.069158 -288.076407) (xy 97.069656 -288.103056) (xy 97.069207 -288.128682)
			(xy 97.061855 -288.179403) (xy 97.04731 -288.228548) (xy 97.025873 -288.275101) (xy 96.997987 -288.318101)
			(xy 96.964226 -288.356662) (xy 96.925288 -288.389987) (xy 96.881976 -288.417388) (xy 96.835185 -288.4383)
			(xy 96.785881 -288.452292) (xy 96.760538 -288.456116) (xy 96.7359 -288.459418) (xy 96.56318 -288.758122)
			(xy 96.572832 -288.781236) (xy 96.580706 -288.802318) (xy 96.59239 -288.836608) (xy 96.834706 -288.836608)
			(xy 96.84639 -288.802318) (xy 96.855214 -288.777816) (xy 96.879006 -288.731493) (xy 96.909292 -288.689129)
			(xy 96.945425 -288.651628) (xy 96.986635 -288.619789) (xy 97.032044 -288.594293) (xy 97.080681 -288.575683)
			(xy 97.131511 -288.564356) (xy 97.183448 -288.560553) (xy 97.235385 -288.564356) (xy 97.286215 -288.575683)
			(xy 97.334852 -288.594293) (xy 97.380261 -288.619789) (xy 97.421471 -288.651628) (xy 97.457604 -288.689129)
			(xy 97.48789 -288.731493) (xy 97.511682 -288.777816) (xy 97.520506 -288.802318) (xy 97.53219 -288.836608)
			(xy 97.774506 -288.836608) (xy 97.78619 -288.802318) (xy 97.795818 -288.77575) (xy 97.822262 -288.725811)
			(xy 97.856256 -288.680672) (xy 97.896947 -288.641463) (xy 97.943316 -288.609167) (xy 97.994201 -288.584593)
			(xy 98.048326 -288.568357) (xy 98.076258 -288.564066) (xy 98.100896 -288.560764) (xy 98.273616 -288.26206)
			(xy 98.263964 -288.238946) (xy 98.255448 -288.217314) (xy 98.243462 -288.172396) (xy 98.23742 -288.126301)
			(xy 98.23704 -288.103056) (xy 98.237538 -288.076407) (xy 98.245481 -288.023703) (xy 98.261191 -287.972773)
			(xy 98.284317 -287.924752) (xy 98.314341 -287.880715) (xy 98.350593 -287.841644) (xy 98.392264 -287.808413)
			(xy 98.438422 -287.781764) (xy 98.488036 -287.762292) (xy 98.539998 -287.750432) (xy 98.593148 -287.746449)
			(xy 98.646298 -287.750432) (xy 98.69826 -287.762292) (xy 98.747874 -287.781764) (xy 98.794032 -287.808413)
			(xy 98.835703 -287.841644) (xy 98.871955 -287.880715) (xy 98.901979 -287.924752) (xy 98.925105 -287.972773)
			(xy 98.940815 -288.023703) (xy 98.948758 -288.076407) (xy 98.949256 -288.103056) (xy 98.948807 -288.128682)
			(xy 98.941455 -288.179403) (xy 98.92691 -288.228548) (xy 98.905473 -288.275101) (xy 98.877587 -288.318101)
			(xy 98.843826 -288.356662) (xy 98.804888 -288.389987) (xy 98.761576 -288.417388) (xy 98.714785 -288.4383)
			(xy 98.665481 -288.452292) (xy 98.640138 -288.456116) (xy 98.6155 -288.459418) (xy 98.44278 -288.758122)
			(xy 98.452432 -288.781236) (xy 98.460306 -288.802318) (xy 98.47199 -288.836608) (xy 98.714306 -288.836608)
			(xy 98.72599 -288.802318) (xy 98.734814 -288.777816) (xy 98.758606 -288.731493) (xy 98.788892 -288.689129)
			(xy 98.825025 -288.651628) (xy 98.866235 -288.619789) (xy 98.911644 -288.594293) (xy 98.960281 -288.575683)
			(xy 99.011111 -288.564356) (xy 99.063048 -288.560553) (xy 99.114985 -288.564356) (xy 99.165815 -288.575683)
			(xy 99.214452 -288.594293) (xy 99.259861 -288.619789) (xy 99.301071 -288.651628) (xy 99.337204 -288.689129)
			(xy 99.36749 -288.731493) (xy 99.391282 -288.777816) (xy 99.400106 -288.802318) (xy 99.41179 -288.836608)
			(xy 99.654106 -288.836608) (xy 99.66579 -288.802318) (xy 99.675418 -288.77575) (xy 99.701862 -288.725811)
			(xy 99.735856 -288.680672) (xy 99.776547 -288.641463) (xy 99.822916 -288.609167) (xy 99.873801 -288.584593)
			(xy 99.927926 -288.568357) (xy 99.955858 -288.564066) (xy 99.980496 -288.560764) (xy 100.153216 -288.26206)
			(xy 100.143564 -288.238946) (xy 100.135048 -288.217314) (xy 100.123062 -288.172396) (xy 100.11702 -288.126301)
			(xy 100.11664 -288.103056) (xy 100.117138 -288.076407) (xy 100.125081 -288.023703) (xy 100.140791 -287.972773)
			(xy 100.163917 -287.924752) (xy 100.193941 -287.880715) (xy 100.230193 -287.841644) (xy 100.271864 -287.808413)
			(xy 100.318022 -287.781764) (xy 100.367636 -287.762292) (xy 100.419598 -287.750432) (xy 100.472748 -287.746449)
			(xy 100.525898 -287.750432) (xy 100.57786 -287.762292) (xy 100.627474 -287.781764) (xy 100.673632 -287.808413)
			(xy 100.715303 -287.841644) (xy 100.751555 -287.880715) (xy 100.781579 -287.924752) (xy 100.804705 -287.972773)
			(xy 100.820415 -288.023703) (xy 100.828358 -288.076407) (xy 100.828856 -288.103056) (xy 100.828407 -288.128682)
			(xy 100.821055 -288.179403) (xy 100.80651 -288.228548) (xy 100.785073 -288.275101) (xy 100.757187 -288.318101)
			(xy 100.723426 -288.356662) (xy 100.684488 -288.389987) (xy 100.641176 -288.417388) (xy 100.594385 -288.4383)
			(xy 100.545081 -288.452292) (xy 100.519738 -288.456116) (xy 100.4951 -288.459418) (xy 100.32238 -288.758122)
			(xy 100.332032 -288.781236) (xy 100.339906 -288.802318) (xy 100.35159 -288.836608) (xy 100.593906 -288.836608)
			(xy 100.60559 -288.802318) (xy 100.614414 -288.777816) (xy 100.638206 -288.731493) (xy 100.668492 -288.689129)
			(xy 100.704625 -288.651628) (xy 100.745835 -288.619789) (xy 100.791244 -288.594293) (xy 100.839881 -288.575683)
			(xy 100.890711 -288.564356) (xy 100.942648 -288.560553) (xy 100.994585 -288.564356) (xy 101.045415 -288.575683)
			(xy 101.094052 -288.594293) (xy 101.139461 -288.619789) (xy 101.180671 -288.651628) (xy 101.216804 -288.689129)
			(xy 101.24709 -288.731493) (xy 101.270882 -288.777816) (xy 101.279706 -288.802318) (xy 101.29139 -288.836608)
			(xy 101.533706 -288.836608) (xy 101.54539 -288.802318) (xy 101.555018 -288.77575) (xy 101.581462 -288.725811)
			(xy 101.615456 -288.680672) (xy 101.656147 -288.641463) (xy 101.702516 -288.609167) (xy 101.753401 -288.584593)
			(xy 101.807526 -288.568357) (xy 101.835458 -288.564066) (xy 101.860096 -288.560764) (xy 102.032816 -288.26206)
			(xy 102.023164 -288.238946) (xy 102.014648 -288.217314) (xy 102.002662 -288.172396) (xy 101.99662 -288.126301)
			(xy 101.99624 -288.103056) (xy 101.996738 -288.076407) (xy 102.004681 -288.023703) (xy 102.020391 -287.972773)
			(xy 102.043517 -287.924752) (xy 102.073541 -287.880715) (xy 102.109793 -287.841644) (xy 102.151464 -287.808413)
			(xy 102.197622 -287.781764) (xy 102.247236 -287.762292) (xy 102.299198 -287.750432) (xy 102.352348 -287.746449)
			(xy 102.405498 -287.750432) (xy 102.45746 -287.762292) (xy 102.507074 -287.781764) (xy 102.553232 -287.808413)
			(xy 102.594903 -287.841644) (xy 102.631155 -287.880715) (xy 102.661179 -287.924752) (xy 102.684305 -287.972773)
			(xy 102.700015 -288.023703) (xy 102.707958 -288.076407) (xy 102.708456 -288.103056) (xy 102.708007 -288.128682)
			(xy 102.700655 -288.179403) (xy 102.68611 -288.228548) (xy 102.664673 -288.275101) (xy 102.636787 -288.318101)
			(xy 102.603026 -288.356662) (xy 102.564088 -288.389987) (xy 102.520776 -288.417388) (xy 102.473985 -288.4383)
			(xy 102.424681 -288.452292) (xy 102.399338 -288.456116) (xy 102.3747 -288.459418) (xy 102.20198 -288.758122)
			(xy 102.211632 -288.781236) (xy 102.219506 -288.802318) (xy 102.23119 -288.836608) (xy 102.473506 -288.836608)
			(xy 102.48519 -288.802318) (xy 102.494014 -288.777816) (xy 102.517806 -288.731493) (xy 102.548092 -288.689129)
			(xy 102.584225 -288.651628) (xy 102.625435 -288.619789) (xy 102.670844 -288.594293) (xy 102.719481 -288.575683)
			(xy 102.770311 -288.564356) (xy 102.822248 -288.560553) (xy 102.874185 -288.564356) (xy 102.925015 -288.575683)
			(xy 102.973652 -288.594293) (xy 103.019061 -288.619789) (xy 103.060271 -288.651628) (xy 103.096404 -288.689129)
			(xy 103.12669 -288.731493) (xy 103.150482 -288.777816) (xy 103.159306 -288.802318) (xy 103.17099 -288.836608)
			(xy 103.413306 -288.836608) (xy 103.42499 -288.802318) (xy 103.434318 -288.776504) (xy 103.459777 -288.72788)
			(xy 103.492397 -288.683739) (xy 103.531405 -288.645128) (xy 103.575877 -288.61296) (xy 103.624758 -288.587999)
			(xy 103.676892 -288.570835) (xy 103.703882 -288.565844) (xy 103.720138 -288.56305) (xy 103.763572 -288.519616)
			(xy 103.912416 -288.26206) (xy 103.902764 -288.238946) (xy 103.894248 -288.217314) (xy 103.882262 -288.172396)
			(xy 103.87622 -288.126301) (xy 103.87584 -288.103056) (xy 103.876427 -288.073886) (xy 103.885937 -288.016326)
			(xy 103.904695 -287.961084) (xy 103.932202 -287.909635) (xy 103.9495 -287.88614) (xy 103.9495 -287.73882)
			(xy 103.94898 -287.723891) (xy 103.940355 -287.695307) (xy 103.923835 -287.670437) (xy 103.90083 -287.651405)
			(xy 103.873306 -287.639835) (xy 103.843612 -287.636716) (xy 103.82885 -287.638998) (xy 103.812248 -287.641988)
			(xy 103.778662 -287.64517) (xy 103.761794 -287.645348) (xy 103.735142 -287.64485) (xy 103.682433 -287.636904)
			(xy 103.631498 -287.621192) (xy 103.583473 -287.598064) (xy 103.539431 -287.568036) (xy 103.500357 -287.53178)
			(xy 103.467123 -287.490105) (xy 103.440471 -287.443942) (xy 103.420997 -287.394323) (xy 103.409136 -287.342355)
			(xy 103.405152 -287.2892) (xy 103.409136 -287.236045) (xy 103.420997 -287.184077) (xy 103.440471 -287.134458)
			(xy 103.467123 -287.088295) (xy 103.500357 -287.04662) (xy 103.539431 -287.010364) (xy 103.583473 -286.980336)
			(xy 103.631498 -286.957208) (xy 103.682433 -286.941496) (xy 103.735142 -286.93355) (xy 103.761794 -286.933132)
			(xy 103.778661 -286.93333) (xy 103.812246 -286.936509) (xy 103.82885 -286.939482) (xy 103.843611 -286.941768)
			(xy 103.873304 -286.938649) (xy 103.900827 -286.927078) (xy 103.923829 -286.908044) (xy 103.940346 -286.883173)
			(xy 103.948967 -286.854588) (xy 103.9495 -286.83966) (xy 103.9495 -286.692594) (xy 103.934037 -286.671732)
			(xy 103.908678 -286.626417) (xy 103.890169 -286.5779) (xy 103.878903 -286.527209) (xy 103.875119 -286.475419)
			(xy 103.878898 -286.423629) (xy 103.890158 -286.372937) (xy 103.908661 -286.324417) (xy 103.934016 -286.2791)
			(xy 103.9495 -286.258254) (xy 103.9495 -286.110934) (xy 103.948982 -286.096004) (xy 103.940359 -286.067416)
			(xy 103.923839 -286.042543) (xy 103.900834 -286.023507) (xy 103.873308 -286.011935) (xy 103.843611 -286.008816)
			(xy 103.82885 -286.011112) (xy 103.812248 -286.014102) (xy 103.778662 -286.017284) (xy 103.761794 -286.017462)
			(xy 103.73381 -286.016941) (xy 103.678532 -286.008184) (xy 103.625305 -285.990887) (xy 103.575439 -285.965476)
			(xy 103.530162 -285.932576) (xy 103.49059 -285.892998) (xy 103.457697 -285.847717) (xy 103.432293 -285.797847)
			(xy 103.415004 -285.744617) (xy 103.406255 -285.689338) (xy 103.405686 -285.661354) (xy 103.406134 -285.635729)
			(xy 103.413486 -285.585008) (xy 103.42803 -285.535865) (xy 103.449467 -285.489313) (xy 103.477355 -285.446314)
			(xy 103.511116 -285.407755) (xy 103.550055 -285.374433) (xy 103.593368 -285.347036) (xy 103.64016 -285.326128)
			(xy 103.689465 -285.312142) (xy 103.714804 -285.308294) (xy 103.739442 -285.304992) (xy 103.912162 -285.006034)
			(xy 103.90251 -284.98292) (xy 103.894067 -284.961359) (xy 103.882189 -284.916605) (xy 103.876197 -284.87069)
			(xy 103.87584 -284.847538) (xy 103.876428 -284.818368) (xy 103.885941 -284.76081) (xy 103.904702 -284.705569)
			(xy 103.93221 -284.654122) (xy 103.9495 -284.630622) (xy 103.9495 -284.483302) (xy 103.948978 -284.468375)
			(xy 103.94035 -284.439796) (xy 103.923829 -284.414931) (xy 103.900826 -284.395902) (xy 103.873304 -284.384335)
			(xy 103.843614 -284.381216) (xy 103.82885 -284.38348) (xy 103.812248 -284.38647) (xy 103.778662 -284.389651)
			(xy 103.761794 -284.38983) (xy 103.735143 -284.389332) (xy 103.682437 -284.381387) (xy 103.631504 -284.365675)
			(xy 103.583482 -284.342548) (xy 103.539442 -284.312522) (xy 103.50037 -284.276268) (xy 103.467138 -284.234595)
			(xy 103.440487 -284.188434) (xy 103.421014 -284.138817) (xy 103.409154 -284.086852) (xy 103.40517 -284.0337)
			(xy 103.409154 -283.980548) (xy 103.421014 -283.928583) (xy 103.440487 -283.878966) (xy 103.467138 -283.832805)
			(xy 103.50037 -283.791132) (xy 103.539442 -283.754878) (xy 103.583482 -283.724852) (xy 103.631504 -283.701725)
			(xy 103.682437 -283.686013) (xy 103.735143 -283.678068) (xy 103.761794 -283.677614) (xy 103.778661 -283.677812)
			(xy 103.812246 -283.680991) (xy 103.82885 -283.683964) (xy 103.84361 -283.68625) (xy 103.873302 -283.683131)
			(xy 103.900823 -283.67156) (xy 103.923822 -283.652526) (xy 103.940336 -283.627654) (xy 103.948952 -283.59907)
			(xy 103.9495 -283.584142) (xy 103.9495 -283.494988) (xy 103.974392 -283.470096) (xy 103.947722 -283.43479)
			(xy 103.930757 -283.411445) (xy 103.903811 -283.360416) (xy 103.885445 -283.30571) (xy 103.87614 -283.248759)
			(xy 103.875586 -283.219906) (xy 103.876135 -283.191922) (xy 103.884889 -283.136644) (xy 103.902183 -283.083416)
			(xy 103.92759 -283.033548) (xy 103.960486 -282.98827) (xy 104.00006 -282.948694) (xy 104.045338 -282.915797)
			(xy 104.095205 -282.890387) (xy 104.148432 -282.873092) (xy 104.20371 -282.864335) (xy 104.231694 -282.863798)
			(xy 104.260547 -282.864356) (xy 104.317498 -282.87366) (xy 104.372204 -282.892025) (xy 104.423232 -282.91897)
			(xy 104.446578 -282.935934) (xy 104.481884 -282.962604) (xy 104.561386 -282.883102) (xy 104.570671 -282.873142)
			(xy 104.584076 -282.849453) (xy 104.590755 -282.823067) (xy 104.590234 -282.795853) (xy 104.582549 -282.769741)
			(xy 104.568246 -282.746583) (xy 104.548339 -282.72802) (xy 104.536494 -282.721304) (xy 104.510413 -282.707009)
			(xy 104.463 -282.671107) (xy 104.422205 -282.627833) (xy 104.405176 -282.603448) (xy 104.058212 -282.603448)
			(xy 104.043974 -282.62402) (xy 104.010654 -282.661338) (xy 103.972441 -282.693627) (xy 103.930085 -282.720252)
			(xy 103.884421 -282.740689) (xy 103.836347 -282.754537) (xy 103.786809 -282.761522) (xy 103.761794 -282.761944)
			(xy 103.735142 -282.761446) (xy 103.682434 -282.753501) (xy 103.631499 -282.737788) (xy 103.583475 -282.71466)
			(xy 103.539434 -282.684633) (xy 103.50036 -282.648377) (xy 103.467126 -282.606703) (xy 103.440475 -282.56054)
			(xy 103.421001 -282.510921) (xy 103.40914 -282.458954) (xy 103.405156 -282.4058) (xy 103.40914 -282.352646)
			(xy 103.421001 -282.300679) (xy 103.440475 -282.25106) (xy 103.467126 -282.204897) (xy 103.50036 -282.163223)
			(xy 103.539434 -282.126967) (xy 103.583475 -282.09694) (xy 103.631499 -282.073812) (xy 103.682434 -282.058099)
			(xy 103.735142 -282.050154) (xy 103.761794 -282.049728) (xy 103.786808 -282.05015) (xy 103.836345 -282.057144)
			(xy 103.884418 -282.070995) (xy 103.930081 -282.091432) (xy 103.972439 -282.118053) (xy 104.010658 -282.150335)
			(xy 104.043988 -282.187644) (xy 104.058212 -282.208224) (xy 104.405176 -282.208224) (xy 104.419414 -282.187653)
			(xy 104.452735 -282.150337) (xy 104.490949 -282.118048) (xy 104.533305 -282.091424) (xy 104.578968 -282.070987)
			(xy 104.627042 -282.05714) (xy 104.67658 -282.050154) (xy 104.701594 -282.049728) (xy 104.729298 -282.050255)
			(xy 104.784038 -282.058839) (xy 104.836786 -282.075801) (xy 104.886269 -282.100732) (xy 104.931292 -282.133028)
			(xy 104.970766 -282.17191) (xy 105.00374 -282.216439) (xy 105.017062 -282.240736) (xy 105.023733 -282.252634)
			(xy 105.042261 -282.272639) (xy 105.065431 -282.287015) (xy 105.091582 -282.294734) (xy 105.118845 -282.295243)
			(xy 105.145266 -282.288506) (xy 105.168956 -282.275006) (xy 105.17886 -282.265628) (xy 105.765346 -281.679142)
			(xy 105.760774 -281.653234) (xy 105.758276 -281.638054) (xy 105.755602 -281.607403) (xy 105.75544 -281.59202)
			(xy 105.755959 -281.564035) (xy 105.764713 -281.508754) (xy 105.782007 -281.455523) (xy 105.807417 -281.405653)
			(xy 105.840316 -281.360373) (xy 105.879895 -281.320798) (xy 105.925177 -281.287903) (xy 105.975049 -281.262497)
			(xy 106.028281 -281.245206) (xy 106.083563 -281.236457) (xy 106.111548 -281.235912) (xy 106.126931 -281.236092)
			(xy 106.15758 -281.238765) (xy 106.172762 -281.241246) (xy 106.19867 -281.245818) (xy 106.30154 -281.142948)
			(xy 106.311768 -281.131914) (xy 106.325861 -281.10535) (xy 106.331605 -281.075833) (xy 106.328502 -281.045923)
			(xy 106.316821 -281.018214) (xy 106.307636 -281.006296) (xy 106.301566 -280.998949) (xy 106.290128 -280.983702)
			(xy 106.284776 -280.975816) (xy 105.937812 -280.975816) (xy 105.923572 -280.996384) (xy 105.890249 -281.033696)
			(xy 105.852034 -281.065979) (xy 105.809678 -281.092599) (xy 105.764015 -281.113032) (xy 105.715943 -281.126876)
			(xy 105.666407 -281.13386) (xy 105.641394 -281.134312) (xy 105.614745 -281.133814) (xy 105.562041 -281.125869)
			(xy 105.511111 -281.110159) (xy 105.463091 -281.087033) (xy 105.419054 -281.057008) (xy 105.379983 -281.020755)
			(xy 105.346752 -280.979085) (xy 105.320103 -280.932926) (xy 105.300631 -280.883312) (xy 105.288771 -280.83135)
			(xy 105.284788 -280.7782) (xy 105.288771 -280.72505) (xy 105.300631 -280.673088) (xy 105.320103 -280.623474)
			(xy 105.346752 -280.577315) (xy 105.379983 -280.535645) (xy 105.419054 -280.499392) (xy 105.463091 -280.469367)
			(xy 105.511111 -280.446241) (xy 105.562041 -280.430531) (xy 105.614745 -280.422586) (xy 105.641394 -280.422096)
			(xy 105.666409 -280.422518) (xy 105.715946 -280.429511) (xy 105.76402 -280.443362) (xy 105.809685 -280.463798)
			(xy 105.852044 -280.490417) (xy 105.890265 -280.522698) (xy 105.923599 -280.560004) (xy 105.937812 -280.580592)
			(xy 106.284776 -280.580592) (xy 106.299015 -280.560023) (xy 106.332338 -280.522709) (xy 106.370553 -280.490424)
			(xy 106.412908 -280.463802) (xy 106.458571 -280.443367) (xy 106.506644 -280.429521) (xy 106.55618 -280.422536)
			(xy 106.581194 -280.422096) (xy 106.605956 -280.422521) (xy 106.655003 -280.429377) (xy 106.702629 -280.442957)
			(xy 106.747915 -280.463) (xy 106.789991 -280.489121) (xy 106.809286 -280.504646) (xy 106.821181 -280.513873)
			(xy 106.848899 -280.525583) (xy 106.878827 -280.528696) (xy 106.908361 -280.522942) (xy 106.934931 -280.50882)
			(xy 106.945938 -280.49855) (xy 107.93476 -279.509728) (xy 107.93476 -278.690324) (xy 107.897422 -278.67991)
			(xy 107.872632 -278.67269) (xy 107.825292 -278.652079) (xy 107.781428 -278.624842) (xy 107.741962 -278.591551)
			(xy 107.707723 -278.552904) (xy 107.67943 -278.509715) (xy 107.657676 -278.462889) (xy 107.64292 -278.41341)
			(xy 107.635471 -278.362318) (xy 107.63504 -278.336502) (xy 107.635415 -278.313257) (xy 107.641461 -278.267162)
			(xy 107.653449 -278.222244) (xy 107.661964 -278.200612) (xy 107.671616 -278.177498) (xy 107.498896 -277.878794)
			(xy 107.474258 -277.875492) (xy 107.448901 -277.871683) (xy 107.399561 -277.857731) (xy 107.352732 -277.836846)
			(xy 107.309383 -277.809459) (xy 107.270411 -277.776138) (xy 107.236621 -277.737571) (xy 107.208712 -277.694557)
			(xy 107.187262 -277.647984) (xy 107.172714 -277.598816) (xy 107.165369 -277.54807) (xy 107.164886 -277.522432)
			(xy 107.165404 -277.494445) (xy 107.174155 -277.439159) (xy 107.191448 -277.385923) (xy 107.216857 -277.336048)
			(xy 107.249755 -277.290762) (xy 107.289333 -277.25118) (xy 107.334615 -277.218277) (xy 107.384488 -277.192863)
			(xy 107.437722 -277.175564) (xy 107.493007 -277.166807) (xy 107.520994 -277.166324) (xy 107.547734 -277.166805)
			(xy 107.600612 -277.174811) (xy 107.651695 -277.190644) (xy 107.699832 -277.213946) (xy 107.743937 -277.244192)
			(xy 107.763818 -277.262082) (xy 107.774966 -277.271795) (xy 107.801446 -277.284922) (xy 107.830575 -277.289919)
			(xy 107.859915 -277.286368) (xy 107.887011 -277.274565) (xy 107.909594 -277.2555) (xy 107.925774 -277.230767)
			(xy 107.934196 -277.202438) (xy 107.93476 -277.18766) (xy 107.93476 -277.062438) (xy 107.897422 -277.052024)
			(xy 107.871175 -277.044362) (xy 107.821235 -277.022103) (xy 107.775287 -276.992468) (xy 107.734411 -276.956155)
			(xy 107.699569 -276.914018) (xy 107.671581 -276.867049) (xy 107.651106 -276.816351) (xy 107.638625 -276.763119)
			(xy 107.634431 -276.708604) (xy 107.638623 -276.654089) (xy 107.651103 -276.600857) (xy 107.671578 -276.550159)
			(xy 107.699564 -276.503188) (xy 107.734405 -276.461051) (xy 107.77528 -276.424737) (xy 107.821228 -276.395101)
			(xy 107.871167 -276.372841) (xy 107.897422 -276.365208) (xy 107.93476 -276.354794) (xy 107.93476 -276.229572)
			(xy 107.934257 -276.2148) (xy 107.925801 -276.186492) (xy 107.909604 -276.161784) (xy 107.887018 -276.14274)
			(xy 107.859929 -276.130949) (xy 107.830599 -276.127397) (xy 107.801479 -276.132379) (xy 107.774999 -276.145481)
			(xy 107.763818 -276.15515) (xy 107.743943 -276.173045) (xy 107.69983 -276.203278) (xy 107.651691 -276.226572)
			(xy 107.600609 -276.242404) (xy 107.547733 -276.250417) (xy 107.520994 -276.250908) (xy 107.49598 -276.250486)
			(xy 107.446443 -276.243491) (xy 107.398371 -276.229639) (xy 107.352707 -276.209202) (xy 107.310349 -276.182582)
			(xy 107.272128 -276.150302) (xy 107.238796 -276.112995) (xy 107.224576 -276.092412) (xy 106.877612 -276.092412)
			(xy 106.863372 -276.11298) (xy 106.830049 -276.150292) (xy 106.791834 -276.182576) (xy 106.749479 -276.209196)
			(xy 106.703816 -276.229629) (xy 106.655744 -276.243474) (xy 106.606207 -276.250457) (xy 106.581194 -276.250908)
			(xy 106.554545 -276.25041) (xy 106.501842 -276.242465) (xy 106.450912 -276.226755) (xy 106.402893 -276.203629)
			(xy 106.358856 -276.173605) (xy 106.319786 -276.137353) (xy 106.286556 -276.095682) (xy 106.259907 -276.049525)
			(xy 106.240435 -275.999911) (xy 106.228575 -275.947949) (xy 106.224592 -275.8948) (xy 106.228575 -275.841651)
			(xy 106.240435 -275.789689) (xy 106.259907 -275.740075) (xy 106.286556 -275.693918) (xy 106.319786 -275.652247)
			(xy 106.358856 -275.615995) (xy 106.402893 -275.585971) (xy 106.450912 -275.562845) (xy 106.501842 -275.547135)
			(xy 106.554545 -275.53919) (xy 106.581194 -275.538692) (xy 106.606209 -275.539114) (xy 106.655746 -275.546107)
			(xy 106.70382 -275.559958) (xy 106.749485 -275.580394) (xy 106.791844 -275.607013) (xy 106.830066 -275.639293)
			(xy 106.8634 -275.676599) (xy 106.877612 -275.697188) (xy 107.224576 -275.697188) (xy 107.238816 -275.676619)
			(xy 107.272138 -275.639306) (xy 107.310353 -275.607021) (xy 107.352708 -275.580399) (xy 107.398371 -275.559965)
			(xy 107.446444 -275.546119) (xy 107.49598 -275.539134) (xy 107.520994 -275.538692) (xy 107.547734 -275.539173)
			(xy 107.600613 -275.547179) (xy 107.651696 -275.56301) (xy 107.699835 -275.586311) (xy 107.743942 -275.616555)
			(xy 107.763818 -275.63445) (xy 107.77497 -275.644158) (xy 107.801454 -275.657277) (xy 107.830584 -275.662269)
			(xy 107.859925 -275.658717) (xy 107.887022 -275.646918) (xy 107.90961 -275.627858) (xy 107.9258 -275.603131)
			(xy 107.934237 -275.574806) (xy 107.93476 -275.560028) (xy 107.93476 -275.434552) (xy 107.897422 -275.424138)
			(xy 107.871174 -275.416476) (xy 107.821232 -275.394217) (xy 107.775281 -275.364581) (xy 107.734404 -275.328267)
			(xy 107.69956 -275.286129) (xy 107.671571 -275.239158) (xy 107.651094 -275.188459) (xy 107.638612 -275.135225)
			(xy 107.634417 -275.080708) (xy 107.638609 -275.026191) (xy 107.651089 -274.972956) (xy 107.671564 -274.922256)
			(xy 107.699551 -274.875284) (xy 107.734393 -274.833144) (xy 107.775269 -274.796828) (xy 107.821218 -274.767191)
			(xy 107.871159 -274.744929) (xy 107.897422 -274.737322) (xy 107.93476 -274.726908) (xy 107.93476 -274.013168)
			(xy 107.54868 -273.627088) (xy 107.36199 -273.627088) (xy 107.348372 -273.650382) (xy 107.315205 -273.692939)
			(xy 107.275996 -273.730005) (xy 107.231643 -273.760731) (xy 107.183163 -273.784412) (xy 107.131664 -273.800508)
			(xy 107.078326 -273.808649) (xy 107.02437 -273.808649) (xy 106.971032 -273.800508) (xy 106.919533 -273.784412)
			(xy 106.871053 -273.760731) (xy 106.8267 -273.730005) (xy 106.787491 -273.692939) (xy 106.754324 -273.650382)
			(xy 106.740706 -273.627088) (xy 106.42219 -273.627088) (xy 106.408572 -273.650382) (xy 106.375405 -273.692939)
			(xy 106.336196 -273.730005) (xy 106.291843 -273.760731) (xy 106.243363 -273.784412) (xy 106.191864 -273.800508)
			(xy 106.138526 -273.808649) (xy 106.08457 -273.808649) (xy 106.031232 -273.800508) (xy 105.979733 -273.784412)
			(xy 105.931253 -273.760731) (xy 105.8869 -273.730005) (xy 105.847691 -273.692939) (xy 105.814524 -273.650382)
			(xy 105.800906 -273.627088) (xy 104.54259 -273.627088) (xy 104.528972 -273.650382) (xy 104.495805 -273.692939)
			(xy 104.456596 -273.730005) (xy 104.412243 -273.760731) (xy 104.363763 -273.784412) (xy 104.312264 -273.800508)
			(xy 104.258926 -273.808649) (xy 104.20497 -273.808649) (xy 104.151632 -273.800508) (xy 104.100133 -273.784412)
			(xy 104.051653 -273.760731) (xy 104.0073 -273.730005) (xy 103.968091 -273.692939) (xy 103.934924 -273.650382)
			(xy 103.921306 -273.627088) (xy 103.602536 -273.627088) (xy 103.588918 -273.650382) (xy 103.555751 -273.692939)
			(xy 103.516542 -273.730005) (xy 103.472189 -273.760731) (xy 103.423709 -273.784412) (xy 103.37221 -273.800508)
			(xy 103.318872 -273.808649) (xy 103.264916 -273.808649) (xy 103.211578 -273.800508) (xy 103.160079 -273.784412)
			(xy 103.111599 -273.760731) (xy 103.067246 -273.730005) (xy 103.028037 -273.692939) (xy 102.99487 -273.650382)
			(xy 102.981252 -273.627088) (xy 102.66299 -273.627088) (xy 102.649372 -273.650382) (xy 102.616205 -273.692939)
			(xy 102.576996 -273.730005) (xy 102.532643 -273.760731) (xy 102.484163 -273.784412) (xy 102.432664 -273.800508)
			(xy 102.379326 -273.808649) (xy 102.32537 -273.808649) (xy 102.272032 -273.800508) (xy 102.220533 -273.784412)
			(xy 102.172053 -273.760731) (xy 102.1277 -273.730005) (xy 102.088491 -273.692939) (xy 102.055324 -273.650382)
			(xy 102.041706 -273.627088) (xy 101.722936 -273.627088) (xy 101.709318 -273.650382) (xy 101.676151 -273.692939)
			(xy 101.636942 -273.730005) (xy 101.592589 -273.760731) (xy 101.544109 -273.784412) (xy 101.49261 -273.800508)
			(xy 101.439272 -273.808649) (xy 101.385316 -273.808649) (xy 101.331978 -273.800508) (xy 101.280479 -273.784412)
			(xy 101.231999 -273.760731) (xy 101.187646 -273.730005) (xy 101.148437 -273.692939) (xy 101.11527 -273.650382)
			(xy 101.101652 -273.627088) (xy 100.78339 -273.627088) (xy 100.769772 -273.650382) (xy 100.736605 -273.692939)
			(xy 100.697396 -273.730005) (xy 100.653043 -273.760731) (xy 100.604563 -273.784412) (xy 100.553064 -273.800508)
			(xy 100.499726 -273.808649) (xy 100.44577 -273.808649) (xy 100.392432 -273.800508) (xy 100.340933 -273.784412)
			(xy 100.292453 -273.760731) (xy 100.2481 -273.730005) (xy 100.208891 -273.692939) (xy 100.175724 -273.650382)
			(xy 100.162106 -273.627088) (xy 99.84359 -273.627088) (xy 99.829972 -273.650382) (xy 99.796805 -273.692939)
			(xy 99.757596 -273.730005) (xy 99.713243 -273.760731) (xy 99.664763 -273.784412) (xy 99.613264 -273.800508)
			(xy 99.559926 -273.808649) (xy 99.50597 -273.808649) (xy 99.452632 -273.800508) (xy 99.401133 -273.784412)
			(xy 99.352653 -273.760731) (xy 99.3083 -273.730005) (xy 99.269091 -273.692939) (xy 99.235924 -273.650382)
			(xy 99.222306 -273.627088) (xy 98.90379 -273.627088) (xy 98.890172 -273.650382) (xy 98.857005 -273.692939)
			(xy 98.817796 -273.730005) (xy 98.773443 -273.760731) (xy 98.724963 -273.784412) (xy 98.673464 -273.800508)
			(xy 98.620126 -273.808649) (xy 98.56617 -273.808649) (xy 98.512832 -273.800508) (xy 98.461333 -273.784412)
			(xy 98.412853 -273.760731) (xy 98.3685 -273.730005) (xy 98.329291 -273.692939) (xy 98.296124 -273.650382)
			(xy 98.282506 -273.627088) (xy 97.96399 -273.627088) (xy 97.950372 -273.650382) (xy 97.917205 -273.692939)
			(xy 97.877996 -273.730005) (xy 97.833643 -273.760731) (xy 97.785163 -273.784412) (xy 97.733664 -273.800508)
			(xy 97.680326 -273.808649) (xy 97.62637 -273.808649) (xy 97.573032 -273.800508) (xy 97.521533 -273.784412)
			(xy 97.473053 -273.760731) (xy 97.4287 -273.730005) (xy 97.389491 -273.692939) (xy 97.356324 -273.650382)
			(xy 97.342706 -273.627088) (xy 97.02419 -273.627088) (xy 97.010572 -273.650382) (xy 96.977405 -273.692939)
			(xy 96.938196 -273.730005) (xy 96.893843 -273.760731) (xy 96.845363 -273.784412) (xy 96.793864 -273.800508)
			(xy 96.740526 -273.808649) (xy 96.68657 -273.808649) (xy 96.633232 -273.800508) (xy 96.581733 -273.784412)
			(xy 96.533253 -273.760731) (xy 96.4889 -273.730005) (xy 96.449691 -273.692939) (xy 96.416524 -273.650382)
			(xy 96.402906 -273.627088) (xy 96.08439 -273.627088) (xy 96.070772 -273.650382) (xy 96.037605 -273.692939)
			(xy 95.998396 -273.730005) (xy 95.954043 -273.760731) (xy 95.905563 -273.784412) (xy 95.854064 -273.800508)
			(xy 95.800726 -273.808649) (xy 95.74677 -273.808649) (xy 95.693432 -273.800508) (xy 95.641933 -273.784412)
			(xy 95.593453 -273.760731) (xy 95.5491 -273.730005) (xy 95.509891 -273.692939) (xy 95.476724 -273.650382)
			(xy 95.463106 -273.627088) (xy 95.144336 -273.627088) (xy 95.130718 -273.650382) (xy 95.097551 -273.692939)
			(xy 95.058342 -273.730005) (xy 95.013989 -273.760731) (xy 94.965509 -273.784412) (xy 94.91401 -273.800508)
			(xy 94.860672 -273.808649) (xy 94.806716 -273.808649) (xy 94.753378 -273.800508) (xy 94.701879 -273.784412)
			(xy 94.653399 -273.760731) (xy 94.609046 -273.730005) (xy 94.569837 -273.692939) (xy 94.53667 -273.650382)
			(xy 94.523052 -273.627088) (xy 94.20479 -273.627088) (xy 94.191172 -273.650382) (xy 94.158005 -273.692939)
			(xy 94.118796 -273.730005) (xy 94.074443 -273.760731) (xy 94.025963 -273.784412) (xy 93.974464 -273.800508)
			(xy 93.921126 -273.808649) (xy 93.86717 -273.808649) (xy 93.813832 -273.800508) (xy 93.762333 -273.784412)
			(xy 93.713853 -273.760731) (xy 93.6695 -273.730005) (xy 93.630291 -273.692939) (xy 93.597124 -273.650382)
			(xy 93.583506 -273.627088) (xy 93.26499 -273.627088) (xy 93.251372 -273.650382) (xy 93.218205 -273.692939)
			(xy 93.178996 -273.730005) (xy 93.134643 -273.760731) (xy 93.086163 -273.784412) (xy 93.034664 -273.800508)
			(xy 92.981326 -273.808649) (xy 92.92737 -273.808649) (xy 92.874032 -273.800508) (xy 92.822533 -273.784412)
			(xy 92.774053 -273.760731) (xy 92.7297 -273.730005) (xy 92.690491 -273.692939) (xy 92.657324 -273.650382)
			(xy 92.643706 -273.627088) (xy 92.32519 -273.627088) (xy 92.311572 -273.650382) (xy 92.278405 -273.692939)
			(xy 92.239196 -273.730005) (xy 92.194843 -273.760731) (xy 92.146363 -273.784412) (xy 92.094864 -273.800508)
			(xy 92.041526 -273.808649) (xy 91.98757 -273.808649) (xy 91.934232 -273.800508) (xy 91.882733 -273.784412)
			(xy 91.834253 -273.760731) (xy 91.7899 -273.730005) (xy 91.750691 -273.692939) (xy 91.717524 -273.650382)
			(xy 91.703906 -273.627088) (xy 91.38539 -273.627088) (xy 91.371772 -273.650382) (xy 91.338605 -273.692939)
			(xy 91.299396 -273.730005) (xy 91.255043 -273.760731) (xy 91.206563 -273.784412) (xy 91.155064 -273.800508)
			(xy 91.101726 -273.808649) (xy 91.04777 -273.808649) (xy 90.994432 -273.800508) (xy 90.942933 -273.784412)
			(xy 90.894453 -273.760731) (xy 90.8501 -273.730005) (xy 90.810891 -273.692939) (xy 90.777724 -273.650382)
			(xy 90.764106 -273.627088) (xy 90.445336 -273.627088) (xy 90.431718 -273.650382) (xy 90.398551 -273.692939)
			(xy 90.359342 -273.730005) (xy 90.314989 -273.760731) (xy 90.266509 -273.784412) (xy 90.21501 -273.800508)
			(xy 90.161672 -273.808649) (xy 90.107716 -273.808649) (xy 90.054378 -273.800508) (xy 90.002879 -273.784412)
			(xy 89.954399 -273.760731) (xy 89.910046 -273.730005) (xy 89.870837 -273.692939) (xy 89.83767 -273.650382)
			(xy 89.824052 -273.627088) (xy 89.505536 -273.627088) (xy 89.491918 -273.650382) (xy 89.458751 -273.692939)
			(xy 89.419542 -273.730005) (xy 89.375189 -273.760731) (xy 89.326709 -273.784412) (xy 89.27521 -273.800508)
			(xy 89.221872 -273.808649) (xy 89.167916 -273.808649) (xy 89.114578 -273.800508) (xy 89.063079 -273.784412)
			(xy 89.014599 -273.760731) (xy 88.970246 -273.730005) (xy 88.931037 -273.692939) (xy 88.89787 -273.650382)
			(xy 88.884252 -273.627088) (xy 88.565736 -273.627088) (xy 88.552114 -273.65038) (xy 88.518941 -273.692935)
			(xy 88.479731 -273.730002) (xy 88.43538 -273.760733) (xy 88.386903 -273.784426) (xy 88.335408 -273.800539)
			(xy 88.282072 -273.808704) (xy 88.255094 -273.809206) (xy 88.223992 -273.808565) (xy 88.162736 -273.797753)
			(xy 88.104291 -273.776458) (xy 88.07704 -273.761454) (xy 88.043258 -273.74215) (xy 87.969598 -273.81581)
			(xy 87.959397 -273.826744) (xy 87.945277 -273.853086) (xy 87.939396 -273.882391) (xy 87.942258 -273.912142)
			(xy 87.953618 -273.939787) (xy 87.972501 -273.962955) (xy 87.984584 -273.971766) (xy 88.004925 -273.986052)
			(xy 88.041822 -274.019357) (xy 88.073733 -274.057466) (xy 88.100041 -274.099638) (xy 88.120235 -274.145056)
			(xy 88.133924 -274.19284) (xy 88.140841 -274.242061) (xy 88.141302 -274.266914) (xy 88.140778 -274.293563)
			(xy 88.369384 -274.293563) (xy 88.369384 -274.240265) (xy 88.377327 -274.187561) (xy 88.393037 -274.136631)
			(xy 88.416163 -274.08861) (xy 88.446187 -274.044573) (xy 88.482439 -274.005502) (xy 88.52411 -273.972271)
			(xy 88.570268 -273.945622) (xy 88.619882 -273.92615) (xy 88.671844 -273.91429) (xy 88.724994 -273.910307)
			(xy 88.778144 -273.91429) (xy 88.830106 -273.92615) (xy 88.87972 -273.945622) (xy 88.925878 -273.972271)
			(xy 88.967549 -274.005502) (xy 89.003801 -274.044573) (xy 89.033825 -274.08861) (xy 89.056951 -274.136631)
			(xy 89.072661 -274.187561) (xy 89.080604 -274.240265) (xy 89.081102 -274.266914) (xy 89.080604 -274.293563)
			(xy 89.309184 -274.293563) (xy 89.309184 -274.240265) (xy 89.317127 -274.187561) (xy 89.332837 -274.136631)
			(xy 89.355963 -274.08861) (xy 89.385987 -274.044573) (xy 89.422239 -274.005502) (xy 89.46391 -273.972271)
			(xy 89.510068 -273.945622) (xy 89.559682 -273.92615) (xy 89.611644 -273.91429) (xy 89.664794 -273.910307)
			(xy 89.717944 -273.91429) (xy 89.769906 -273.92615) (xy 89.81952 -273.945622) (xy 89.865678 -273.972271)
			(xy 89.907349 -274.005502) (xy 89.943601 -274.044573) (xy 89.973625 -274.08861) (xy 89.996751 -274.136631)
			(xy 90.012461 -274.187561) (xy 90.020404 -274.240265) (xy 90.020902 -274.266914) (xy 90.020404 -274.293563)
			(xy 90.248984 -274.293563) (xy 90.248984 -274.240265) (xy 90.256927 -274.187561) (xy 90.272637 -274.136631)
			(xy 90.295763 -274.08861) (xy 90.325787 -274.044573) (xy 90.362039 -274.005502) (xy 90.40371 -273.972271)
			(xy 90.449868 -273.945622) (xy 90.499482 -273.92615) (xy 90.551444 -273.91429) (xy 90.604594 -273.910307)
			(xy 90.657744 -273.91429) (xy 90.709706 -273.92615) (xy 90.75932 -273.945622) (xy 90.805478 -273.972271)
			(xy 90.847149 -274.005502) (xy 90.883401 -274.044573) (xy 90.913425 -274.08861) (xy 90.936551 -274.136631)
			(xy 90.952261 -274.187561) (xy 90.960204 -274.240265) (xy 90.960702 -274.266914) (xy 90.960204 -274.293563)
			(xy 91.189038 -274.293563) (xy 91.189038 -274.240265) (xy 91.196981 -274.187561) (xy 91.212691 -274.136631)
			(xy 91.235817 -274.08861) (xy 91.265841 -274.044573) (xy 91.302093 -274.005502) (xy 91.343764 -273.972271)
			(xy 91.389922 -273.945622) (xy 91.439536 -273.92615) (xy 91.491498 -273.91429) (xy 91.544648 -273.910307)
			(xy 91.597798 -273.91429) (xy 91.64976 -273.92615) (xy 91.699374 -273.945622) (xy 91.745532 -273.972271)
			(xy 91.787203 -274.005502) (xy 91.823455 -274.044573) (xy 91.853479 -274.08861) (xy 91.876605 -274.136631)
			(xy 91.892315 -274.187561) (xy 91.900258 -274.240265) (xy 91.900756 -274.266914) (xy 91.900258 -274.293563)
			(xy 92.128584 -274.293563) (xy 92.128584 -274.240265) (xy 92.136527 -274.187561) (xy 92.152237 -274.136631)
			(xy 92.175363 -274.08861) (xy 92.205387 -274.044573) (xy 92.241639 -274.005502) (xy 92.28331 -273.972271)
			(xy 92.329468 -273.945622) (xy 92.379082 -273.92615) (xy 92.431044 -273.91429) (xy 92.484194 -273.910307)
			(xy 92.537344 -273.91429) (xy 92.589306 -273.92615) (xy 92.63892 -273.945622) (xy 92.685078 -273.972271)
			(xy 92.726749 -274.005502) (xy 92.763001 -274.044573) (xy 92.793025 -274.08861) (xy 92.816151 -274.136631)
			(xy 92.831861 -274.187561) (xy 92.839804 -274.240265) (xy 92.840302 -274.266914) (xy 92.839804 -274.293563)
			(xy 93.068384 -274.293563) (xy 93.068384 -274.240265) (xy 93.076327 -274.187561) (xy 93.092037 -274.136631)
			(xy 93.115163 -274.08861) (xy 93.145187 -274.044573) (xy 93.181439 -274.005502) (xy 93.22311 -273.972271)
			(xy 93.269268 -273.945622) (xy 93.318882 -273.92615) (xy 93.370844 -273.91429) (xy 93.423994 -273.910307)
			(xy 93.477144 -273.91429) (xy 93.529106 -273.92615) (xy 93.57872 -273.945622) (xy 93.624878 -273.972271)
			(xy 93.666549 -274.005502) (xy 93.702801 -274.044573) (xy 93.732825 -274.08861) (xy 93.755951 -274.136631)
			(xy 93.771661 -274.187561) (xy 93.779604 -274.240265) (xy 93.780102 -274.266914) (xy 93.779604 -274.293563)
			(xy 94.008184 -274.293563) (xy 94.008184 -274.240265) (xy 94.016127 -274.187561) (xy 94.031837 -274.136631)
			(xy 94.054963 -274.08861) (xy 94.084987 -274.044573) (xy 94.121239 -274.005502) (xy 94.16291 -273.972271)
			(xy 94.209068 -273.945622) (xy 94.258682 -273.92615) (xy 94.310644 -273.91429) (xy 94.363794 -273.910307)
			(xy 94.416944 -273.91429) (xy 94.468906 -273.92615) (xy 94.51852 -273.945622) (xy 94.564678 -273.972271)
			(xy 94.606349 -274.005502) (xy 94.642601 -274.044573) (xy 94.672625 -274.08861) (xy 94.695751 -274.136631)
			(xy 94.711461 -274.187561) (xy 94.719404 -274.240265) (xy 94.719902 -274.266914) (xy 94.719404 -274.293563)
			(xy 94.947984 -274.293563) (xy 94.947984 -274.240265) (xy 94.955927 -274.187561) (xy 94.971637 -274.136631)
			(xy 94.994763 -274.08861) (xy 95.024787 -274.044573) (xy 95.061039 -274.005502) (xy 95.10271 -273.972271)
			(xy 95.148868 -273.945622) (xy 95.198482 -273.92615) (xy 95.250444 -273.91429) (xy 95.303594 -273.910307)
			(xy 95.356744 -273.91429) (xy 95.408706 -273.92615) (xy 95.45832 -273.945622) (xy 95.504478 -273.972271)
			(xy 95.546149 -274.005502) (xy 95.582401 -274.044573) (xy 95.612425 -274.08861) (xy 95.635551 -274.136631)
			(xy 95.651261 -274.187561) (xy 95.659204 -274.240265) (xy 95.659702 -274.266914) (xy 95.659204 -274.293563)
			(xy 95.887784 -274.293563) (xy 95.887784 -274.240265) (xy 95.895727 -274.187561) (xy 95.911437 -274.136631)
			(xy 95.934563 -274.08861) (xy 95.964587 -274.044573) (xy 96.000839 -274.005502) (xy 96.04251 -273.972271)
			(xy 96.088668 -273.945622) (xy 96.138282 -273.92615) (xy 96.190244 -273.91429) (xy 96.243394 -273.910307)
			(xy 96.296544 -273.91429) (xy 96.348506 -273.92615) (xy 96.39812 -273.945622) (xy 96.444278 -273.972271)
			(xy 96.485949 -274.005502) (xy 96.522201 -274.044573) (xy 96.552225 -274.08861) (xy 96.575351 -274.136631)
			(xy 96.591061 -274.187561) (xy 96.599004 -274.240265) (xy 96.599502 -274.266914) (xy 96.599004 -274.293563)
			(xy 96.827584 -274.293563) (xy 96.827584 -274.240265) (xy 96.835527 -274.187561) (xy 96.851237 -274.136631)
			(xy 96.874363 -274.08861) (xy 96.904387 -274.044573) (xy 96.940639 -274.005502) (xy 96.98231 -273.972271)
			(xy 97.028468 -273.945622) (xy 97.078082 -273.92615) (xy 97.130044 -273.91429) (xy 97.183194 -273.910307)
			(xy 97.236344 -273.91429) (xy 97.288306 -273.92615) (xy 97.33792 -273.945622) (xy 97.384078 -273.972271)
			(xy 97.425749 -274.005502) (xy 97.462001 -274.044573) (xy 97.492025 -274.08861) (xy 97.515151 -274.136631)
			(xy 97.530861 -274.187561) (xy 97.538804 -274.240265) (xy 97.539302 -274.266914) (xy 97.538804 -274.293563)
			(xy 97.767384 -274.293563) (xy 97.767384 -274.240265) (xy 97.775327 -274.187561) (xy 97.791037 -274.136631)
			(xy 97.814163 -274.08861) (xy 97.844187 -274.044573) (xy 97.880439 -274.005502) (xy 97.92211 -273.972271)
			(xy 97.968268 -273.945622) (xy 98.017882 -273.92615) (xy 98.069844 -273.91429) (xy 98.122994 -273.910307)
			(xy 98.176144 -273.91429) (xy 98.228106 -273.92615) (xy 98.27772 -273.945622) (xy 98.323878 -273.972271)
			(xy 98.365549 -274.005502) (xy 98.401801 -274.044573) (xy 98.431825 -274.08861) (xy 98.454951 -274.136631)
			(xy 98.470661 -274.187561) (xy 98.478604 -274.240265) (xy 98.479102 -274.266914) (xy 98.478604 -274.293563)
			(xy 98.707184 -274.293563) (xy 98.707184 -274.240265) (xy 98.715127 -274.187561) (xy 98.730837 -274.136631)
			(xy 98.753963 -274.08861) (xy 98.783987 -274.044573) (xy 98.820239 -274.005502) (xy 98.86191 -273.972271)
			(xy 98.908068 -273.945622) (xy 98.957682 -273.92615) (xy 99.009644 -273.91429) (xy 99.062794 -273.910307)
			(xy 99.115944 -273.91429) (xy 99.167906 -273.92615) (xy 99.21752 -273.945622) (xy 99.263678 -273.972271)
			(xy 99.305349 -274.005502) (xy 99.341601 -274.044573) (xy 99.371625 -274.08861) (xy 99.394751 -274.136631)
			(xy 99.410461 -274.187561) (xy 99.418404 -274.240265) (xy 99.418902 -274.266914) (xy 99.418404 -274.293563)
			(xy 99.646984 -274.293563) (xy 99.646984 -274.240265) (xy 99.654927 -274.187561) (xy 99.670637 -274.136631)
			(xy 99.693763 -274.08861) (xy 99.723787 -274.044573) (xy 99.760039 -274.005502) (xy 99.80171 -273.972271)
			(xy 99.847868 -273.945622) (xy 99.897482 -273.92615) (xy 99.949444 -273.91429) (xy 100.002594 -273.910307)
			(xy 100.055744 -273.91429) (xy 100.107706 -273.92615) (xy 100.15732 -273.945622) (xy 100.203478 -273.972271)
			(xy 100.245149 -274.005502) (xy 100.281401 -274.044573) (xy 100.311425 -274.08861) (xy 100.334551 -274.136631)
			(xy 100.350261 -274.187561) (xy 100.358204 -274.240265) (xy 100.358702 -274.266914) (xy 100.358204 -274.293563)
			(xy 100.586784 -274.293563) (xy 100.586784 -274.240265) (xy 100.594727 -274.187561) (xy 100.610437 -274.136631)
			(xy 100.633563 -274.08861) (xy 100.663587 -274.044573) (xy 100.699839 -274.005502) (xy 100.74151 -273.972271)
			(xy 100.787668 -273.945622) (xy 100.837282 -273.92615) (xy 100.889244 -273.91429) (xy 100.942394 -273.910307)
			(xy 100.995544 -273.91429) (xy 101.047506 -273.92615) (xy 101.09712 -273.945622) (xy 101.143278 -273.972271)
			(xy 101.184949 -274.005502) (xy 101.221201 -274.044573) (xy 101.251225 -274.08861) (xy 101.274351 -274.136631)
			(xy 101.290061 -274.187561) (xy 101.298004 -274.240265) (xy 101.298502 -274.266914) (xy 101.298004 -274.293563)
			(xy 101.526584 -274.293563) (xy 101.526584 -274.240265) (xy 101.534527 -274.187561) (xy 101.550237 -274.136631)
			(xy 101.573363 -274.08861) (xy 101.603387 -274.044573) (xy 101.639639 -274.005502) (xy 101.68131 -273.972271)
			(xy 101.727468 -273.945622) (xy 101.777082 -273.92615) (xy 101.829044 -273.91429) (xy 101.882194 -273.910307)
			(xy 101.935344 -273.91429) (xy 101.987306 -273.92615) (xy 102.03692 -273.945622) (xy 102.083078 -273.972271)
			(xy 102.124749 -274.005502) (xy 102.161001 -274.044573) (xy 102.191025 -274.08861) (xy 102.214151 -274.136631)
			(xy 102.229861 -274.187561) (xy 102.237804 -274.240265) (xy 102.238302 -274.266914) (xy 102.237804 -274.293563)
			(xy 102.466384 -274.293563) (xy 102.466384 -274.240265) (xy 102.474327 -274.187561) (xy 102.490037 -274.136631)
			(xy 102.513163 -274.08861) (xy 102.543187 -274.044573) (xy 102.579439 -274.005502) (xy 102.62111 -273.972271)
			(xy 102.667268 -273.945622) (xy 102.716882 -273.92615) (xy 102.768844 -273.91429) (xy 102.821994 -273.910307)
			(xy 102.875144 -273.91429) (xy 102.927106 -273.92615) (xy 102.97672 -273.945622) (xy 103.022878 -273.972271)
			(xy 103.064549 -274.005502) (xy 103.100801 -274.044573) (xy 103.130825 -274.08861) (xy 103.153951 -274.136631)
			(xy 103.169661 -274.187561) (xy 103.177604 -274.240265) (xy 103.178102 -274.266914) (xy 103.405686 -274.266914)
			(xy 103.406184 -274.240265) (xy 103.414127 -274.187561) (xy 103.429837 -274.136631) (xy 103.452963 -274.08861)
			(xy 103.482987 -274.044573) (xy 103.519239 -274.005502) (xy 103.56091 -273.972271) (xy 103.607068 -273.945622)
			(xy 103.656682 -273.92615) (xy 103.708644 -273.91429) (xy 103.761794 -273.910307) (xy 103.814944 -273.91429)
			(xy 103.866906 -273.92615) (xy 103.91652 -273.945622) (xy 103.962678 -273.972271) (xy 104.004349 -274.005502)
			(xy 104.040601 -274.044573) (xy 104.070625 -274.08861) (xy 104.093751 -274.136631) (xy 104.109461 -274.187561)
			(xy 104.117404 -274.240265) (xy 104.117902 -274.266914) (xy 104.117535 -274.290066) (xy 104.117079 -274.293563)
			(xy 104.345984 -274.293563) (xy 104.345984 -274.240265) (xy 104.353927 -274.187561) (xy 104.369637 -274.136631)
			(xy 104.392763 -274.08861) (xy 104.422787 -274.044573) (xy 104.459039 -274.005502) (xy 104.50071 -273.972271)
			(xy 104.546868 -273.945622) (xy 104.596482 -273.92615) (xy 104.648444 -273.91429) (xy 104.701594 -273.910307)
			(xy 104.754744 -273.91429) (xy 104.806706 -273.92615) (xy 104.85632 -273.945622) (xy 104.902478 -273.972271)
			(xy 104.944149 -274.005502) (xy 104.980401 -274.044573) (xy 105.010425 -274.08861) (xy 105.033551 -274.136631)
			(xy 105.049261 -274.187561) (xy 105.057204 -274.240265) (xy 105.057702 -274.266914) (xy 105.057204 -274.293563)
			(xy 106.225584 -274.293563) (xy 106.225584 -274.240265) (xy 106.233527 -274.187561) (xy 106.249237 -274.136631)
			(xy 106.272363 -274.08861) (xy 106.302387 -274.044573) (xy 106.338639 -274.005502) (xy 106.38031 -273.972271)
			(xy 106.426468 -273.945622) (xy 106.476082 -273.92615) (xy 106.528044 -273.91429) (xy 106.581194 -273.910307)
			(xy 106.634344 -273.91429) (xy 106.686306 -273.92615) (xy 106.73592 -273.945622) (xy 106.782078 -273.972271)
			(xy 106.823749 -274.005502) (xy 106.860001 -274.044573) (xy 106.890025 -274.08861) (xy 106.913151 -274.136631)
			(xy 106.928861 -274.187561) (xy 106.936804 -274.240265) (xy 106.937302 -274.266914) (xy 106.936804 -274.293563)
			(xy 106.928861 -274.346267) (xy 106.913151 -274.397197) (xy 106.890025 -274.445218) (xy 106.860001 -274.489255)
			(xy 106.823749 -274.528326) (xy 106.782078 -274.561557) (xy 106.73592 -274.588206) (xy 106.686306 -274.607678)
			(xy 106.634344 -274.619538) (xy 106.581194 -274.623522) (xy 106.528044 -274.619538) (xy 106.476082 -274.607678)
			(xy 106.426468 -274.588206) (xy 106.38031 -274.561557) (xy 106.338639 -274.528326) (xy 106.302387 -274.489255)
			(xy 106.272363 -274.445218) (xy 106.249237 -274.397197) (xy 106.233527 -274.346267) (xy 106.225584 -274.293563)
			(xy 105.057204 -274.293563) (xy 105.049261 -274.346267) (xy 105.033551 -274.397197) (xy 105.010425 -274.445218)
			(xy 104.980401 -274.489255) (xy 104.944149 -274.528326) (xy 104.902478 -274.561557) (xy 104.85632 -274.588206)
			(xy 104.806706 -274.607678) (xy 104.754744 -274.619538) (xy 104.701594 -274.623522) (xy 104.648444 -274.619538)
			(xy 104.596482 -274.607678) (xy 104.546868 -274.588206) (xy 104.50071 -274.561557) (xy 104.459039 -274.528326)
			(xy 104.422787 -274.489255) (xy 104.392763 -274.445218) (xy 104.369637 -274.397197) (xy 104.353927 -274.346267)
			(xy 104.345984 -274.293563) (xy 104.117079 -274.293563) (xy 104.111546 -274.33598) (xy 104.099672 -274.380735)
			(xy 104.091232 -274.402296) (xy 104.08158 -274.42541) (xy 104.2543 -274.724368) (xy 104.278938 -274.72767)
			(xy 104.304278 -274.731508) (xy 104.353582 -274.745498) (xy 104.400372 -274.766409) (xy 104.443683 -274.793809)
			(xy 104.482621 -274.827133) (xy 104.516381 -274.865692) (xy 104.544268 -274.908691) (xy 104.565706 -274.955242)
			(xy 104.580252 -275.004385) (xy 104.587606 -275.055105) (xy 104.588056 -275.08073) (xy 104.587558 -275.107379)
			(xy 104.579615 -275.160083) (xy 104.563905 -275.211013) (xy 104.540779 -275.259034) (xy 104.510755 -275.303071)
			(xy 104.474503 -275.342142) (xy 104.432832 -275.375373) (xy 104.386674 -275.402022) (xy 104.33706 -275.421494)
			(xy 104.285098 -275.433354) (xy 104.231948 -275.437338) (xy 104.178798 -275.433354) (xy 104.126836 -275.421494)
			(xy 104.077222 -275.402022) (xy 104.031064 -275.375373) (xy 103.989393 -275.342142) (xy 103.953141 -275.303071)
			(xy 103.923117 -275.259034) (xy 103.899991 -275.211013) (xy 103.884281 -275.160083) (xy 103.876338 -275.107379)
			(xy 103.87584 -275.08073) (xy 103.876216 -275.057485) (xy 103.882259 -275.01139) (xy 103.894247 -274.966472)
			(xy 103.902764 -274.94484) (xy 103.912416 -274.921726) (xy 103.73995 -274.623276) (xy 103.715058 -274.619974)
			(xy 103.689694 -274.616206) (xy 103.640353 -274.602242) (xy 103.593525 -274.581349) (xy 103.550176 -274.553956)
			(xy 103.511203 -274.52063) (xy 103.477411 -274.482061) (xy 103.449499 -274.439045) (xy 103.428044 -274.392471)
			(xy 103.413488 -274.343301) (xy 103.406133 -274.292553) (xy 103.405686 -274.266914) (xy 103.178102 -274.266914)
			(xy 103.177604 -274.293563) (xy 103.169661 -274.346267) (xy 103.153951 -274.397197) (xy 103.130825 -274.445218)
			(xy 103.100801 -274.489255) (xy 103.064549 -274.528326) (xy 103.022878 -274.561557) (xy 102.97672 -274.588206)
			(xy 102.927106 -274.607678) (xy 102.875144 -274.619538) (xy 102.821994 -274.623522) (xy 102.768844 -274.619538)
			(xy 102.716882 -274.607678) (xy 102.667268 -274.588206) (xy 102.62111 -274.561557) (xy 102.579439 -274.528326)
			(xy 102.543187 -274.489255) (xy 102.513163 -274.445218) (xy 102.490037 -274.397197) (xy 102.474327 -274.346267)
			(xy 102.466384 -274.293563) (xy 102.237804 -274.293563) (xy 102.229861 -274.346267) (xy 102.214151 -274.397197)
			(xy 102.191025 -274.445218) (xy 102.161001 -274.489255) (xy 102.124749 -274.528326) (xy 102.083078 -274.561557)
			(xy 102.03692 -274.588206) (xy 101.987306 -274.607678) (xy 101.935344 -274.619538) (xy 101.882194 -274.623522)
			(xy 101.829044 -274.619538) (xy 101.777082 -274.607678) (xy 101.727468 -274.588206) (xy 101.68131 -274.561557)
			(xy 101.639639 -274.528326) (xy 101.603387 -274.489255) (xy 101.573363 -274.445218) (xy 101.550237 -274.397197)
			(xy 101.534527 -274.346267) (xy 101.526584 -274.293563) (xy 101.298004 -274.293563) (xy 101.290061 -274.346267)
			(xy 101.274351 -274.397197) (xy 101.251225 -274.445218) (xy 101.221201 -274.489255) (xy 101.184949 -274.528326)
			(xy 101.143278 -274.561557) (xy 101.09712 -274.588206) (xy 101.047506 -274.607678) (xy 100.995544 -274.619538)
			(xy 100.942394 -274.623522) (xy 100.889244 -274.619538) (xy 100.837282 -274.607678) (xy 100.787668 -274.588206)
			(xy 100.74151 -274.561557) (xy 100.699839 -274.528326) (xy 100.663587 -274.489255) (xy 100.633563 -274.445218)
			(xy 100.610437 -274.397197) (xy 100.594727 -274.346267) (xy 100.586784 -274.293563) (xy 100.358204 -274.293563)
			(xy 100.350261 -274.346267) (xy 100.334551 -274.397197) (xy 100.311425 -274.445218) (xy 100.281401 -274.489255)
			(xy 100.245149 -274.528326) (xy 100.203478 -274.561557) (xy 100.15732 -274.588206) (xy 100.107706 -274.607678)
			(xy 100.055744 -274.619538) (xy 100.002594 -274.623522) (xy 99.949444 -274.619538) (xy 99.897482 -274.607678)
			(xy 99.847868 -274.588206) (xy 99.80171 -274.561557) (xy 99.760039 -274.528326) (xy 99.723787 -274.489255)
			(xy 99.693763 -274.445218) (xy 99.670637 -274.397197) (xy 99.654927 -274.346267) (xy 99.646984 -274.293563)
			(xy 99.418404 -274.293563) (xy 99.410461 -274.346267) (xy 99.394751 -274.397197) (xy 99.371625 -274.445218)
			(xy 99.341601 -274.489255) (xy 99.305349 -274.528326) (xy 99.263678 -274.561557) (xy 99.21752 -274.588206)
			(xy 99.167906 -274.607678) (xy 99.115944 -274.619538) (xy 99.062794 -274.623522) (xy 99.009644 -274.619538)
			(xy 98.957682 -274.607678) (xy 98.908068 -274.588206) (xy 98.86191 -274.561557) (xy 98.820239 -274.528326)
			(xy 98.783987 -274.489255) (xy 98.753963 -274.445218) (xy 98.730837 -274.397197) (xy 98.715127 -274.346267)
			(xy 98.707184 -274.293563) (xy 98.478604 -274.293563) (xy 98.470661 -274.346267) (xy 98.454951 -274.397197)
			(xy 98.431825 -274.445218) (xy 98.401801 -274.489255) (xy 98.365549 -274.528326) (xy 98.323878 -274.561557)
			(xy 98.27772 -274.588206) (xy 98.228106 -274.607678) (xy 98.176144 -274.619538) (xy 98.122994 -274.623522)
			(xy 98.069844 -274.619538) (xy 98.017882 -274.607678) (xy 97.968268 -274.588206) (xy 97.92211 -274.561557)
			(xy 97.880439 -274.528326) (xy 97.844187 -274.489255) (xy 97.814163 -274.445218) (xy 97.791037 -274.397197)
			(xy 97.775327 -274.346267) (xy 97.767384 -274.293563) (xy 97.538804 -274.293563) (xy 97.530861 -274.346267)
			(xy 97.515151 -274.397197) (xy 97.492025 -274.445218) (xy 97.462001 -274.489255) (xy 97.425749 -274.528326)
			(xy 97.384078 -274.561557) (xy 97.33792 -274.588206) (xy 97.288306 -274.607678) (xy 97.236344 -274.619538)
			(xy 97.183194 -274.623522) (xy 97.130044 -274.619538) (xy 97.078082 -274.607678) (xy 97.028468 -274.588206)
			(xy 96.98231 -274.561557) (xy 96.940639 -274.528326) (xy 96.904387 -274.489255) (xy 96.874363 -274.445218)
			(xy 96.851237 -274.397197) (xy 96.835527 -274.346267) (xy 96.827584 -274.293563) (xy 96.599004 -274.293563)
			(xy 96.591061 -274.346267) (xy 96.575351 -274.397197) (xy 96.552225 -274.445218) (xy 96.522201 -274.489255)
			(xy 96.485949 -274.528326) (xy 96.444278 -274.561557) (xy 96.39812 -274.588206) (xy 96.348506 -274.607678)
			(xy 96.296544 -274.619538) (xy 96.243394 -274.623522) (xy 96.190244 -274.619538) (xy 96.138282 -274.607678)
			(xy 96.088668 -274.588206) (xy 96.04251 -274.561557) (xy 96.000839 -274.528326) (xy 95.964587 -274.489255)
			(xy 95.934563 -274.445218) (xy 95.911437 -274.397197) (xy 95.895727 -274.346267) (xy 95.887784 -274.293563)
			(xy 95.659204 -274.293563) (xy 95.651261 -274.346267) (xy 95.635551 -274.397197) (xy 95.612425 -274.445218)
			(xy 95.582401 -274.489255) (xy 95.546149 -274.528326) (xy 95.504478 -274.561557) (xy 95.45832 -274.588206)
			(xy 95.408706 -274.607678) (xy 95.356744 -274.619538) (xy 95.303594 -274.623522) (xy 95.250444 -274.619538)
			(xy 95.198482 -274.607678) (xy 95.148868 -274.588206) (xy 95.10271 -274.561557) (xy 95.061039 -274.528326)
			(xy 95.024787 -274.489255) (xy 94.994763 -274.445218) (xy 94.971637 -274.397197) (xy 94.955927 -274.346267)
			(xy 94.947984 -274.293563) (xy 94.719404 -274.293563) (xy 94.711461 -274.346267) (xy 94.695751 -274.397197)
			(xy 94.672625 -274.445218) (xy 94.642601 -274.489255) (xy 94.606349 -274.528326) (xy 94.564678 -274.561557)
			(xy 94.51852 -274.588206) (xy 94.468906 -274.607678) (xy 94.416944 -274.619538) (xy 94.363794 -274.623522)
			(xy 94.310644 -274.619538) (xy 94.258682 -274.607678) (xy 94.209068 -274.588206) (xy 94.16291 -274.561557)
			(xy 94.121239 -274.528326) (xy 94.084987 -274.489255) (xy 94.054963 -274.445218) (xy 94.031837 -274.397197)
			(xy 94.016127 -274.346267) (xy 94.008184 -274.293563) (xy 93.779604 -274.293563) (xy 93.771661 -274.346267)
			(xy 93.755951 -274.397197) (xy 93.732825 -274.445218) (xy 93.702801 -274.489255) (xy 93.666549 -274.528326)
			(xy 93.624878 -274.561557) (xy 93.57872 -274.588206) (xy 93.529106 -274.607678) (xy 93.477144 -274.619538)
			(xy 93.423994 -274.623522) (xy 93.370844 -274.619538) (xy 93.318882 -274.607678) (xy 93.269268 -274.588206)
			(xy 93.22311 -274.561557) (xy 93.181439 -274.528326) (xy 93.145187 -274.489255) (xy 93.115163 -274.445218)
			(xy 93.092037 -274.397197) (xy 93.076327 -274.346267) (xy 93.068384 -274.293563) (xy 92.839804 -274.293563)
			(xy 92.831861 -274.346267) (xy 92.816151 -274.397197) (xy 92.793025 -274.445218) (xy 92.763001 -274.489255)
			(xy 92.726749 -274.528326) (xy 92.685078 -274.561557) (xy 92.63892 -274.588206) (xy 92.589306 -274.607678)
			(xy 92.537344 -274.619538) (xy 92.484194 -274.623522) (xy 92.431044 -274.619538) (xy 92.379082 -274.607678)
			(xy 92.329468 -274.588206) (xy 92.28331 -274.561557) (xy 92.241639 -274.528326) (xy 92.205387 -274.489255)
			(xy 92.175363 -274.445218) (xy 92.152237 -274.397197) (xy 92.136527 -274.346267) (xy 92.128584 -274.293563)
			(xy 91.900258 -274.293563) (xy 91.892315 -274.346267) (xy 91.876605 -274.397197) (xy 91.853479 -274.445218)
			(xy 91.823455 -274.489255) (xy 91.787203 -274.528326) (xy 91.745532 -274.561557) (xy 91.699374 -274.588206)
			(xy 91.64976 -274.607678) (xy 91.597798 -274.619538) (xy 91.544648 -274.623522) (xy 91.491498 -274.619538)
			(xy 91.439536 -274.607678) (xy 91.389922 -274.588206) (xy 91.343764 -274.561557) (xy 91.302093 -274.528326)
			(xy 91.265841 -274.489255) (xy 91.235817 -274.445218) (xy 91.212691 -274.397197) (xy 91.196981 -274.346267)
			(xy 91.189038 -274.293563) (xy 90.960204 -274.293563) (xy 90.952261 -274.346267) (xy 90.936551 -274.397197)
			(xy 90.913425 -274.445218) (xy 90.883401 -274.489255) (xy 90.847149 -274.528326) (xy 90.805478 -274.561557)
			(xy 90.75932 -274.588206) (xy 90.709706 -274.607678) (xy 90.657744 -274.619538) (xy 90.604594 -274.623522)
			(xy 90.551444 -274.619538) (xy 90.499482 -274.607678) (xy 90.449868 -274.588206) (xy 90.40371 -274.561557)
			(xy 90.362039 -274.528326) (xy 90.325787 -274.489255) (xy 90.295763 -274.445218) (xy 90.272637 -274.397197)
			(xy 90.256927 -274.346267) (xy 90.248984 -274.293563) (xy 90.020404 -274.293563) (xy 90.012461 -274.346267)
			(xy 89.996751 -274.397197) (xy 89.973625 -274.445218) (xy 89.943601 -274.489255) (xy 89.907349 -274.528326)
			(xy 89.865678 -274.561557) (xy 89.81952 -274.588206) (xy 89.769906 -274.607678) (xy 89.717944 -274.619538)
			(xy 89.664794 -274.623522) (xy 89.611644 -274.619538) (xy 89.559682 -274.607678) (xy 89.510068 -274.588206)
			(xy 89.46391 -274.561557) (xy 89.422239 -274.528326) (xy 89.385987 -274.489255) (xy 89.355963 -274.445218)
			(xy 89.332837 -274.397197) (xy 89.317127 -274.346267) (xy 89.309184 -274.293563) (xy 89.080604 -274.293563)
			(xy 89.072661 -274.346267) (xy 89.056951 -274.397197) (xy 89.033825 -274.445218) (xy 89.003801 -274.489255)
			(xy 88.967549 -274.528326) (xy 88.925878 -274.561557) (xy 88.87972 -274.588206) (xy 88.830106 -274.607678)
			(xy 88.778144 -274.619538) (xy 88.724994 -274.623522) (xy 88.671844 -274.619538) (xy 88.619882 -274.607678)
			(xy 88.570268 -274.588206) (xy 88.52411 -274.561557) (xy 88.482439 -274.528326) (xy 88.446187 -274.489255)
			(xy 88.416163 -274.445218) (xy 88.393037 -274.397197) (xy 88.377327 -274.346267) (xy 88.369384 -274.293563)
			(xy 88.140778 -274.293563) (xy 88.140752 -274.294896) (xy 88.131995 -274.350171) (xy 88.114699 -274.403396)
			(xy 88.08929 -274.45326) (xy 88.056394 -274.498535) (xy 88.01682 -274.538107) (xy 87.971543 -274.571001)
			(xy 87.921678 -274.596407) (xy 87.868452 -274.6137) (xy 87.813176 -274.622454) (xy 87.785194 -274.623022)
			(xy 87.76034 -274.62259) (xy 87.711115 -274.615678) (xy 87.66333 -274.601989) (xy 87.617911 -274.58179)
			(xy 87.575742 -274.555472) (xy 87.537641 -274.523547) (xy 87.50435 -274.486635) (xy 87.490046 -274.466304)
			(xy 87.481232 -274.454243) (xy 87.458046 -274.435431) (xy 87.430413 -274.424119) (xy 87.400692 -274.42127)
			(xy 87.371414 -274.427128) (xy 87.345076 -274.441192) (xy 87.33409 -274.451318) (xy 87.234014 -274.551394)
			(xy 87.223763 -274.562475) (xy 87.209665 -274.58915) (xy 87.203979 -274.61878) (xy 87.207199 -274.648779)
			(xy 87.219045 -274.676527) (xy 87.238484 -274.699601) (xy 87.263817 -274.715988) (xy 87.292833 -274.724256)
			(xy 87.307928 -274.724622) (xy 87.31504 -274.724622) (xy 87.342117 -274.72513) (xy 87.395645 -274.733337)
			(xy 87.447313 -274.749553) (xy 87.49593 -274.773407) (xy 87.540375 -274.804347) (xy 87.579622 -274.84166)
			(xy 87.612767 -274.884486) (xy 87.639044 -274.931836) (xy 87.657849 -274.98262) (xy 87.668747 -275.035666)
			(xy 87.671487 -275.08975) (xy 87.669694 -275.107379) (xy 87.899484 -275.107379) (xy 87.899484 -275.054081)
			(xy 87.907427 -275.001377) (xy 87.923137 -274.950447) (xy 87.946263 -274.902426) (xy 87.976287 -274.858389)
			(xy 88.012539 -274.819318) (xy 88.05421 -274.786087) (xy 88.100368 -274.759438) (xy 88.149982 -274.739966)
			(xy 88.201944 -274.728106) (xy 88.255094 -274.724123) (xy 88.308244 -274.728106) (xy 88.360206 -274.739966)
			(xy 88.40982 -274.759438) (xy 88.455978 -274.786087) (xy 88.497649 -274.819318) (xy 88.533901 -274.858389)
			(xy 88.563925 -274.902426) (xy 88.587051 -274.950447) (xy 88.602761 -275.001377) (xy 88.610704 -275.054081)
			(xy 88.611202 -275.08073) (xy 88.610704 -275.107379) (xy 88.839284 -275.107379) (xy 88.839284 -275.054081)
			(xy 88.847227 -275.001377) (xy 88.862937 -274.950447) (xy 88.886063 -274.902426) (xy 88.916087 -274.858389)
			(xy 88.952339 -274.819318) (xy 88.99401 -274.786087) (xy 89.040168 -274.759438) (xy 89.089782 -274.739966)
			(xy 89.141744 -274.728106) (xy 89.194894 -274.724123) (xy 89.248044 -274.728106) (xy 89.300006 -274.739966)
			(xy 89.34962 -274.759438) (xy 89.395778 -274.786087) (xy 89.437449 -274.819318) (xy 89.473701 -274.858389)
			(xy 89.503725 -274.902426) (xy 89.526851 -274.950447) (xy 89.542561 -275.001377) (xy 89.550504 -275.054081)
			(xy 89.551002 -275.08073) (xy 89.550504 -275.107379) (xy 89.779084 -275.107379) (xy 89.779084 -275.054081)
			(xy 89.787027 -275.001377) (xy 89.802737 -274.950447) (xy 89.825863 -274.902426) (xy 89.855887 -274.858389)
			(xy 89.892139 -274.819318) (xy 89.93381 -274.786087) (xy 89.979968 -274.759438) (xy 90.029582 -274.739966)
			(xy 90.081544 -274.728106) (xy 90.134694 -274.724123) (xy 90.187844 -274.728106) (xy 90.239806 -274.739966)
			(xy 90.28942 -274.759438) (xy 90.335578 -274.786087) (xy 90.377249 -274.819318) (xy 90.413501 -274.858389)
			(xy 90.443525 -274.902426) (xy 90.466651 -274.950447) (xy 90.482361 -275.001377) (xy 90.490304 -275.054081)
			(xy 90.490802 -275.08073) (xy 90.490304 -275.107379) (xy 90.719138 -275.107379) (xy 90.719138 -275.054081)
			(xy 90.727081 -275.001377) (xy 90.742791 -274.950447) (xy 90.765917 -274.902426) (xy 90.795941 -274.858389)
			(xy 90.832193 -274.819318) (xy 90.873864 -274.786087) (xy 90.920022 -274.759438) (xy 90.969636 -274.739966)
			(xy 91.021598 -274.728106) (xy 91.074748 -274.724123) (xy 91.127898 -274.728106) (xy 91.17986 -274.739966)
			(xy 91.229474 -274.759438) (xy 91.275632 -274.786087) (xy 91.317303 -274.819318) (xy 91.353555 -274.858389)
			(xy 91.383579 -274.902426) (xy 91.406705 -274.950447) (xy 91.422415 -275.001377) (xy 91.430358 -275.054081)
			(xy 91.430856 -275.08073) (xy 91.430358 -275.107379) (xy 91.658684 -275.107379) (xy 91.658684 -275.054081)
			(xy 91.666627 -275.001377) (xy 91.682337 -274.950447) (xy 91.705463 -274.902426) (xy 91.735487 -274.858389)
			(xy 91.771739 -274.819318) (xy 91.81341 -274.786087) (xy 91.859568 -274.759438) (xy 91.909182 -274.739966)
			(xy 91.961144 -274.728106) (xy 92.014294 -274.724123) (xy 92.067444 -274.728106) (xy 92.119406 -274.739966)
			(xy 92.16902 -274.759438) (xy 92.215178 -274.786087) (xy 92.256849 -274.819318) (xy 92.293101 -274.858389)
			(xy 92.323125 -274.902426) (xy 92.346251 -274.950447) (xy 92.361961 -275.001377) (xy 92.369904 -275.054081)
			(xy 92.370402 -275.08073) (xy 92.369904 -275.107379) (xy 92.598738 -275.107379) (xy 92.598738 -275.054081)
			(xy 92.606681 -275.001377) (xy 92.622391 -274.950447) (xy 92.645517 -274.902426) (xy 92.675541 -274.858389)
			(xy 92.711793 -274.819318) (xy 92.753464 -274.786087) (xy 92.799622 -274.759438) (xy 92.849236 -274.739966)
			(xy 92.901198 -274.728106) (xy 92.954348 -274.724123) (xy 93.007498 -274.728106) (xy 93.05946 -274.739966)
			(xy 93.109074 -274.759438) (xy 93.155232 -274.786087) (xy 93.196903 -274.819318) (xy 93.233155 -274.858389)
			(xy 93.263179 -274.902426) (xy 93.286305 -274.950447) (xy 93.302015 -275.001377) (xy 93.309958 -275.054081)
			(xy 93.310456 -275.08073) (xy 93.309958 -275.107379) (xy 93.538538 -275.107379) (xy 93.538538 -275.054081)
			(xy 93.546481 -275.001377) (xy 93.562191 -274.950447) (xy 93.585317 -274.902426) (xy 93.615341 -274.858389)
			(xy 93.651593 -274.819318) (xy 93.693264 -274.786087) (xy 93.739422 -274.759438) (xy 93.789036 -274.739966)
			(xy 93.840998 -274.728106) (xy 93.894148 -274.724123) (xy 93.947298 -274.728106) (xy 93.99926 -274.739966)
			(xy 94.048874 -274.759438) (xy 94.095032 -274.786087) (xy 94.136703 -274.819318) (xy 94.172955 -274.858389)
			(xy 94.202979 -274.902426) (xy 94.226105 -274.950447) (xy 94.241815 -275.001377) (xy 94.249758 -275.054081)
			(xy 94.250256 -275.08073) (xy 94.249758 -275.107379) (xy 94.478338 -275.107379) (xy 94.478338 -275.054081)
			(xy 94.486281 -275.001377) (xy 94.501991 -274.950447) (xy 94.525117 -274.902426) (xy 94.555141 -274.858389)
			(xy 94.591393 -274.819318) (xy 94.633064 -274.786087) (xy 94.679222 -274.759438) (xy 94.728836 -274.739966)
			(xy 94.780798 -274.728106) (xy 94.833948 -274.724123) (xy 94.887098 -274.728106) (xy 94.93906 -274.739966)
			(xy 94.988674 -274.759438) (xy 95.034832 -274.786087) (xy 95.076503 -274.819318) (xy 95.112755 -274.858389)
			(xy 95.142779 -274.902426) (xy 95.165905 -274.950447) (xy 95.181615 -275.001377) (xy 95.189558 -275.054081)
			(xy 95.190056 -275.08073) (xy 95.189558 -275.107379) (xy 95.418138 -275.107379) (xy 95.418138 -275.054081)
			(xy 95.426081 -275.001377) (xy 95.441791 -274.950447) (xy 95.464917 -274.902426) (xy 95.494941 -274.858389)
			(xy 95.531193 -274.819318) (xy 95.572864 -274.786087) (xy 95.619022 -274.759438) (xy 95.668636 -274.739966)
			(xy 95.720598 -274.728106) (xy 95.773748 -274.724123) (xy 95.826898 -274.728106) (xy 95.87886 -274.739966)
			(xy 95.928474 -274.759438) (xy 95.974632 -274.786087) (xy 96.016303 -274.819318) (xy 96.052555 -274.858389)
			(xy 96.082579 -274.902426) (xy 96.105705 -274.950447) (xy 96.121415 -275.001377) (xy 96.129358 -275.054081)
			(xy 96.129856 -275.08073) (xy 96.129358 -275.107379) (xy 96.357938 -275.107379) (xy 96.357938 -275.054081)
			(xy 96.365881 -275.001377) (xy 96.381591 -274.950447) (xy 96.404717 -274.902426) (xy 96.434741 -274.858389)
			(xy 96.470993 -274.819318) (xy 96.512664 -274.786087) (xy 96.558822 -274.759438) (xy 96.608436 -274.739966)
			(xy 96.660398 -274.728106) (xy 96.713548 -274.724123) (xy 96.766698 -274.728106) (xy 96.81866 -274.739966)
			(xy 96.868274 -274.759438) (xy 96.914432 -274.786087) (xy 96.956103 -274.819318) (xy 96.992355 -274.858389)
			(xy 97.022379 -274.902426) (xy 97.045505 -274.950447) (xy 97.061215 -275.001377) (xy 97.069158 -275.054081)
			(xy 97.069656 -275.08073) (xy 97.069158 -275.107379) (xy 97.297738 -275.107379) (xy 97.297738 -275.054081)
			(xy 97.305681 -275.001377) (xy 97.321391 -274.950447) (xy 97.344517 -274.902426) (xy 97.374541 -274.858389)
			(xy 97.410793 -274.819318) (xy 97.452464 -274.786087) (xy 97.498622 -274.759438) (xy 97.548236 -274.739966)
			(xy 97.600198 -274.728106) (xy 97.653348 -274.724123) (xy 97.706498 -274.728106) (xy 97.75846 -274.739966)
			(xy 97.808074 -274.759438) (xy 97.854232 -274.786087) (xy 97.895903 -274.819318) (xy 97.932155 -274.858389)
			(xy 97.962179 -274.902426) (xy 97.985305 -274.950447) (xy 98.001015 -275.001377) (xy 98.008958 -275.054081)
			(xy 98.009456 -275.08073) (xy 98.008958 -275.107379) (xy 98.237284 -275.107379) (xy 98.237284 -275.054081)
			(xy 98.245227 -275.001377) (xy 98.260937 -274.950447) (xy 98.284063 -274.902426) (xy 98.314087 -274.858389)
			(xy 98.350339 -274.819318) (xy 98.39201 -274.786087) (xy 98.438168 -274.759438) (xy 98.487782 -274.739966)
			(xy 98.539744 -274.728106) (xy 98.592894 -274.724123) (xy 98.646044 -274.728106) (xy 98.698006 -274.739966)
			(xy 98.74762 -274.759438) (xy 98.793778 -274.786087) (xy 98.835449 -274.819318) (xy 98.871701 -274.858389)
			(xy 98.901725 -274.902426) (xy 98.924851 -274.950447) (xy 98.940561 -275.001377) (xy 98.948504 -275.054081)
			(xy 98.949002 -275.08073) (xy 98.948504 -275.107379) (xy 99.177338 -275.107379) (xy 99.177338 -275.054081)
			(xy 99.185281 -275.001377) (xy 99.200991 -274.950447) (xy 99.224117 -274.902426) (xy 99.254141 -274.858389)
			(xy 99.290393 -274.819318) (xy 99.332064 -274.786087) (xy 99.378222 -274.759438) (xy 99.427836 -274.739966)
			(xy 99.479798 -274.728106) (xy 99.532948 -274.724123) (xy 99.586098 -274.728106) (xy 99.63806 -274.739966)
			(xy 99.687674 -274.759438) (xy 99.733832 -274.786087) (xy 99.775503 -274.819318) (xy 99.811755 -274.858389)
			(xy 99.841779 -274.902426) (xy 99.864905 -274.950447) (xy 99.880615 -275.001377) (xy 99.888558 -275.054081)
			(xy 99.889056 -275.08073) (xy 99.888558 -275.107379) (xy 100.117138 -275.107379) (xy 100.117138 -275.054081)
			(xy 100.125081 -275.001377) (xy 100.140791 -274.950447) (xy 100.163917 -274.902426) (xy 100.193941 -274.858389)
			(xy 100.230193 -274.819318) (xy 100.271864 -274.786087) (xy 100.318022 -274.759438) (xy 100.367636 -274.739966)
			(xy 100.419598 -274.728106) (xy 100.472748 -274.724123) (xy 100.525898 -274.728106) (xy 100.57786 -274.739966)
			(xy 100.627474 -274.759438) (xy 100.673632 -274.786087) (xy 100.715303 -274.819318) (xy 100.751555 -274.858389)
			(xy 100.781579 -274.902426) (xy 100.804705 -274.950447) (xy 100.820415 -275.001377) (xy 100.828358 -275.054081)
			(xy 100.828855 -275.0807) (xy 101.995698 -275.0807) (xy 101.999682 -275.027547) (xy 102.011544 -274.975581)
			(xy 102.031019 -274.925964) (xy 102.057672 -274.879804) (xy 102.090908 -274.838132) (xy 102.129984 -274.80188)
			(xy 102.174027 -274.771858) (xy 102.222053 -274.748735) (xy 102.272989 -274.73303) (xy 102.325697 -274.725092)
			(xy 102.352348 -274.724622) (xy 102.377372 -274.725072) (xy 102.426929 -274.732074) (xy 102.475017 -274.745946)
			(xy 102.520688 -274.766416) (xy 102.563042 -274.793081) (xy 102.601245 -274.825414) (xy 102.634543 -274.862778)
			(xy 102.648766 -274.883372) (xy 102.99573 -274.883372) (xy 103.009932 -274.862762) (xy 103.043233 -274.825395)
			(xy 103.081438 -274.793059) (xy 103.123796 -274.766392) (xy 103.16947 -274.74592) (xy 103.217561 -274.732046)
			(xy 103.267122 -274.725043) (xy 103.292148 -274.724622) (xy 103.318797 -274.725063) (xy 103.371499 -274.733013)
			(xy 103.422428 -274.748729) (xy 103.470447 -274.771859) (xy 103.514481 -274.801887) (xy 103.553549 -274.838142)
			(xy 103.586778 -274.879814) (xy 103.613425 -274.925973) (xy 103.632896 -274.975588) (xy 103.644755 -275.02755)
			(xy 103.648738 -275.0807) (xy 103.644755 -275.13385) (xy 103.632896 -275.185812) (xy 103.613425 -275.235427)
			(xy 103.586778 -275.281586) (xy 103.553549 -275.323258) (xy 103.514481 -275.359513) (xy 103.470447 -275.389541)
			(xy 103.422428 -275.412671) (xy 103.371499 -275.428387) (xy 103.318797 -275.436337) (xy 103.292148 -275.436838)
			(xy 103.267125 -275.436365) (xy 103.21757 -275.429364) (xy 103.169484 -275.415494) (xy 103.123814 -275.395027)
			(xy 103.08146 -275.368367) (xy 103.043255 -275.336039) (xy 103.009954 -275.29868) (xy 102.99573 -275.278088)
			(xy 102.648766 -275.278088) (xy 102.634522 -275.298667) (xy 102.601226 -275.336032) (xy 102.563027 -275.368368)
			(xy 102.520676 -275.395037) (xy 102.47501 -275.415515) (xy 102.426926 -275.429397) (xy 102.377372 -275.436411)
			(xy 102.352348 -275.436838) (xy 102.325697 -275.436308) (xy 102.272989 -275.42837) (xy 102.222053 -275.412665)
			(xy 102.174027 -275.389542) (xy 102.129984 -275.35952) (xy 102.090908 -275.323268) (xy 102.057672 -275.281596)
			(xy 102.031019 -275.235436) (xy 102.011544 -275.185819) (xy 101.999682 -275.133853) (xy 101.995698 -275.0807)
			(xy 100.828855 -275.0807) (xy 100.828856 -275.08073) (xy 100.828358 -275.107379) (xy 100.820415 -275.160083)
			(xy 100.804705 -275.211013) (xy 100.781579 -275.259034) (xy 100.751555 -275.303071) (xy 100.715303 -275.342142)
			(xy 100.673632 -275.375373) (xy 100.627474 -275.402022) (xy 100.57786 -275.421494) (xy 100.525898 -275.433354)
			(xy 100.472748 -275.437338) (xy 100.419598 -275.433354) (xy 100.367636 -275.421494) (xy 100.318022 -275.402022)
			(xy 100.271864 -275.375373) (xy 100.230193 -275.342142) (xy 100.193941 -275.303071) (xy 100.163917 -275.259034)
			(xy 100.140791 -275.211013) (xy 100.125081 -275.160083) (xy 100.117138 -275.107379) (xy 99.888558 -275.107379)
			(xy 99.880615 -275.160083) (xy 99.864905 -275.211013) (xy 99.841779 -275.259034) (xy 99.811755 -275.303071)
			(xy 99.775503 -275.342142) (xy 99.733832 -275.375373) (xy 99.687674 -275.402022) (xy 99.63806 -275.421494)
			(xy 99.586098 -275.433354) (xy 99.532948 -275.437338) (xy 99.479798 -275.433354) (xy 99.427836 -275.421494)
			(xy 99.378222 -275.402022) (xy 99.332064 -275.375373) (xy 99.290393 -275.342142) (xy 99.254141 -275.303071)
			(xy 99.224117 -275.259034) (xy 99.200991 -275.211013) (xy 99.185281 -275.160083) (xy 99.177338 -275.107379)
			(xy 98.948504 -275.107379) (xy 98.940561 -275.160083) (xy 98.924851 -275.211013) (xy 98.901725 -275.259034)
			(xy 98.871701 -275.303071) (xy 98.835449 -275.342142) (xy 98.793778 -275.375373) (xy 98.74762 -275.402022)
			(xy 98.698006 -275.421494) (xy 98.646044 -275.433354) (xy 98.592894 -275.437338) (xy 98.539744 -275.433354)
			(xy 98.487782 -275.421494) (xy 98.438168 -275.402022) (xy 98.39201 -275.375373) (xy 98.350339 -275.342142)
			(xy 98.314087 -275.303071) (xy 98.284063 -275.259034) (xy 98.260937 -275.211013) (xy 98.245227 -275.160083)
			(xy 98.237284 -275.107379) (xy 98.008958 -275.107379) (xy 98.001015 -275.160083) (xy 97.985305 -275.211013)
			(xy 97.962179 -275.259034) (xy 97.932155 -275.303071) (xy 97.895903 -275.342142) (xy 97.854232 -275.375373)
			(xy 97.808074 -275.402022) (xy 97.75846 -275.421494) (xy 97.706498 -275.433354) (xy 97.653348 -275.437338)
			(xy 97.600198 -275.433354) (xy 97.548236 -275.421494) (xy 97.498622 -275.402022) (xy 97.452464 -275.375373)
			(xy 97.410793 -275.342142) (xy 97.374541 -275.303071) (xy 97.344517 -275.259034) (xy 97.321391 -275.211013)
			(xy 97.305681 -275.160083) (xy 97.297738 -275.107379) (xy 97.069158 -275.107379) (xy 97.061215 -275.160083)
			(xy 97.045505 -275.211013) (xy 97.022379 -275.259034) (xy 96.992355 -275.303071) (xy 96.956103 -275.342142)
			(xy 96.914432 -275.375373) (xy 96.868274 -275.402022) (xy 96.81866 -275.421494) (xy 96.766698 -275.433354)
			(xy 96.713548 -275.437338) (xy 96.660398 -275.433354) (xy 96.608436 -275.421494) (xy 96.558822 -275.402022)
			(xy 96.512664 -275.375373) (xy 96.470993 -275.342142) (xy 96.434741 -275.303071) (xy 96.404717 -275.259034)
			(xy 96.381591 -275.211013) (xy 96.365881 -275.160083) (xy 96.357938 -275.107379) (xy 96.129358 -275.107379)
			(xy 96.121415 -275.160083) (xy 96.105705 -275.211013) (xy 96.082579 -275.259034) (xy 96.052555 -275.303071)
			(xy 96.016303 -275.342142) (xy 95.974632 -275.375373) (xy 95.928474 -275.402022) (xy 95.87886 -275.421494)
			(xy 95.826898 -275.433354) (xy 95.773748 -275.437338) (xy 95.720598 -275.433354) (xy 95.668636 -275.421494)
			(xy 95.619022 -275.402022) (xy 95.572864 -275.375373) (xy 95.531193 -275.342142) (xy 95.494941 -275.303071)
			(xy 95.464917 -275.259034) (xy 95.441791 -275.211013) (xy 95.426081 -275.160083) (xy 95.418138 -275.107379)
			(xy 95.189558 -275.107379) (xy 95.181615 -275.160083) (xy 95.165905 -275.211013) (xy 95.142779 -275.259034)
			(xy 95.112755 -275.303071) (xy 95.076503 -275.342142) (xy 95.034832 -275.375373) (xy 94.988674 -275.402022)
			(xy 94.93906 -275.421494) (xy 94.887098 -275.433354) (xy 94.833948 -275.437338) (xy 94.780798 -275.433354)
			(xy 94.728836 -275.421494) (xy 94.679222 -275.402022) (xy 94.633064 -275.375373) (xy 94.591393 -275.342142)
			(xy 94.555141 -275.303071) (xy 94.525117 -275.259034) (xy 94.501991 -275.211013) (xy 94.486281 -275.160083)
			(xy 94.478338 -275.107379) (xy 94.249758 -275.107379) (xy 94.241815 -275.160083) (xy 94.226105 -275.211013)
			(xy 94.202979 -275.259034) (xy 94.172955 -275.303071) (xy 94.136703 -275.342142) (xy 94.095032 -275.375373)
			(xy 94.048874 -275.402022) (xy 93.99926 -275.421494) (xy 93.947298 -275.433354) (xy 93.894148 -275.437338)
			(xy 93.840998 -275.433354) (xy 93.789036 -275.421494) (xy 93.739422 -275.402022) (xy 93.693264 -275.375373)
			(xy 93.651593 -275.342142) (xy 93.615341 -275.303071) (xy 93.585317 -275.259034) (xy 93.562191 -275.211013)
			(xy 93.546481 -275.160083) (xy 93.538538 -275.107379) (xy 93.309958 -275.107379) (xy 93.302015 -275.160083)
			(xy 93.286305 -275.211013) (xy 93.263179 -275.259034) (xy 93.233155 -275.303071) (xy 93.196903 -275.342142)
			(xy 93.155232 -275.375373) (xy 93.109074 -275.402022) (xy 93.05946 -275.421494) (xy 93.007498 -275.433354)
			(xy 92.954348 -275.437338) (xy 92.901198 -275.433354) (xy 92.849236 -275.421494) (xy 92.799622 -275.402022)
			(xy 92.753464 -275.375373) (xy 92.711793 -275.342142) (xy 92.675541 -275.303071) (xy 92.645517 -275.259034)
			(xy 92.622391 -275.211013) (xy 92.606681 -275.160083) (xy 92.598738 -275.107379) (xy 92.369904 -275.107379)
			(xy 92.361961 -275.160083) (xy 92.346251 -275.211013) (xy 92.323125 -275.259034) (xy 92.293101 -275.303071)
			(xy 92.256849 -275.342142) (xy 92.215178 -275.375373) (xy 92.16902 -275.402022) (xy 92.119406 -275.421494)
			(xy 92.067444 -275.433354) (xy 92.014294 -275.437338) (xy 91.961144 -275.433354) (xy 91.909182 -275.421494)
			(xy 91.859568 -275.402022) (xy 91.81341 -275.375373) (xy 91.771739 -275.342142) (xy 91.735487 -275.303071)
			(xy 91.705463 -275.259034) (xy 91.682337 -275.211013) (xy 91.666627 -275.160083) (xy 91.658684 -275.107379)
			(xy 91.430358 -275.107379) (xy 91.422415 -275.160083) (xy 91.406705 -275.211013) (xy 91.383579 -275.259034)
			(xy 91.353555 -275.303071) (xy 91.317303 -275.342142) (xy 91.275632 -275.375373) (xy 91.229474 -275.402022)
			(xy 91.17986 -275.421494) (xy 91.127898 -275.433354) (xy 91.074748 -275.437338) (xy 91.021598 -275.433354)
			(xy 90.969636 -275.421494) (xy 90.920022 -275.402022) (xy 90.873864 -275.375373) (xy 90.832193 -275.342142)
			(xy 90.795941 -275.303071) (xy 90.765917 -275.259034) (xy 90.742791 -275.211013) (xy 90.727081 -275.160083)
			(xy 90.719138 -275.107379) (xy 90.490304 -275.107379) (xy 90.482361 -275.160083) (xy 90.466651 -275.211013)
			(xy 90.443525 -275.259034) (xy 90.413501 -275.303071) (xy 90.377249 -275.342142) (xy 90.335578 -275.375373)
			(xy 90.28942 -275.402022) (xy 90.239806 -275.421494) (xy 90.187844 -275.433354) (xy 90.134694 -275.437338)
			(xy 90.081544 -275.433354) (xy 90.029582 -275.421494) (xy 89.979968 -275.402022) (xy 89.93381 -275.375373)
			(xy 89.892139 -275.342142) (xy 89.855887 -275.303071) (xy 89.825863 -275.259034) (xy 89.802737 -275.211013)
			(xy 89.787027 -275.160083) (xy 89.779084 -275.107379) (xy 89.550504 -275.107379) (xy 89.542561 -275.160083)
			(xy 89.526851 -275.211013) (xy 89.503725 -275.259034) (xy 89.473701 -275.303071) (xy 89.437449 -275.342142)
			(xy 89.395778 -275.375373) (xy 89.34962 -275.402022) (xy 89.300006 -275.421494) (xy 89.248044 -275.433354)
			(xy 89.194894 -275.437338) (xy 89.141744 -275.433354) (xy 89.089782 -275.421494) (xy 89.040168 -275.402022)
			(xy 88.99401 -275.375373) (xy 88.952339 -275.342142) (xy 88.916087 -275.303071) (xy 88.886063 -275.259034)
			(xy 88.862937 -275.211013) (xy 88.847227 -275.160083) (xy 88.839284 -275.107379) (xy 88.610704 -275.107379)
			(xy 88.602761 -275.160083) (xy 88.587051 -275.211013) (xy 88.563925 -275.259034) (xy 88.533901 -275.303071)
			(xy 88.497649 -275.342142) (xy 88.455978 -275.375373) (xy 88.40982 -275.402022) (xy 88.360206 -275.421494)
			(xy 88.308244 -275.433354) (xy 88.255094 -275.437338) (xy 88.201944 -275.433354) (xy 88.149982 -275.421494)
			(xy 88.100368 -275.402022) (xy 88.05421 -275.375373) (xy 88.012539 -275.342142) (xy 87.976287 -275.303071)
			(xy 87.946263 -275.259034) (xy 87.923137 -275.211013) (xy 87.907427 -275.160083) (xy 87.899484 -275.107379)
			(xy 87.669694 -275.107379) (xy 87.666006 -275.143625) (xy 87.652431 -275.19605) (xy 87.631073 -275.245814)
			(xy 87.602427 -275.29177) (xy 87.567152 -275.332859) (xy 87.526062 -275.368133) (xy 87.480105 -275.396778)
			(xy 87.43034 -275.418134) (xy 87.377916 -275.431708) (xy 87.32404 -275.437187) (xy 87.269956 -275.434446)
			(xy 87.216911 -275.423546) (xy 87.166127 -275.40474) (xy 87.118777 -275.378461) (xy 87.075952 -275.345315)
			(xy 87.03864 -275.306067) (xy 87.007702 -275.261622) (xy 86.98385 -275.213004) (xy 86.967634 -275.161335)
			(xy 86.95943 -275.107807) (xy 86.958932 -275.08073) (xy 86.958932 -275.073618) (xy 86.958696 -275.058497)
			(xy 86.950454 -275.029418) (xy 86.934062 -275.004024) (xy 86.910955 -274.984541) (xy 86.883157 -274.972674)
			(xy 86.853103 -274.969463) (xy 86.823425 -274.975189) (xy 86.796723 -274.989351) (xy 86.785704 -274.999704)
			(xy 86.718902 -275.066506) (xy 86.718648 -275.086826) (xy 86.717696 -275.113194) (xy 86.7087 -275.165182)
			(xy 86.69186 -275.215183) (xy 86.667573 -275.262021) (xy 86.636409 -275.304595) (xy 86.599102 -275.341903)
			(xy 86.55653 -275.373067) (xy 86.509692 -275.397356) (xy 86.459691 -275.414197) (xy 86.407704 -275.423195)
			(xy 86.381336 -275.424138) (xy 86.361016 -275.424392) (xy 85.863959 -275.921449) (xy 87.42933 -275.921449)
			(xy 87.42933 -275.868151) (xy 87.437273 -275.815447) (xy 87.452983 -275.764517) (xy 87.476109 -275.716496)
			(xy 87.506133 -275.672459) (xy 87.542385 -275.633388) (xy 87.584056 -275.600157) (xy 87.630214 -275.573508)
			(xy 87.679828 -275.554036) (xy 87.73179 -275.542176) (xy 87.78494 -275.538193) (xy 87.83809 -275.542176)
			(xy 87.890052 -275.554036) (xy 87.939666 -275.573508) (xy 87.985824 -275.600157) (xy 88.027495 -275.633388)
			(xy 88.063747 -275.672459) (xy 88.093771 -275.716496) (xy 88.116897 -275.764517) (xy 88.132607 -275.815447)
			(xy 88.14055 -275.868151) (xy 88.141048 -275.8948) (xy 88.14055 -275.921449) (xy 88.369384 -275.921449)
			(xy 88.369384 -275.868151) (xy 88.377327 -275.815447) (xy 88.393037 -275.764517) (xy 88.416163 -275.716496)
			(xy 88.446187 -275.672459) (xy 88.482439 -275.633388) (xy 88.52411 -275.600157) (xy 88.570268 -275.573508)
			(xy 88.619882 -275.554036) (xy 88.671844 -275.542176) (xy 88.724994 -275.538193) (xy 88.778144 -275.542176)
			(xy 88.830106 -275.554036) (xy 88.87972 -275.573508) (xy 88.925878 -275.600157) (xy 88.967549 -275.633388)
			(xy 89.003801 -275.672459) (xy 89.033825 -275.716496) (xy 89.056951 -275.764517) (xy 89.072661 -275.815447)
			(xy 89.080604 -275.868151) (xy 89.081102 -275.8948) (xy 89.080604 -275.921449) (xy 89.309184 -275.921449)
			(xy 89.309184 -275.868151) (xy 89.317127 -275.815447) (xy 89.332837 -275.764517) (xy 89.355963 -275.716496)
			(xy 89.385987 -275.672459) (xy 89.422239 -275.633388) (xy 89.46391 -275.600157) (xy 89.510068 -275.573508)
			(xy 89.559682 -275.554036) (xy 89.611644 -275.542176) (xy 89.664794 -275.538193) (xy 89.717944 -275.542176)
			(xy 89.769906 -275.554036) (xy 89.81952 -275.573508) (xy 89.865678 -275.600157) (xy 89.907349 -275.633388)
			(xy 89.943601 -275.672459) (xy 89.973625 -275.716496) (xy 89.996751 -275.764517) (xy 90.012461 -275.815447)
			(xy 90.020404 -275.868151) (xy 90.020902 -275.8948) (xy 90.020404 -275.921449) (xy 90.248984 -275.921449)
			(xy 90.248984 -275.868151) (xy 90.256927 -275.815447) (xy 90.272637 -275.764517) (xy 90.295763 -275.716496)
			(xy 90.325787 -275.672459) (xy 90.362039 -275.633388) (xy 90.40371 -275.600157) (xy 90.449868 -275.573508)
			(xy 90.499482 -275.554036) (xy 90.551444 -275.542176) (xy 90.604594 -275.538193) (xy 90.657744 -275.542176)
			(xy 90.709706 -275.554036) (xy 90.75932 -275.573508) (xy 90.805478 -275.600157) (xy 90.847149 -275.633388)
			(xy 90.883401 -275.672459) (xy 90.913425 -275.716496) (xy 90.936551 -275.764517) (xy 90.952261 -275.815447)
			(xy 90.960204 -275.868151) (xy 90.960702 -275.8948) (xy 90.960204 -275.921449) (xy 91.188784 -275.921449)
			(xy 91.188784 -275.868151) (xy 91.196727 -275.815447) (xy 91.212437 -275.764517) (xy 91.235563 -275.716496)
			(xy 91.265587 -275.672459) (xy 91.301839 -275.633388) (xy 91.34351 -275.600157) (xy 91.389668 -275.573508)
			(xy 91.439282 -275.554036) (xy 91.491244 -275.542176) (xy 91.544394 -275.538193) (xy 91.597544 -275.542176)
			(xy 91.649506 -275.554036) (xy 91.69912 -275.573508) (xy 91.745278 -275.600157) (xy 91.786949 -275.633388)
			(xy 91.823201 -275.672459) (xy 91.853225 -275.716496) (xy 91.876351 -275.764517) (xy 91.892061 -275.815447)
			(xy 91.900004 -275.868151) (xy 91.900502 -275.8948) (xy 91.900004 -275.921449) (xy 92.128584 -275.921449)
			(xy 92.128584 -275.868151) (xy 92.136527 -275.815447) (xy 92.152237 -275.764517) (xy 92.175363 -275.716496)
			(xy 92.205387 -275.672459) (xy 92.241639 -275.633388) (xy 92.28331 -275.600157) (xy 92.329468 -275.573508)
			(xy 92.379082 -275.554036) (xy 92.431044 -275.542176) (xy 92.484194 -275.538193) (xy 92.537344 -275.542176)
			(xy 92.589306 -275.554036) (xy 92.63892 -275.573508) (xy 92.685078 -275.600157) (xy 92.726749 -275.633388)
			(xy 92.763001 -275.672459) (xy 92.793025 -275.716496) (xy 92.816151 -275.764517) (xy 92.831861 -275.815447)
			(xy 92.839804 -275.868151) (xy 92.840302 -275.8948) (xy 92.839804 -275.921449) (xy 93.068384 -275.921449)
			(xy 93.068384 -275.868151) (xy 93.076327 -275.815447) (xy 93.092037 -275.764517) (xy 93.115163 -275.716496)
			(xy 93.145187 -275.672459) (xy 93.181439 -275.633388) (xy 93.22311 -275.600157) (xy 93.269268 -275.573508)
			(xy 93.318882 -275.554036) (xy 93.370844 -275.542176) (xy 93.423994 -275.538193) (xy 93.477144 -275.542176)
			(xy 93.529106 -275.554036) (xy 93.57872 -275.573508) (xy 93.624878 -275.600157) (xy 93.666549 -275.633388)
			(xy 93.702801 -275.672459) (xy 93.732825 -275.716496) (xy 93.755951 -275.764517) (xy 93.771661 -275.815447)
			(xy 93.779604 -275.868151) (xy 93.780102 -275.8948) (xy 93.779604 -275.921449) (xy 94.008438 -275.921449)
			(xy 94.008438 -275.868151) (xy 94.016381 -275.815447) (xy 94.032091 -275.764517) (xy 94.055217 -275.716496)
			(xy 94.085241 -275.672459) (xy 94.121493 -275.633388) (xy 94.163164 -275.600157) (xy 94.209322 -275.573508)
			(xy 94.258936 -275.554036) (xy 94.310898 -275.542176) (xy 94.364048 -275.538193) (xy 94.417198 -275.542176)
			(xy 94.46916 -275.554036) (xy 94.518774 -275.573508) (xy 94.564932 -275.600157) (xy 94.606603 -275.633388)
			(xy 94.642855 -275.672459) (xy 94.672879 -275.716496) (xy 94.696005 -275.764517) (xy 94.711715 -275.815447)
			(xy 94.719658 -275.868151) (xy 94.720156 -275.8948) (xy 94.719658 -275.921449) (xy 94.947984 -275.921449)
			(xy 94.947984 -275.868151) (xy 94.955927 -275.815447) (xy 94.971637 -275.764517) (xy 94.994763 -275.716496)
			(xy 95.024787 -275.672459) (xy 95.061039 -275.633388) (xy 95.10271 -275.600157) (xy 95.148868 -275.573508)
			(xy 95.198482 -275.554036) (xy 95.250444 -275.542176) (xy 95.303594 -275.538193) (xy 95.356744 -275.542176)
			(xy 95.408706 -275.554036) (xy 95.45832 -275.573508) (xy 95.504478 -275.600157) (xy 95.546149 -275.633388)
			(xy 95.582401 -275.672459) (xy 95.612425 -275.716496) (xy 95.635551 -275.764517) (xy 95.651261 -275.815447)
			(xy 95.659204 -275.868151) (xy 95.659702 -275.8948) (xy 95.659204 -275.921449) (xy 95.887784 -275.921449)
			(xy 95.887784 -275.868151) (xy 95.895727 -275.815447) (xy 95.911437 -275.764517) (xy 95.934563 -275.716496)
			(xy 95.964587 -275.672459) (xy 96.000839 -275.633388) (xy 96.04251 -275.600157) (xy 96.088668 -275.573508)
			(xy 96.138282 -275.554036) (xy 96.190244 -275.542176) (xy 96.243394 -275.538193) (xy 96.296544 -275.542176)
			(xy 96.348506 -275.554036) (xy 96.39812 -275.573508) (xy 96.444278 -275.600157) (xy 96.485949 -275.633388)
			(xy 96.522201 -275.672459) (xy 96.552225 -275.716496) (xy 96.575351 -275.764517) (xy 96.591061 -275.815447)
			(xy 96.599004 -275.868151) (xy 96.599502 -275.8948) (xy 96.599004 -275.921449) (xy 96.827584 -275.921449)
			(xy 96.827584 -275.868151) (xy 96.835527 -275.815447) (xy 96.851237 -275.764517) (xy 96.874363 -275.716496)
			(xy 96.904387 -275.672459) (xy 96.940639 -275.633388) (xy 96.98231 -275.600157) (xy 97.028468 -275.573508)
			(xy 97.078082 -275.554036) (xy 97.130044 -275.542176) (xy 97.183194 -275.538193) (xy 97.236344 -275.542176)
			(xy 97.288306 -275.554036) (xy 97.33792 -275.573508) (xy 97.384078 -275.600157) (xy 97.425749 -275.633388)
			(xy 97.462001 -275.672459) (xy 97.492025 -275.716496) (xy 97.515151 -275.764517) (xy 97.530861 -275.815447)
			(xy 97.538804 -275.868151) (xy 97.539302 -275.8948) (xy 97.538804 -275.921449) (xy 97.767384 -275.921449)
			(xy 97.767384 -275.868151) (xy 97.775327 -275.815447) (xy 97.791037 -275.764517) (xy 97.814163 -275.716496)
			(xy 97.844187 -275.672459) (xy 97.880439 -275.633388) (xy 97.92211 -275.600157) (xy 97.968268 -275.573508)
			(xy 98.017882 -275.554036) (xy 98.069844 -275.542176) (xy 98.122994 -275.538193) (xy 98.176144 -275.542176)
			(xy 98.228106 -275.554036) (xy 98.27772 -275.573508) (xy 98.323878 -275.600157) (xy 98.365549 -275.633388)
			(xy 98.401801 -275.672459) (xy 98.431825 -275.716496) (xy 98.454951 -275.764517) (xy 98.470661 -275.815447)
			(xy 98.478604 -275.868151) (xy 98.479102 -275.8948) (xy 98.478604 -275.921449) (xy 98.707184 -275.921449)
			(xy 98.707184 -275.868151) (xy 98.715127 -275.815447) (xy 98.730837 -275.764517) (xy 98.753963 -275.716496)
			(xy 98.783987 -275.672459) (xy 98.820239 -275.633388) (xy 98.86191 -275.600157) (xy 98.908068 -275.573508)
			(xy 98.957682 -275.554036) (xy 99.009644 -275.542176) (xy 99.062794 -275.538193) (xy 99.115944 -275.542176)
			(xy 99.167906 -275.554036) (xy 99.21752 -275.573508) (xy 99.263678 -275.600157) (xy 99.305349 -275.633388)
			(xy 99.341601 -275.672459) (xy 99.371625 -275.716496) (xy 99.394751 -275.764517) (xy 99.410461 -275.815447)
			(xy 99.418404 -275.868151) (xy 99.418902 -275.8948) (xy 99.418404 -275.921449) (xy 99.646984 -275.921449)
			(xy 99.646984 -275.868151) (xy 99.654927 -275.815447) (xy 99.670637 -275.764517) (xy 99.693763 -275.716496)
			(xy 99.723787 -275.672459) (xy 99.760039 -275.633388) (xy 99.80171 -275.600157) (xy 99.847868 -275.573508)
			(xy 99.897482 -275.554036) (xy 99.949444 -275.542176) (xy 100.002594 -275.538193) (xy 100.055744 -275.542176)
			(xy 100.107706 -275.554036) (xy 100.15732 -275.573508) (xy 100.203478 -275.600157) (xy 100.245149 -275.633388)
			(xy 100.281401 -275.672459) (xy 100.311425 -275.716496) (xy 100.334551 -275.764517) (xy 100.350261 -275.815447)
			(xy 100.358204 -275.868151) (xy 100.358702 -275.8948) (xy 100.358204 -275.921449) (xy 100.587038 -275.921449)
			(xy 100.587038 -275.868151) (xy 100.594981 -275.815447) (xy 100.610691 -275.764517) (xy 100.633817 -275.716496)
			(xy 100.663841 -275.672459) (xy 100.700093 -275.633388) (xy 100.741764 -275.600157) (xy 100.787922 -275.573508)
			(xy 100.837536 -275.554036) (xy 100.889498 -275.542176) (xy 100.942648 -275.538193) (xy 100.995798 -275.542176)
			(xy 101.04776 -275.554036) (xy 101.097374 -275.573508) (xy 101.143532 -275.600157) (xy 101.185203 -275.633388)
			(xy 101.221455 -275.672459) (xy 101.251479 -275.716496) (xy 101.274605 -275.764517) (xy 101.290315 -275.815447)
			(xy 101.298258 -275.868151) (xy 101.298756 -275.8948) (xy 101.298258 -275.921449) (xy 101.526584 -275.921449)
			(xy 101.526584 -275.868151) (xy 101.534527 -275.815447) (xy 101.550237 -275.764517) (xy 101.573363 -275.716496)
			(xy 101.603387 -275.672459) (xy 101.639639 -275.633388) (xy 101.68131 -275.600157) (xy 101.727468 -275.573508)
			(xy 101.777082 -275.554036) (xy 101.829044 -275.542176) (xy 101.882194 -275.538193) (xy 101.935344 -275.542176)
			(xy 101.987306 -275.554036) (xy 102.03692 -275.573508) (xy 102.083078 -275.600157) (xy 102.124749 -275.633388)
			(xy 102.161001 -275.672459) (xy 102.191025 -275.716496) (xy 102.214151 -275.764517) (xy 102.229861 -275.815447)
			(xy 102.237804 -275.868151) (xy 102.238302 -275.8948) (xy 102.237804 -275.921449) (xy 102.229861 -275.974153)
			(xy 102.214151 -276.025083) (xy 102.191025 -276.073104) (xy 102.161001 -276.117141) (xy 102.124749 -276.156212)
			(xy 102.083078 -276.189443) (xy 102.03692 -276.216092) (xy 101.987306 -276.235564) (xy 101.935344 -276.247424)
			(xy 101.882194 -276.251408) (xy 101.829044 -276.247424) (xy 101.777082 -276.235564) (xy 101.727468 -276.216092)
			(xy 101.68131 -276.189443) (xy 101.639639 -276.156212) (xy 101.603387 -276.117141) (xy 101.573363 -276.073104)
			(xy 101.550237 -276.025083) (xy 101.534527 -275.974153) (xy 101.526584 -275.921449) (xy 101.298258 -275.921449)
			(xy 101.290315 -275.974153) (xy 101.274605 -276.025083) (xy 101.251479 -276.073104) (xy 101.221455 -276.117141)
			(xy 101.185203 -276.156212) (xy 101.143532 -276.189443) (xy 101.097374 -276.216092) (xy 101.04776 -276.235564)
			(xy 100.995798 -276.247424) (xy 100.942648 -276.251408) (xy 100.889498 -276.247424) (xy 100.837536 -276.235564)
			(xy 100.787922 -276.216092) (xy 100.741764 -276.189443) (xy 100.700093 -276.156212) (xy 100.663841 -276.117141)
			(xy 100.633817 -276.073104) (xy 100.610691 -276.025083) (xy 100.594981 -275.974153) (xy 100.587038 -275.921449)
			(xy 100.358204 -275.921449) (xy 100.350261 -275.974153) (xy 100.334551 -276.025083) (xy 100.311425 -276.073104)
			(xy 100.281401 -276.117141) (xy 100.245149 -276.156212) (xy 100.203478 -276.189443) (xy 100.15732 -276.216092)
			(xy 100.107706 -276.235564) (xy 100.055744 -276.247424) (xy 100.002594 -276.251408) (xy 99.949444 -276.247424)
			(xy 99.897482 -276.235564) (xy 99.847868 -276.216092) (xy 99.80171 -276.189443) (xy 99.760039 -276.156212)
			(xy 99.723787 -276.117141) (xy 99.693763 -276.073104) (xy 99.670637 -276.025083) (xy 99.654927 -275.974153)
			(xy 99.646984 -275.921449) (xy 99.418404 -275.921449) (xy 99.410461 -275.974153) (xy 99.394751 -276.025083)
			(xy 99.371625 -276.073104) (xy 99.341601 -276.117141) (xy 99.305349 -276.156212) (xy 99.263678 -276.189443)
			(xy 99.21752 -276.216092) (xy 99.167906 -276.235564) (xy 99.115944 -276.247424) (xy 99.062794 -276.251408)
			(xy 99.009644 -276.247424) (xy 98.957682 -276.235564) (xy 98.908068 -276.216092) (xy 98.86191 -276.189443)
			(xy 98.820239 -276.156212) (xy 98.783987 -276.117141) (xy 98.753963 -276.073104) (xy 98.730837 -276.025083)
			(xy 98.715127 -275.974153) (xy 98.707184 -275.921449) (xy 98.478604 -275.921449) (xy 98.470661 -275.974153)
			(xy 98.454951 -276.025083) (xy 98.431825 -276.073104) (xy 98.401801 -276.117141) (xy 98.365549 -276.156212)
			(xy 98.323878 -276.189443) (xy 98.27772 -276.216092) (xy 98.228106 -276.235564) (xy 98.176144 -276.247424)
			(xy 98.122994 -276.251408) (xy 98.069844 -276.247424) (xy 98.017882 -276.235564) (xy 97.968268 -276.216092)
			(xy 97.92211 -276.189443) (xy 97.880439 -276.156212) (xy 97.844187 -276.117141) (xy 97.814163 -276.073104)
			(xy 97.791037 -276.025083) (xy 97.775327 -275.974153) (xy 97.767384 -275.921449) (xy 97.538804 -275.921449)
			(xy 97.530861 -275.974153) (xy 97.515151 -276.025083) (xy 97.492025 -276.073104) (xy 97.462001 -276.117141)
			(xy 97.425749 -276.156212) (xy 97.384078 -276.189443) (xy 97.33792 -276.216092) (xy 97.288306 -276.235564)
			(xy 97.236344 -276.247424) (xy 97.183194 -276.251408) (xy 97.130044 -276.247424) (xy 97.078082 -276.235564)
			(xy 97.028468 -276.216092) (xy 96.98231 -276.189443) (xy 96.940639 -276.156212) (xy 96.904387 -276.117141)
			(xy 96.874363 -276.073104) (xy 96.851237 -276.025083) (xy 96.835527 -275.974153) (xy 96.827584 -275.921449)
			(xy 96.599004 -275.921449) (xy 96.591061 -275.974153) (xy 96.575351 -276.025083) (xy 96.552225 -276.073104)
			(xy 96.522201 -276.117141) (xy 96.485949 -276.156212) (xy 96.444278 -276.189443) (xy 96.39812 -276.216092)
			(xy 96.348506 -276.235564) (xy 96.296544 -276.247424) (xy 96.243394 -276.251408) (xy 96.190244 -276.247424)
			(xy 96.138282 -276.235564) (xy 96.088668 -276.216092) (xy 96.04251 -276.189443) (xy 96.000839 -276.156212)
			(xy 95.964587 -276.117141) (xy 95.934563 -276.073104) (xy 95.911437 -276.025083) (xy 95.895727 -275.974153)
			(xy 95.887784 -275.921449) (xy 95.659204 -275.921449) (xy 95.651261 -275.974153) (xy 95.635551 -276.025083)
			(xy 95.612425 -276.073104) (xy 95.582401 -276.117141) (xy 95.546149 -276.156212) (xy 95.504478 -276.189443)
			(xy 95.45832 -276.216092) (xy 95.408706 -276.235564) (xy 95.356744 -276.247424) (xy 95.303594 -276.251408)
			(xy 95.250444 -276.247424) (xy 95.198482 -276.235564) (xy 95.148868 -276.216092) (xy 95.10271 -276.189443)
			(xy 95.061039 -276.156212) (xy 95.024787 -276.117141) (xy 94.994763 -276.073104) (xy 94.971637 -276.025083)
			(xy 94.955927 -275.974153) (xy 94.947984 -275.921449) (xy 94.719658 -275.921449) (xy 94.711715 -275.974153)
			(xy 94.696005 -276.025083) (xy 94.672879 -276.073104) (xy 94.642855 -276.117141) (xy 94.606603 -276.156212)
			(xy 94.564932 -276.189443) (xy 94.518774 -276.216092) (xy 94.46916 -276.235564) (xy 94.417198 -276.247424)
			(xy 94.364048 -276.251408) (xy 94.310898 -276.247424) (xy 94.258936 -276.235564) (xy 94.209322 -276.216092)
			(xy 94.163164 -276.189443) (xy 94.121493 -276.156212) (xy 94.085241 -276.117141) (xy 94.055217 -276.073104)
			(xy 94.032091 -276.025083) (xy 94.016381 -275.974153) (xy 94.008438 -275.921449) (xy 93.779604 -275.921449)
			(xy 93.771661 -275.974153) (xy 93.755951 -276.025083) (xy 93.732825 -276.073104) (xy 93.702801 -276.117141)
			(xy 93.666549 -276.156212) (xy 93.624878 -276.189443) (xy 93.57872 -276.216092) (xy 93.529106 -276.235564)
			(xy 93.477144 -276.247424) (xy 93.423994 -276.251408) (xy 93.370844 -276.247424) (xy 93.318882 -276.235564)
			(xy 93.269268 -276.216092) (xy 93.22311 -276.189443) (xy 93.181439 -276.156212) (xy 93.145187 -276.117141)
			(xy 93.115163 -276.073104) (xy 93.092037 -276.025083) (xy 93.076327 -275.974153) (xy 93.068384 -275.921449)
			(xy 92.839804 -275.921449) (xy 92.831861 -275.974153) (xy 92.816151 -276.025083) (xy 92.793025 -276.073104)
			(xy 92.763001 -276.117141) (xy 92.726749 -276.156212) (xy 92.685078 -276.189443) (xy 92.63892 -276.216092)
			(xy 92.589306 -276.235564) (xy 92.537344 -276.247424) (xy 92.484194 -276.251408) (xy 92.431044 -276.247424)
			(xy 92.379082 -276.235564) (xy 92.329468 -276.216092) (xy 92.28331 -276.189443) (xy 92.241639 -276.156212)
			(xy 92.205387 -276.117141) (xy 92.175363 -276.073104) (xy 92.152237 -276.025083) (xy 92.136527 -275.974153)
			(xy 92.128584 -275.921449) (xy 91.900004 -275.921449) (xy 91.892061 -275.974153) (xy 91.876351 -276.025083)
			(xy 91.853225 -276.073104) (xy 91.823201 -276.117141) (xy 91.786949 -276.156212) (xy 91.745278 -276.189443)
			(xy 91.69912 -276.216092) (xy 91.649506 -276.235564) (xy 91.597544 -276.247424) (xy 91.544394 -276.251408)
			(xy 91.491244 -276.247424) (xy 91.439282 -276.235564) (xy 91.389668 -276.216092) (xy 91.34351 -276.189443)
			(xy 91.301839 -276.156212) (xy 91.265587 -276.117141) (xy 91.235563 -276.073104) (xy 91.212437 -276.025083)
			(xy 91.196727 -275.974153) (xy 91.188784 -275.921449) (xy 90.960204 -275.921449) (xy 90.952261 -275.974153)
			(xy 90.936551 -276.025083) (xy 90.913425 -276.073104) (xy 90.883401 -276.117141) (xy 90.847149 -276.156212)
			(xy 90.805478 -276.189443) (xy 90.75932 -276.216092) (xy 90.709706 -276.235564) (xy 90.657744 -276.247424)
			(xy 90.604594 -276.251408) (xy 90.551444 -276.247424) (xy 90.499482 -276.235564) (xy 90.449868 -276.216092)
			(xy 90.40371 -276.189443) (xy 90.362039 -276.156212) (xy 90.325787 -276.117141) (xy 90.295763 -276.073104)
			(xy 90.272637 -276.025083) (xy 90.256927 -275.974153) (xy 90.248984 -275.921449) (xy 90.020404 -275.921449)
			(xy 90.012461 -275.974153) (xy 89.996751 -276.025083) (xy 89.973625 -276.073104) (xy 89.943601 -276.117141)
			(xy 89.907349 -276.156212) (xy 89.865678 -276.189443) (xy 89.81952 -276.216092) (xy 89.769906 -276.235564)
			(xy 89.717944 -276.247424) (xy 89.664794 -276.251408) (xy 89.611644 -276.247424) (xy 89.559682 -276.235564)
			(xy 89.510068 -276.216092) (xy 89.46391 -276.189443) (xy 89.422239 -276.156212) (xy 89.385987 -276.117141)
			(xy 89.355963 -276.073104) (xy 89.332837 -276.025083) (xy 89.317127 -275.974153) (xy 89.309184 -275.921449)
			(xy 89.080604 -275.921449) (xy 89.072661 -275.974153) (xy 89.056951 -276.025083) (xy 89.033825 -276.073104)
			(xy 89.003801 -276.117141) (xy 88.967549 -276.156212) (xy 88.925878 -276.189443) (xy 88.87972 -276.216092)
			(xy 88.830106 -276.235564) (xy 88.778144 -276.247424) (xy 88.724994 -276.251408) (xy 88.671844 -276.247424)
			(xy 88.619882 -276.235564) (xy 88.570268 -276.216092) (xy 88.52411 -276.189443) (xy 88.482439 -276.156212)
			(xy 88.446187 -276.117141) (xy 88.416163 -276.073104) (xy 88.393037 -276.025083) (xy 88.377327 -275.974153)
			(xy 88.369384 -275.921449) (xy 88.14055 -275.921449) (xy 88.132607 -275.974153) (xy 88.116897 -276.025083)
			(xy 88.093771 -276.073104) (xy 88.063747 -276.117141) (xy 88.027495 -276.156212) (xy 87.985824 -276.189443)
			(xy 87.939666 -276.216092) (xy 87.890052 -276.235564) (xy 87.83809 -276.247424) (xy 87.78494 -276.251408)
			(xy 87.73179 -276.247424) (xy 87.679828 -276.235564) (xy 87.630214 -276.216092) (xy 87.584056 -276.189443)
			(xy 87.542385 -276.156212) (xy 87.506133 -276.117141) (xy 87.476109 -276.073104) (xy 87.452983 -276.025083)
			(xy 87.437273 -275.974153) (xy 87.42933 -275.921449) (xy 85.863959 -275.921449) (xy 85.52688 -276.258528)
			(xy 85.52688 -276.735265) (xy 87.899484 -276.735265) (xy 87.899484 -276.681967) (xy 87.907427 -276.629263)
			(xy 87.923137 -276.578333) (xy 87.946263 -276.530312) (xy 87.976287 -276.486275) (xy 88.012539 -276.447204)
			(xy 88.05421 -276.413973) (xy 88.100368 -276.387324) (xy 88.149982 -276.367852) (xy 88.201944 -276.355992)
			(xy 88.255094 -276.352009) (xy 88.308244 -276.355992) (xy 88.360206 -276.367852) (xy 88.40982 -276.387324)
			(xy 88.455978 -276.413973) (xy 88.497649 -276.447204) (xy 88.533901 -276.486275) (xy 88.563925 -276.530312)
			(xy 88.587051 -276.578333) (xy 88.602761 -276.629263) (xy 88.610704 -276.681967) (xy 88.611202 -276.708616)
			(xy 88.610704 -276.735265) (xy 88.839284 -276.735265) (xy 88.839284 -276.681967) (xy 88.847227 -276.629263)
			(xy 88.862937 -276.578333) (xy 88.886063 -276.530312) (xy 88.916087 -276.486275) (xy 88.952339 -276.447204)
			(xy 88.99401 -276.413973) (xy 89.040168 -276.387324) (xy 89.089782 -276.367852) (xy 89.141744 -276.355992)
			(xy 89.194894 -276.352009) (xy 89.248044 -276.355992) (xy 89.300006 -276.367852) (xy 89.34962 -276.387324)
			(xy 89.395778 -276.413973) (xy 89.437449 -276.447204) (xy 89.473701 -276.486275) (xy 89.503725 -276.530312)
			(xy 89.526851 -276.578333) (xy 89.542561 -276.629263) (xy 89.550504 -276.681967) (xy 89.551002 -276.708616)
			(xy 89.550504 -276.735265) (xy 89.779084 -276.735265) (xy 89.779084 -276.681967) (xy 89.787027 -276.629263)
			(xy 89.802737 -276.578333) (xy 89.825863 -276.530312) (xy 89.855887 -276.486275) (xy 89.892139 -276.447204)
			(xy 89.93381 -276.413973) (xy 89.979968 -276.387324) (xy 90.029582 -276.367852) (xy 90.081544 -276.355992)
			(xy 90.134694 -276.352009) (xy 90.187844 -276.355992) (xy 90.239806 -276.367852) (xy 90.28942 -276.387324)
			(xy 90.335578 -276.413973) (xy 90.377249 -276.447204) (xy 90.413501 -276.486275) (xy 90.443525 -276.530312)
			(xy 90.466651 -276.578333) (xy 90.482361 -276.629263) (xy 90.490304 -276.681967) (xy 90.490802 -276.708616)
			(xy 90.490304 -276.735265) (xy 90.718884 -276.735265) (xy 90.718884 -276.681967) (xy 90.726827 -276.629263)
			(xy 90.742537 -276.578333) (xy 90.765663 -276.530312) (xy 90.795687 -276.486275) (xy 90.831939 -276.447204)
			(xy 90.87361 -276.413973) (xy 90.919768 -276.387324) (xy 90.969382 -276.367852) (xy 91.021344 -276.355992)
			(xy 91.074494 -276.352009) (xy 91.127644 -276.355992) (xy 91.179606 -276.367852) (xy 91.22922 -276.387324)
			(xy 91.275378 -276.413973) (xy 91.317049 -276.447204) (xy 91.353301 -276.486275) (xy 91.383325 -276.530312)
			(xy 91.406451 -276.578333) (xy 91.422161 -276.629263) (xy 91.430104 -276.681967) (xy 91.430602 -276.708616)
			(xy 91.430104 -276.735265) (xy 91.658938 -276.735265) (xy 91.658938 -276.681967) (xy 91.666881 -276.629263)
			(xy 91.682591 -276.578333) (xy 91.705717 -276.530312) (xy 91.735741 -276.486275) (xy 91.771993 -276.447204)
			(xy 91.813664 -276.413973) (xy 91.859822 -276.387324) (xy 91.909436 -276.367852) (xy 91.961398 -276.355992)
			(xy 92.014548 -276.352009) (xy 92.067698 -276.355992) (xy 92.11966 -276.367852) (xy 92.169274 -276.387324)
			(xy 92.215432 -276.413973) (xy 92.257103 -276.447204) (xy 92.293355 -276.486275) (xy 92.323379 -276.530312)
			(xy 92.346505 -276.578333) (xy 92.362215 -276.629263) (xy 92.370158 -276.681967) (xy 92.370656 -276.708616)
			(xy 92.370158 -276.735265) (xy 92.598738 -276.735265) (xy 92.598738 -276.681967) (xy 92.606681 -276.629263)
			(xy 92.622391 -276.578333) (xy 92.645517 -276.530312) (xy 92.675541 -276.486275) (xy 92.711793 -276.447204)
			(xy 92.753464 -276.413973) (xy 92.799622 -276.387324) (xy 92.849236 -276.367852) (xy 92.901198 -276.355992)
			(xy 92.954348 -276.352009) (xy 93.007498 -276.355992) (xy 93.05946 -276.367852) (xy 93.109074 -276.387324)
			(xy 93.155232 -276.413973) (xy 93.196903 -276.447204) (xy 93.233155 -276.486275) (xy 93.263179 -276.530312)
			(xy 93.286305 -276.578333) (xy 93.302015 -276.629263) (xy 93.309958 -276.681967) (xy 93.310456 -276.708616)
			(xy 93.309958 -276.735265) (xy 93.538538 -276.735265) (xy 93.538538 -276.681967) (xy 93.546481 -276.629263)
			(xy 93.562191 -276.578333) (xy 93.585317 -276.530312) (xy 93.615341 -276.486275) (xy 93.651593 -276.447204)
			(xy 93.693264 -276.413973) (xy 93.739422 -276.387324) (xy 93.789036 -276.367852) (xy 93.840998 -276.355992)
			(xy 93.894148 -276.352009) (xy 93.947298 -276.355992) (xy 93.99926 -276.367852) (xy 94.048874 -276.387324)
			(xy 94.095032 -276.413973) (xy 94.136703 -276.447204) (xy 94.172955 -276.486275) (xy 94.202979 -276.530312)
			(xy 94.226105 -276.578333) (xy 94.241815 -276.629263) (xy 94.249758 -276.681967) (xy 94.250256 -276.708616)
			(xy 94.249758 -276.735265) (xy 94.478338 -276.735265) (xy 94.478338 -276.681967) (xy 94.486281 -276.629263)
			(xy 94.501991 -276.578333) (xy 94.525117 -276.530312) (xy 94.555141 -276.486275) (xy 94.591393 -276.447204)
			(xy 94.633064 -276.413973) (xy 94.679222 -276.387324) (xy 94.728836 -276.367852) (xy 94.780798 -276.355992)
			(xy 94.833948 -276.352009) (xy 94.887098 -276.355992) (xy 94.93906 -276.367852) (xy 94.988674 -276.387324)
			(xy 95.034832 -276.413973) (xy 95.076503 -276.447204) (xy 95.112755 -276.486275) (xy 95.142779 -276.530312)
			(xy 95.165905 -276.578333) (xy 95.181615 -276.629263) (xy 95.189558 -276.681967) (xy 95.190056 -276.708616)
			(xy 95.189558 -276.735265) (xy 95.418138 -276.735265) (xy 95.418138 -276.681967) (xy 95.426081 -276.629263)
			(xy 95.441791 -276.578333) (xy 95.464917 -276.530312) (xy 95.494941 -276.486275) (xy 95.531193 -276.447204)
			(xy 95.572864 -276.413973) (xy 95.619022 -276.387324) (xy 95.668636 -276.367852) (xy 95.720598 -276.355992)
			(xy 95.773748 -276.352009) (xy 95.826898 -276.355992) (xy 95.87886 -276.367852) (xy 95.928474 -276.387324)
			(xy 95.974632 -276.413973) (xy 96.016303 -276.447204) (xy 96.052555 -276.486275) (xy 96.082579 -276.530312)
			(xy 96.105705 -276.578333) (xy 96.121415 -276.629263) (xy 96.129358 -276.681967) (xy 96.129856 -276.708616)
			(xy 96.129358 -276.735265) (xy 96.357938 -276.735265) (xy 96.357938 -276.681967) (xy 96.365881 -276.629263)
			(xy 96.381591 -276.578333) (xy 96.404717 -276.530312) (xy 96.434741 -276.486275) (xy 96.470993 -276.447204)
			(xy 96.512664 -276.413973) (xy 96.558822 -276.387324) (xy 96.608436 -276.367852) (xy 96.660398 -276.355992)
			(xy 96.713548 -276.352009) (xy 96.766698 -276.355992) (xy 96.81866 -276.367852) (xy 96.868274 -276.387324)
			(xy 96.914432 -276.413973) (xy 96.956103 -276.447204) (xy 96.992355 -276.486275) (xy 97.022379 -276.530312)
			(xy 97.045505 -276.578333) (xy 97.061215 -276.629263) (xy 97.069158 -276.681967) (xy 97.069656 -276.708616)
			(xy 97.069158 -276.735265) (xy 97.297484 -276.735265) (xy 97.297484 -276.681967) (xy 97.305427 -276.629263)
			(xy 97.321137 -276.578333) (xy 97.344263 -276.530312) (xy 97.374287 -276.486275) (xy 97.410539 -276.447204)
			(xy 97.45221 -276.413973) (xy 97.498368 -276.387324) (xy 97.547982 -276.367852) (xy 97.599944 -276.355992)
			(xy 97.653094 -276.352009) (xy 97.706244 -276.355992) (xy 97.758206 -276.367852) (xy 97.80782 -276.387324)
			(xy 97.853978 -276.413973) (xy 97.895649 -276.447204) (xy 97.931901 -276.486275) (xy 97.961925 -276.530312)
			(xy 97.985051 -276.578333) (xy 98.000761 -276.629263) (xy 98.008704 -276.681967) (xy 98.009202 -276.708616)
			(xy 98.008704 -276.735265) (xy 98.237538 -276.735265) (xy 98.237538 -276.681967) (xy 98.245481 -276.629263)
			(xy 98.261191 -276.578333) (xy 98.284317 -276.530312) (xy 98.314341 -276.486275) (xy 98.350593 -276.447204)
			(xy 98.392264 -276.413973) (xy 98.438422 -276.387324) (xy 98.488036 -276.367852) (xy 98.539998 -276.355992)
			(xy 98.593148 -276.352009) (xy 98.646298 -276.355992) (xy 98.69826 -276.367852) (xy 98.747874 -276.387324)
			(xy 98.794032 -276.413973) (xy 98.835703 -276.447204) (xy 98.871955 -276.486275) (xy 98.901979 -276.530312)
			(xy 98.925105 -276.578333) (xy 98.940815 -276.629263) (xy 98.948758 -276.681967) (xy 98.949256 -276.708616)
			(xy 98.948758 -276.735265) (xy 99.177338 -276.735265) (xy 99.177338 -276.681967) (xy 99.185281 -276.629263)
			(xy 99.200991 -276.578333) (xy 99.224117 -276.530312) (xy 99.254141 -276.486275) (xy 99.290393 -276.447204)
			(xy 99.332064 -276.413973) (xy 99.378222 -276.387324) (xy 99.427836 -276.367852) (xy 99.479798 -276.355992)
			(xy 99.532948 -276.352009) (xy 99.586098 -276.355992) (xy 99.63806 -276.367852) (xy 99.687674 -276.387324)
			(xy 99.733832 -276.413973) (xy 99.775503 -276.447204) (xy 99.811755 -276.486275) (xy 99.841779 -276.530312)
			(xy 99.864905 -276.578333) (xy 99.880615 -276.629263) (xy 99.888558 -276.681967) (xy 99.889056 -276.708616)
			(xy 99.888558 -276.735265) (xy 100.117138 -276.735265) (xy 100.117138 -276.681967) (xy 100.125081 -276.629263)
			(xy 100.140791 -276.578333) (xy 100.163917 -276.530312) (xy 100.193941 -276.486275) (xy 100.230193 -276.447204)
			(xy 100.271864 -276.413973) (xy 100.318022 -276.387324) (xy 100.367636 -276.367852) (xy 100.419598 -276.355992)
			(xy 100.472748 -276.352009) (xy 100.525898 -276.355992) (xy 100.57786 -276.367852) (xy 100.627474 -276.387324)
			(xy 100.673632 -276.413973) (xy 100.715303 -276.447204) (xy 100.751555 -276.486275) (xy 100.781579 -276.530312)
			(xy 100.804705 -276.578333) (xy 100.820415 -276.629263) (xy 100.828358 -276.681967) (xy 100.828856 -276.708616)
			(xy 100.828358 -276.735265) (xy 101.056938 -276.735265) (xy 101.056938 -276.681967) (xy 101.064881 -276.629263)
			(xy 101.080591 -276.578333) (xy 101.103717 -276.530312) (xy 101.133741 -276.486275) (xy 101.169993 -276.447204)
			(xy 101.211664 -276.413973) (xy 101.257822 -276.387324) (xy 101.307436 -276.367852) (xy 101.359398 -276.355992)
			(xy 101.412548 -276.352009) (xy 101.465698 -276.355992) (xy 101.51766 -276.367852) (xy 101.567274 -276.387324)
			(xy 101.613432 -276.413973) (xy 101.655103 -276.447204) (xy 101.691355 -276.486275) (xy 101.721379 -276.530312)
			(xy 101.744505 -276.578333) (xy 101.760215 -276.629263) (xy 101.768158 -276.681967) (xy 101.768656 -276.708616)
			(xy 101.995986 -276.708616) (xy 101.996392 -276.682986) (xy 102.003727 -276.632253) (xy 102.018261 -276.583097)
			(xy 102.039694 -276.536532) (xy 102.067583 -276.493523) (xy 102.101352 -276.454958) (xy 102.140302 -276.421634)
			(xy 102.183629 -276.394241) (xy 102.230436 -276.373343) (xy 102.279756 -276.359374) (xy 102.305104 -276.355556)
			(xy 102.329742 -276.352254) (xy 102.502208 -276.05355) (xy 102.49281 -276.030436) (xy 102.484305 -276.008845)
			(xy 102.472334 -275.964011) (xy 102.466278 -275.918002) (xy 102.465886 -275.8948) (xy 102.466384 -275.868151)
			(xy 102.474327 -275.815447) (xy 102.490037 -275.764517) (xy 102.513163 -275.716496) (xy 102.543187 -275.672459)
			(xy 102.579439 -275.633388) (xy 102.62111 -275.600157) (xy 102.667268 -275.573508) (xy 102.716882 -275.554036)
			(xy 102.768844 -275.542176) (xy 102.821994 -275.538193) (xy 102.875144 -275.542176) (xy 102.927106 -275.554036)
			(xy 102.97672 -275.573508) (xy 103.022878 -275.600157) (xy 103.064549 -275.633388) (xy 103.100801 -275.672459)
			(xy 103.130825 -275.716496) (xy 103.153951 -275.764517) (xy 103.169661 -275.815447) (xy 103.177604 -275.868151)
			(xy 103.178102 -275.8948) (xy 103.177721 -275.920431) (xy 103.177574 -275.921449) (xy 103.406184 -275.921449)
			(xy 103.406184 -275.868151) (xy 103.414127 -275.815447) (xy 103.429837 -275.764517) (xy 103.452963 -275.716496)
			(xy 103.482987 -275.672459) (xy 103.519239 -275.633388) (xy 103.56091 -275.600157) (xy 103.607068 -275.573508)
			(xy 103.656682 -275.554036) (xy 103.708644 -275.542176) (xy 103.761794 -275.538193) (xy 103.814944 -275.542176)
			(xy 103.866906 -275.554036) (xy 103.91652 -275.573508) (xy 103.962678 -275.600157) (xy 104.004349 -275.633388)
			(xy 104.040601 -275.672459) (xy 104.070625 -275.716496) (xy 104.093751 -275.764517) (xy 104.109461 -275.815447)
			(xy 104.117404 -275.868151) (xy 104.117902 -275.8948) (xy 104.345486 -275.8948) (xy 104.345877 -275.869169)
			(xy 104.353214 -275.818436) (xy 104.36775 -275.769279) (xy 104.389185 -275.722715) (xy 104.417076 -275.679706)
			(xy 104.450847 -275.641141) (xy 104.489798 -275.607817) (xy 104.533126 -275.580424) (xy 104.579934 -275.559527)
			(xy 104.629256 -275.545558) (xy 104.654604 -275.54174) (xy 104.679242 -275.538438) (xy 104.851962 -275.23948)
			(xy 104.842564 -275.216366) (xy 104.834071 -275.194771) (xy 104.822095 -275.149939) (xy 104.816034 -275.103932)
			(xy 104.81564 -275.08073) (xy 104.816138 -275.054081) (xy 104.824081 -275.001377) (xy 104.839791 -274.950447)
			(xy 104.862917 -274.902426) (xy 104.892941 -274.858389) (xy 104.929193 -274.819318) (xy 104.970864 -274.786087)
			(xy 105.017022 -274.759438) (xy 105.066636 -274.739966) (xy 105.118598 -274.728106) (xy 105.171748 -274.724123)
			(xy 105.224898 -274.728106) (xy 105.27686 -274.739966) (xy 105.326474 -274.759438) (xy 105.372632 -274.786087)
			(xy 105.414303 -274.819318) (xy 105.450555 -274.858389) (xy 105.480579 -274.902426) (xy 105.503705 -274.950447)
			(xy 105.519415 -275.001377) (xy 105.527358 -275.054081) (xy 105.527856 -275.08073) (xy 105.527422 -275.10637)
			(xy 105.527276 -275.107379) (xy 105.755684 -275.107379) (xy 105.755684 -275.054081) (xy 105.763627 -275.001377)
			(xy 105.779337 -274.950447) (xy 105.802463 -274.902426) (xy 105.832487 -274.858389) (xy 105.868739 -274.819318)
			(xy 105.91041 -274.786087) (xy 105.956568 -274.759438) (xy 106.006182 -274.739966) (xy 106.058144 -274.728106)
			(xy 106.111294 -274.724123) (xy 106.164444 -274.728106) (xy 106.216406 -274.739966) (xy 106.26602 -274.759438)
			(xy 106.312178 -274.786087) (xy 106.353849 -274.819318) (xy 106.390101 -274.858389) (xy 106.420125 -274.902426)
			(xy 106.443251 -274.950447) (xy 106.458961 -275.001377) (xy 106.466904 -275.054081) (xy 106.467402 -275.08073)
			(xy 106.466904 -275.107379) (xy 106.695738 -275.107379) (xy 106.695738 -275.054081) (xy 106.703681 -275.001377)
			(xy 106.719391 -274.950447) (xy 106.742517 -274.902426) (xy 106.772541 -274.858389) (xy 106.808793 -274.819318)
			(xy 106.850464 -274.786087) (xy 106.896622 -274.759438) (xy 106.946236 -274.739966) (xy 106.998198 -274.728106)
			(xy 107.051348 -274.724123) (xy 107.104498 -274.728106) (xy 107.15646 -274.739966) (xy 107.206074 -274.759438)
			(xy 107.252232 -274.786087) (xy 107.293903 -274.819318) (xy 107.330155 -274.858389) (xy 107.360179 -274.902426)
			(xy 107.383305 -274.950447) (xy 107.399015 -275.001377) (xy 107.406958 -275.054081) (xy 107.407456 -275.08073)
			(xy 107.406958 -275.107379) (xy 107.399015 -275.160083) (xy 107.383305 -275.211013) (xy 107.360179 -275.259034)
			(xy 107.330155 -275.303071) (xy 107.293903 -275.342142) (xy 107.252232 -275.375373) (xy 107.206074 -275.402022)
			(xy 107.15646 -275.421494) (xy 107.104498 -275.433354) (xy 107.051348 -275.437338) (xy 106.998198 -275.433354)
			(xy 106.946236 -275.421494) (xy 106.896622 -275.402022) (xy 106.850464 -275.375373) (xy 106.808793 -275.342142)
			(xy 106.772541 -275.303071) (xy 106.742517 -275.259034) (xy 106.719391 -275.211013) (xy 106.703681 -275.160083)
			(xy 106.695738 -275.107379) (xy 106.466904 -275.107379) (xy 106.458961 -275.160083) (xy 106.443251 -275.211013)
			(xy 106.420125 -275.259034) (xy 106.390101 -275.303071) (xy 106.353849 -275.342142) (xy 106.312178 -275.375373)
			(xy 106.26602 -275.402022) (xy 106.216406 -275.421494) (xy 106.164444 -275.433354) (xy 106.111294 -275.437338)
			(xy 106.058144 -275.433354) (xy 106.006182 -275.421494) (xy 105.956568 -275.402022) (xy 105.91041 -275.375373)
			(xy 105.868739 -275.342142) (xy 105.832487 -275.303071) (xy 105.802463 -275.259034) (xy 105.779337 -275.211013)
			(xy 105.763627 -275.160083) (xy 105.755684 -275.107379) (xy 105.527276 -275.107379) (xy 105.520075 -275.157121)
			(xy 105.505525 -275.206293) (xy 105.484071 -275.252869) (xy 105.456157 -275.295885) (xy 105.422361 -275.334453)
			(xy 105.383382 -275.367773) (xy 105.340026 -275.395157) (xy 105.293191 -275.416039) (xy 105.243844 -275.429985)
			(xy 105.218484 -275.43379) (xy 105.193846 -275.437092) (xy 105.021126 -275.735796) (xy 105.030778 -275.75891)
			(xy 105.039294 -275.780542) (xy 105.051282 -275.82546) (xy 105.057326 -275.871555) (xy 105.057702 -275.8948)
			(xy 105.057204 -275.921449) (xy 105.286038 -275.921449) (xy 105.286038 -275.868151) (xy 105.293981 -275.815447)
			(xy 105.309691 -275.764517) (xy 105.332817 -275.716496) (xy 105.362841 -275.672459) (xy 105.399093 -275.633388)
			(xy 105.440764 -275.600157) (xy 105.486922 -275.573508) (xy 105.536536 -275.554036) (xy 105.588498 -275.542176)
			(xy 105.641648 -275.538193) (xy 105.694798 -275.542176) (xy 105.74676 -275.554036) (xy 105.796374 -275.573508)
			(xy 105.842532 -275.600157) (xy 105.884203 -275.633388) (xy 105.920455 -275.672459) (xy 105.950479 -275.716496)
			(xy 105.973605 -275.764517) (xy 105.989315 -275.815447) (xy 105.997258 -275.868151) (xy 105.997756 -275.8948)
			(xy 105.997258 -275.921449) (xy 105.989315 -275.974153) (xy 105.973605 -276.025083) (xy 105.950479 -276.073104)
			(xy 105.920455 -276.117141) (xy 105.884203 -276.156212) (xy 105.842532 -276.189443) (xy 105.796374 -276.216092)
			(xy 105.74676 -276.235564) (xy 105.694798 -276.247424) (xy 105.641648 -276.251408) (xy 105.588498 -276.247424)
			(xy 105.536536 -276.235564) (xy 105.486922 -276.216092) (xy 105.440764 -276.189443) (xy 105.399093 -276.156212)
			(xy 105.362841 -276.117141) (xy 105.332817 -276.073104) (xy 105.309691 -276.025083) (xy 105.293981 -275.974153)
			(xy 105.286038 -275.921449) (xy 105.057204 -275.921449) (xy 105.049261 -275.974153) (xy 105.033551 -276.025083)
			(xy 105.010425 -276.073104) (xy 104.980401 -276.117141) (xy 104.944149 -276.156212) (xy 104.902478 -276.189443)
			(xy 104.85632 -276.216092) (xy 104.806706 -276.235564) (xy 104.754744 -276.247424) (xy 104.701594 -276.251408)
			(xy 104.648444 -276.247424) (xy 104.596482 -276.235564) (xy 104.546868 -276.216092) (xy 104.50071 -276.189443)
			(xy 104.459039 -276.156212) (xy 104.422787 -276.117141) (xy 104.392763 -276.073104) (xy 104.369637 -276.025083)
			(xy 104.353927 -275.974153) (xy 104.345984 -275.921449) (xy 104.345486 -275.8948) (xy 104.117902 -275.8948)
			(xy 104.117404 -275.921449) (xy 104.109461 -275.974153) (xy 104.093751 -276.025083) (xy 104.070625 -276.073104)
			(xy 104.040601 -276.117141) (xy 104.004349 -276.156212) (xy 103.962678 -276.189443) (xy 103.91652 -276.216092)
			(xy 103.866906 -276.235564) (xy 103.814944 -276.247424) (xy 103.761794 -276.251408) (xy 103.708644 -276.247424)
			(xy 103.656682 -276.235564) (xy 103.607068 -276.216092) (xy 103.56091 -276.189443) (xy 103.519239 -276.156212)
			(xy 103.482987 -276.117141) (xy 103.452963 -276.073104) (xy 103.429837 -276.025083) (xy 103.414127 -275.974153)
			(xy 103.406184 -275.921449) (xy 103.177574 -275.921449) (xy 103.170384 -275.971165) (xy 103.155847 -276.020323)
			(xy 103.134411 -276.066888) (xy 103.106519 -276.109897) (xy 103.072747 -276.148463) (xy 103.033794 -276.181786)
			(xy 102.990465 -276.209179) (xy 102.943655 -276.230075) (xy 102.894333 -276.244042) (xy 102.868984 -276.24786)
			(xy 102.844092 -276.251162) (xy 102.671626 -276.549612) (xy 102.681278 -276.572726) (xy 102.689799 -276.594356)
			(xy 102.701785 -276.639275) (xy 102.707828 -276.685371) (xy 102.708202 -276.708616) (xy 102.93604 -276.708616)
			(xy 102.936538 -276.681967) (xy 102.944481 -276.629263) (xy 102.960191 -276.578333) (xy 102.983317 -276.530312)
			(xy 103.013341 -276.486275) (xy 103.049593 -276.447204) (xy 103.091264 -276.413973) (xy 103.137422 -276.387324)
			(xy 103.187036 -276.367852) (xy 103.238998 -276.355992) (xy 103.292148 -276.352009) (xy 103.345298 -276.355992)
			(xy 103.39726 -276.367852) (xy 103.446874 -276.387324) (xy 103.493032 -276.413973) (xy 103.534703 -276.447204)
			(xy 103.570955 -276.486275) (xy 103.600979 -276.530312) (xy 103.624105 -276.578333) (xy 103.639815 -276.629263)
			(xy 103.647758 -276.681967) (xy 103.648256 -276.7086) (xy 103.875284 -276.7086) (xy 103.879268 -276.655445)
			(xy 103.89113 -276.603477) (xy 103.910606 -276.553858) (xy 103.93726 -276.507696) (xy 103.970498 -276.466023)
			(xy 104.009575 -276.429769) (xy 104.05362 -276.399745) (xy 104.101648 -276.376622) (xy 104.152586 -276.360916)
			(xy 104.205296 -276.352978) (xy 104.231948 -276.352508) (xy 104.256963 -276.35291) (xy 104.306502 -276.359902)
			(xy 104.354575 -276.373754) (xy 104.400239 -276.394195) (xy 104.442593 -276.420823) (xy 104.480807 -276.453114)
			(xy 104.514128 -276.490432) (xy 104.528366 -276.511004) (xy 104.87533 -276.511004) (xy 104.889584 -276.490446)
			(xy 104.92291 -276.453138) (xy 104.961125 -276.420855) (xy 105.003477 -276.394232) (xy 105.049135 -276.373791)
			(xy 105.097203 -276.359934) (xy 105.146736 -276.352934) (xy 105.171748 -276.352508) (xy 105.198396 -276.352977)
			(xy 105.251096 -276.360927) (xy 105.302023 -276.376642) (xy 105.35004 -276.399771) (xy 105.394073 -276.429798)
			(xy 105.433139 -276.466051) (xy 105.466366 -276.507722) (xy 105.493013 -276.553879) (xy 105.512482 -276.603492)
			(xy 105.524341 -276.655453) (xy 105.528324 -276.7086) (xy 105.526326 -276.735265) (xy 105.755684 -276.735265)
			(xy 105.755684 -276.681967) (xy 105.763627 -276.629263) (xy 105.779337 -276.578333) (xy 105.802463 -276.530312)
			(xy 105.832487 -276.486275) (xy 105.868739 -276.447204) (xy 105.91041 -276.413973) (xy 105.956568 -276.387324)
			(xy 106.006182 -276.367852) (xy 106.058144 -276.355992) (xy 106.111294 -276.352009) (xy 106.164444 -276.355992)
			(xy 106.216406 -276.367852) (xy 106.26602 -276.387324) (xy 106.312178 -276.413973) (xy 106.353849 -276.447204)
			(xy 106.390101 -276.486275) (xy 106.420125 -276.530312) (xy 106.443251 -276.578333) (xy 106.458961 -276.629263)
			(xy 106.466904 -276.681967) (xy 106.467402 -276.708616) (xy 106.466904 -276.735265) (xy 106.458961 -276.787969)
			(xy 106.443251 -276.838899) (xy 106.420125 -276.88692) (xy 106.390101 -276.930957) (xy 106.353849 -276.970028)
			(xy 106.312178 -277.003259) (xy 106.26602 -277.029908) (xy 106.216406 -277.04938) (xy 106.164444 -277.06124)
			(xy 106.111294 -277.065224) (xy 106.058144 -277.06124) (xy 106.006182 -277.04938) (xy 105.956568 -277.029908)
			(xy 105.91041 -277.003259) (xy 105.868739 -276.970028) (xy 105.832487 -276.930957) (xy 105.802463 -276.88692)
			(xy 105.779337 -276.838899) (xy 105.763627 -276.787969) (xy 105.755684 -276.735265) (xy 105.526326 -276.735265)
			(xy 105.524341 -276.761747) (xy 105.512482 -276.813708) (xy 105.493013 -276.863321) (xy 105.466366 -276.909478)
			(xy 105.433139 -276.951149) (xy 105.394073 -276.987402) (xy 105.35004 -277.017429) (xy 105.302023 -277.040558)
			(xy 105.251096 -277.056273) (xy 105.198396 -277.064223) (xy 105.171748 -277.064724) (xy 105.146732 -277.064355)
			(xy 105.09719 -277.057361) (xy 105.049114 -277.043506) (xy 105.00345 -277.02306) (xy 104.961095 -276.996426)
			(xy 104.922883 -276.964129) (xy 104.889566 -276.926803) (xy 104.87533 -276.906228) (xy 104.528366 -276.906228)
			(xy 104.514124 -276.926795) (xy 104.480795 -276.964101) (xy 104.442578 -276.996382) (xy 104.400224 -277.023004)
			(xy 104.354564 -277.043443) (xy 104.306495 -277.057299) (xy 104.256961 -277.064299) (xy 104.231948 -277.064724)
			(xy 104.205296 -277.064222) (xy 104.152586 -277.056284) (xy 104.101648 -277.040578) (xy 104.05362 -277.017455)
			(xy 104.009575 -276.987431) (xy 103.970498 -276.951177) (xy 103.93726 -276.909504) (xy 103.910606 -276.863342)
			(xy 103.89113 -276.813723) (xy 103.879268 -276.761755) (xy 103.875284 -276.7086) (xy 103.648256 -276.7086)
			(xy 103.648256 -276.708616) (xy 103.647895 -276.731862) (xy 103.641846 -276.777957) (xy 103.629852 -276.822875)
			(xy 103.621332 -276.844506) (xy 103.61168 -276.86762) (xy 103.784146 -277.16607) (xy 103.808784 -277.169372)
			(xy 103.834118 -277.17325) (xy 103.883421 -277.187234) (xy 103.930212 -277.208138) (xy 103.973524 -277.235533)
			(xy 104.012463 -277.268851) (xy 104.046225 -277.307406) (xy 104.074113 -277.350402) (xy 104.095551 -277.39695)
			(xy 104.110098 -277.44609) (xy 104.117452 -277.496808) (xy 104.117902 -277.522432) (xy 104.117404 -277.549081)
			(xy 104.345984 -277.549081) (xy 104.345984 -277.495783) (xy 104.353927 -277.443079) (xy 104.369637 -277.392149)
			(xy 104.392763 -277.344128) (xy 104.422787 -277.300091) (xy 104.459039 -277.26102) (xy 104.50071 -277.227789)
			(xy 104.546868 -277.20114) (xy 104.596482 -277.181668) (xy 104.648444 -277.169808) (xy 104.701594 -277.165825)
			(xy 104.754744 -277.169808) (xy 104.806706 -277.181668) (xy 104.85632 -277.20114) (xy 104.902478 -277.227789)
			(xy 104.944149 -277.26102) (xy 104.980401 -277.300091) (xy 105.010425 -277.344128) (xy 105.033551 -277.392149)
			(xy 105.049261 -277.443079) (xy 105.057204 -277.495783) (xy 105.057702 -277.522432) (xy 105.057204 -277.549081)
			(xy 105.285784 -277.549081) (xy 105.285784 -277.495783) (xy 105.293727 -277.443079) (xy 105.309437 -277.392149)
			(xy 105.332563 -277.344128) (xy 105.362587 -277.300091) (xy 105.398839 -277.26102) (xy 105.44051 -277.227789)
			(xy 105.486668 -277.20114) (xy 105.536282 -277.181668) (xy 105.588244 -277.169808) (xy 105.641394 -277.165825)
			(xy 105.694544 -277.169808) (xy 105.746506 -277.181668) (xy 105.79612 -277.20114) (xy 105.842278 -277.227789)
			(xy 105.883949 -277.26102) (xy 105.920201 -277.300091) (xy 105.950225 -277.344128) (xy 105.973351 -277.392149)
			(xy 105.989061 -277.443079) (xy 105.997004 -277.495783) (xy 105.997502 -277.522432) (xy 106.225086 -277.522432)
			(xy 106.225507 -277.496802) (xy 106.232839 -277.44607) (xy 106.247371 -277.396914) (xy 106.268803 -277.35035)
			(xy 106.29669 -277.307341) (xy 106.330457 -277.268775) (xy 106.369406 -277.235451) (xy 106.412731 -277.208057)
			(xy 106.459537 -277.18716) (xy 106.508856 -277.17319) (xy 106.534204 -277.169372) (xy 106.558842 -277.16607)
			(xy 106.731562 -276.867112) (xy 106.72191 -276.843998) (xy 106.713439 -276.822447) (xy 106.701556 -276.777691)
			(xy 106.695588 -276.73177) (xy 106.69524 -276.708616) (xy 106.695738 -276.681967) (xy 106.703681 -276.629263)
			(xy 106.719391 -276.578333) (xy 106.742517 -276.530312) (xy 106.772541 -276.486275) (xy 106.808793 -276.447204)
			(xy 106.850464 -276.413973) (xy 106.896622 -276.387324) (xy 106.946236 -276.367852) (xy 106.998198 -276.355992)
			(xy 107.051348 -276.352009) (xy 107.104498 -276.355992) (xy 107.15646 -276.367852) (xy 107.206074 -276.387324)
			(xy 107.252232 -276.413973) (xy 107.293903 -276.447204) (xy 107.330155 -276.486275) (xy 107.360179 -276.530312)
			(xy 107.383305 -276.578333) (xy 107.399015 -276.629263) (xy 107.406958 -276.681967) (xy 107.407456 -276.708616)
			(xy 107.407009 -276.734256) (xy 107.399664 -276.785006) (xy 107.385115 -276.834178) (xy 107.363663 -276.880753)
			(xy 107.335751 -276.92377) (xy 107.301956 -276.962338) (xy 107.262979 -276.995658) (xy 107.219624 -277.023043)
			(xy 107.172789 -277.043924) (xy 107.123443 -277.057871) (xy 107.098084 -277.061676) (xy 107.073192 -277.064978)
			(xy 106.900726 -277.363428) (xy 106.910378 -277.386542) (xy 106.918904 -277.40817) (xy 106.930888 -277.45309)
			(xy 106.936929 -277.499187) (xy 106.937302 -277.522432) (xy 106.936804 -277.549081) (xy 106.928861 -277.601785)
			(xy 106.913151 -277.652715) (xy 106.890025 -277.700736) (xy 106.860001 -277.744773) (xy 106.823749 -277.783844)
			(xy 106.782078 -277.817075) (xy 106.73592 -277.843724) (xy 106.686306 -277.863196) (xy 106.634344 -277.875056)
			(xy 106.581194 -277.87904) (xy 106.528044 -277.875056) (xy 106.476082 -277.863196) (xy 106.426468 -277.843724)
			(xy 106.38031 -277.817075) (xy 106.338639 -277.783844) (xy 106.302387 -277.744773) (xy 106.272363 -277.700736)
			(xy 106.249237 -277.652715) (xy 106.233527 -277.601785) (xy 106.225584 -277.549081) (xy 106.225086 -277.522432)
			(xy 105.997502 -277.522432) (xy 105.997004 -277.549081) (xy 105.989061 -277.601785) (xy 105.973351 -277.652715)
			(xy 105.950225 -277.700736) (xy 105.920201 -277.744773) (xy 105.883949 -277.783844) (xy 105.842278 -277.817075)
			(xy 105.79612 -277.843724) (xy 105.746506 -277.863196) (xy 105.694544 -277.875056) (xy 105.641394 -277.87904)
			(xy 105.588244 -277.875056) (xy 105.536282 -277.863196) (xy 105.486668 -277.843724) (xy 105.44051 -277.817075)
			(xy 105.398839 -277.783844) (xy 105.362587 -277.744773) (xy 105.332563 -277.700736) (xy 105.309437 -277.652715)
			(xy 105.293727 -277.601785) (xy 105.285784 -277.549081) (xy 105.057204 -277.549081) (xy 105.049261 -277.601785)
			(xy 105.033551 -277.652715) (xy 105.010425 -277.700736) (xy 104.980401 -277.744773) (xy 104.944149 -277.783844)
			(xy 104.902478 -277.817075) (xy 104.85632 -277.843724) (xy 104.806706 -277.863196) (xy 104.754744 -277.875056)
			(xy 104.701594 -277.87904) (xy 104.648444 -277.875056) (xy 104.596482 -277.863196) (xy 104.546868 -277.843724)
			(xy 104.50071 -277.817075) (xy 104.459039 -277.783844) (xy 104.422787 -277.744773) (xy 104.392763 -277.700736)
			(xy 104.369637 -277.652715) (xy 104.353927 -277.601785) (xy 104.345984 -277.549081) (xy 104.117404 -277.549081)
			(xy 104.109461 -277.601785) (xy 104.093751 -277.652715) (xy 104.070625 -277.700736) (xy 104.040601 -277.744773)
			(xy 104.004349 -277.783844) (xy 103.962678 -277.817075) (xy 103.91652 -277.843724) (xy 103.866906 -277.863196)
			(xy 103.814944 -277.875056) (xy 103.761794 -277.87904) (xy 103.708644 -277.875056) (xy 103.656682 -277.863196)
			(xy 103.607068 -277.843724) (xy 103.56091 -277.817075) (xy 103.519239 -277.783844) (xy 103.482987 -277.744773)
			(xy 103.452963 -277.700736) (xy 103.429837 -277.652715) (xy 103.414127 -277.601785) (xy 103.406184 -277.549081)
			(xy 103.405686 -277.522432) (xy 103.406066 -277.499187) (xy 103.412108 -277.453092) (xy 103.424094 -277.408174)
			(xy 103.43261 -277.386542) (xy 103.442262 -277.363428) (xy 103.269796 -277.064978) (xy 103.244904 -277.061676)
			(xy 103.219591 -277.057748) (xy 103.170324 -277.043735) (xy 103.123571 -277.022811) (xy 103.080297 -276.995407)
			(xy 103.041393 -276.962088) (xy 103.007663 -276.923541) (xy 102.9798 -276.880561) (xy 102.95838 -276.834033)
			(xy 102.943844 -276.784918) (xy 102.936492 -276.734227) (xy 102.93604 -276.708616) (xy 102.708202 -276.708616)
			(xy 102.707704 -276.735265) (xy 102.699761 -276.787969) (xy 102.684051 -276.838899) (xy 102.660925 -276.88692)
			(xy 102.630901 -276.930957) (xy 102.594649 -276.970028) (xy 102.552978 -277.003259) (xy 102.50682 -277.029908)
			(xy 102.457206 -277.04938) (xy 102.405244 -277.06124) (xy 102.352094 -277.065224) (xy 102.298944 -277.06124)
			(xy 102.246982 -277.04938) (xy 102.197368 -277.029908) (xy 102.15121 -277.003259) (xy 102.109539 -276.970028)
			(xy 102.073287 -276.930957) (xy 102.043263 -276.88692) (xy 102.020137 -276.838899) (xy 102.004427 -276.787969)
			(xy 101.996484 -276.735265) (xy 101.995986 -276.708616) (xy 101.768656 -276.708616) (xy 101.768158 -276.735265)
			(xy 101.760215 -276.787969) (xy 101.744505 -276.838899) (xy 101.721379 -276.88692) (xy 101.691355 -276.930957)
			(xy 101.655103 -276.970028) (xy 101.613432 -277.003259) (xy 101.567274 -277.029908) (xy 101.51766 -277.04938)
			(xy 101.465698 -277.06124) (xy 101.412548 -277.065224) (xy 101.359398 -277.06124) (xy 101.307436 -277.04938)
			(xy 101.257822 -277.029908) (xy 101.211664 -277.003259) (xy 101.169993 -276.970028) (xy 101.133741 -276.930957)
			(xy 101.103717 -276.88692) (xy 101.080591 -276.838899) (xy 101.064881 -276.787969) (xy 101.056938 -276.735265)
			(xy 100.828358 -276.735265) (xy 100.820415 -276.787969) (xy 100.804705 -276.838899) (xy 100.781579 -276.88692)
			(xy 100.751555 -276.930957) (xy 100.715303 -276.970028) (xy 100.673632 -277.003259) (xy 100.627474 -277.029908)
			(xy 100.57786 -277.04938) (xy 100.525898 -277.06124) (xy 100.472748 -277.065224) (xy 100.419598 -277.06124)
			(xy 100.367636 -277.04938) (xy 100.318022 -277.029908) (xy 100.271864 -277.003259) (xy 100.230193 -276.970028)
			(xy 100.193941 -276.930957) (xy 100.163917 -276.88692) (xy 100.140791 -276.838899) (xy 100.125081 -276.787969)
			(xy 100.117138 -276.735265) (xy 99.888558 -276.735265) (xy 99.880615 -276.787969) (xy 99.864905 -276.838899)
			(xy 99.841779 -276.88692) (xy 99.811755 -276.930957) (xy 99.775503 -276.970028) (xy 99.733832 -277.003259)
			(xy 99.687674 -277.029908) (xy 99.63806 -277.04938) (xy 99.586098 -277.06124) (xy 99.532948 -277.065224)
			(xy 99.479798 -277.06124) (xy 99.427836 -277.04938) (xy 99.378222 -277.029908) (xy 99.332064 -277.003259)
			(xy 99.290393 -276.970028) (xy 99.254141 -276.930957) (xy 99.224117 -276.88692) (xy 99.200991 -276.838899)
			(xy 99.185281 -276.787969) (xy 99.177338 -276.735265) (xy 98.948758 -276.735265) (xy 98.940815 -276.787969)
			(xy 98.925105 -276.838899) (xy 98.901979 -276.88692) (xy 98.871955 -276.930957) (xy 98.835703 -276.970028)
			(xy 98.794032 -277.003259) (xy 98.747874 -277.029908) (xy 98.69826 -277.04938) (xy 98.646298 -277.06124)
			(xy 98.593148 -277.065224) (xy 98.539998 -277.06124) (xy 98.488036 -277.04938) (xy 98.438422 -277.029908)
			(xy 98.392264 -277.003259) (xy 98.350593 -276.970028) (xy 98.314341 -276.930957) (xy 98.284317 -276.88692)
			(xy 98.261191 -276.838899) (xy 98.245481 -276.787969) (xy 98.237538 -276.735265) (xy 98.008704 -276.735265)
			(xy 98.000761 -276.787969) (xy 97.985051 -276.838899) (xy 97.961925 -276.88692) (xy 97.931901 -276.930957)
			(xy 97.895649 -276.970028) (xy 97.853978 -277.003259) (xy 97.80782 -277.029908) (xy 97.758206 -277.04938)
			(xy 97.706244 -277.06124) (xy 97.653094 -277.065224) (xy 97.599944 -277.06124) (xy 97.547982 -277.04938)
			(xy 97.498368 -277.029908) (xy 97.45221 -277.003259) (xy 97.410539 -276.970028) (xy 97.374287 -276.930957)
			(xy 97.344263 -276.88692) (xy 97.321137 -276.838899) (xy 97.305427 -276.787969) (xy 97.297484 -276.735265)
			(xy 97.069158 -276.735265) (xy 97.061215 -276.787969) (xy 97.045505 -276.838899) (xy 97.022379 -276.88692)
			(xy 96.992355 -276.930957) (xy 96.956103 -276.970028) (xy 96.914432 -277.003259) (xy 96.868274 -277.029908)
			(xy 96.81866 -277.04938) (xy 96.766698 -277.06124) (xy 96.713548 -277.065224) (xy 96.660398 -277.06124)
			(xy 96.608436 -277.04938) (xy 96.558822 -277.029908) (xy 96.512664 -277.003259) (xy 96.470993 -276.970028)
			(xy 96.434741 -276.930957) (xy 96.404717 -276.88692) (xy 96.381591 -276.838899) (xy 96.365881 -276.787969)
			(xy 96.357938 -276.735265) (xy 96.129358 -276.735265) (xy 96.121415 -276.787969) (xy 96.105705 -276.838899)
			(xy 96.082579 -276.88692) (xy 96.052555 -276.930957) (xy 96.016303 -276.970028) (xy 95.974632 -277.003259)
			(xy 95.928474 -277.029908) (xy 95.87886 -277.04938) (xy 95.826898 -277.06124) (xy 95.773748 -277.065224)
			(xy 95.720598 -277.06124) (xy 95.668636 -277.04938) (xy 95.619022 -277.029908) (xy 95.572864 -277.003259)
			(xy 95.531193 -276.970028) (xy 95.494941 -276.930957) (xy 95.464917 -276.88692) (xy 95.441791 -276.838899)
			(xy 95.426081 -276.787969) (xy 95.418138 -276.735265) (xy 95.189558 -276.735265) (xy 95.181615 -276.787969)
			(xy 95.165905 -276.838899) (xy 95.142779 -276.88692) (xy 95.112755 -276.930957) (xy 95.076503 -276.970028)
			(xy 95.034832 -277.003259) (xy 94.988674 -277.029908) (xy 94.93906 -277.04938) (xy 94.887098 -277.06124)
			(xy 94.833948 -277.065224) (xy 94.780798 -277.06124) (xy 94.728836 -277.04938) (xy 94.679222 -277.029908)
			(xy 94.633064 -277.003259) (xy 94.591393 -276.970028) (xy 94.555141 -276.930957) (xy 94.525117 -276.88692)
			(xy 94.501991 -276.838899) (xy 94.486281 -276.787969) (xy 94.478338 -276.735265) (xy 94.249758 -276.735265)
			(xy 94.241815 -276.787969) (xy 94.226105 -276.838899) (xy 94.202979 -276.88692) (xy 94.172955 -276.930957)
			(xy 94.136703 -276.970028) (xy 94.095032 -277.003259) (xy 94.048874 -277.029908) (xy 93.99926 -277.04938)
			(xy 93.947298 -277.06124) (xy 93.894148 -277.065224) (xy 93.840998 -277.06124) (xy 93.789036 -277.04938)
			(xy 93.739422 -277.029908) (xy 93.693264 -277.003259) (xy 93.651593 -276.970028) (xy 93.615341 -276.930957)
			(xy 93.585317 -276.88692) (xy 93.562191 -276.838899) (xy 93.546481 -276.787969) (xy 93.538538 -276.735265)
			(xy 93.309958 -276.735265) (xy 93.302015 -276.787969) (xy 93.286305 -276.838899) (xy 93.263179 -276.88692)
			(xy 93.233155 -276.930957) (xy 93.196903 -276.970028) (xy 93.155232 -277.003259) (xy 93.109074 -277.029908)
			(xy 93.05946 -277.04938) (xy 93.007498 -277.06124) (xy 92.954348 -277.065224) (xy 92.901198 -277.06124)
			(xy 92.849236 -277.04938) (xy 92.799622 -277.029908) (xy 92.753464 -277.003259) (xy 92.711793 -276.970028)
			(xy 92.675541 -276.930957) (xy 92.645517 -276.88692) (xy 92.622391 -276.838899) (xy 92.606681 -276.787969)
			(xy 92.598738 -276.735265) (xy 92.370158 -276.735265) (xy 92.362215 -276.787969) (xy 92.346505 -276.838899)
			(xy 92.323379 -276.88692) (xy 92.293355 -276.930957) (xy 92.257103 -276.970028) (xy 92.215432 -277.003259)
			(xy 92.169274 -277.029908) (xy 92.11966 -277.04938) (xy 92.067698 -277.06124) (xy 92.014548 -277.065224)
			(xy 91.961398 -277.06124) (xy 91.909436 -277.04938) (xy 91.859822 -277.029908) (xy 91.813664 -277.003259)
			(xy 91.771993 -276.970028) (xy 91.735741 -276.930957) (xy 91.705717 -276.88692) (xy 91.682591 -276.838899)
			(xy 91.666881 -276.787969) (xy 91.658938 -276.735265) (xy 91.430104 -276.735265) (xy 91.422161 -276.787969)
			(xy 91.406451 -276.838899) (xy 91.383325 -276.88692) (xy 91.353301 -276.930957) (xy 91.317049 -276.970028)
			(xy 91.275378 -277.003259) (xy 91.22922 -277.029908) (xy 91.179606 -277.04938) (xy 91.127644 -277.06124)
			(xy 91.074494 -277.065224) (xy 91.021344 -277.06124) (xy 90.969382 -277.04938) (xy 90.919768 -277.029908)
			(xy 90.87361 -277.003259) (xy 90.831939 -276.970028) (xy 90.795687 -276.930957) (xy 90.765663 -276.88692)
			(xy 90.742537 -276.838899) (xy 90.726827 -276.787969) (xy 90.718884 -276.735265) (xy 90.490304 -276.735265)
			(xy 90.482361 -276.787969) (xy 90.466651 -276.838899) (xy 90.443525 -276.88692) (xy 90.413501 -276.930957)
			(xy 90.377249 -276.970028) (xy 90.335578 -277.003259) (xy 90.28942 -277.029908) (xy 90.239806 -277.04938)
			(xy 90.187844 -277.06124) (xy 90.134694 -277.065224) (xy 90.081544 -277.06124) (xy 90.029582 -277.04938)
			(xy 89.979968 -277.029908) (xy 89.93381 -277.003259) (xy 89.892139 -276.970028) (xy 89.855887 -276.930957)
			(xy 89.825863 -276.88692) (xy 89.802737 -276.838899) (xy 89.787027 -276.787969) (xy 89.779084 -276.735265)
			(xy 89.550504 -276.735265) (xy 89.542561 -276.787969) (xy 89.526851 -276.838899) (xy 89.503725 -276.88692)
			(xy 89.473701 -276.930957) (xy 89.437449 -276.970028) (xy 89.395778 -277.003259) (xy 89.34962 -277.029908)
			(xy 89.300006 -277.04938) (xy 89.248044 -277.06124) (xy 89.194894 -277.065224) (xy 89.141744 -277.06124)
			(xy 89.089782 -277.04938) (xy 89.040168 -277.029908) (xy 88.99401 -277.003259) (xy 88.952339 -276.970028)
			(xy 88.916087 -276.930957) (xy 88.886063 -276.88692) (xy 88.862937 -276.838899) (xy 88.847227 -276.787969)
			(xy 88.839284 -276.735265) (xy 88.610704 -276.735265) (xy 88.602761 -276.787969) (xy 88.587051 -276.838899)
			(xy 88.563925 -276.88692) (xy 88.533901 -276.930957) (xy 88.497649 -276.970028) (xy 88.455978 -277.003259)
			(xy 88.40982 -277.029908) (xy 88.360206 -277.04938) (xy 88.308244 -277.06124) (xy 88.255094 -277.065224)
			(xy 88.201944 -277.06124) (xy 88.149982 -277.04938) (xy 88.100368 -277.029908) (xy 88.05421 -277.003259)
			(xy 88.012539 -276.970028) (xy 87.976287 -276.930957) (xy 87.946263 -276.88692) (xy 87.923137 -276.838899)
			(xy 87.907427 -276.787969) (xy 87.899484 -276.735265) (xy 85.52688 -276.735265) (xy 85.52688 -277.270951)
			(xy 86.945968 -277.270951) (xy 86.945968 -277.217653) (xy 86.953911 -277.164949) (xy 86.969621 -277.114019)
			(xy 86.992747 -277.065998) (xy 87.022771 -277.021961) (xy 87.059023 -276.98289) (xy 87.100694 -276.949659)
			(xy 87.146852 -276.92301) (xy 87.196466 -276.903538) (xy 87.248428 -276.891678) (xy 87.301578 -276.887695)
			(xy 87.354728 -276.891678) (xy 87.40669 -276.903538) (xy 87.456304 -276.92301) (xy 87.502462 -276.949659)
			(xy 87.544133 -276.98289) (xy 87.580385 -277.021961) (xy 87.610409 -277.065998) (xy 87.633535 -277.114019)
			(xy 87.649245 -277.164949) (xy 87.657188 -277.217653) (xy 87.657686 -277.244302) (xy 87.657188 -277.270951)
			(xy 87.649245 -277.323655) (xy 87.633535 -277.374585) (xy 87.610409 -277.422606) (xy 87.580385 -277.466643)
			(xy 87.544133 -277.505714) (xy 87.502462 -277.538945) (xy 87.484466 -277.549335) (xy 88.36913 -277.549335)
			(xy 88.36913 -277.496037) (xy 88.377073 -277.443333) (xy 88.392783 -277.392403) (xy 88.415909 -277.344382)
			(xy 88.445933 -277.300345) (xy 88.482185 -277.261274) (xy 88.523856 -277.228043) (xy 88.570014 -277.201394)
			(xy 88.619628 -277.181922) (xy 88.67159 -277.170062) (xy 88.72474 -277.166079) (xy 88.77789 -277.170062)
			(xy 88.829852 -277.181922) (xy 88.879466 -277.201394) (xy 88.925624 -277.228043) (xy 88.967295 -277.261274)
			(xy 89.003547 -277.300345) (xy 89.033571 -277.344382) (xy 89.056697 -277.392403) (xy 89.072407 -277.443333)
			(xy 89.08035 -277.496037) (xy 89.080848 -277.522686) (xy 89.080355 -277.549081) (xy 89.309184 -277.549081)
			(xy 89.309184 -277.495783) (xy 89.317127 -277.443079) (xy 89.332837 -277.392149) (xy 89.355963 -277.344128)
			(xy 89.385987 -277.300091) (xy 89.422239 -277.26102) (xy 89.46391 -277.227789) (xy 89.510068 -277.20114)
			(xy 89.559682 -277.181668) (xy 89.611644 -277.169808) (xy 89.664794 -277.165825) (xy 89.717944 -277.169808)
			(xy 89.769906 -277.181668) (xy 89.81952 -277.20114) (xy 89.865678 -277.227789) (xy 89.907349 -277.26102)
			(xy 89.943601 -277.300091) (xy 89.973625 -277.344128) (xy 89.996751 -277.392149) (xy 90.012461 -277.443079)
			(xy 90.020404 -277.495783) (xy 90.020902 -277.522432) (xy 90.020404 -277.549081) (xy 90.249238 -277.549081)
			(xy 90.249238 -277.495783) (xy 90.257181 -277.443079) (xy 90.272891 -277.392149) (xy 90.296017 -277.344128)
			(xy 90.326041 -277.300091) (xy 90.362293 -277.26102) (xy 90.403964 -277.227789) (xy 90.450122 -277.20114)
			(xy 90.499736 -277.181668) (xy 90.551698 -277.169808) (xy 90.604848 -277.165825) (xy 90.657998 -277.169808)
			(xy 90.70996 -277.181668) (xy 90.759574 -277.20114) (xy 90.805732 -277.227789) (xy 90.847403 -277.26102)
			(xy 90.883655 -277.300091) (xy 90.913679 -277.344128) (xy 90.936805 -277.392149) (xy 90.952515 -277.443079)
			(xy 90.960458 -277.495783) (xy 90.960956 -277.522432) (xy 90.960458 -277.549081) (xy 91.188784 -277.549081)
			(xy 91.188784 -277.495783) (xy 91.196727 -277.443079) (xy 91.212437 -277.392149) (xy 91.235563 -277.344128)
			(xy 91.265587 -277.300091) (xy 91.301839 -277.26102) (xy 91.34351 -277.227789) (xy 91.389668 -277.20114)
			(xy 91.439282 -277.181668) (xy 91.491244 -277.169808) (xy 91.544394 -277.165825) (xy 91.597544 -277.169808)
			(xy 91.649506 -277.181668) (xy 91.69912 -277.20114) (xy 91.745278 -277.227789) (xy 91.786949 -277.26102)
			(xy 91.823201 -277.300091) (xy 91.853225 -277.344128) (xy 91.876351 -277.392149) (xy 91.892061 -277.443079)
			(xy 91.900004 -277.495783) (xy 91.900502 -277.522432) (xy 91.900004 -277.549081) (xy 92.128584 -277.549081)
			(xy 92.128584 -277.495783) (xy 92.136527 -277.443079) (xy 92.152237 -277.392149) (xy 92.175363 -277.344128)
			(xy 92.205387 -277.300091) (xy 92.241639 -277.26102) (xy 92.28331 -277.227789) (xy 92.329468 -277.20114)
			(xy 92.379082 -277.181668) (xy 92.431044 -277.169808) (xy 92.484194 -277.165825) (xy 92.537344 -277.169808)
			(xy 92.589306 -277.181668) (xy 92.63892 -277.20114) (xy 92.685078 -277.227789) (xy 92.726749 -277.26102)
			(xy 92.763001 -277.300091) (xy 92.793025 -277.344128) (xy 92.816151 -277.392149) (xy 92.831861 -277.443079)
			(xy 92.839804 -277.495783) (xy 92.840302 -277.522432) (xy 92.839804 -277.549081) (xy 93.068384 -277.549081)
			(xy 93.068384 -277.495783) (xy 93.076327 -277.443079) (xy 93.092037 -277.392149) (xy 93.115163 -277.344128)
			(xy 93.145187 -277.300091) (xy 93.181439 -277.26102) (xy 93.22311 -277.227789) (xy 93.269268 -277.20114)
			(xy 93.318882 -277.181668) (xy 93.370844 -277.169808) (xy 93.423994 -277.165825) (xy 93.477144 -277.169808)
			(xy 93.529106 -277.181668) (xy 93.57872 -277.20114) (xy 93.624878 -277.227789) (xy 93.666549 -277.26102)
			(xy 93.702801 -277.300091) (xy 93.732825 -277.344128) (xy 93.755951 -277.392149) (xy 93.771661 -277.443079)
			(xy 93.779604 -277.495783) (xy 93.780102 -277.522432) (xy 93.779604 -277.549081) (xy 94.008184 -277.549081)
			(xy 94.008184 -277.495783) (xy 94.016127 -277.443079) (xy 94.031837 -277.392149) (xy 94.054963 -277.344128)
			(xy 94.084987 -277.300091) (xy 94.121239 -277.26102) (xy 94.16291 -277.227789) (xy 94.209068 -277.20114)
			(xy 94.258682 -277.181668) (xy 94.310644 -277.169808) (xy 94.363794 -277.165825) (xy 94.416944 -277.169808)
			(xy 94.468906 -277.181668) (xy 94.51852 -277.20114) (xy 94.564678 -277.227789) (xy 94.606349 -277.26102)
			(xy 94.642601 -277.300091) (xy 94.672625 -277.344128) (xy 94.695751 -277.392149) (xy 94.711461 -277.443079)
			(xy 94.719404 -277.495783) (xy 94.719902 -277.522432) (xy 94.719404 -277.549081) (xy 94.947984 -277.549081)
			(xy 94.947984 -277.495783) (xy 94.955927 -277.443079) (xy 94.971637 -277.392149) (xy 94.994763 -277.344128)
			(xy 95.024787 -277.300091) (xy 95.061039 -277.26102) (xy 95.10271 -277.227789) (xy 95.148868 -277.20114)
			(xy 95.198482 -277.181668) (xy 95.250444 -277.169808) (xy 95.303594 -277.165825) (xy 95.356744 -277.169808)
			(xy 95.408706 -277.181668) (xy 95.45832 -277.20114) (xy 95.504478 -277.227789) (xy 95.546149 -277.26102)
			(xy 95.582401 -277.300091) (xy 95.612425 -277.344128) (xy 95.635551 -277.392149) (xy 95.651261 -277.443079)
			(xy 95.659204 -277.495783) (xy 95.659702 -277.522432) (xy 95.659204 -277.549081) (xy 95.887784 -277.549081)
			(xy 95.887784 -277.495783) (xy 95.895727 -277.443079) (xy 95.911437 -277.392149) (xy 95.934563 -277.344128)
			(xy 95.964587 -277.300091) (xy 96.000839 -277.26102) (xy 96.04251 -277.227789) (xy 96.088668 -277.20114)
			(xy 96.138282 -277.181668) (xy 96.190244 -277.169808) (xy 96.243394 -277.165825) (xy 96.296544 -277.169808)
			(xy 96.348506 -277.181668) (xy 96.39812 -277.20114) (xy 96.444278 -277.227789) (xy 96.485949 -277.26102)
			(xy 96.522201 -277.300091) (xy 96.552225 -277.344128) (xy 96.575351 -277.392149) (xy 96.591061 -277.443079)
			(xy 96.599004 -277.495783) (xy 96.599502 -277.522432) (xy 96.599004 -277.549081) (xy 96.827584 -277.549081)
			(xy 96.827584 -277.495783) (xy 96.835527 -277.443079) (xy 96.851237 -277.392149) (xy 96.874363 -277.344128)
			(xy 96.904387 -277.300091) (xy 96.940639 -277.26102) (xy 96.98231 -277.227789) (xy 97.028468 -277.20114)
			(xy 97.078082 -277.181668) (xy 97.130044 -277.169808) (xy 97.183194 -277.165825) (xy 97.236344 -277.169808)
			(xy 97.288306 -277.181668) (xy 97.33792 -277.20114) (xy 97.384078 -277.227789) (xy 97.425749 -277.26102)
			(xy 97.462001 -277.300091) (xy 97.492025 -277.344128) (xy 97.515151 -277.392149) (xy 97.530861 -277.443079)
			(xy 97.538804 -277.495783) (xy 97.539302 -277.522432) (xy 97.538804 -277.549081) (xy 97.767384 -277.549081)
			(xy 97.767384 -277.495783) (xy 97.775327 -277.443079) (xy 97.791037 -277.392149) (xy 97.814163 -277.344128)
			(xy 97.844187 -277.300091) (xy 97.880439 -277.26102) (xy 97.92211 -277.227789) (xy 97.968268 -277.20114)
			(xy 98.017882 -277.181668) (xy 98.069844 -277.169808) (xy 98.122994 -277.165825) (xy 98.176144 -277.169808)
			(xy 98.228106 -277.181668) (xy 98.27772 -277.20114) (xy 98.323878 -277.227789) (xy 98.365549 -277.26102)
			(xy 98.401801 -277.300091) (xy 98.431825 -277.344128) (xy 98.454951 -277.392149) (xy 98.470661 -277.443079)
			(xy 98.478604 -277.495783) (xy 98.479102 -277.522432) (xy 98.478604 -277.549081) (xy 98.707184 -277.549081)
			(xy 98.707184 -277.495783) (xy 98.715127 -277.443079) (xy 98.730837 -277.392149) (xy 98.753963 -277.344128)
			(xy 98.783987 -277.300091) (xy 98.820239 -277.26102) (xy 98.86191 -277.227789) (xy 98.908068 -277.20114)
			(xy 98.957682 -277.181668) (xy 99.009644 -277.169808) (xy 99.062794 -277.165825) (xy 99.115944 -277.169808)
			(xy 99.167906 -277.181668) (xy 99.21752 -277.20114) (xy 99.263678 -277.227789) (xy 99.305349 -277.26102)
			(xy 99.341601 -277.300091) (xy 99.371625 -277.344128) (xy 99.394751 -277.392149) (xy 99.410461 -277.443079)
			(xy 99.418404 -277.495783) (xy 99.418902 -277.522432) (xy 99.418404 -277.549081) (xy 99.646984 -277.549081)
			(xy 99.646984 -277.495783) (xy 99.654927 -277.443079) (xy 99.670637 -277.392149) (xy 99.693763 -277.344128)
			(xy 99.723787 -277.300091) (xy 99.760039 -277.26102) (xy 99.80171 -277.227789) (xy 99.847868 -277.20114)
			(xy 99.897482 -277.181668) (xy 99.949444 -277.169808) (xy 100.002594 -277.165825) (xy 100.055744 -277.169808)
			(xy 100.107706 -277.181668) (xy 100.15732 -277.20114) (xy 100.203478 -277.227789) (xy 100.245149 -277.26102)
			(xy 100.281401 -277.300091) (xy 100.311425 -277.344128) (xy 100.334551 -277.392149) (xy 100.350261 -277.443079)
			(xy 100.358204 -277.495783) (xy 100.358702 -277.522432) (xy 100.358204 -277.549081) (xy 100.586784 -277.549081)
			(xy 100.586784 -277.495783) (xy 100.594727 -277.443079) (xy 100.610437 -277.392149) (xy 100.633563 -277.344128)
			(xy 100.663587 -277.300091) (xy 100.699839 -277.26102) (xy 100.74151 -277.227789) (xy 100.787668 -277.20114)
			(xy 100.837282 -277.181668) (xy 100.889244 -277.169808) (xy 100.942394 -277.165825) (xy 100.995544 -277.169808)
			(xy 101.047506 -277.181668) (xy 101.09712 -277.20114) (xy 101.143278 -277.227789) (xy 101.184949 -277.26102)
			(xy 101.221201 -277.300091) (xy 101.251225 -277.344128) (xy 101.274351 -277.392149) (xy 101.290061 -277.443079)
			(xy 101.298004 -277.495783) (xy 101.298502 -277.522432) (xy 101.298004 -277.549081) (xy 101.526838 -277.549081)
			(xy 101.526838 -277.495783) (xy 101.534781 -277.443079) (xy 101.550491 -277.392149) (xy 101.573617 -277.344128)
			(xy 101.603641 -277.300091) (xy 101.639893 -277.26102) (xy 101.681564 -277.227789) (xy 101.727722 -277.20114)
			(xy 101.777336 -277.181668) (xy 101.829298 -277.169808) (xy 101.882448 -277.165825) (xy 101.935598 -277.169808)
			(xy 101.98756 -277.181668) (xy 102.037174 -277.20114) (xy 102.083332 -277.227789) (xy 102.125003 -277.26102)
			(xy 102.161255 -277.300091) (xy 102.191279 -277.344128) (xy 102.214405 -277.392149) (xy 102.230115 -277.443079)
			(xy 102.238058 -277.495783) (xy 102.238556 -277.522432) (xy 102.238058 -277.549081) (xy 102.230115 -277.601785)
			(xy 102.214405 -277.652715) (xy 102.191279 -277.700736) (xy 102.161255 -277.744773) (xy 102.125003 -277.783844)
			(xy 102.083332 -277.817075) (xy 102.037174 -277.843724) (xy 101.98756 -277.863196) (xy 101.935598 -277.875056)
			(xy 101.882448 -277.87904) (xy 101.829298 -277.875056) (xy 101.777336 -277.863196) (xy 101.727722 -277.843724)
			(xy 101.681564 -277.817075) (xy 101.639893 -277.783844) (xy 101.603641 -277.744773) (xy 101.573617 -277.700736)
			(xy 101.550491 -277.652715) (xy 101.534781 -277.601785) (xy 101.526838 -277.549081) (xy 101.298004 -277.549081)
			(xy 101.290061 -277.601785) (xy 101.274351 -277.652715) (xy 101.251225 -277.700736) (xy 101.221201 -277.744773)
			(xy 101.184949 -277.783844) (xy 101.143278 -277.817075) (xy 101.09712 -277.843724) (xy 101.047506 -277.863196)
			(xy 100.995544 -277.875056) (xy 100.942394 -277.87904) (xy 100.889244 -277.875056) (xy 100.837282 -277.863196)
			(xy 100.787668 -277.843724) (xy 100.74151 -277.817075) (xy 100.699839 -277.783844) (xy 100.663587 -277.744773)
			(xy 100.633563 -277.700736) (xy 100.610437 -277.652715) (xy 100.594727 -277.601785) (xy 100.586784 -277.549081)
			(xy 100.358204 -277.549081) (xy 100.350261 -277.601785) (xy 100.334551 -277.652715) (xy 100.311425 -277.700736)
			(xy 100.281401 -277.744773) (xy 100.245149 -277.783844) (xy 100.203478 -277.817075) (xy 100.15732 -277.843724)
			(xy 100.107706 -277.863196) (xy 100.055744 -277.875056) (xy 100.002594 -277.87904) (xy 99.949444 -277.875056)
			(xy 99.897482 -277.863196) (xy 99.847868 -277.843724) (xy 99.80171 -277.817075) (xy 99.760039 -277.783844)
			(xy 99.723787 -277.744773) (xy 99.693763 -277.700736) (xy 99.670637 -277.652715) (xy 99.654927 -277.601785)
			(xy 99.646984 -277.549081) (xy 99.418404 -277.549081) (xy 99.410461 -277.601785) (xy 99.394751 -277.652715)
			(xy 99.371625 -277.700736) (xy 99.341601 -277.744773) (xy 99.305349 -277.783844) (xy 99.263678 -277.817075)
			(xy 99.21752 -277.843724) (xy 99.167906 -277.863196) (xy 99.115944 -277.875056) (xy 99.062794 -277.87904)
			(xy 99.009644 -277.875056) (xy 98.957682 -277.863196) (xy 98.908068 -277.843724) (xy 98.86191 -277.817075)
			(xy 98.820239 -277.783844) (xy 98.783987 -277.744773) (xy 98.753963 -277.700736) (xy 98.730837 -277.652715)
			(xy 98.715127 -277.601785) (xy 98.707184 -277.549081) (xy 98.478604 -277.549081) (xy 98.470661 -277.601785)
			(xy 98.454951 -277.652715) (xy 98.431825 -277.700736) (xy 98.401801 -277.744773) (xy 98.365549 -277.783844)
			(xy 98.323878 -277.817075) (xy 98.27772 -277.843724) (xy 98.228106 -277.863196) (xy 98.176144 -277.875056)
			(xy 98.122994 -277.87904) (xy 98.069844 -277.875056) (xy 98.017882 -277.863196) (xy 97.968268 -277.843724)
			(xy 97.92211 -277.817075) (xy 97.880439 -277.783844) (xy 97.844187 -277.744773) (xy 97.814163 -277.700736)
			(xy 97.791037 -277.652715) (xy 97.775327 -277.601785) (xy 97.767384 -277.549081) (xy 97.538804 -277.549081)
			(xy 97.530861 -277.601785) (xy 97.515151 -277.652715) (xy 97.492025 -277.700736) (xy 97.462001 -277.744773)
			(xy 97.425749 -277.783844) (xy 97.384078 -277.817075) (xy 97.33792 -277.843724) (xy 97.288306 -277.863196)
			(xy 97.236344 -277.875056) (xy 97.183194 -277.87904) (xy 97.130044 -277.875056) (xy 97.078082 -277.863196)
			(xy 97.028468 -277.843724) (xy 96.98231 -277.817075) (xy 96.940639 -277.783844) (xy 96.904387 -277.744773)
			(xy 96.874363 -277.700736) (xy 96.851237 -277.652715) (xy 96.835527 -277.601785) (xy 96.827584 -277.549081)
			(xy 96.599004 -277.549081) (xy 96.591061 -277.601785) (xy 96.575351 -277.652715) (xy 96.552225 -277.700736)
			(xy 96.522201 -277.744773) (xy 96.485949 -277.783844) (xy 96.444278 -277.817075) (xy 96.39812 -277.843724)
			(xy 96.348506 -277.863196) (xy 96.296544 -277.875056) (xy 96.243394 -277.87904) (xy 96.190244 -277.875056)
			(xy 96.138282 -277.863196) (xy 96.088668 -277.843724) (xy 96.04251 -277.817075) (xy 96.000839 -277.783844)
			(xy 95.964587 -277.744773) (xy 95.934563 -277.700736) (xy 95.911437 -277.652715) (xy 95.895727 -277.601785)
			(xy 95.887784 -277.549081) (xy 95.659204 -277.549081) (xy 95.651261 -277.601785) (xy 95.635551 -277.652715)
			(xy 95.612425 -277.700736) (xy 95.582401 -277.744773) (xy 95.546149 -277.783844) (xy 95.504478 -277.817075)
			(xy 95.45832 -277.843724) (xy 95.408706 -277.863196) (xy 95.356744 -277.875056) (xy 95.303594 -277.87904)
			(xy 95.250444 -277.875056) (xy 95.198482 -277.863196) (xy 95.148868 -277.843724) (xy 95.10271 -277.817075)
			(xy 95.061039 -277.783844) (xy 95.024787 -277.744773) (xy 94.994763 -277.700736) (xy 94.971637 -277.652715)
			(xy 94.955927 -277.601785) (xy 94.947984 -277.549081) (xy 94.719404 -277.549081) (xy 94.711461 -277.601785)
			(xy 94.695751 -277.652715) (xy 94.672625 -277.700736) (xy 94.642601 -277.744773) (xy 94.606349 -277.783844)
			(xy 94.564678 -277.817075) (xy 94.51852 -277.843724) (xy 94.468906 -277.863196) (xy 94.416944 -277.875056)
			(xy 94.363794 -277.87904) (xy 94.310644 -277.875056) (xy 94.258682 -277.863196) (xy 94.209068 -277.843724)
			(xy 94.16291 -277.817075) (xy 94.121239 -277.783844) (xy 94.084987 -277.744773) (xy 94.054963 -277.700736)
			(xy 94.031837 -277.652715) (xy 94.016127 -277.601785) (xy 94.008184 -277.549081) (xy 93.779604 -277.549081)
			(xy 93.771661 -277.601785) (xy 93.755951 -277.652715) (xy 93.732825 -277.700736) (xy 93.702801 -277.744773)
			(xy 93.666549 -277.783844) (xy 93.624878 -277.817075) (xy 93.57872 -277.843724) (xy 93.529106 -277.863196)
			(xy 93.477144 -277.875056) (xy 93.423994 -277.87904) (xy 93.370844 -277.875056) (xy 93.318882 -277.863196)
			(xy 93.269268 -277.843724) (xy 93.22311 -277.817075) (xy 93.181439 -277.783844) (xy 93.145187 -277.744773)
			(xy 93.115163 -277.700736) (xy 93.092037 -277.652715) (xy 93.076327 -277.601785) (xy 93.068384 -277.549081)
			(xy 92.839804 -277.549081) (xy 92.831861 -277.601785) (xy 92.816151 -277.652715) (xy 92.793025 -277.700736)
			(xy 92.763001 -277.744773) (xy 92.726749 -277.783844) (xy 92.685078 -277.817075) (xy 92.63892 -277.843724)
			(xy 92.589306 -277.863196) (xy 92.537344 -277.875056) (xy 92.484194 -277.87904) (xy 92.431044 -277.875056)
			(xy 92.379082 -277.863196) (xy 92.329468 -277.843724) (xy 92.28331 -277.817075) (xy 92.241639 -277.783844)
			(xy 92.205387 -277.744773) (xy 92.175363 -277.700736) (xy 92.152237 -277.652715) (xy 92.136527 -277.601785)
			(xy 92.128584 -277.549081) (xy 91.900004 -277.549081) (xy 91.892061 -277.601785) (xy 91.876351 -277.652715)
			(xy 91.853225 -277.700736) (xy 91.823201 -277.744773) (xy 91.786949 -277.783844) (xy 91.745278 -277.817075)
			(xy 91.69912 -277.843724) (xy 91.649506 -277.863196) (xy 91.597544 -277.875056) (xy 91.544394 -277.87904)
			(xy 91.491244 -277.875056) (xy 91.439282 -277.863196) (xy 91.389668 -277.843724) (xy 91.34351 -277.817075)
			(xy 91.301839 -277.783844) (xy 91.265587 -277.744773) (xy 91.235563 -277.700736) (xy 91.212437 -277.652715)
			(xy 91.196727 -277.601785) (xy 91.188784 -277.549081) (xy 90.960458 -277.549081) (xy 90.952515 -277.601785)
			(xy 90.936805 -277.652715) (xy 90.913679 -277.700736) (xy 90.883655 -277.744773) (xy 90.847403 -277.783844)
			(xy 90.805732 -277.817075) (xy 90.759574 -277.843724) (xy 90.70996 -277.863196) (xy 90.657998 -277.875056)
			(xy 90.604848 -277.87904) (xy 90.551698 -277.875056) (xy 90.499736 -277.863196) (xy 90.450122 -277.843724)
			(xy 90.403964 -277.817075) (xy 90.362293 -277.783844) (xy 90.326041 -277.744773) (xy 90.296017 -277.700736)
			(xy 90.272891 -277.652715) (xy 90.257181 -277.601785) (xy 90.249238 -277.549081) (xy 90.020404 -277.549081)
			(xy 90.012461 -277.601785) (xy 89.996751 -277.652715) (xy 89.973625 -277.700736) (xy 89.943601 -277.744773)
			(xy 89.907349 -277.783844) (xy 89.865678 -277.817075) (xy 89.81952 -277.843724) (xy 89.769906 -277.863196)
			(xy 89.717944 -277.875056) (xy 89.664794 -277.87904) (xy 89.611644 -277.875056) (xy 89.559682 -277.863196)
			(xy 89.510068 -277.843724) (xy 89.46391 -277.817075) (xy 89.422239 -277.783844) (xy 89.385987 -277.744773)
			(xy 89.355963 -277.700736) (xy 89.332837 -277.652715) (xy 89.317127 -277.601785) (xy 89.309184 -277.549081)
			(xy 89.080355 -277.549081) (xy 89.08035 -277.549335) (xy 89.072407 -277.602039) (xy 89.056697 -277.652969)
			(xy 89.033571 -277.70099) (xy 89.003547 -277.745027) (xy 88.967295 -277.784098) (xy 88.925624 -277.817329)
			(xy 88.879466 -277.843978) (xy 88.829852 -277.86345) (xy 88.77789 -277.87531) (xy 88.72474 -277.879294)
			(xy 88.67159 -277.87531) (xy 88.619628 -277.86345) (xy 88.570014 -277.843978) (xy 88.523856 -277.817329)
			(xy 88.482185 -277.784098) (xy 88.445933 -277.745027) (xy 88.415909 -277.70099) (xy 88.392783 -277.652969)
			(xy 88.377073 -277.602039) (xy 88.36913 -277.549335) (xy 87.484466 -277.549335) (xy 87.456304 -277.565594)
			(xy 87.40669 -277.585066) (xy 87.354728 -277.596926) (xy 87.301578 -277.60091) (xy 87.248428 -277.596926)
			(xy 87.196466 -277.585066) (xy 87.146852 -277.565594) (xy 87.100694 -277.538945) (xy 87.059023 -277.505714)
			(xy 87.022771 -277.466643) (xy 86.992747 -277.422606) (xy 86.969621 -277.374585) (xy 86.953911 -277.323655)
			(xy 86.945968 -277.270951) (xy 85.52688 -277.270951) (xy 85.52688 -278.336502) (xy 86.031581 -278.336502)
			(xy 86.035611 -278.284004) (xy 86.047608 -278.232736) (xy 86.067291 -278.183901) (xy 86.094197 -278.138642)
			(xy 86.127697 -278.098021) (xy 86.167005 -278.06299) (xy 86.2112 -278.03437) (xy 86.259245 -278.012831)
			(xy 86.310016 -277.998879) (xy 86.362321 -277.992841) (xy 86.414935 -277.994858) (xy 86.466625 -278.004882)
			(xy 86.516178 -278.02268) (xy 86.562434 -278.047833) (xy 86.604308 -278.079752) (xy 86.64082 -278.11769)
			(xy 86.671112 -278.160756) (xy 86.694475 -278.207941) (xy 86.710361 -278.25814) (xy 86.718398 -278.310176)
			(xy 86.718902 -278.336502) (xy 86.718398 -278.362828) (xy 86.718348 -278.363151) (xy 90.718884 -278.363151)
			(xy 90.718884 -278.309853) (xy 90.726827 -278.257149) (xy 90.742537 -278.206219) (xy 90.765663 -278.158198)
			(xy 90.795687 -278.114161) (xy 90.831939 -278.07509) (xy 90.87361 -278.041859) (xy 90.919768 -278.01521)
			(xy 90.969382 -277.995738) (xy 91.021344 -277.983878) (xy 91.074494 -277.979895) (xy 91.127644 -277.983878)
			(xy 91.179606 -277.995738) (xy 91.22922 -278.01521) (xy 91.275378 -278.041859) (xy 91.317049 -278.07509)
			(xy 91.353301 -278.114161) (xy 91.383325 -278.158198) (xy 91.406451 -278.206219) (xy 91.422161 -278.257149)
			(xy 91.430104 -278.309853) (xy 91.430602 -278.336502) (xy 91.430104 -278.363151) (xy 91.658938 -278.363151)
			(xy 91.658938 -278.309853) (xy 91.666881 -278.257149) (xy 91.682591 -278.206219) (xy 91.705717 -278.158198)
			(xy 91.735741 -278.114161) (xy 91.771993 -278.07509) (xy 91.813664 -278.041859) (xy 91.859822 -278.01521)
			(xy 91.909436 -277.995738) (xy 91.961398 -277.983878) (xy 92.014548 -277.979895) (xy 92.067698 -277.983878)
			(xy 92.11966 -277.995738) (xy 92.169274 -278.01521) (xy 92.215432 -278.041859) (xy 92.257103 -278.07509)
			(xy 92.293355 -278.114161) (xy 92.323379 -278.158198) (xy 92.346505 -278.206219) (xy 92.362215 -278.257149)
			(xy 92.370158 -278.309853) (xy 92.370656 -278.336502) (xy 92.370158 -278.363151) (xy 92.598738 -278.363151)
			(xy 92.598738 -278.309853) (xy 92.606681 -278.257149) (xy 92.622391 -278.206219) (xy 92.645517 -278.158198)
			(xy 92.675541 -278.114161) (xy 92.711793 -278.07509) (xy 92.753464 -278.041859) (xy 92.799622 -278.01521)
			(xy 92.849236 -277.995738) (xy 92.901198 -277.983878) (xy 92.954348 -277.979895) (xy 93.007498 -277.983878)
			(xy 93.05946 -277.995738) (xy 93.109074 -278.01521) (xy 93.155232 -278.041859) (xy 93.196903 -278.07509)
			(xy 93.233155 -278.114161) (xy 93.263179 -278.158198) (xy 93.286305 -278.206219) (xy 93.302015 -278.257149)
			(xy 93.309958 -278.309853) (xy 93.310456 -278.336502) (xy 93.309958 -278.363151) (xy 93.538538 -278.363151)
			(xy 93.538538 -278.309853) (xy 93.546481 -278.257149) (xy 93.562191 -278.206219) (xy 93.585317 -278.158198)
			(xy 93.615341 -278.114161) (xy 93.651593 -278.07509) (xy 93.693264 -278.041859) (xy 93.739422 -278.01521)
			(xy 93.789036 -277.995738) (xy 93.840998 -277.983878) (xy 93.894148 -277.979895) (xy 93.947298 -277.983878)
			(xy 93.99926 -277.995738) (xy 94.048874 -278.01521) (xy 94.095032 -278.041859) (xy 94.136703 -278.07509)
			(xy 94.172955 -278.114161) (xy 94.202979 -278.158198) (xy 94.226105 -278.206219) (xy 94.241815 -278.257149)
			(xy 94.249758 -278.309853) (xy 94.250256 -278.336502) (xy 94.249758 -278.363151) (xy 94.478338 -278.363151)
			(xy 94.478338 -278.309853) (xy 94.486281 -278.257149) (xy 94.501991 -278.206219) (xy 94.525117 -278.158198)
			(xy 94.555141 -278.114161) (xy 94.591393 -278.07509) (xy 94.633064 -278.041859) (xy 94.679222 -278.01521)
			(xy 94.728836 -277.995738) (xy 94.780798 -277.983878) (xy 94.833948 -277.979895) (xy 94.887098 -277.983878)
			(xy 94.93906 -277.995738) (xy 94.988674 -278.01521) (xy 95.034832 -278.041859) (xy 95.076503 -278.07509)
			(xy 95.112755 -278.114161) (xy 95.142779 -278.158198) (xy 95.165905 -278.206219) (xy 95.181615 -278.257149)
			(xy 95.189558 -278.309853) (xy 95.190056 -278.336502) (xy 95.189558 -278.363151) (xy 97.297738 -278.363151)
			(xy 97.297738 -278.309853) (xy 97.305681 -278.257149) (xy 97.321391 -278.206219) (xy 97.344517 -278.158198)
			(xy 97.374541 -278.114161) (xy 97.410793 -278.07509) (xy 97.452464 -278.041859) (xy 97.498622 -278.01521)
			(xy 97.548236 -277.995738) (xy 97.600198 -277.983878) (xy 97.653348 -277.979895) (xy 97.706498 -277.983878)
			(xy 97.75846 -277.995738) (xy 97.808074 -278.01521) (xy 97.854232 -278.041859) (xy 97.895903 -278.07509)
			(xy 97.932155 -278.114161) (xy 97.962179 -278.158198) (xy 97.985305 -278.206219) (xy 98.001015 -278.257149)
			(xy 98.008958 -278.309853) (xy 98.009456 -278.336502) (xy 98.008958 -278.363151) (xy 98.237538 -278.363151)
			(xy 98.237538 -278.309853) (xy 98.245481 -278.257149) (xy 98.261191 -278.206219) (xy 98.284317 -278.158198)
			(xy 98.314341 -278.114161) (xy 98.350593 -278.07509) (xy 98.392264 -278.041859) (xy 98.438422 -278.01521)
			(xy 98.488036 -277.995738) (xy 98.539998 -277.983878) (xy 98.593148 -277.979895) (xy 98.646298 -277.983878)
			(xy 98.69826 -277.995738) (xy 98.747874 -278.01521) (xy 98.794032 -278.041859) (xy 98.835703 -278.07509)
			(xy 98.871955 -278.114161) (xy 98.901979 -278.158198) (xy 98.925105 -278.206219) (xy 98.940815 -278.257149)
			(xy 98.948758 -278.309853) (xy 98.949256 -278.336502) (xy 98.948758 -278.363151) (xy 99.177338 -278.363151)
			(xy 99.177338 -278.309853) (xy 99.185281 -278.257149) (xy 99.200991 -278.206219) (xy 99.224117 -278.158198)
			(xy 99.254141 -278.114161) (xy 99.290393 -278.07509) (xy 99.332064 -278.041859) (xy 99.378222 -278.01521)
			(xy 99.427836 -277.995738) (xy 99.479798 -277.983878) (xy 99.532948 -277.979895) (xy 99.586098 -277.983878)
			(xy 99.63806 -277.995738) (xy 99.687674 -278.01521) (xy 99.733832 -278.041859) (xy 99.775503 -278.07509)
			(xy 99.811755 -278.114161) (xy 99.841779 -278.158198) (xy 99.864905 -278.206219) (xy 99.880615 -278.257149)
			(xy 99.888558 -278.309853) (xy 99.889056 -278.336502) (xy 99.888558 -278.363151) (xy 100.117138 -278.363151)
			(xy 100.117138 -278.309853) (xy 100.125081 -278.257149) (xy 100.140791 -278.206219) (xy 100.163917 -278.158198)
			(xy 100.193941 -278.114161) (xy 100.230193 -278.07509) (xy 100.271864 -278.041859) (xy 100.318022 -278.01521)
			(xy 100.367636 -277.995738) (xy 100.419598 -277.983878) (xy 100.472748 -277.979895) (xy 100.525898 -277.983878)
			(xy 100.57786 -277.995738) (xy 100.627474 -278.01521) (xy 100.673632 -278.041859) (xy 100.715303 -278.07509)
			(xy 100.751555 -278.114161) (xy 100.781579 -278.158198) (xy 100.804705 -278.206219) (xy 100.820415 -278.257149)
			(xy 100.828358 -278.309853) (xy 100.828856 -278.336502) (xy 100.828358 -278.363151) (xy 101.056684 -278.363151)
			(xy 101.056684 -278.309853) (xy 101.064627 -278.257149) (xy 101.080337 -278.206219) (xy 101.103463 -278.158198)
			(xy 101.133487 -278.114161) (xy 101.169739 -278.07509) (xy 101.21141 -278.041859) (xy 101.257568 -278.01521)
			(xy 101.307182 -277.995738) (xy 101.359144 -277.983878) (xy 101.412294 -277.979895) (xy 101.465444 -277.983878)
			(xy 101.517406 -277.995738) (xy 101.56702 -278.01521) (xy 101.613178 -278.041859) (xy 101.654849 -278.07509)
			(xy 101.691101 -278.114161) (xy 101.721125 -278.158198) (xy 101.744251 -278.206219) (xy 101.759961 -278.257149)
			(xy 101.767904 -278.309853) (xy 101.768402 -278.336502) (xy 101.767904 -278.363151) (xy 101.996738 -278.363151)
			(xy 101.996738 -278.309853) (xy 102.004681 -278.257149) (xy 102.020391 -278.206219) (xy 102.043517 -278.158198)
			(xy 102.073541 -278.114161) (xy 102.109793 -278.07509) (xy 102.151464 -278.041859) (xy 102.197622 -278.01521)
			(xy 102.247236 -277.995738) (xy 102.299198 -277.983878) (xy 102.352348 -277.979895) (xy 102.405498 -277.983878)
			(xy 102.45746 -277.995738) (xy 102.507074 -278.01521) (xy 102.553232 -278.041859) (xy 102.594903 -278.07509)
			(xy 102.631155 -278.114161) (xy 102.661179 -278.158198) (xy 102.684305 -278.206219) (xy 102.700015 -278.257149)
			(xy 102.707958 -278.309853) (xy 102.708456 -278.336502) (xy 102.707958 -278.363151) (xy 102.936538 -278.363151)
			(xy 102.936538 -278.309853) (xy 102.944481 -278.257149) (xy 102.960191 -278.206219) (xy 102.983317 -278.158198)
			(xy 103.013341 -278.114161) (xy 103.049593 -278.07509) (xy 103.091264 -278.041859) (xy 103.137422 -278.01521)
			(xy 103.187036 -277.995738) (xy 103.238998 -277.983878) (xy 103.292148 -277.979895) (xy 103.345298 -277.983878)
			(xy 103.39726 -277.995738) (xy 103.446874 -278.01521) (xy 103.493032 -278.041859) (xy 103.534703 -278.07509)
			(xy 103.570955 -278.114161) (xy 103.600979 -278.158198) (xy 103.624105 -278.206219) (xy 103.639815 -278.257149)
			(xy 103.647758 -278.309853) (xy 103.648256 -278.336502) (xy 103.647758 -278.363151) (xy 103.876338 -278.363151)
			(xy 103.876338 -278.309853) (xy 103.884281 -278.257149) (xy 103.899991 -278.206219) (xy 103.923117 -278.158198)
			(xy 103.953141 -278.114161) (xy 103.989393 -278.07509) (xy 104.031064 -278.041859) (xy 104.077222 -278.01521)
			(xy 104.126836 -277.995738) (xy 104.178798 -277.983878) (xy 104.231948 -277.979895) (xy 104.285098 -277.983878)
			(xy 104.33706 -277.995738) (xy 104.386674 -278.01521) (xy 104.432832 -278.041859) (xy 104.474503 -278.07509)
			(xy 104.510755 -278.114161) (xy 104.540779 -278.158198) (xy 104.563905 -278.206219) (xy 104.579615 -278.257149)
			(xy 104.587558 -278.309853) (xy 104.588056 -278.336502) (xy 104.587558 -278.363151) (xy 104.815884 -278.363151)
			(xy 104.815884 -278.309853) (xy 104.823827 -278.257149) (xy 104.839537 -278.206219) (xy 104.862663 -278.158198)
			(xy 104.892687 -278.114161) (xy 104.928939 -278.07509) (xy 104.97061 -278.041859) (xy 105.016768 -278.01521)
			(xy 105.066382 -277.995738) (xy 105.118344 -277.983878) (xy 105.171494 -277.979895) (xy 105.224644 -277.983878)
			(xy 105.276606 -277.995738) (xy 105.32622 -278.01521) (xy 105.372378 -278.041859) (xy 105.414049 -278.07509)
			(xy 105.450301 -278.114161) (xy 105.480325 -278.158198) (xy 105.503451 -278.206219) (xy 105.519161 -278.257149)
			(xy 105.527104 -278.309853) (xy 105.527602 -278.336502) (xy 105.527104 -278.363151) (xy 106.695738 -278.363151)
			(xy 106.695738 -278.309853) (xy 106.703681 -278.257149) (xy 106.719391 -278.206219) (xy 106.742517 -278.158198)
			(xy 106.772541 -278.114161) (xy 106.808793 -278.07509) (xy 106.850464 -278.041859) (xy 106.896622 -278.01521)
			(xy 106.946236 -277.995738) (xy 106.998198 -277.983878) (xy 107.051348 -277.979895) (xy 107.104498 -277.983878)
			(xy 107.15646 -277.995738) (xy 107.206074 -278.01521) (xy 107.252232 -278.041859) (xy 107.293903 -278.07509)
			(xy 107.330155 -278.114161) (xy 107.360179 -278.158198) (xy 107.383305 -278.206219) (xy 107.399015 -278.257149)
			(xy 107.406958 -278.309853) (xy 107.407456 -278.336502) (xy 107.406958 -278.363151) (xy 107.399015 -278.415855)
			(xy 107.383305 -278.466785) (xy 107.360179 -278.514806) (xy 107.330155 -278.558843) (xy 107.293903 -278.597914)
			(xy 107.252232 -278.631145) (xy 107.206074 -278.657794) (xy 107.15646 -278.677266) (xy 107.104498 -278.689126)
			(xy 107.051348 -278.69311) (xy 106.998198 -278.689126) (xy 106.946236 -278.677266) (xy 106.896622 -278.657794)
			(xy 106.850464 -278.631145) (xy 106.808793 -278.597914) (xy 106.772541 -278.558843) (xy 106.742517 -278.514806)
			(xy 106.719391 -278.466785) (xy 106.703681 -278.415855) (xy 106.695738 -278.363151) (xy 105.527104 -278.363151)
			(xy 105.519161 -278.415855) (xy 105.503451 -278.466785) (xy 105.480325 -278.514806) (xy 105.450301 -278.558843)
			(xy 105.414049 -278.597914) (xy 105.372378 -278.631145) (xy 105.32622 -278.657794) (xy 105.276606 -278.677266)
			(xy 105.224644 -278.689126) (xy 105.171494 -278.69311) (xy 105.118344 -278.689126) (xy 105.066382 -278.677266)
			(xy 105.016768 -278.657794) (xy 104.97061 -278.631145) (xy 104.928939 -278.597914) (xy 104.892687 -278.558843)
			(xy 104.862663 -278.514806) (xy 104.839537 -278.466785) (xy 104.823827 -278.415855) (xy 104.815884 -278.363151)
			(xy 104.587558 -278.363151) (xy 104.579615 -278.415855) (xy 104.563905 -278.466785) (xy 104.540779 -278.514806)
			(xy 104.510755 -278.558843) (xy 104.474503 -278.597914) (xy 104.432832 -278.631145) (xy 104.386674 -278.657794)
			(xy 104.33706 -278.677266) (xy 104.285098 -278.689126) (xy 104.231948 -278.69311) (xy 104.178798 -278.689126)
			(xy 104.126836 -278.677266) (xy 104.077222 -278.657794) (xy 104.031064 -278.631145) (xy 103.989393 -278.597914)
			(xy 103.953141 -278.558843) (xy 103.923117 -278.514806) (xy 103.899991 -278.466785) (xy 103.884281 -278.415855)
			(xy 103.876338 -278.363151) (xy 103.647758 -278.363151) (xy 103.639815 -278.415855) (xy 103.624105 -278.466785)
			(xy 103.600979 -278.514806) (xy 103.570955 -278.558843) (xy 103.534703 -278.597914) (xy 103.493032 -278.631145)
			(xy 103.446874 -278.657794) (xy 103.39726 -278.677266) (xy 103.345298 -278.689126) (xy 103.292148 -278.69311)
			(xy 103.238998 -278.689126) (xy 103.187036 -278.677266) (xy 103.137422 -278.657794) (xy 103.091264 -278.631145)
			(xy 103.049593 -278.597914) (xy 103.013341 -278.558843) (xy 102.983317 -278.514806) (xy 102.960191 -278.466785)
			(xy 102.944481 -278.415855) (xy 102.936538 -278.363151) (xy 102.707958 -278.363151) (xy 102.700015 -278.415855)
			(xy 102.684305 -278.466785) (xy 102.661179 -278.514806) (xy 102.631155 -278.558843) (xy 102.594903 -278.597914)
			(xy 102.553232 -278.631145) (xy 102.507074 -278.657794) (xy 102.45746 -278.677266) (xy 102.405498 -278.689126)
			(xy 102.352348 -278.69311) (xy 102.299198 -278.689126) (xy 102.247236 -278.677266) (xy 102.197622 -278.657794)
			(xy 102.151464 -278.631145) (xy 102.109793 -278.597914) (xy 102.073541 -278.558843) (xy 102.043517 -278.514806)
			(xy 102.020391 -278.466785) (xy 102.004681 -278.415855) (xy 101.996738 -278.363151) (xy 101.767904 -278.363151)
			(xy 101.759961 -278.415855) (xy 101.744251 -278.466785) (xy 101.721125 -278.514806) (xy 101.691101 -278.558843)
			(xy 101.654849 -278.597914) (xy 101.613178 -278.631145) (xy 101.56702 -278.657794) (xy 101.517406 -278.677266)
			(xy 101.465444 -278.689126) (xy 101.412294 -278.69311) (xy 101.359144 -278.689126) (xy 101.307182 -278.677266)
			(xy 101.257568 -278.657794) (xy 101.21141 -278.631145) (xy 101.169739 -278.597914) (xy 101.133487 -278.558843)
			(xy 101.103463 -278.514806) (xy 101.080337 -278.466785) (xy 101.064627 -278.415855) (xy 101.056684 -278.363151)
			(xy 100.828358 -278.363151) (xy 100.820415 -278.415855) (xy 100.804705 -278.466785) (xy 100.781579 -278.514806)
			(xy 100.751555 -278.558843) (xy 100.715303 -278.597914) (xy 100.673632 -278.631145) (xy 100.627474 -278.657794)
			(xy 100.57786 -278.677266) (xy 100.525898 -278.689126) (xy 100.472748 -278.69311) (xy 100.419598 -278.689126)
			(xy 100.367636 -278.677266) (xy 100.318022 -278.657794) (xy 100.271864 -278.631145) (xy 100.230193 -278.597914)
			(xy 100.193941 -278.558843) (xy 100.163917 -278.514806) (xy 100.140791 -278.466785) (xy 100.125081 -278.415855)
			(xy 100.117138 -278.363151) (xy 99.888558 -278.363151) (xy 99.880615 -278.415855) (xy 99.864905 -278.466785)
			(xy 99.841779 -278.514806) (xy 99.811755 -278.558843) (xy 99.775503 -278.597914) (xy 99.733832 -278.631145)
			(xy 99.687674 -278.657794) (xy 99.63806 -278.677266) (xy 99.586098 -278.689126) (xy 99.532948 -278.69311)
			(xy 99.479798 -278.689126) (xy 99.427836 -278.677266) (xy 99.378222 -278.657794) (xy 99.332064 -278.631145)
			(xy 99.290393 -278.597914) (xy 99.254141 -278.558843) (xy 99.224117 -278.514806) (xy 99.200991 -278.466785)
			(xy 99.185281 -278.415855) (xy 99.177338 -278.363151) (xy 98.948758 -278.363151) (xy 98.940815 -278.415855)
			(xy 98.925105 -278.466785) (xy 98.901979 -278.514806) (xy 98.871955 -278.558843) (xy 98.835703 -278.597914)
			(xy 98.794032 -278.631145) (xy 98.747874 -278.657794) (xy 98.69826 -278.677266) (xy 98.646298 -278.689126)
			(xy 98.593148 -278.69311) (xy 98.539998 -278.689126) (xy 98.488036 -278.677266) (xy 98.438422 -278.657794)
			(xy 98.392264 -278.631145) (xy 98.350593 -278.597914) (xy 98.314341 -278.558843) (xy 98.284317 -278.514806)
			(xy 98.261191 -278.466785) (xy 98.245481 -278.415855) (xy 98.237538 -278.363151) (xy 98.008958 -278.363151)
			(xy 98.001015 -278.415855) (xy 97.985305 -278.466785) (xy 97.962179 -278.514806) (xy 97.932155 -278.558843)
			(xy 97.895903 -278.597914) (xy 97.854232 -278.631145) (xy 97.808074 -278.657794) (xy 97.75846 -278.677266)
			(xy 97.706498 -278.689126) (xy 97.653348 -278.69311) (xy 97.600198 -278.689126) (xy 97.548236 -278.677266)
			(xy 97.498622 -278.657794) (xy 97.452464 -278.631145) (xy 97.410793 -278.597914) (xy 97.374541 -278.558843)
			(xy 97.344517 -278.514806) (xy 97.321391 -278.466785) (xy 97.305681 -278.415855) (xy 97.297738 -278.363151)
			(xy 95.189558 -278.363151) (xy 95.181615 -278.415855) (xy 95.165905 -278.466785) (xy 95.142779 -278.514806)
			(xy 95.112755 -278.558843) (xy 95.076503 -278.597914) (xy 95.034832 -278.631145) (xy 94.988674 -278.657794)
			(xy 94.93906 -278.677266) (xy 94.887098 -278.689126) (xy 94.833948 -278.69311) (xy 94.780798 -278.689126)
			(xy 94.728836 -278.677266) (xy 94.679222 -278.657794) (xy 94.633064 -278.631145) (xy 94.591393 -278.597914)
			(xy 94.555141 -278.558843) (xy 94.525117 -278.514806) (xy 94.501991 -278.466785) (xy 94.486281 -278.415855)
			(xy 94.478338 -278.363151) (xy 94.249758 -278.363151) (xy 94.241815 -278.415855) (xy 94.226105 -278.466785)
			(xy 94.202979 -278.514806) (xy 94.172955 -278.558843) (xy 94.136703 -278.597914) (xy 94.095032 -278.631145)
			(xy 94.048874 -278.657794) (xy 93.99926 -278.677266) (xy 93.947298 -278.689126) (xy 93.894148 -278.69311)
			(xy 93.840998 -278.689126) (xy 93.789036 -278.677266) (xy 93.739422 -278.657794) (xy 93.693264 -278.631145)
			(xy 93.651593 -278.597914) (xy 93.615341 -278.558843) (xy 93.585317 -278.514806) (xy 93.562191 -278.466785)
			(xy 93.546481 -278.415855) (xy 93.538538 -278.363151) (xy 93.309958 -278.363151) (xy 93.302015 -278.415855)
			(xy 93.286305 -278.466785) (xy 93.263179 -278.514806) (xy 93.233155 -278.558843) (xy 93.196903 -278.597914)
			(xy 93.155232 -278.631145) (xy 93.109074 -278.657794) (xy 93.05946 -278.677266) (xy 93.007498 -278.689126)
			(xy 92.954348 -278.69311) (xy 92.901198 -278.689126) (xy 92.849236 -278.677266) (xy 92.799622 -278.657794)
			(xy 92.753464 -278.631145) (xy 92.711793 -278.597914) (xy 92.675541 -278.558843) (xy 92.645517 -278.514806)
			(xy 92.622391 -278.466785) (xy 92.606681 -278.415855) (xy 92.598738 -278.363151) (xy 92.370158 -278.363151)
			(xy 92.362215 -278.415855) (xy 92.346505 -278.466785) (xy 92.323379 -278.514806) (xy 92.293355 -278.558843)
			(xy 92.257103 -278.597914) (xy 92.215432 -278.631145) (xy 92.169274 -278.657794) (xy 92.11966 -278.677266)
			(xy 92.067698 -278.689126) (xy 92.014548 -278.69311) (xy 91.961398 -278.689126) (xy 91.909436 -278.677266)
			(xy 91.859822 -278.657794) (xy 91.813664 -278.631145) (xy 91.771993 -278.597914) (xy 91.735741 -278.558843)
			(xy 91.705717 -278.514806) (xy 91.682591 -278.466785) (xy 91.666881 -278.415855) (xy 91.658938 -278.363151)
			(xy 91.430104 -278.363151) (xy 91.422161 -278.415855) (xy 91.406451 -278.466785) (xy 91.383325 -278.514806)
			(xy 91.353301 -278.558843) (xy 91.317049 -278.597914) (xy 91.275378 -278.631145) (xy 91.22922 -278.657794)
			(xy 91.179606 -278.677266) (xy 91.127644 -278.689126) (xy 91.074494 -278.69311) (xy 91.021344 -278.689126)
			(xy 90.969382 -278.677266) (xy 90.919768 -278.657794) (xy 90.87361 -278.631145) (xy 90.831939 -278.597914)
			(xy 90.795687 -278.558843) (xy 90.765663 -278.514806) (xy 90.742537 -278.466785) (xy 90.726827 -278.415855)
			(xy 90.718884 -278.363151) (xy 86.718348 -278.363151) (xy 86.710361 -278.414864) (xy 86.694475 -278.465063)
			(xy 86.671112 -278.512248) (xy 86.64082 -278.555314) (xy 86.604308 -278.593252) (xy 86.562434 -278.625171)
			(xy 86.516178 -278.650324) (xy 86.466625 -278.668122) (xy 86.414935 -278.678146) (xy 86.362321 -278.680163)
			(xy 86.310016 -278.674125) (xy 86.259245 -278.660173) (xy 86.2112 -278.638634) (xy 86.167005 -278.610014)
			(xy 86.127697 -278.574983) (xy 86.094197 -278.534362) (xy 86.067291 -278.489103) (xy 86.047608 -278.440268)
			(xy 86.035611 -278.389) (xy 86.031581 -278.336502) (xy 85.52688 -278.336502) (xy 85.52688 -278.64308)
			(xy 85.527642 -278.647398) (xy 85.53037 -278.663259) (xy 85.533296 -278.695313) (xy 85.533484 -278.711406)
			(xy 85.533292 -278.727499) (xy 85.530364 -278.759552) (xy 85.527642 -278.775414) (xy 85.52688 -278.779732)
			(xy 85.52688 -279.176967) (xy 88.369384 -279.176967) (xy 88.369384 -279.123669) (xy 88.377327 -279.070965)
			(xy 88.393037 -279.020035) (xy 88.416163 -278.972014) (xy 88.446187 -278.927977) (xy 88.482439 -278.888906)
			(xy 88.52411 -278.855675) (xy 88.570268 -278.829026) (xy 88.619882 -278.809554) (xy 88.671844 -278.797694)
			(xy 88.724994 -278.793711) (xy 88.778144 -278.797694) (xy 88.830106 -278.809554) (xy 88.87972 -278.829026)
			(xy 88.925878 -278.855675) (xy 88.967549 -278.888906) (xy 89.003801 -278.927977) (xy 89.033825 -278.972014)
			(xy 89.056951 -279.020035) (xy 89.072661 -279.070965) (xy 89.080604 -279.123669) (xy 89.081102 -279.150318)
			(xy 89.080604 -279.176967) (xy 89.309184 -279.176967) (xy 89.309184 -279.123669) (xy 89.317127 -279.070965)
			(xy 89.332837 -279.020035) (xy 89.355963 -278.972014) (xy 89.385987 -278.927977) (xy 89.422239 -278.888906)
			(xy 89.46391 -278.855675) (xy 89.510068 -278.829026) (xy 89.559682 -278.809554) (xy 89.611644 -278.797694)
			(xy 89.664794 -278.793711) (xy 89.717944 -278.797694) (xy 89.769906 -278.809554) (xy 89.81952 -278.829026)
			(xy 89.865678 -278.855675) (xy 89.907349 -278.888906) (xy 89.943601 -278.927977) (xy 89.973625 -278.972014)
			(xy 89.996751 -279.020035) (xy 90.012461 -279.070965) (xy 90.020404 -279.123669) (xy 90.020902 -279.150318)
			(xy 90.020404 -279.176967) (xy 90.248984 -279.176967) (xy 90.248984 -279.123669) (xy 90.256927 -279.070965)
			(xy 90.272637 -279.020035) (xy 90.295763 -278.972014) (xy 90.325787 -278.927977) (xy 90.362039 -278.888906)
			(xy 90.40371 -278.855675) (xy 90.449868 -278.829026) (xy 90.499482 -278.809554) (xy 90.551444 -278.797694)
			(xy 90.604594 -278.793711) (xy 90.657744 -278.797694) (xy 90.709706 -278.809554) (xy 90.75932 -278.829026)
			(xy 90.805478 -278.855675) (xy 90.847149 -278.888906) (xy 90.883401 -278.927977) (xy 90.913425 -278.972014)
			(xy 90.936551 -279.020035) (xy 90.952261 -279.070965) (xy 90.960204 -279.123669) (xy 90.960702 -279.150318)
			(xy 90.960204 -279.176967) (xy 91.188784 -279.176967) (xy 91.188784 -279.123669) (xy 91.196727 -279.070965)
			(xy 91.212437 -279.020035) (xy 91.235563 -278.972014) (xy 91.265587 -278.927977) (xy 91.301839 -278.888906)
			(xy 91.34351 -278.855675) (xy 91.389668 -278.829026) (xy 91.439282 -278.809554) (xy 91.491244 -278.797694)
			(xy 91.544394 -278.793711) (xy 91.597544 -278.797694) (xy 91.649506 -278.809554) (xy 91.69912 -278.829026)
			(xy 91.745278 -278.855675) (xy 91.786949 -278.888906) (xy 91.823201 -278.927977) (xy 91.853225 -278.972014)
			(xy 91.876351 -279.020035) (xy 91.892061 -279.070965) (xy 91.900004 -279.123669) (xy 91.900502 -279.150318)
			(xy 91.900004 -279.176967) (xy 92.128584 -279.176967) (xy 92.128584 -279.123669) (xy 92.136527 -279.070965)
			(xy 92.152237 -279.020035) (xy 92.175363 -278.972014) (xy 92.205387 -278.927977) (xy 92.241639 -278.888906)
			(xy 92.28331 -278.855675) (xy 92.329468 -278.829026) (xy 92.379082 -278.809554) (xy 92.431044 -278.797694)
			(xy 92.484194 -278.793711) (xy 92.537344 -278.797694) (xy 92.589306 -278.809554) (xy 92.63892 -278.829026)
			(xy 92.685078 -278.855675) (xy 92.726749 -278.888906) (xy 92.763001 -278.927977) (xy 92.793025 -278.972014)
			(xy 92.816151 -279.020035) (xy 92.831861 -279.070965) (xy 92.839804 -279.123669) (xy 92.840302 -279.150318)
			(xy 92.839804 -279.176967) (xy 93.068384 -279.176967) (xy 93.068384 -279.123669) (xy 93.076327 -279.070965)
			(xy 93.092037 -279.020035) (xy 93.115163 -278.972014) (xy 93.145187 -278.927977) (xy 93.181439 -278.888906)
			(xy 93.22311 -278.855675) (xy 93.269268 -278.829026) (xy 93.318882 -278.809554) (xy 93.370844 -278.797694)
			(xy 93.423994 -278.793711) (xy 93.477144 -278.797694) (xy 93.529106 -278.809554) (xy 93.57872 -278.829026)
			(xy 93.624878 -278.855675) (xy 93.666549 -278.888906) (xy 93.702801 -278.927977) (xy 93.732825 -278.972014)
			(xy 93.755951 -279.020035) (xy 93.771661 -279.070965) (xy 93.779604 -279.123669) (xy 93.780102 -279.150318)
			(xy 93.779604 -279.176967) (xy 94.008438 -279.176967) (xy 94.008438 -279.123669) (xy 94.016381 -279.070965)
			(xy 94.032091 -279.020035) (xy 94.055217 -278.972014) (xy 94.085241 -278.927977) (xy 94.121493 -278.888906)
			(xy 94.163164 -278.855675) (xy 94.209322 -278.829026) (xy 94.258936 -278.809554) (xy 94.310898 -278.797694)
			(xy 94.364048 -278.793711) (xy 94.417198 -278.797694) (xy 94.46916 -278.809554) (xy 94.518774 -278.829026)
			(xy 94.564932 -278.855675) (xy 94.606603 -278.888906) (xy 94.642855 -278.927977) (xy 94.672879 -278.972014)
			(xy 94.696005 -279.020035) (xy 94.711715 -279.070965) (xy 94.719658 -279.123669) (xy 94.720156 -279.150318)
			(xy 94.719658 -279.176967) (xy 94.947984 -279.176967) (xy 94.947984 -279.123669) (xy 94.955927 -279.070965)
			(xy 94.971637 -279.020035) (xy 94.994763 -278.972014) (xy 95.024787 -278.927977) (xy 95.061039 -278.888906)
			(xy 95.10271 -278.855675) (xy 95.148868 -278.829026) (xy 95.198482 -278.809554) (xy 95.250444 -278.797694)
			(xy 95.303594 -278.793711) (xy 95.356744 -278.797694) (xy 95.408706 -278.809554) (xy 95.45832 -278.829026)
			(xy 95.504478 -278.855675) (xy 95.546149 -278.888906) (xy 95.582401 -278.927977) (xy 95.612425 -278.972014)
			(xy 95.635551 -279.020035) (xy 95.651261 -279.070965) (xy 95.659204 -279.123669) (xy 95.659702 -279.150318)
			(xy 95.659204 -279.176967) (xy 95.887784 -279.176967) (xy 95.887784 -279.123669) (xy 95.895727 -279.070965)
			(xy 95.911437 -279.020035) (xy 95.934563 -278.972014) (xy 95.964587 -278.927977) (xy 96.000839 -278.888906)
			(xy 96.04251 -278.855675) (xy 96.088668 -278.829026) (xy 96.138282 -278.809554) (xy 96.190244 -278.797694)
			(xy 96.243394 -278.793711) (xy 96.296544 -278.797694) (xy 96.348506 -278.809554) (xy 96.39812 -278.829026)
			(xy 96.444278 -278.855675) (xy 96.485949 -278.888906) (xy 96.522201 -278.927977) (xy 96.552225 -278.972014)
			(xy 96.575351 -279.020035) (xy 96.591061 -279.070965) (xy 96.599004 -279.123669) (xy 96.599502 -279.150318)
			(xy 96.599004 -279.176967) (xy 97.767638 -279.176967) (xy 97.767638 -279.123669) (xy 97.775581 -279.070965)
			(xy 97.791291 -279.020035) (xy 97.814417 -278.972014) (xy 97.844441 -278.927977) (xy 97.880693 -278.888906)
			(xy 97.922364 -278.855675) (xy 97.968522 -278.829026) (xy 98.018136 -278.809554) (xy 98.070098 -278.797694)
			(xy 98.123248 -278.793711) (xy 98.176398 -278.797694) (xy 98.22836 -278.809554) (xy 98.277974 -278.829026)
			(xy 98.324132 -278.855675) (xy 98.365803 -278.888906) (xy 98.402055 -278.927977) (xy 98.432079 -278.972014)
			(xy 98.455205 -279.020035) (xy 98.470915 -279.070965) (xy 98.478858 -279.123669) (xy 98.479356 -279.150318)
			(xy 98.478858 -279.176967) (xy 98.707184 -279.176967) (xy 98.707184 -279.123669) (xy 98.715127 -279.070965)
			(xy 98.730837 -279.020035) (xy 98.753963 -278.972014) (xy 98.783987 -278.927977) (xy 98.820239 -278.888906)
			(xy 98.86191 -278.855675) (xy 98.908068 -278.829026) (xy 98.957682 -278.809554) (xy 99.009644 -278.797694)
			(xy 99.062794 -278.793711) (xy 99.115944 -278.797694) (xy 99.167906 -278.809554) (xy 99.21752 -278.829026)
			(xy 99.263678 -278.855675) (xy 99.305349 -278.888906) (xy 99.341601 -278.927977) (xy 99.371625 -278.972014)
			(xy 99.394751 -279.020035) (xy 99.410461 -279.070965) (xy 99.418404 -279.123669) (xy 99.418902 -279.150318)
			(xy 99.418404 -279.176967) (xy 99.646984 -279.176967) (xy 99.646984 -279.123669) (xy 99.654927 -279.070965)
			(xy 99.670637 -279.020035) (xy 99.693763 -278.972014) (xy 99.723787 -278.927977) (xy 99.760039 -278.888906)
			(xy 99.80171 -278.855675) (xy 99.847868 -278.829026) (xy 99.897482 -278.809554) (xy 99.949444 -278.797694)
			(xy 100.002594 -278.793711) (xy 100.055744 -278.797694) (xy 100.107706 -278.809554) (xy 100.15732 -278.829026)
			(xy 100.203478 -278.855675) (xy 100.245149 -278.888906) (xy 100.281401 -278.927977) (xy 100.311425 -278.972014)
			(xy 100.334551 -279.020035) (xy 100.350261 -279.070965) (xy 100.358204 -279.123669) (xy 100.358702 -279.150318)
			(xy 100.358204 -279.176967) (xy 100.587038 -279.176967) (xy 100.587038 -279.123669) (xy 100.594981 -279.070965)
			(xy 100.610691 -279.020035) (xy 100.633817 -278.972014) (xy 100.663841 -278.927977) (xy 100.700093 -278.888906)
			(xy 100.741764 -278.855675) (xy 100.787922 -278.829026) (xy 100.837536 -278.809554) (xy 100.889498 -278.797694)
			(xy 100.942648 -278.793711) (xy 100.995798 -278.797694) (xy 101.04776 -278.809554) (xy 101.097374 -278.829026)
			(xy 101.143532 -278.855675) (xy 101.185203 -278.888906) (xy 101.221455 -278.927977) (xy 101.251479 -278.972014)
			(xy 101.274605 -279.020035) (xy 101.290315 -279.070965) (xy 101.298258 -279.123669) (xy 101.298756 -279.150318)
			(xy 101.526086 -279.150318) (xy 101.526584 -279.123669) (xy 101.534527 -279.070965) (xy 101.550237 -279.020035)
			(xy 101.573363 -278.972014) (xy 101.603387 -278.927977) (xy 101.639639 -278.888906) (xy 101.68131 -278.855675)
			(xy 101.727468 -278.829026) (xy 101.777082 -278.809554) (xy 101.829044 -278.797694) (xy 101.882194 -278.793711)
			(xy 101.935344 -278.797694) (xy 101.987306 -278.809554) (xy 102.03692 -278.829026) (xy 102.083078 -278.855675)
			(xy 102.124749 -278.888906) (xy 102.161001 -278.927977) (xy 102.191025 -278.972014) (xy 102.214151 -279.020035)
			(xy 102.229861 -279.070965) (xy 102.237804 -279.123669) (xy 102.238302 -279.1503) (xy 102.465411 -279.1503)
			(xy 102.469394 -279.097154) (xy 102.481253 -279.045195) (xy 102.500724 -278.995583) (xy 102.527371 -278.949428)
			(xy 102.5606 -278.90776) (xy 102.599668 -278.87151) (xy 102.643702 -278.841487) (xy 102.691719 -278.818362)
			(xy 102.742646 -278.802653) (xy 102.795346 -278.794709) (xy 102.821994 -278.79421) (xy 102.847019 -278.79463)
			(xy 102.896577 -278.801637) (xy 102.944665 -278.815516) (xy 102.990336 -278.835991) (xy 103.03269 -278.86266)
			(xy 103.070893 -278.894996) (xy 103.10419 -278.932364) (xy 103.118412 -278.95296) (xy 103.465376 -278.95296)
			(xy 103.479609 -278.932372) (xy 103.512905 -278.895005) (xy 103.551105 -278.862668) (xy 103.593457 -278.835999)
			(xy 103.639127 -278.815523) (xy 103.687213 -278.801644) (xy 103.736769 -278.794635) (xy 103.761794 -278.79421)
			(xy 103.788447 -278.794647) (xy 103.841157 -278.802591) (xy 103.892095 -278.818302) (xy 103.940122 -278.84143)
			(xy 103.984165 -278.871458) (xy 104.023241 -278.907714) (xy 104.056477 -278.94939) (xy 104.08313 -278.995554)
			(xy 104.102605 -279.045174) (xy 104.114466 -279.097144) (xy 104.11845 -279.1503) (xy 104.116451 -279.176967)
			(xy 104.345984 -279.176967) (xy 104.345984 -279.123669) (xy 104.353927 -279.070965) (xy 104.369637 -279.020035)
			(xy 104.392763 -278.972014) (xy 104.422787 -278.927977) (xy 104.459039 -278.888906) (xy 104.50071 -278.855675)
			(xy 104.546868 -278.829026) (xy 104.596482 -278.809554) (xy 104.648444 -278.797694) (xy 104.701594 -278.793711)
			(xy 104.754744 -278.797694) (xy 104.806706 -278.809554) (xy 104.85632 -278.829026) (xy 104.902478 -278.855675)
			(xy 104.944149 -278.888906) (xy 104.980401 -278.927977) (xy 105.010425 -278.972014) (xy 105.033551 -279.020035)
			(xy 105.049261 -279.070965) (xy 105.057204 -279.123669) (xy 105.057702 -279.150318) (xy 105.057204 -279.176967)
			(xy 105.286038 -279.176967) (xy 105.286038 -279.123669) (xy 105.293981 -279.070965) (xy 105.309691 -279.020035)
			(xy 105.332817 -278.972014) (xy 105.362841 -278.927977) (xy 105.399093 -278.888906) (xy 105.440764 -278.855675)
			(xy 105.486922 -278.829026) (xy 105.536536 -278.809554) (xy 105.588498 -278.797694) (xy 105.641648 -278.793711)
			(xy 105.694798 -278.797694) (xy 105.74676 -278.809554) (xy 105.796374 -278.829026) (xy 105.842532 -278.855675)
			(xy 105.884203 -278.888906) (xy 105.920455 -278.927977) (xy 105.950479 -278.972014) (xy 105.973605 -279.020035)
			(xy 105.989315 -279.070965) (xy 105.997258 -279.123669) (xy 105.997756 -279.150318) (xy 105.997258 -279.176967)
			(xy 106.225838 -279.176967) (xy 106.225838 -279.123669) (xy 106.233781 -279.070965) (xy 106.249491 -279.020035)
			(xy 106.272617 -278.972014) (xy 106.302641 -278.927977) (xy 106.338893 -278.888906) (xy 106.380564 -278.855675)
			(xy 106.426722 -278.829026) (xy 106.476336 -278.809554) (xy 106.528298 -278.797694) (xy 106.581448 -278.793711)
			(xy 106.634598 -278.797694) (xy 106.68656 -278.809554) (xy 106.736174 -278.829026) (xy 106.782332 -278.855675)
			(xy 106.824003 -278.888906) (xy 106.860255 -278.927977) (xy 106.890279 -278.972014) (xy 106.913405 -279.020035)
			(xy 106.929115 -279.070965) (xy 106.937058 -279.123669) (xy 106.937556 -279.150318) (xy 106.937058 -279.176967)
			(xy 106.929115 -279.229671) (xy 106.913405 -279.280601) (xy 106.890279 -279.328622) (xy 106.860255 -279.372659)
			(xy 106.824003 -279.41173) (xy 106.782332 -279.444961) (xy 106.736174 -279.47161) (xy 106.68656 -279.491082)
			(xy 106.634598 -279.502942) (xy 106.581448 -279.506926) (xy 106.528298 -279.502942) (xy 106.476336 -279.491082)
			(xy 106.426722 -279.47161) (xy 106.380564 -279.444961) (xy 106.338893 -279.41173) (xy 106.302641 -279.372659)
			(xy 106.272617 -279.328622) (xy 106.249491 -279.280601) (xy 106.233781 -279.229671) (xy 106.225838 -279.176967)
			(xy 105.997258 -279.176967) (xy 105.989315 -279.229671) (xy 105.973605 -279.280601) (xy 105.950479 -279.328622)
			(xy 105.920455 -279.372659) (xy 105.884203 -279.41173) (xy 105.842532 -279.444961) (xy 105.796374 -279.47161)
			(xy 105.74676 -279.491082) (xy 105.694798 -279.502942) (xy 105.641648 -279.506926) (xy 105.588498 -279.502942)
			(xy 105.536536 -279.491082) (xy 105.486922 -279.47161) (xy 105.440764 -279.444961) (xy 105.399093 -279.41173)
			(xy 105.362841 -279.372659) (xy 105.332817 -279.328622) (xy 105.309691 -279.280601) (xy 105.293981 -279.229671)
			(xy 105.286038 -279.176967) (xy 105.057204 -279.176967) (xy 105.049261 -279.229671) (xy 105.033551 -279.280601)
			(xy 105.010425 -279.328622) (xy 104.980401 -279.372659) (xy 104.944149 -279.41173) (xy 104.902478 -279.444961)
			(xy 104.85632 -279.47161) (xy 104.806706 -279.491082) (xy 104.754744 -279.502942) (xy 104.701594 -279.506926)
			(xy 104.648444 -279.502942) (xy 104.596482 -279.491082) (xy 104.546868 -279.47161) (xy 104.50071 -279.444961)
			(xy 104.459039 -279.41173) (xy 104.422787 -279.372659) (xy 104.392763 -279.328622) (xy 104.369637 -279.280601)
			(xy 104.353927 -279.229671) (xy 104.345984 -279.176967) (xy 104.116451 -279.176967) (xy 104.114466 -279.203456)
			(xy 104.102605 -279.255426) (xy 104.08313 -279.305046) (xy 104.056477 -279.35121) (xy 104.023241 -279.392886)
			(xy 103.984165 -279.429142) (xy 103.940122 -279.45917) (xy 103.892095 -279.482298) (xy 103.841157 -279.498009)
			(xy 103.788447 -279.505953) (xy 103.761794 -279.506426) (xy 103.736769 -279.506) (xy 103.687212 -279.498991)
			(xy 103.639125 -279.485113) (xy 103.593454 -279.464638) (xy 103.551101 -279.437971) (xy 103.512898 -279.405636)
			(xy 103.479599 -279.368271) (xy 103.465376 -279.347676) (xy 103.118412 -279.347676) (xy 103.104198 -279.368277)
			(xy 103.070898 -279.405643) (xy 103.032693 -279.437977) (xy 102.990338 -279.464644) (xy 102.944666 -279.485118)
			(xy 102.896577 -279.498995) (xy 102.847019 -279.506002) (xy 102.821994 -279.506426) (xy 102.795346 -279.505891)
			(xy 102.742646 -279.497947) (xy 102.691719 -279.482238) (xy 102.643702 -279.459113) (xy 102.599668 -279.42909)
			(xy 102.5606 -279.39284) (xy 102.527371 -279.351172) (xy 102.500724 -279.305017) (xy 102.481253 -279.255405)
			(xy 102.469394 -279.203446) (xy 102.465411 -279.1503) (xy 102.238302 -279.1503) (xy 102.238302 -279.150318)
			(xy 102.237936 -279.17347) (xy 102.231947 -279.219384) (xy 102.220072 -279.264139) (xy 102.211632 -279.2857)
			(xy 102.20198 -279.308814) (xy 102.3747 -279.607772) (xy 102.399338 -279.611074) (xy 102.424679 -279.614908)
			(xy 102.473983 -279.628899) (xy 102.520773 -279.64981) (xy 102.564084 -279.67721) (xy 102.603022 -279.710534)
			(xy 102.636783 -279.749094) (xy 102.66467 -279.792093) (xy 102.686107 -279.838645) (xy 102.700653 -279.887788)
			(xy 102.708006 -279.938509) (xy 102.708456 -279.964134) (xy 102.707958 -279.990783) (xy 102.936284 -279.990783)
			(xy 102.936284 -279.937485) (xy 102.944227 -279.884781) (xy 102.959937 -279.833851) (xy 102.983063 -279.78583)
			(xy 103.013087 -279.741793) (xy 103.049339 -279.702722) (xy 103.09101 -279.669491) (xy 103.137168 -279.642842)
			(xy 103.186782 -279.62337) (xy 103.238744 -279.61151) (xy 103.291894 -279.607527) (xy 103.345044 -279.61151)
			(xy 103.397006 -279.62337) (xy 103.44662 -279.642842) (xy 103.492778 -279.669491) (xy 103.534449 -279.702722)
			(xy 103.570701 -279.741793) (xy 103.600725 -279.78583) (xy 103.623851 -279.833851) (xy 103.639561 -279.884781)
			(xy 103.647504 -279.937485) (xy 103.648002 -279.964134) (xy 103.647504 -279.990783) (xy 103.876338 -279.990783)
			(xy 103.876338 -279.937485) (xy 103.884281 -279.884781) (xy 103.899991 -279.833851) (xy 103.923117 -279.78583)
			(xy 103.953141 -279.741793) (xy 103.989393 -279.702722) (xy 104.031064 -279.669491) (xy 104.077222 -279.642842)
			(xy 104.126836 -279.62337) (xy 104.178798 -279.61151) (xy 104.231948 -279.607527) (xy 104.285098 -279.61151)
			(xy 104.33706 -279.62337) (xy 104.386674 -279.642842) (xy 104.432832 -279.669491) (xy 104.474503 -279.702722)
			(xy 104.510755 -279.741793) (xy 104.540779 -279.78583) (xy 104.563905 -279.833851) (xy 104.579615 -279.884781)
			(xy 104.587558 -279.937485) (xy 104.588056 -279.964134) (xy 104.587558 -279.990783) (xy 104.579615 -280.043487)
			(xy 104.563905 -280.094417) (xy 104.540779 -280.142438) (xy 104.510755 -280.186475) (xy 104.474503 -280.225546)
			(xy 104.432832 -280.258777) (xy 104.386674 -280.285426) (xy 104.33706 -280.304898) (xy 104.285098 -280.316758)
			(xy 104.231948 -280.320742) (xy 104.178798 -280.316758) (xy 104.126836 -280.304898) (xy 104.077222 -280.285426)
			(xy 104.031064 -280.258777) (xy 103.989393 -280.225546) (xy 103.953141 -280.186475) (xy 103.923117 -280.142438)
			(xy 103.899991 -280.094417) (xy 103.884281 -280.043487) (xy 103.876338 -279.990783) (xy 103.647504 -279.990783)
			(xy 103.639561 -280.043487) (xy 103.623851 -280.094417) (xy 103.600725 -280.142438) (xy 103.570701 -280.186475)
			(xy 103.534449 -280.225546) (xy 103.492778 -280.258777) (xy 103.44662 -280.285426) (xy 103.397006 -280.304898)
			(xy 103.345044 -280.316758) (xy 103.291894 -280.320742) (xy 103.238744 -280.316758) (xy 103.186782 -280.304898)
			(xy 103.137168 -280.285426) (xy 103.09101 -280.258777) (xy 103.049339 -280.225546) (xy 103.013087 -280.186475)
			(xy 102.983063 -280.142438) (xy 102.959937 -280.094417) (xy 102.944227 -280.043487) (xy 102.936284 -279.990783)
			(xy 102.707958 -279.990783) (xy 102.700015 -280.043487) (xy 102.684305 -280.094417) (xy 102.661179 -280.142438)
			(xy 102.631155 -280.186475) (xy 102.594903 -280.225546) (xy 102.553232 -280.258777) (xy 102.507074 -280.285426)
			(xy 102.45746 -280.304898) (xy 102.405498 -280.316758) (xy 102.352348 -280.320742) (xy 102.299198 -280.316758)
			(xy 102.247236 -280.304898) (xy 102.197622 -280.285426) (xy 102.151464 -280.258777) (xy 102.109793 -280.225546)
			(xy 102.073541 -280.186475) (xy 102.043517 -280.142438) (xy 102.020391 -280.094417) (xy 102.004681 -280.043487)
			(xy 101.996738 -279.990783) (xy 101.99624 -279.964134) (xy 101.996617 -279.940889) (xy 102.00266 -279.894794)
			(xy 102.014648 -279.849876) (xy 102.023164 -279.828244) (xy 102.032816 -279.80513) (xy 101.86035 -279.50668)
			(xy 101.835458 -279.503378) (xy 101.810095 -279.499606) (xy 101.760754 -279.485643) (xy 101.713926 -279.464749)
			(xy 101.670577 -279.437357) (xy 101.631604 -279.404032) (xy 101.597813 -279.365463) (xy 101.5699 -279.322447)
			(xy 101.548445 -279.275874) (xy 101.533889 -279.226705) (xy 101.526533 -279.175957) (xy 101.526086 -279.150318)
			(xy 101.298756 -279.150318) (xy 101.298258 -279.176967) (xy 101.290315 -279.229671) (xy 101.274605 -279.280601)
			(xy 101.251479 -279.328622) (xy 101.221455 -279.372659) (xy 101.185203 -279.41173) (xy 101.143532 -279.444961)
			(xy 101.097374 -279.47161) (xy 101.04776 -279.491082) (xy 100.995798 -279.502942) (xy 100.942648 -279.506926)
			(xy 100.889498 -279.502942) (xy 100.837536 -279.491082) (xy 100.787922 -279.47161) (xy 100.741764 -279.444961)
			(xy 100.700093 -279.41173) (xy 100.663841 -279.372659) (xy 100.633817 -279.328622) (xy 100.610691 -279.280601)
			(xy 100.594981 -279.229671) (xy 100.587038 -279.176967) (xy 100.358204 -279.176967) (xy 100.350261 -279.229671)
			(xy 100.334551 -279.280601) (xy 100.311425 -279.328622) (xy 100.281401 -279.372659) (xy 100.245149 -279.41173)
			(xy 100.203478 -279.444961) (xy 100.15732 -279.47161) (xy 100.107706 -279.491082) (xy 100.055744 -279.502942)
			(xy 100.002594 -279.506926) (xy 99.949444 -279.502942) (xy 99.897482 -279.491082) (xy 99.847868 -279.47161)
			(xy 99.80171 -279.444961) (xy 99.760039 -279.41173) (xy 99.723787 -279.372659) (xy 99.693763 -279.328622)
			(xy 99.670637 -279.280601) (xy 99.654927 -279.229671) (xy 99.646984 -279.176967) (xy 99.418404 -279.176967)
			(xy 99.410461 -279.229671) (xy 99.394751 -279.280601) (xy 99.371625 -279.328622) (xy 99.341601 -279.372659)
			(xy 99.305349 -279.41173) (xy 99.263678 -279.444961) (xy 99.21752 -279.47161) (xy 99.167906 -279.491082)
			(xy 99.115944 -279.502942) (xy 99.062794 -279.506926) (xy 99.009644 -279.502942) (xy 98.957682 -279.491082)
			(xy 98.908068 -279.47161) (xy 98.86191 -279.444961) (xy 98.820239 -279.41173) (xy 98.783987 -279.372659)
			(xy 98.753963 -279.328622) (xy 98.730837 -279.280601) (xy 98.715127 -279.229671) (xy 98.707184 -279.176967)
			(xy 98.478858 -279.176967) (xy 98.470915 -279.229671) (xy 98.455205 -279.280601) (xy 98.432079 -279.328622)
			(xy 98.402055 -279.372659) (xy 98.365803 -279.41173) (xy 98.324132 -279.444961) (xy 98.277974 -279.47161)
			(xy 98.22836 -279.491082) (xy 98.176398 -279.502942) (xy 98.123248 -279.506926) (xy 98.070098 -279.502942)
			(xy 98.018136 -279.491082) (xy 97.968522 -279.47161) (xy 97.922364 -279.444961) (xy 97.880693 -279.41173)
			(xy 97.844441 -279.372659) (xy 97.814417 -279.328622) (xy 97.791291 -279.280601) (xy 97.775581 -279.229671)
			(xy 97.767638 -279.176967) (xy 96.599004 -279.176967) (xy 96.591061 -279.229671) (xy 96.575351 -279.280601)
			(xy 96.552225 -279.328622) (xy 96.522201 -279.372659) (xy 96.485949 -279.41173) (xy 96.444278 -279.444961)
			(xy 96.39812 -279.47161) (xy 96.348506 -279.491082) (xy 96.296544 -279.502942) (xy 96.243394 -279.506926)
			(xy 96.190244 -279.502942) (xy 96.138282 -279.491082) (xy 96.088668 -279.47161) (xy 96.04251 -279.444961)
			(xy 96.000839 -279.41173) (xy 95.964587 -279.372659) (xy 95.934563 -279.328622) (xy 95.911437 -279.280601)
			(xy 95.895727 -279.229671) (xy 95.887784 -279.176967) (xy 95.659204 -279.176967) (xy 95.651261 -279.229671)
			(xy 95.635551 -279.280601) (xy 95.612425 -279.328622) (xy 95.582401 -279.372659) (xy 95.546149 -279.41173)
			(xy 95.504478 -279.444961) (xy 95.45832 -279.47161) (xy 95.408706 -279.491082) (xy 95.356744 -279.502942)
			(xy 95.303594 -279.506926) (xy 95.250444 -279.502942) (xy 95.198482 -279.491082) (xy 95.148868 -279.47161)
			(xy 95.10271 -279.444961) (xy 95.061039 -279.41173) (xy 95.024787 -279.372659) (xy 94.994763 -279.328622)
			(xy 94.971637 -279.280601) (xy 94.955927 -279.229671) (xy 94.947984 -279.176967) (xy 94.719658 -279.176967)
			(xy 94.711715 -279.229671) (xy 94.696005 -279.280601) (xy 94.672879 -279.328622) (xy 94.642855 -279.372659)
			(xy 94.606603 -279.41173) (xy 94.564932 -279.444961) (xy 94.518774 -279.47161) (xy 94.46916 -279.491082)
			(xy 94.417198 -279.502942) (xy 94.364048 -279.506926) (xy 94.310898 -279.502942) (xy 94.258936 -279.491082)
			(xy 94.209322 -279.47161) (xy 94.163164 -279.444961) (xy 94.121493 -279.41173) (xy 94.085241 -279.372659)
			(xy 94.055217 -279.328622) (xy 94.032091 -279.280601) (xy 94.016381 -279.229671) (xy 94.008438 -279.176967)
			(xy 93.779604 -279.176967) (xy 93.771661 -279.229671) (xy 93.755951 -279.280601) (xy 93.732825 -279.328622)
			(xy 93.702801 -279.372659) (xy 93.666549 -279.41173) (xy 93.624878 -279.444961) (xy 93.57872 -279.47161)
			(xy 93.529106 -279.491082) (xy 93.477144 -279.502942) (xy 93.423994 -279.506926) (xy 93.370844 -279.502942)
			(xy 93.318882 -279.491082) (xy 93.269268 -279.47161) (xy 93.22311 -279.444961) (xy 93.181439 -279.41173)
			(xy 93.145187 -279.372659) (xy 93.115163 -279.328622) (xy 93.092037 -279.280601) (xy 93.076327 -279.229671)
			(xy 93.068384 -279.176967) (xy 92.839804 -279.176967) (xy 92.831861 -279.229671) (xy 92.816151 -279.280601)
			(xy 92.793025 -279.328622) (xy 92.763001 -279.372659) (xy 92.726749 -279.41173) (xy 92.685078 -279.444961)
			(xy 92.63892 -279.47161) (xy 92.589306 -279.491082) (xy 92.537344 -279.502942) (xy 92.484194 -279.506926)
			(xy 92.431044 -279.502942) (xy 92.379082 -279.491082) (xy 92.329468 -279.47161) (xy 92.28331 -279.444961)
			(xy 92.241639 -279.41173) (xy 92.205387 -279.372659) (xy 92.175363 -279.328622) (xy 92.152237 -279.280601)
			(xy 92.136527 -279.229671) (xy 92.128584 -279.176967) (xy 91.900004 -279.176967) (xy 91.892061 -279.229671)
			(xy 91.876351 -279.280601) (xy 91.853225 -279.328622) (xy 91.823201 -279.372659) (xy 91.786949 -279.41173)
			(xy 91.745278 -279.444961) (xy 91.69912 -279.47161) (xy 91.649506 -279.491082) (xy 91.597544 -279.502942)
			(xy 91.544394 -279.506926) (xy 91.491244 -279.502942) (xy 91.439282 -279.491082) (xy 91.389668 -279.47161)
			(xy 91.34351 -279.444961) (xy 91.301839 -279.41173) (xy 91.265587 -279.372659) (xy 91.235563 -279.328622)
			(xy 91.212437 -279.280601) (xy 91.196727 -279.229671) (xy 91.188784 -279.176967) (xy 90.960204 -279.176967)
			(xy 90.952261 -279.229671) (xy 90.936551 -279.280601) (xy 90.913425 -279.328622) (xy 90.883401 -279.372659)
			(xy 90.847149 -279.41173) (xy 90.805478 -279.444961) (xy 90.75932 -279.47161) (xy 90.709706 -279.491082)
			(xy 90.657744 -279.502942) (xy 90.604594 -279.506926) (xy 90.551444 -279.502942) (xy 90.499482 -279.491082)
			(xy 90.449868 -279.47161) (xy 90.40371 -279.444961) (xy 90.362039 -279.41173) (xy 90.325787 -279.372659)
			(xy 90.295763 -279.328622) (xy 90.272637 -279.280601) (xy 90.256927 -279.229671) (xy 90.248984 -279.176967)
			(xy 90.020404 -279.176967) (xy 90.012461 -279.229671) (xy 89.996751 -279.280601) (xy 89.973625 -279.328622)
			(xy 89.943601 -279.372659) (xy 89.907349 -279.41173) (xy 89.865678 -279.444961) (xy 89.81952 -279.47161)
			(xy 89.769906 -279.491082) (xy 89.717944 -279.502942) (xy 89.664794 -279.506926) (xy 89.611644 -279.502942)
			(xy 89.559682 -279.491082) (xy 89.510068 -279.47161) (xy 89.46391 -279.444961) (xy 89.422239 -279.41173)
			(xy 89.385987 -279.372659) (xy 89.355963 -279.328622) (xy 89.332837 -279.280601) (xy 89.317127 -279.229671)
			(xy 89.309184 -279.176967) (xy 89.080604 -279.176967) (xy 89.072661 -279.229671) (xy 89.056951 -279.280601)
			(xy 89.033825 -279.328622) (xy 89.003801 -279.372659) (xy 88.967549 -279.41173) (xy 88.925878 -279.444961)
			(xy 88.87972 -279.47161) (xy 88.830106 -279.491082) (xy 88.778144 -279.502942) (xy 88.724994 -279.506926)
			(xy 88.671844 -279.502942) (xy 88.619882 -279.491082) (xy 88.570268 -279.47161) (xy 88.52411 -279.444961)
			(xy 88.482439 -279.41173) (xy 88.446187 -279.372659) (xy 88.416163 -279.328622) (xy 88.393037 -279.280601)
			(xy 88.377327 -279.229671) (xy 88.369384 -279.176967) (xy 85.52688 -279.176967) (xy 85.52688 -279.990783)
			(xy 86.019884 -279.990783) (xy 86.019884 -279.937485) (xy 86.027827 -279.884781) (xy 86.043537 -279.833851)
			(xy 86.066663 -279.78583) (xy 86.096687 -279.741793) (xy 86.132939 -279.702722) (xy 86.17461 -279.669491)
			(xy 86.220768 -279.642842) (xy 86.270382 -279.62337) (xy 86.322344 -279.61151) (xy 86.375494 -279.607527)
			(xy 86.428644 -279.61151) (xy 86.480606 -279.62337) (xy 86.53022 -279.642842) (xy 86.576378 -279.669491)
			(xy 86.618049 -279.702722) (xy 86.654301 -279.741793) (xy 86.684325 -279.78583) (xy 86.707451 -279.833851)
			(xy 86.723161 -279.884781) (xy 86.731104 -279.937485) (xy 86.731602 -279.964134) (xy 86.731104 -279.990783)
			(xy 86.959684 -279.990783) (xy 86.959684 -279.937485) (xy 86.967627 -279.884781) (xy 86.983337 -279.833851)
			(xy 87.006463 -279.78583) (xy 87.036487 -279.741793) (xy 87.072739 -279.702722) (xy 87.11441 -279.669491)
			(xy 87.160568 -279.642842) (xy 87.210182 -279.62337) (xy 87.262144 -279.61151) (xy 87.315294 -279.607527)
			(xy 87.368444 -279.61151) (xy 87.420406 -279.62337) (xy 87.47002 -279.642842) (xy 87.516178 -279.669491)
			(xy 87.557849 -279.702722) (xy 87.594101 -279.741793) (xy 87.624125 -279.78583) (xy 87.647251 -279.833851)
			(xy 87.662961 -279.884781) (xy 87.670904 -279.937485) (xy 87.671402 -279.964134) (xy 87.670904 -279.990783)
			(xy 87.899484 -279.990783) (xy 87.899484 -279.937485) (xy 87.907427 -279.884781) (xy 87.923137 -279.833851)
			(xy 87.946263 -279.78583) (xy 87.976287 -279.741793) (xy 88.012539 -279.702722) (xy 88.05421 -279.669491)
			(xy 88.100368 -279.642842) (xy 88.149982 -279.62337) (xy 88.201944 -279.61151) (xy 88.255094 -279.607527)
			(xy 88.308244 -279.61151) (xy 88.360206 -279.62337) (xy 88.40982 -279.642842) (xy 88.455978 -279.669491)
			(xy 88.497649 -279.702722) (xy 88.533901 -279.741793) (xy 88.563925 -279.78583) (xy 88.587051 -279.833851)
			(xy 88.602761 -279.884781) (xy 88.610704 -279.937485) (xy 88.611201 -279.9641) (xy 88.838327 -279.9641)
			(xy 88.84231 -279.910956) (xy 88.854168 -279.858999) (xy 88.873638 -279.80939) (xy 88.900284 -279.763237)
			(xy 88.933512 -279.721571) (xy 88.972578 -279.685322) (xy 89.01661 -279.655301) (xy 89.064625 -279.632177)
			(xy 89.11555 -279.616468) (xy 89.168248 -279.608524) (xy 89.194894 -279.608026) (xy 89.21992 -279.608439)
			(xy 89.269478 -279.615447) (xy 89.317567 -279.629326) (xy 89.363238 -279.649802) (xy 89.405592 -279.676472)
			(xy 89.443794 -279.70881) (xy 89.477091 -279.746179) (xy 89.491312 -279.766776) (xy 89.838276 -279.766776)
			(xy 89.852514 -279.746192) (xy 89.885809 -279.708824) (xy 89.924008 -279.676486) (xy 89.966359 -279.649816)
			(xy 90.012028 -279.62934) (xy 90.060114 -279.61546) (xy 90.109669 -279.608451) (xy 90.134694 -279.608026)
			(xy 90.161348 -279.608431) (xy 90.214061 -279.616375) (xy 90.265 -279.632087) (xy 90.31303 -279.655216)
			(xy 90.357075 -279.685245) (xy 90.396153 -279.721503) (xy 90.42939 -279.763181) (xy 90.456044 -279.809347)
			(xy 90.47552 -279.85897) (xy 90.487382 -279.910941) (xy 90.491366 -279.9641) (xy 90.489366 -279.990783)
			(xy 91.658938 -279.990783) (xy 91.658938 -279.937485) (xy 91.666881 -279.884781) (xy 91.682591 -279.833851)
			(xy 91.705717 -279.78583) (xy 91.735741 -279.741793) (xy 91.771993 -279.702722) (xy 91.813664 -279.669491)
			(xy 91.859822 -279.642842) (xy 91.909436 -279.62337) (xy 91.961398 -279.61151) (xy 92.014548 -279.607527)
			(xy 92.067698 -279.61151) (xy 92.11966 -279.62337) (xy 92.169274 -279.642842) (xy 92.215432 -279.669491)
			(xy 92.257103 -279.702722) (xy 92.293355 -279.741793) (xy 92.323379 -279.78583) (xy 92.346505 -279.833851)
			(xy 92.362215 -279.884781) (xy 92.370158 -279.937485) (xy 92.370656 -279.964134) (xy 92.370158 -279.990783)
			(xy 92.598738 -279.990783) (xy 92.598738 -279.937485) (xy 92.606681 -279.884781) (xy 92.622391 -279.833851)
			(xy 92.645517 -279.78583) (xy 92.675541 -279.741793) (xy 92.711793 -279.702722) (xy 92.753464 -279.669491)
			(xy 92.799622 -279.642842) (xy 92.849236 -279.62337) (xy 92.901198 -279.61151) (xy 92.954348 -279.607527)
			(xy 93.007498 -279.61151) (xy 93.05946 -279.62337) (xy 93.109074 -279.642842) (xy 93.155232 -279.669491)
			(xy 93.196903 -279.702722) (xy 93.233155 -279.741793) (xy 93.263179 -279.78583) (xy 93.286305 -279.833851)
			(xy 93.302015 -279.884781) (xy 93.309958 -279.937485) (xy 93.310456 -279.964134) (xy 93.309958 -279.990783)
			(xy 94.478084 -279.990783) (xy 94.478084 -279.937485) (xy 94.486027 -279.884781) (xy 94.501737 -279.833851)
			(xy 94.524863 -279.78583) (xy 94.554887 -279.741793) (xy 94.591139 -279.702722) (xy 94.63281 -279.669491)
			(xy 94.678968 -279.642842) (xy 94.728582 -279.62337) (xy 94.780544 -279.61151) (xy 94.833694 -279.607527)
			(xy 94.886844 -279.61151) (xy 94.938806 -279.62337) (xy 94.98842 -279.642842) (xy 95.034578 -279.669491)
			(xy 95.076249 -279.702722) (xy 95.112501 -279.741793) (xy 95.142525 -279.78583) (xy 95.165651 -279.833851)
			(xy 95.181361 -279.884781) (xy 95.189304 -279.937485) (xy 95.189802 -279.964134) (xy 95.189304 -279.990783)
			(xy 95.418138 -279.990783) (xy 95.418138 -279.937485) (xy 95.426081 -279.884781) (xy 95.441791 -279.833851)
			(xy 95.464917 -279.78583) (xy 95.494941 -279.741793) (xy 95.531193 -279.702722) (xy 95.572864 -279.669491)
			(xy 95.619022 -279.642842) (xy 95.668636 -279.62337) (xy 95.720598 -279.61151) (xy 95.773748 -279.607527)
			(xy 95.826898 -279.61151) (xy 95.87886 -279.62337) (xy 95.928474 -279.642842) (xy 95.974632 -279.669491)
			(xy 96.016303 -279.702722) (xy 96.052555 -279.741793) (xy 96.082579 -279.78583) (xy 96.105705 -279.833851)
			(xy 96.121415 -279.884781) (xy 96.129358 -279.937485) (xy 96.129856 -279.964134) (xy 96.35744 -279.964134)
			(xy 96.357938 -279.937485) (xy 96.365881 -279.884781) (xy 96.381591 -279.833851) (xy 96.404717 -279.78583)
			(xy 96.434741 -279.741793) (xy 96.470993 -279.702722) (xy 96.512664 -279.669491) (xy 96.558822 -279.642842)
			(xy 96.608436 -279.62337) (xy 96.660398 -279.61151) (xy 96.713548 -279.607527) (xy 96.766698 -279.61151)
			(xy 96.81866 -279.62337) (xy 96.868274 -279.642842) (xy 96.914432 -279.669491) (xy 96.956103 -279.702722)
			(xy 96.992355 -279.741793) (xy 97.022379 -279.78583) (xy 97.045505 -279.833851) (xy 97.061215 -279.884781)
			(xy 97.069158 -279.937485) (xy 97.069656 -279.964134) (xy 97.069304 -279.987423) (xy 97.068866 -279.990783)
			(xy 97.297738 -279.990783) (xy 97.297738 -279.937485) (xy 97.305681 -279.884781) (xy 97.321391 -279.833851)
			(xy 97.344517 -279.78583) (xy 97.374541 -279.741793) (xy 97.410793 -279.702722) (xy 97.452464 -279.669491)
			(xy 97.498622 -279.642842) (xy 97.548236 -279.62337) (xy 97.600198 -279.61151) (xy 97.653348 -279.607527)
			(xy 97.706498 -279.61151) (xy 97.75846 -279.62337) (xy 97.808074 -279.642842) (xy 97.854232 -279.669491)
			(xy 97.895903 -279.702722) (xy 97.932155 -279.741793) (xy 97.962179 -279.78583) (xy 97.985305 -279.833851)
			(xy 98.001015 -279.884781) (xy 98.008958 -279.937485) (xy 98.009456 -279.964134) (xy 98.008958 -279.990783)
			(xy 98.237538 -279.990783) (xy 98.237538 -279.937485) (xy 98.245481 -279.884781) (xy 98.261191 -279.833851)
			(xy 98.284317 -279.78583) (xy 98.314341 -279.741793) (xy 98.350593 -279.702722) (xy 98.392264 -279.669491)
			(xy 98.438422 -279.642842) (xy 98.488036 -279.62337) (xy 98.539998 -279.61151) (xy 98.593148 -279.607527)
			(xy 98.646298 -279.61151) (xy 98.69826 -279.62337) (xy 98.747874 -279.642842) (xy 98.794032 -279.669491)
			(xy 98.835703 -279.702722) (xy 98.871955 -279.741793) (xy 98.901979 -279.78583) (xy 98.925105 -279.833851)
			(xy 98.940815 -279.884781) (xy 98.948758 -279.937485) (xy 98.949256 -279.964134) (xy 98.948758 -279.990783)
			(xy 100.117138 -279.990783) (xy 100.117138 -279.937485) (xy 100.125081 -279.884781) (xy 100.140791 -279.833851)
			(xy 100.163917 -279.78583) (xy 100.193941 -279.741793) (xy 100.230193 -279.702722) (xy 100.271864 -279.669491)
			(xy 100.318022 -279.642842) (xy 100.367636 -279.62337) (xy 100.419598 -279.61151) (xy 100.472748 -279.607527)
			(xy 100.525898 -279.61151) (xy 100.57786 -279.62337) (xy 100.627474 -279.642842) (xy 100.673632 -279.669491)
			(xy 100.715303 -279.702722) (xy 100.751555 -279.741793) (xy 100.781579 -279.78583) (xy 100.804705 -279.833851)
			(xy 100.820415 -279.884781) (xy 100.828358 -279.937485) (xy 100.828856 -279.964134) (xy 100.828358 -279.990783)
			(xy 101.056938 -279.990783) (xy 101.056938 -279.937485) (xy 101.064881 -279.884781) (xy 101.080591 -279.833851)
			(xy 101.103717 -279.78583) (xy 101.133741 -279.741793) (xy 101.169993 -279.702722) (xy 101.211664 -279.669491)
			(xy 101.257822 -279.642842) (xy 101.307436 -279.62337) (xy 101.359398 -279.61151) (xy 101.412548 -279.607527)
			(xy 101.465698 -279.61151) (xy 101.51766 -279.62337) (xy 101.567274 -279.642842) (xy 101.613432 -279.669491)
			(xy 101.655103 -279.702722) (xy 101.691355 -279.741793) (xy 101.721379 -279.78583) (xy 101.744505 -279.833851)
			(xy 101.760215 -279.884781) (xy 101.768158 -279.937485) (xy 101.768656 -279.964134) (xy 101.768158 -279.990783)
			(xy 101.760215 -280.043487) (xy 101.744505 -280.094417) (xy 101.721379 -280.142438) (xy 101.691355 -280.186475)
			(xy 101.655103 -280.225546) (xy 101.613432 -280.258777) (xy 101.567274 -280.285426) (xy 101.51766 -280.304898)
			(xy 101.465698 -280.316758) (xy 101.412548 -280.320742) (xy 101.359398 -280.316758) (xy 101.307436 -280.304898)
			(xy 101.257822 -280.285426) (xy 101.211664 -280.258777) (xy 101.169993 -280.225546) (xy 101.133741 -280.186475)
			(xy 101.103717 -280.142438) (xy 101.080591 -280.094417) (xy 101.064881 -280.043487) (xy 101.056938 -279.990783)
			(xy 100.828358 -279.990783) (xy 100.820415 -280.043487) (xy 100.804705 -280.094417) (xy 100.781579 -280.142438)
			(xy 100.751555 -280.186475) (xy 100.715303 -280.225546) (xy 100.673632 -280.258777) (xy 100.627474 -280.285426)
			(xy 100.57786 -280.304898) (xy 100.525898 -280.316758) (xy 100.472748 -280.320742) (xy 100.419598 -280.316758)
			(xy 100.367636 -280.304898) (xy 100.318022 -280.285426) (xy 100.271864 -280.258777) (xy 100.230193 -280.225546)
			(xy 100.193941 -280.186475) (xy 100.163917 -280.142438) (xy 100.140791 -280.094417) (xy 100.125081 -280.043487)
			(xy 100.117138 -279.990783) (xy 98.948758 -279.990783) (xy 98.940815 -280.043487) (xy 98.925105 -280.094417)
			(xy 98.901979 -280.142438) (xy 98.871955 -280.186475) (xy 98.835703 -280.225546) (xy 98.794032 -280.258777)
			(xy 98.747874 -280.285426) (xy 98.69826 -280.304898) (xy 98.646298 -280.316758) (xy 98.593148 -280.320742)
			(xy 98.539998 -280.316758) (xy 98.488036 -280.304898) (xy 98.438422 -280.285426) (xy 98.392264 -280.258777)
			(xy 98.350593 -280.225546) (xy 98.314341 -280.186475) (xy 98.284317 -280.142438) (xy 98.261191 -280.094417)
			(xy 98.245481 -280.043487) (xy 98.237538 -279.990783) (xy 98.008958 -279.990783) (xy 98.001015 -280.043487)
			(xy 97.985305 -280.094417) (xy 97.962179 -280.142438) (xy 97.932155 -280.186475) (xy 97.895903 -280.225546)
			(xy 97.854232 -280.258777) (xy 97.808074 -280.285426) (xy 97.75846 -280.304898) (xy 97.706498 -280.316758)
			(xy 97.653348 -280.320742) (xy 97.600198 -280.316758) (xy 97.548236 -280.304898) (xy 97.498622 -280.285426)
			(xy 97.452464 -280.258777) (xy 97.410793 -280.225546) (xy 97.374541 -280.186475) (xy 97.344517 -280.142438)
			(xy 97.321391 -280.094417) (xy 97.305681 -280.043487) (xy 97.297738 -279.990783) (xy 97.068866 -279.990783)
			(xy 97.063283 -280.033609) (xy 97.051282 -280.078613) (xy 97.042732 -280.100278) (xy 97.03308 -280.123392)
			(xy 97.205546 -280.421842) (xy 97.230184 -280.425144) (xy 97.255513 -280.429049) (xy 97.304814 -280.443031)
			(xy 97.351603 -280.463934) (xy 97.394914 -280.491325) (xy 97.433852 -280.524641) (xy 97.467614 -280.563193)
			(xy 97.495503 -280.606185) (xy 97.516944 -280.65273) (xy 97.531493 -280.701867) (xy 97.53885 -280.752581)
			(xy 97.539302 -280.778204) (xy 97.538804 -280.804853) (xy 97.530861 -280.857557) (xy 97.515151 -280.908487)
			(xy 97.492025 -280.956508) (xy 97.462001 -281.000545) (xy 97.425749 -281.039616) (xy 97.384078 -281.072847)
			(xy 97.33792 -281.099496) (xy 97.288306 -281.118968) (xy 97.236344 -281.130828) (xy 97.183194 -281.134812)
			(xy 97.130044 -281.130828) (xy 97.078082 -281.118968) (xy 97.028468 -281.099496) (xy 96.98231 -281.072847)
			(xy 96.940639 -281.039616) (xy 96.904387 -281.000545) (xy 96.874363 -280.956508) (xy 96.851237 -280.908487)
			(xy 96.835527 -280.857557) (xy 96.827584 -280.804853) (xy 96.827086 -280.778204) (xy 96.827457 -280.754959)
			(xy 96.833503 -280.708863) (xy 96.845493 -280.663946) (xy 96.85401 -280.642314) (xy 96.863662 -280.6192)
			(xy 96.690942 -280.320496) (xy 96.666304 -280.317194) (xy 96.640977 -280.313345) (xy 96.591703 -280.299328)
			(xy 96.544946 -280.278397) (xy 96.501668 -280.250986) (xy 96.462763 -280.217658) (xy 96.429033 -280.179101)
			(xy 96.401173 -280.136111) (xy 96.379758 -280.089573) (xy 96.365229 -280.040448) (xy 96.357887 -279.989748)
			(xy 96.35744 -279.964134) (xy 96.129856 -279.964134) (xy 96.129358 -279.990783) (xy 96.121415 -280.043487)
			(xy 96.105705 -280.094417) (xy 96.082579 -280.142438) (xy 96.052555 -280.186475) (xy 96.016303 -280.225546)
			(xy 95.974632 -280.258777) (xy 95.928474 -280.285426) (xy 95.87886 -280.304898) (xy 95.826898 -280.316758)
			(xy 95.773748 -280.320742) (xy 95.720598 -280.316758) (xy 95.668636 -280.304898) (xy 95.619022 -280.285426)
			(xy 95.572864 -280.258777) (xy 95.531193 -280.225546) (xy 95.494941 -280.186475) (xy 95.464917 -280.142438)
			(xy 95.441791 -280.094417) (xy 95.426081 -280.043487) (xy 95.418138 -279.990783) (xy 95.189304 -279.990783)
			(xy 95.181361 -280.043487) (xy 95.165651 -280.094417) (xy 95.142525 -280.142438) (xy 95.112501 -280.186475)
			(xy 95.076249 -280.225546) (xy 95.034578 -280.258777) (xy 94.98842 -280.285426) (xy 94.938806 -280.304898)
			(xy 94.886844 -280.316758) (xy 94.833694 -280.320742) (xy 94.780544 -280.316758) (xy 94.728582 -280.304898)
			(xy 94.678968 -280.285426) (xy 94.63281 -280.258777) (xy 94.591139 -280.225546) (xy 94.554887 -280.186475)
			(xy 94.524863 -280.142438) (xy 94.501737 -280.094417) (xy 94.486027 -280.043487) (xy 94.478084 -279.990783)
			(xy 93.309958 -279.990783) (xy 93.302015 -280.043487) (xy 93.286305 -280.094417) (xy 93.263179 -280.142438)
			(xy 93.233155 -280.186475) (xy 93.196903 -280.225546) (xy 93.155232 -280.258777) (xy 93.109074 -280.285426)
			(xy 93.05946 -280.304898) (xy 93.007498 -280.316758) (xy 92.954348 -280.320742) (xy 92.901198 -280.316758)
			(xy 92.849236 -280.304898) (xy 92.799622 -280.285426) (xy 92.753464 -280.258777) (xy 92.711793 -280.225546)
			(xy 92.675541 -280.186475) (xy 92.645517 -280.142438) (xy 92.622391 -280.094417) (xy 92.606681 -280.043487)
			(xy 92.598738 -279.990783) (xy 92.370158 -279.990783) (xy 92.362215 -280.043487) (xy 92.346505 -280.094417)
			(xy 92.323379 -280.142438) (xy 92.293355 -280.186475) (xy 92.257103 -280.225546) (xy 92.215432 -280.258777)
			(xy 92.169274 -280.285426) (xy 92.11966 -280.304898) (xy 92.067698 -280.316758) (xy 92.014548 -280.320742)
			(xy 91.961398 -280.316758) (xy 91.909436 -280.304898) (xy 91.859822 -280.285426) (xy 91.813664 -280.258777)
			(xy 91.771993 -280.225546) (xy 91.735741 -280.186475) (xy 91.705717 -280.142438) (xy 91.682591 -280.094417)
			(xy 91.666881 -280.043487) (xy 91.658938 -279.990783) (xy 90.489366 -279.990783) (xy 90.487382 -280.017259)
			(xy 90.47552 -280.06923) (xy 90.456044 -280.118853) (xy 90.42939 -280.165019) (xy 90.396153 -280.206697)
			(xy 90.357075 -280.242955) (xy 90.31303 -280.272984) (xy 90.265 -280.296113) (xy 90.214061 -280.311825)
			(xy 90.161348 -280.319769) (xy 90.134694 -280.320242) (xy 90.109669 -280.319809) (xy 90.060113 -280.3128)
			(xy 90.012026 -280.298923) (xy 89.966356 -280.278449) (xy 89.924002 -280.251783) (xy 89.885799 -280.21945)
			(xy 89.852499 -280.182086) (xy 89.838276 -280.161492) (xy 89.491312 -280.161492) (xy 89.477103 -280.182097)
			(xy 89.443801 -280.219461) (xy 89.405596 -280.251795) (xy 89.36324 -280.278461) (xy 89.317567 -280.298935)
			(xy 89.269478 -280.312811) (xy 89.21992 -280.319818) (xy 89.194894 -280.320242) (xy 89.168248 -280.319676)
			(xy 89.11555 -280.311732) (xy 89.064625 -280.296023) (xy 89.01661 -280.272899) (xy 88.972578 -280.242878)
			(xy 88.933512 -280.206629) (xy 88.900284 -280.164963) (xy 88.873638 -280.11881) (xy 88.854168 -280.069201)
			(xy 88.84231 -280.017244) (xy 88.838327 -279.9641) (xy 88.611201 -279.9641) (xy 88.611202 -279.964134)
			(xy 88.610704 -279.990783) (xy 88.602761 -280.043487) (xy 88.587051 -280.094417) (xy 88.563925 -280.142438)
			(xy 88.533901 -280.186475) (xy 88.497649 -280.225546) (xy 88.455978 -280.258777) (xy 88.40982 -280.285426)
			(xy 88.360206 -280.304898) (xy 88.308244 -280.316758) (xy 88.255094 -280.320742) (xy 88.201944 -280.316758)
			(xy 88.149982 -280.304898) (xy 88.100368 -280.285426) (xy 88.05421 -280.258777) (xy 88.012539 -280.225546)
			(xy 87.976287 -280.186475) (xy 87.946263 -280.142438) (xy 87.923137 -280.094417) (xy 87.907427 -280.043487)
			(xy 87.899484 -279.990783) (xy 87.670904 -279.990783) (xy 87.662961 -280.043487) (xy 87.647251 -280.094417)
			(xy 87.624125 -280.142438) (xy 87.594101 -280.186475) (xy 87.557849 -280.225546) (xy 87.516178 -280.258777)
			(xy 87.47002 -280.285426) (xy 87.420406 -280.304898) (xy 87.368444 -280.316758) (xy 87.315294 -280.320742)
			(xy 87.262144 -280.316758) (xy 87.210182 -280.304898) (xy 87.160568 -280.285426) (xy 87.11441 -280.258777)
			(xy 87.072739 -280.225546) (xy 87.036487 -280.186475) (xy 87.006463 -280.142438) (xy 86.983337 -280.094417)
			(xy 86.967627 -280.043487) (xy 86.959684 -279.990783) (xy 86.731104 -279.990783) (xy 86.723161 -280.043487)
			(xy 86.707451 -280.094417) (xy 86.684325 -280.142438) (xy 86.654301 -280.186475) (xy 86.618049 -280.225546)
			(xy 86.576378 -280.258777) (xy 86.53022 -280.285426) (xy 86.480606 -280.304898) (xy 86.428644 -280.316758)
			(xy 86.375494 -280.320742) (xy 86.322344 -280.316758) (xy 86.270382 -280.304898) (xy 86.220768 -280.285426)
			(xy 86.17461 -280.258777) (xy 86.132939 -280.225546) (xy 86.096687 -280.186475) (xy 86.066663 -280.142438)
			(xy 86.043537 -280.094417) (xy 86.027827 -280.043487) (xy 86.019884 -279.990783) (xy 85.52688 -279.990783)
			(xy 85.52688 -280.42997) (xy 85.527355 -280.444243) (xy 85.535247 -280.471677) (xy 85.550422 -280.495855)
			(xy 85.571695 -280.51489) (xy 85.597406 -280.527295) (xy 85.625544 -280.5321) (xy 85.653914 -280.52893)
			(xy 85.680299 -280.518034) (xy 85.691726 -280.509472) (xy 85.714695 -280.491965) (xy 85.765267 -280.464083)
			(xy 85.819786 -280.445042) (xy 85.87672 -280.435376) (xy 85.905594 -280.434796) (xy 85.931295 -280.435252)
			(xy 85.982122 -280.442912) (xy 86.03124 -280.458062) (xy 86.077551 -280.480364) (xy 86.120021 -280.509319)
			(xy 86.157702 -280.54428) (xy 86.18975 -280.584467) (xy 86.215451 -280.628982) (xy 86.23423 -280.67683)
			(xy 86.245668 -280.726942) (xy 86.24951 -280.7782) (xy 86.488796 -280.7782) (xy 86.492779 -280.725052)
			(xy 86.504639 -280.67309) (xy 86.524111 -280.623477) (xy 86.550759 -280.57732) (xy 86.583989 -280.53565)
			(xy 86.623059 -280.499398) (xy 86.667095 -280.469374) (xy 86.715114 -280.446249) (xy 86.766043 -280.430538)
			(xy 86.818745 -280.422594) (xy 86.845394 -280.422096) (xy 86.870407 -280.422545) (xy 86.919944 -280.429528)
			(xy 86.968016 -280.443373) (xy 87.013679 -280.463807) (xy 87.056035 -280.490427) (xy 87.094249 -280.522711)
			(xy 87.127572 -280.560023) (xy 87.141812 -280.580592) (xy 87.488776 -280.580592) (xy 87.502997 -280.56001)
			(xy 87.536329 -280.522703) (xy 87.574549 -280.490422) (xy 87.616907 -280.463802) (xy 87.662571 -280.443366)
			(xy 87.710643 -280.429514) (xy 87.76018 -280.422518) (xy 87.785194 -280.422096) (xy 87.811846 -280.422561)
			(xy 87.864554 -280.430504) (xy 87.915489 -280.446215) (xy 87.963515 -280.469342) (xy 88.007556 -280.499369)
			(xy 88.046631 -280.535624) (xy 88.079865 -280.577298) (xy 88.106517 -280.62346) (xy 88.125991 -280.673079)
			(xy 88.137853 -280.725046) (xy 88.141836 -280.7782) (xy 88.137853 -280.831354) (xy 88.125991 -280.883321)
			(xy 88.106517 -280.93294) (xy 88.079865 -280.979102) (xy 88.046631 -281.020776) (xy 88.007556 -281.057031)
			(xy 87.963515 -281.087058) (xy 87.915489 -281.110185) (xy 87.864554 -281.125896) (xy 87.811846 -281.133839)
			(xy 87.785194 -281.134312) (xy 87.760181 -281.133869) (xy 87.710644 -281.126884) (xy 87.662572 -281.113038)
			(xy 87.616909 -281.092603) (xy 87.574553 -281.065982) (xy 87.536339 -281.033698) (xy 87.503016 -280.996385)
			(xy 87.488776 -280.975816) (xy 87.141812 -280.975816) (xy 87.127601 -280.996405) (xy 87.094267 -281.033712)
			(xy 87.056045 -281.065992) (xy 87.013685 -281.092611) (xy 86.96802 -281.113046) (xy 86.919947 -281.126897)
			(xy 86.870409 -281.13389) (xy 86.845394 -281.134312) (xy 86.818745 -281.133806) (xy 86.766043 -281.125862)
			(xy 86.715114 -281.110151) (xy 86.667095 -281.087026) (xy 86.623059 -281.057002) (xy 86.583989 -281.02075)
			(xy 86.550759 -280.97908) (xy 86.524111 -280.932923) (xy 86.504639 -280.88331) (xy 86.492779 -280.831348)
			(xy 86.488796 -280.7782) (xy 86.24951 -280.7782) (xy 86.245668 -280.829458) (xy 86.23423 -280.87957)
			(xy 86.215451 -280.927418) (xy 86.18975 -280.971933) (xy 86.157702 -281.01212) (xy 86.120021 -281.047081)
			(xy 86.077551 -281.076036) (xy 86.03124 -281.098338) (xy 85.982122 -281.113488) (xy 85.931295 -281.121148)
			(xy 85.905594 -281.121612) (xy 85.87672 -281.121019) (xy 85.819787 -281.111362) (xy 85.765269 -281.092321)
			(xy 85.714703 -281.064432) (xy 85.691726 -281.046936) (xy 85.680266 -281.03843) (xy 85.653899 -281.02754)
			(xy 85.625547 -281.024372) (xy 85.597427 -281.029174) (xy 85.571734 -281.041571) (xy 85.550475 -281.060594)
			(xy 85.535311 -281.084758) (xy 85.527426 -281.112174) (xy 85.52688 -281.126438) (xy 85.52688 -281.618669)
			(xy 86.019884 -281.618669) (xy 86.019884 -281.565371) (xy 86.027827 -281.512667) (xy 86.043537 -281.461737)
			(xy 86.066663 -281.413716) (xy 86.096687 -281.369679) (xy 86.132939 -281.330608) (xy 86.17461 -281.297377)
			(xy 86.220768 -281.270728) (xy 86.270382 -281.251256) (xy 86.322344 -281.239396) (xy 86.375494 -281.235413)
			(xy 86.428644 -281.239396) (xy 86.480606 -281.251256) (xy 86.53022 -281.270728) (xy 86.576378 -281.297377)
			(xy 86.618049 -281.330608) (xy 86.654301 -281.369679) (xy 86.684325 -281.413716) (xy 86.707451 -281.461737)
			(xy 86.723161 -281.512667) (xy 86.731104 -281.565371) (xy 86.731602 -281.59202) (xy 86.731104 -281.618669)
			(xy 86.723161 -281.671373) (xy 86.707451 -281.722303) (xy 86.684325 -281.770324) (xy 86.654301 -281.814361)
			(xy 86.618049 -281.853432) (xy 86.576378 -281.886663) (xy 86.53022 -281.913312) (xy 86.480606 -281.932784)
			(xy 86.428644 -281.944644) (xy 86.375494 -281.948628) (xy 86.322344 -281.944644) (xy 86.270382 -281.932784)
			(xy 86.220768 -281.913312) (xy 86.17461 -281.886663) (xy 86.132939 -281.853432) (xy 86.096687 -281.814361)
			(xy 86.066663 -281.770324) (xy 86.043537 -281.722303) (xy 86.027827 -281.671373) (xy 86.019884 -281.618669)
			(xy 85.52688 -281.618669) (xy 85.52688 -282.0416) (xy 85.527328 -282.055736) (xy 85.535058 -282.082929)
			(xy 85.549952 -282.106957) (xy 85.570867 -282.125977) (xy 85.596199 -282.138528) (xy 85.624002 -282.143647)
			(xy 85.652142 -282.140942) (xy 85.67846 -282.130619) (xy 85.689948 -282.122372) (xy 85.713352 -282.105289)
			(xy 85.764541 -282.078146) (xy 85.819447 -282.059642) (xy 85.876624 -282.050266) (xy 85.905594 -282.049728)
			(xy 85.932243 -282.050201) (xy 85.984945 -282.058143) (xy 86.035875 -282.073852) (xy 86.083895 -282.096977)
			(xy 86.127931 -282.127) (xy 86.167001 -282.163251) (xy 86.200232 -282.20492) (xy 86.226881 -282.251077)
			(xy 86.246353 -282.30069) (xy 86.258213 -282.352652) (xy 86.262196 -282.4058) (xy 86.262193 -282.405836)
			(xy 86.48954 -282.405836) (xy 86.490004 -282.380208) (xy 86.497335 -282.32948) (xy 86.511864 -282.280327)
			(xy 86.533292 -282.233765) (xy 86.561175 -282.190758) (xy 86.594936 -282.152193) (xy 86.63388 -282.118868)
			(xy 86.677199 -282.091472) (xy 86.723999 -282.070571) (xy 86.773313 -282.056597) (xy 86.798658 -282.052776)
			(xy 86.823296 -282.049474) (xy 86.995762 -281.75077) (xy 86.986364 -281.727656) (xy 86.977868 -281.706062)
			(xy 86.965893 -281.661229) (xy 86.959833 -281.615222) (xy 86.95944 -281.59202) (xy 86.959938 -281.565371)
			(xy 86.967881 -281.512667) (xy 86.983591 -281.461737) (xy 87.006717 -281.413716) (xy 87.036741 -281.369679)
			(xy 87.072993 -281.330608) (xy 87.114664 -281.297377) (xy 87.160822 -281.270728) (xy 87.210436 -281.251256)
			(xy 87.262398 -281.239396) (xy 87.315548 -281.235413) (xy 87.368698 -281.239396) (xy 87.42066 -281.251256)
			(xy 87.470274 -281.270728) (xy 87.516432 -281.297377) (xy 87.558103 -281.330608) (xy 87.594355 -281.369679)
			(xy 87.624379 -281.413716) (xy 87.647505 -281.461737) (xy 87.663215 -281.512667) (xy 87.671158 -281.565371)
			(xy 87.671656 -281.59202) (xy 87.671247 -281.617649) (xy 87.671099 -281.618669) (xy 87.899484 -281.618669)
			(xy 87.899484 -281.565371) (xy 87.907427 -281.512667) (xy 87.923137 -281.461737) (xy 87.946263 -281.413716)
			(xy 87.976287 -281.369679) (xy 88.012539 -281.330608) (xy 88.05421 -281.297377) (xy 88.100368 -281.270728)
			(xy 88.149982 -281.251256) (xy 88.201944 -281.239396) (xy 88.255094 -281.235413) (xy 88.308244 -281.239396)
			(xy 88.360206 -281.251256) (xy 88.40982 -281.270728) (xy 88.455978 -281.297377) (xy 88.497649 -281.330608)
			(xy 88.533901 -281.369679) (xy 88.563925 -281.413716) (xy 88.587051 -281.461737) (xy 88.602761 -281.512667)
			(xy 88.610704 -281.565371) (xy 88.611202 -281.59202) (xy 88.83904 -281.59202) (xy 88.83949 -281.566392)
			(xy 88.846822 -281.515663) (xy 88.861354 -281.466509) (xy 88.882783 -281.419948) (xy 88.910668 -281.37694)
			(xy 88.944431 -281.338376) (xy 88.983376 -281.305051) (xy 89.026696 -281.277655) (xy 89.073498 -281.256755)
			(xy 89.122812 -281.242781) (xy 89.148158 -281.23896) (xy 89.17305 -281.235658) (xy 89.345262 -280.937462)
			(xy 89.33561 -280.914348) (xy 89.327087 -280.892674) (xy 89.315089 -280.847672) (xy 89.309051 -280.801491)
			(xy 89.308686 -280.778204) (xy 89.309184 -280.751555) (xy 89.317127 -280.698851) (xy 89.332837 -280.647921)
			(xy 89.355963 -280.5999) (xy 89.385987 -280.555863) (xy 89.422239 -280.516792) (xy 89.46391 -280.483561)
			(xy 89.510068 -280.456912) (xy 89.559682 -280.43744) (xy 89.611644 -280.42558) (xy 89.664794 -280.421597)
			(xy 89.717944 -280.42558) (xy 89.769906 -280.43744) (xy 89.81952 -280.456912) (xy 89.865678 -280.483561)
			(xy 89.907349 -280.516792) (xy 89.943601 -280.555863) (xy 89.973625 -280.5999) (xy 89.996751 -280.647921)
			(xy 90.012461 -280.698851) (xy 90.020404 -280.751555) (xy 90.020902 -280.778204) (xy 90.020467 -280.803822)
			(xy 90.020318 -280.804853) (xy 90.248984 -280.804853) (xy 90.248984 -280.751555) (xy 90.256927 -280.698851)
			(xy 90.272637 -280.647921) (xy 90.295763 -280.5999) (xy 90.325787 -280.555863) (xy 90.362039 -280.516792)
			(xy 90.40371 -280.483561) (xy 90.449868 -280.456912) (xy 90.499482 -280.43744) (xy 90.551444 -280.42558)
			(xy 90.604594 -280.421597) (xy 90.657744 -280.42558) (xy 90.709706 -280.43744) (xy 90.75932 -280.456912)
			(xy 90.805478 -280.483561) (xy 90.847149 -280.516792) (xy 90.883401 -280.555863) (xy 90.913425 -280.5999)
			(xy 90.936551 -280.647921) (xy 90.952261 -280.698851) (xy 90.960204 -280.751555) (xy 90.960702 -280.778204)
			(xy 92.12834 -280.778204) (xy 92.128838 -280.751555) (xy 92.136781 -280.698851) (xy 92.152491 -280.647921)
			(xy 92.175617 -280.5999) (xy 92.205641 -280.555863) (xy 92.241893 -280.516792) (xy 92.283564 -280.483561)
			(xy 92.329722 -280.456912) (xy 92.379336 -280.43744) (xy 92.431298 -280.42558) (xy 92.484448 -280.421597)
			(xy 92.537598 -280.42558) (xy 92.58956 -280.43744) (xy 92.639174 -280.456912) (xy 92.685332 -280.483561)
			(xy 92.727003 -280.516792) (xy 92.763255 -280.555863) (xy 92.793279 -280.5999) (xy 92.816405 -280.647921)
			(xy 92.832115 -280.698851) (xy 92.840058 -280.751555) (xy 92.840556 -280.778204) (xy 92.840226 -280.801494)
			(xy 92.839787 -280.804853) (xy 94.008438 -280.804853) (xy 94.008438 -280.751555) (xy 94.016381 -280.698851)
			(xy 94.032091 -280.647921) (xy 94.055217 -280.5999) (xy 94.085241 -280.555863) (xy 94.121493 -280.516792)
			(xy 94.163164 -280.483561) (xy 94.209322 -280.456912) (xy 94.258936 -280.43744) (xy 94.310898 -280.42558)
			(xy 94.364048 -280.421597) (xy 94.417198 -280.42558) (xy 94.46916 -280.43744) (xy 94.518774 -280.456912)
			(xy 94.564932 -280.483561) (xy 94.606603 -280.516792) (xy 94.642855 -280.555863) (xy 94.672879 -280.5999)
			(xy 94.696005 -280.647921) (xy 94.711715 -280.698851) (xy 94.719658 -280.751555) (xy 94.720156 -280.7782)
			(xy 94.946996 -280.7782) (xy 94.950979 -280.725052) (xy 94.962839 -280.67309) (xy 94.982311 -280.623477)
			(xy 95.008959 -280.57732) (xy 95.042189 -280.53565) (xy 95.081259 -280.499398) (xy 95.125295 -280.469374)
			(xy 95.173314 -280.446249) (xy 95.224243 -280.430538) (xy 95.276945 -280.422594) (xy 95.303594 -280.422096)
			(xy 95.328607 -280.422545) (xy 95.378144 -280.429528) (xy 95.426216 -280.443373) (xy 95.471879 -280.463807)
			(xy 95.514235 -280.490427) (xy 95.552449 -280.522711) (xy 95.585772 -280.560023) (xy 95.600012 -280.580592)
			(xy 95.94723 -280.580592) (xy 95.961481 -280.560031) (xy 95.994807 -280.522724) (xy 96.033023 -280.490442)
			(xy 96.075376 -280.463819) (xy 96.121034 -280.443379) (xy 96.169102 -280.429522) (xy 96.218635 -280.422522)
			(xy 96.243648 -280.422096) (xy 96.270295 -280.422589) (xy 96.322994 -280.430539) (xy 96.373919 -280.446253)
			(xy 96.421934 -280.469381) (xy 96.465965 -280.499407) (xy 96.50503 -280.535659) (xy 96.538257 -280.577329)
			(xy 96.564902 -280.623484) (xy 96.584371 -280.673096) (xy 96.596229 -280.725054) (xy 96.600212 -280.7782)
			(xy 96.596229 -280.831346) (xy 96.584371 -280.883304) (xy 96.564902 -280.932916) (xy 96.538257 -280.979071)
			(xy 96.50503 -281.020741) (xy 96.465965 -281.056993) (xy 96.421934 -281.087019) (xy 96.373919 -281.110147)
			(xy 96.322994 -281.125861) (xy 96.270295 -281.133811) (xy 96.243648 -281.134312) (xy 96.218633 -281.133904)
			(xy 96.169095 -281.126912) (xy 96.121022 -281.11306) (xy 96.075359 -281.09262) (xy 96.033004 -281.065994)
			(xy 95.99479 -281.033704) (xy 95.961469 -280.996387) (xy 95.94723 -280.975816) (xy 95.600012 -280.975816)
			(xy 95.585801 -280.996405) (xy 95.552467 -281.033712) (xy 95.514245 -281.065992) (xy 95.471885 -281.092611)
			(xy 95.42622 -281.113046) (xy 95.378147 -281.126897) (xy 95.328609 -281.13389) (xy 95.303594 -281.134312)
			(xy 95.276945 -281.133806) (xy 95.224243 -281.125862) (xy 95.173314 -281.110151) (xy 95.125295 -281.087026)
			(xy 95.081259 -281.057002) (xy 95.042189 -281.02075) (xy 95.008959 -280.97908) (xy 94.982311 -280.932923)
			(xy 94.962839 -280.88331) (xy 94.950979 -280.831348) (xy 94.946996 -280.7782) (xy 94.720156 -280.7782)
			(xy 94.720156 -280.778204) (xy 94.719658 -280.804853) (xy 94.711715 -280.857557) (xy 94.696005 -280.908487)
			(xy 94.672879 -280.956508) (xy 94.642855 -281.000545) (xy 94.606603 -281.039616) (xy 94.564932 -281.072847)
			(xy 94.518774 -281.099496) (xy 94.46916 -281.118968) (xy 94.417198 -281.130828) (xy 94.364048 -281.134812)
			(xy 94.310898 -281.130828) (xy 94.258936 -281.118968) (xy 94.209322 -281.099496) (xy 94.163164 -281.072847)
			(xy 94.121493 -281.039616) (xy 94.085241 -281.000545) (xy 94.055217 -280.956508) (xy 94.032091 -280.908487)
			(xy 94.016381 -280.857557) (xy 94.008438 -280.804853) (xy 92.839787 -280.804853) (xy 92.834196 -280.84768)
			(xy 92.822186 -280.892684) (xy 92.813632 -280.914348) (xy 92.80398 -280.937462) (xy 92.976192 -281.235658)
			(xy 93.001084 -281.23896) (xy 93.026416 -281.24285) (xy 93.075718 -281.256833) (xy 93.122508 -281.277736)
			(xy 93.165819 -281.305129) (xy 93.204758 -281.338447) (xy 93.23852 -281.377) (xy 93.266409 -281.419994)
			(xy 93.287848 -281.466541) (xy 93.302396 -281.51568) (xy 93.309751 -281.566397) (xy 93.310202 -281.59202)
			(xy 93.309704 -281.618669) (xy 93.301761 -281.671373) (xy 93.286051 -281.722303) (xy 93.262925 -281.770324)
			(xy 93.232901 -281.814361) (xy 93.196649 -281.853432) (xy 93.154978 -281.886663) (xy 93.10882 -281.913312)
			(xy 93.059206 -281.932784) (xy 93.007244 -281.944644) (xy 92.954094 -281.948628) (xy 92.900944 -281.944644)
			(xy 92.848982 -281.932784) (xy 92.799368 -281.913312) (xy 92.75321 -281.886663) (xy 92.711539 -281.853432)
			(xy 92.675287 -281.814361) (xy 92.645263 -281.770324) (xy 92.622137 -281.722303) (xy 92.606427 -281.671373)
			(xy 92.598484 -281.618669) (xy 92.597986 -281.59202) (xy 92.598374 -281.568817) (xy 92.604421 -281.522807)
			(xy 92.616402 -281.477974) (xy 92.62491 -281.456384) (xy 92.634308 -281.43327) (xy 92.461842 -281.134566)
			(xy 92.437204 -281.131264) (xy 92.411889 -281.127348) (xy 92.362621 -281.113334) (xy 92.315867 -281.092409)
			(xy 92.272593 -281.065004) (xy 92.233689 -281.031684) (xy 92.199958 -280.993135) (xy 92.172096 -280.950153)
			(xy 92.150677 -280.903624) (xy 92.136142 -280.854507) (xy 92.128792 -280.803815) (xy 92.12834 -280.778204)
			(xy 90.960702 -280.778204) (xy 90.960204 -280.804853) (xy 90.952261 -280.857557) (xy 90.936551 -280.908487)
			(xy 90.913425 -280.956508) (xy 90.883401 -281.000545) (xy 90.847149 -281.039616) (xy 90.805478 -281.072847)
			(xy 90.75932 -281.099496) (xy 90.709706 -281.118968) (xy 90.657744 -281.130828) (xy 90.604594 -281.134812)
			(xy 90.551444 -281.130828) (xy 90.499482 -281.118968) (xy 90.449868 -281.099496) (xy 90.40371 -281.072847)
			(xy 90.362039 -281.039616) (xy 90.325787 -281.000545) (xy 90.295763 -280.956508) (xy 90.272637 -280.908487)
			(xy 90.256927 -280.857557) (xy 90.248984 -280.804853) (xy 90.020318 -280.804853) (xy 90.01315 -280.854534)
			(xy 89.998638 -280.903672) (xy 89.977232 -280.950222) (xy 89.949374 -280.993223) (xy 89.915638 -281.031786)
			(xy 89.876723 -281.065114) (xy 89.833432 -281.092519) (xy 89.78666 -281.113435) (xy 89.737372 -281.12743)
			(xy 89.712038 -281.131264) (xy 89.6874 -281.134566) (xy 89.514934 -281.433016) (xy 89.524332 -281.45613)
			(xy 89.532852 -281.477761) (xy 89.544839 -281.522679) (xy 89.550882 -281.568775) (xy 89.551256 -281.59202)
			(xy 89.550758 -281.618669) (xy 89.779084 -281.618669) (xy 89.779084 -281.565371) (xy 89.787027 -281.512667)
			(xy 89.802737 -281.461737) (xy 89.825863 -281.413716) (xy 89.855887 -281.369679) (xy 89.892139 -281.330608)
			(xy 89.93381 -281.297377) (xy 89.979968 -281.270728) (xy 90.029582 -281.251256) (xy 90.081544 -281.239396)
			(xy 90.134694 -281.235413) (xy 90.187844 -281.239396) (xy 90.239806 -281.251256) (xy 90.28942 -281.270728)
			(xy 90.335578 -281.297377) (xy 90.377249 -281.330608) (xy 90.413501 -281.369679) (xy 90.443525 -281.413716)
			(xy 90.466651 -281.461737) (xy 90.482361 -281.512667) (xy 90.490304 -281.565371) (xy 90.490802 -281.592)
			(xy 90.717913 -281.592) (xy 90.721896 -281.538854) (xy 90.733755 -281.486895) (xy 90.753225 -281.437284)
			(xy 90.779873 -281.391129) (xy 90.813101 -281.349461) (xy 90.852169 -281.313211) (xy 90.896203 -281.283189)
			(xy 90.94422 -281.260064) (xy 90.995147 -281.244355) (xy 91.047847 -281.236411) (xy 91.074494 -281.235912)
			(xy 91.099508 -281.236354) (xy 91.149045 -281.243338) (xy 91.197118 -281.257183) (xy 91.242781 -281.277618)
			(xy 91.285136 -281.304239) (xy 91.323351 -281.336525) (xy 91.356673 -281.373839) (xy 91.370912 -281.394408)
			(xy 91.717876 -281.394408) (xy 91.732102 -281.37383) (xy 91.765433 -281.336522) (xy 91.803652 -281.30424)
			(xy 91.846009 -281.27762) (xy 91.891672 -281.257182) (xy 91.939744 -281.24333) (xy 91.98928 -281.236334)
			(xy 92.014294 -281.235912) (xy 92.040947 -281.236345) (xy 92.093658 -281.244289) (xy 92.144595 -281.26)
			(xy 92.192623 -281.283128) (xy 92.236666 -281.313156) (xy 92.275742 -281.349413) (xy 92.308978 -281.391089)
			(xy 92.335632 -281.437253) (xy 92.355107 -281.486874) (xy 92.366968 -281.538843) (xy 92.370952 -281.592)
			(xy 92.366968 -281.645157) (xy 92.355107 -281.697126) (xy 92.335632 -281.746747) (xy 92.308978 -281.792911)
			(xy 92.275742 -281.834587) (xy 92.236666 -281.870844) (xy 92.192623 -281.900872) (xy 92.144595 -281.924)
			(xy 92.093658 -281.939711) (xy 92.040947 -281.947655) (xy 92.014294 -281.948128) (xy 91.989279 -281.947722)
			(xy 91.939739 -281.940735) (xy 91.891664 -281.926885) (xy 91.846 -281.906446) (xy 91.803645 -281.879818)
			(xy 91.765432 -281.847526) (xy 91.732113 -281.810205) (xy 91.717876 -281.789632) (xy 91.370912 -281.789632)
			(xy 91.356706 -281.810225) (xy 91.323371 -281.847531) (xy 91.285148 -281.87981) (xy 91.242787 -281.906428)
			(xy 91.197121 -281.926863) (xy 91.149047 -281.940713) (xy 91.099509 -281.947706) (xy 91.074494 -281.948128)
			(xy 91.047847 -281.947589) (xy 90.995147 -281.939645) (xy 90.94422 -281.923936) (xy 90.896203 -281.900811)
			(xy 90.852169 -281.870789) (xy 90.813101 -281.834539) (xy 90.779873 -281.792871) (xy 90.753225 -281.746716)
			(xy 90.733755 -281.697105) (xy 90.721896 -281.645146) (xy 90.717913 -281.592) (xy 90.490802 -281.592)
			(xy 90.490802 -281.59202) (xy 90.490304 -281.618669) (xy 90.482361 -281.671373) (xy 90.466651 -281.722303)
			(xy 90.443525 -281.770324) (xy 90.413501 -281.814361) (xy 90.377249 -281.853432) (xy 90.335578 -281.886663)
			(xy 90.28942 -281.913312) (xy 90.239806 -281.932784) (xy 90.187844 -281.944644) (xy 90.134694 -281.948628)
			(xy 90.081544 -281.944644) (xy 90.029582 -281.932784) (xy 89.979968 -281.913312) (xy 89.93381 -281.886663)
			(xy 89.892139 -281.853432) (xy 89.855887 -281.814361) (xy 89.825863 -281.770324) (xy 89.802737 -281.722303)
			(xy 89.787027 -281.671373) (xy 89.779084 -281.618669) (xy 89.550758 -281.618669) (xy 89.542815 -281.671373)
			(xy 89.527105 -281.722303) (xy 89.503979 -281.770324) (xy 89.473955 -281.814361) (xy 89.437703 -281.853432)
			(xy 89.396032 -281.886663) (xy 89.349874 -281.913312) (xy 89.30026 -281.932784) (xy 89.248298 -281.944644)
			(xy 89.195148 -281.948628) (xy 89.141998 -281.944644) (xy 89.090036 -281.932784) (xy 89.040422 -281.913312)
			(xy 88.994264 -281.886663) (xy 88.952593 -281.853432) (xy 88.916341 -281.814361) (xy 88.886317 -281.770324)
			(xy 88.863191 -281.722303) (xy 88.847481 -281.671373) (xy 88.839538 -281.618669) (xy 88.83904 -281.59202)
			(xy 88.611202 -281.59202) (xy 88.610704 -281.618669) (xy 88.602761 -281.671373) (xy 88.587051 -281.722303)
			(xy 88.563925 -281.770324) (xy 88.533901 -281.814361) (xy 88.497649 -281.853432) (xy 88.455978 -281.886663)
			(xy 88.40982 -281.913312) (xy 88.360206 -281.932784) (xy 88.308244 -281.944644) (xy 88.255094 -281.948628)
			(xy 88.201944 -281.944644) (xy 88.149982 -281.932784) (xy 88.100368 -281.913312) (xy 88.05421 -281.886663)
			(xy 88.012539 -281.853432) (xy 87.976287 -281.814361) (xy 87.946263 -281.770324) (xy 87.923137 -281.722303)
			(xy 87.907427 -281.671373) (xy 87.899484 -281.618669) (xy 87.671099 -281.618669) (xy 87.663908 -281.66838)
			(xy 87.649372 -281.717535) (xy 87.627937 -281.764097) (xy 87.600048 -281.807104) (xy 87.56628 -281.845668)
			(xy 87.527331 -281.878992) (xy 87.484007 -281.906387) (xy 87.437203 -281.927287) (xy 87.387885 -281.941259)
			(xy 87.362538 -281.94508) (xy 87.3379 -281.948382) (xy 87.165434 -282.247086) (xy 87.174832 -282.2702)
			(xy 87.183315 -282.291799) (xy 87.195295 -282.336629) (xy 87.20136 -282.382635) (xy 87.201756 -282.405836)
			(xy 87.429086 -282.405836) (xy 87.429584 -282.379187) (xy 87.437527 -282.326483) (xy 87.453237 -282.275553)
			(xy 87.476363 -282.227532) (xy 87.506387 -282.183495) (xy 87.542639 -282.144424) (xy 87.58431 -282.111193)
			(xy 87.630468 -282.084544) (xy 87.680082 -282.065072) (xy 87.732044 -282.053212) (xy 87.785194 -282.049229)
			(xy 87.838344 -282.053212) (xy 87.890306 -282.065072) (xy 87.93992 -282.084544) (xy 87.986078 -282.111193)
			(xy 88.027749 -282.144424) (xy 88.064001 -282.183495) (xy 88.094025 -282.227532) (xy 88.117151 -282.275553)
			(xy 88.132861 -282.326483) (xy 88.140804 -282.379187) (xy 88.141301 -282.4058) (xy 88.368604 -282.4058)
			(xy 88.372588 -282.352648) (xy 88.384449 -282.300683) (xy 88.403924 -282.251066) (xy 88.430577 -282.204907)
			(xy 88.463812 -282.163236) (xy 88.502888 -282.126985) (xy 88.54693 -282.096963) (xy 88.594955 -282.073841)
			(xy 88.64589 -282.058135) (xy 88.698597 -282.050198) (xy 88.725248 -282.049728) (xy 88.750263 -282.050122)
			(xy 88.799803 -282.057113) (xy 88.847877 -282.070967) (xy 88.893541 -282.091409) (xy 88.935896 -282.118038)
			(xy 88.974109 -282.150331) (xy 89.007428 -282.187651) (xy 89.021666 -282.208224) (xy 89.36863 -282.208224)
			(xy 89.382891 -282.18767) (xy 89.416215 -282.150361) (xy 89.454428 -282.118078) (xy 89.496779 -282.091454)
			(xy 89.542436 -282.071012) (xy 89.590503 -282.057155) (xy 89.640036 -282.050154) (xy 89.665048 -282.049728)
			(xy 89.691698 -282.050157) (xy 89.744401 -282.058107) (xy 89.795331 -282.073823) (xy 89.84335 -282.096954)
			(xy 89.887385 -282.126982) (xy 89.926454 -282.163238) (xy 89.959683 -282.204911) (xy 89.986331 -282.251071)
			(xy 90.005802 -282.300686) (xy 90.017661 -282.35265) (xy 90.021644 -282.4058) (xy 90.019644 -282.432485)
			(xy 90.249238 -282.432485) (xy 90.249238 -282.379187) (xy 90.257181 -282.326483) (xy 90.272891 -282.275553)
			(xy 90.296017 -282.227532) (xy 90.326041 -282.183495) (xy 90.362293 -282.144424) (xy 90.403964 -282.111193)
			(xy 90.450122 -282.084544) (xy 90.499736 -282.065072) (xy 90.551698 -282.053212) (xy 90.604848 -282.049229)
			(xy 90.657998 -282.053212) (xy 90.70996 -282.065072) (xy 90.759574 -282.084544) (xy 90.805732 -282.111193)
			(xy 90.847403 -282.144424) (xy 90.883655 -282.183495) (xy 90.913679 -282.227532) (xy 90.936805 -282.275553)
			(xy 90.952515 -282.326483) (xy 90.960458 -282.379187) (xy 90.960956 -282.405836) (xy 90.960458 -282.432485)
			(xy 90.952515 -282.485189) (xy 90.936805 -282.536119) (xy 90.913679 -282.58414) (xy 90.883655 -282.628177)
			(xy 90.847403 -282.667248) (xy 90.805732 -282.700479) (xy 90.759574 -282.727128) (xy 90.70996 -282.7466)
			(xy 90.657998 -282.75846) (xy 90.604848 -282.762444) (xy 90.551698 -282.75846) (xy 90.499736 -282.7466)
			(xy 90.450122 -282.727128) (xy 90.403964 -282.700479) (xy 90.362293 -282.667248) (xy 90.326041 -282.628177)
			(xy 90.296017 -282.58414) (xy 90.272891 -282.536119) (xy 90.257181 -282.485189) (xy 90.249238 -282.432485)
			(xy 90.019644 -282.432485) (xy 90.017661 -282.45895) (xy 90.005802 -282.510914) (xy 89.986331 -282.560529)
			(xy 89.959683 -282.606689) (xy 89.926454 -282.648362) (xy 89.887385 -282.684618) (xy 89.84335 -282.714646)
			(xy 89.795331 -282.737777) (xy 89.744401 -282.753493) (xy 89.691698 -282.761443) (xy 89.665048 -282.761944)
			(xy 89.640032 -282.761566) (xy 89.590491 -282.754573) (xy 89.542416 -282.740718) (xy 89.496752 -282.720274)
			(xy 89.454397 -282.693642) (xy 89.416185 -282.661346) (xy 89.382867 -282.624022) (xy 89.36863 -282.603448)
			(xy 89.021666 -282.603448) (xy 89.007399 -282.623997) (xy 88.974077 -282.661307) (xy 88.935865 -282.693592)
			(xy 88.893515 -282.720217) (xy 88.847858 -282.740659) (xy 88.799792 -282.754517) (xy 88.75026 -282.761518)
			(xy 88.725248 -282.761944) (xy 88.698597 -282.761402) (xy 88.64589 -282.753465) (xy 88.594955 -282.737759)
			(xy 88.54693 -282.714637) (xy 88.502887 -282.684615) (xy 88.463812 -282.648364) (xy 88.430577 -282.606693)
			(xy 88.403924 -282.560534) (xy 88.384449 -282.510917) (xy 88.372588 -282.458952) (xy 88.368604 -282.4058)
			(xy 88.141301 -282.4058) (xy 88.141302 -282.405836) (xy 88.140912 -282.42908) (xy 88.134874 -282.475175)
			(xy 88.122892 -282.520094) (xy 88.114378 -282.541726) (xy 88.104726 -282.56484) (xy 88.277446 -282.863544)
			(xy 88.302084 -282.866846) (xy 88.327413 -282.87075) (xy 88.376715 -282.884731) (xy 88.423504 -282.905634)
			(xy 88.466815 -282.933026) (xy 88.505753 -282.966342) (xy 88.539515 -283.004894) (xy 88.567404 -283.047886)
			(xy 88.588844 -283.094431) (xy 88.603393 -283.143568) (xy 88.61075 -283.194283) (xy 88.611202 -283.219906)
			(xy 88.610704 -283.246555) (xy 88.839284 -283.246555) (xy 88.839284 -283.193257) (xy 88.847227 -283.140553)
			(xy 88.862937 -283.089623) (xy 88.886063 -283.041602) (xy 88.916087 -282.997565) (xy 88.952339 -282.958494)
			(xy 88.99401 -282.925263) (xy 89.040168 -282.898614) (xy 89.089782 -282.879142) (xy 89.141744 -282.867282)
			(xy 89.194894 -282.863299) (xy 89.248044 -282.867282) (xy 89.300006 -282.879142) (xy 89.34962 -282.898614)
			(xy 89.395778 -282.925263) (xy 89.437449 -282.958494) (xy 89.473701 -282.997565) (xy 89.503725 -283.041602)
			(xy 89.526851 -283.089623) (xy 89.542561 -283.140553) (xy 89.550504 -283.193257) (xy 89.551002 -283.219906)
			(xy 89.550504 -283.246555) (xy 89.779084 -283.246555) (xy 89.779084 -283.193257) (xy 89.787027 -283.140553)
			(xy 89.802737 -283.089623) (xy 89.825863 -283.041602) (xy 89.855887 -282.997565) (xy 89.892139 -282.958494)
			(xy 89.93381 -282.925263) (xy 89.979968 -282.898614) (xy 90.029582 -282.879142) (xy 90.081544 -282.867282)
			(xy 90.134694 -282.863299) (xy 90.187844 -282.867282) (xy 90.239806 -282.879142) (xy 90.28942 -282.898614)
			(xy 90.335578 -282.925263) (xy 90.377249 -282.958494) (xy 90.413501 -282.997565) (xy 90.443525 -283.041602)
			(xy 90.466651 -283.089623) (xy 90.482361 -283.140553) (xy 90.490304 -283.193257) (xy 90.490802 -283.219906)
			(xy 90.718386 -283.219906) (xy 90.718783 -283.194276) (xy 90.726119 -283.143542) (xy 90.740654 -283.094386)
			(xy 90.762089 -283.047822) (xy 90.789979 -283.004812) (xy 90.823749 -282.966247) (xy 90.8627 -282.932924)
			(xy 90.906027 -282.90553) (xy 90.952835 -282.884633) (xy 91.002156 -282.870664) (xy 91.027504 -282.866846)
			(xy 91.052396 -282.863544) (xy 91.224862 -282.564586) (xy 91.215464 -282.541472) (xy 91.206973 -282.519876)
			(xy 91.194996 -282.475044) (xy 91.188934 -282.429038) (xy 91.18854 -282.405836) (xy 91.189038 -282.379187)
			(xy 91.196981 -282.326483) (xy 91.212691 -282.275553) (xy 91.235817 -282.227532) (xy 91.265841 -282.183495)
			(xy 91.302093 -282.144424) (xy 91.343764 -282.111193) (xy 91.389922 -282.084544) (xy 91.439536 -282.065072)
			(xy 91.491498 -282.053212) (xy 91.544648 -282.049229) (xy 91.597798 -282.053212) (xy 91.64976 -282.065072)
			(xy 91.699374 -282.084544) (xy 91.745532 -282.111193) (xy 91.787203 -282.144424) (xy 91.823455 -282.183495)
			(xy 91.853479 -282.227532) (xy 91.876605 -282.275553) (xy 91.892315 -282.326483) (xy 91.900258 -282.379187)
			(xy 91.900756 -282.405836) (xy 91.900327 -282.431476) (xy 91.900181 -282.432485) (xy 92.128838 -282.432485)
			(xy 92.128838 -282.379187) (xy 92.136781 -282.326483) (xy 92.152491 -282.275553) (xy 92.175617 -282.227532)
			(xy 92.205641 -282.183495) (xy 92.241893 -282.144424) (xy 92.283564 -282.111193) (xy 92.329722 -282.084544)
			(xy 92.379336 -282.065072) (xy 92.431298 -282.053212) (xy 92.484448 -282.049229) (xy 92.537598 -282.053212)
			(xy 92.58956 -282.065072) (xy 92.639174 -282.084544) (xy 92.685332 -282.111193) (xy 92.727003 -282.144424)
			(xy 92.763255 -282.183495) (xy 92.793279 -282.227532) (xy 92.816405 -282.275553) (xy 92.832115 -282.326483)
			(xy 92.840058 -282.379187) (xy 92.840556 -282.405836) (xy 93.06814 -282.405836) (xy 93.068604 -282.380208)
			(xy 93.075935 -282.32948) (xy 93.090464 -282.280327) (xy 93.111892 -282.233765) (xy 93.139775 -282.190758)
			(xy 93.173536 -282.152193) (xy 93.21248 -282.118868) (xy 93.255799 -282.091472) (xy 93.302599 -282.070571)
			(xy 93.351913 -282.056597) (xy 93.377258 -282.052776) (xy 93.401896 -282.049474) (xy 93.574362 -281.751024)
			(xy 93.56471 -281.72791) (xy 93.556199 -281.706276) (xy 93.54421 -281.661359) (xy 93.538163 -281.615265)
			(xy 93.537786 -281.59202) (xy 93.538284 -281.565371) (xy 93.546227 -281.512667) (xy 93.561937 -281.461737)
			(xy 93.585063 -281.413716) (xy 93.615087 -281.369679) (xy 93.651339 -281.330608) (xy 93.69301 -281.297377)
			(xy 93.739168 -281.270728) (xy 93.788782 -281.251256) (xy 93.840744 -281.239396) (xy 93.893894 -281.235413)
			(xy 93.947044 -281.239396) (xy 93.999006 -281.251256) (xy 94.04862 -281.270728) (xy 94.094778 -281.297377)
			(xy 94.136449 -281.330608) (xy 94.172701 -281.369679) (xy 94.202725 -281.413716) (xy 94.225851 -281.461737)
			(xy 94.241561 -281.512667) (xy 94.249504 -281.565371) (xy 94.250002 -281.59202) (xy 94.249582 -281.617639)
			(xy 94.249433 -281.618669) (xy 94.478084 -281.618669) (xy 94.478084 -281.565371) (xy 94.486027 -281.512667)
			(xy 94.501737 -281.461737) (xy 94.524863 -281.413716) (xy 94.554887 -281.369679) (xy 94.591139 -281.330608)
			(xy 94.63281 -281.297377) (xy 94.678968 -281.270728) (xy 94.728582 -281.251256) (xy 94.780544 -281.239396)
			(xy 94.833694 -281.235413) (xy 94.886844 -281.239396) (xy 94.938806 -281.251256) (xy 94.98842 -281.270728)
			(xy 95.034578 -281.297377) (xy 95.076249 -281.330608) (xy 95.112501 -281.369679) (xy 95.142525 -281.413716)
			(xy 95.165651 -281.461737) (xy 95.181361 -281.512667) (xy 95.189304 -281.565371) (xy 95.189802 -281.59202)
			(xy 95.189304 -281.618669) (xy 95.181361 -281.671373) (xy 95.165651 -281.722303) (xy 95.142525 -281.770324)
			(xy 95.112501 -281.814361) (xy 95.076249 -281.853432) (xy 95.034578 -281.886663) (xy 94.98842 -281.913312)
			(xy 94.938806 -281.932784) (xy 94.886844 -281.944644) (xy 94.833694 -281.948628) (xy 94.780544 -281.944644)
			(xy 94.728582 -281.932784) (xy 94.678968 -281.913312) (xy 94.63281 -281.886663) (xy 94.591139 -281.853432)
			(xy 94.554887 -281.814361) (xy 94.524863 -281.770324) (xy 94.501737 -281.722303) (xy 94.486027 -281.671373)
			(xy 94.478084 -281.618669) (xy 94.249433 -281.618669) (xy 94.242262 -281.668351) (xy 94.227749 -281.717489)
			(xy 94.20634 -281.76404) (xy 94.17848 -281.80704) (xy 94.144744 -281.845603) (xy 94.105827 -281.878931)
			(xy 94.062535 -281.906336) (xy 94.015761 -281.927252) (xy 93.966472 -281.941246) (xy 93.941138 -281.94508)
			(xy 93.916246 -281.948382) (xy 93.74378 -282.246832) (xy 93.753432 -282.269946) (xy 93.761957 -282.291575)
			(xy 93.773942 -282.336494) (xy 93.779983 -282.382591) (xy 93.780356 -282.405836) (xy 93.779858 -282.432485)
			(xy 94.008438 -282.432485) (xy 94.008438 -282.379187) (xy 94.016381 -282.326483) (xy 94.032091 -282.275553)
			(xy 94.055217 -282.227532) (xy 94.085241 -282.183495) (xy 94.121493 -282.144424) (xy 94.163164 -282.111193)
			(xy 94.209322 -282.084544) (xy 94.258936 -282.065072) (xy 94.310898 -282.053212) (xy 94.364048 -282.049229)
			(xy 94.417198 -282.053212) (xy 94.46916 -282.065072) (xy 94.518774 -282.084544) (xy 94.564932 -282.111193)
			(xy 94.606603 -282.144424) (xy 94.642855 -282.183495) (xy 94.672879 -282.227532) (xy 94.696005 -282.275553)
			(xy 94.711715 -282.326483) (xy 94.719658 -282.379187) (xy 94.720156 -282.405836) (xy 94.947486 -282.405836)
			(xy 94.947911 -282.380206) (xy 94.955242 -282.329474) (xy 94.969774 -282.280318) (xy 94.991205 -282.233754)
			(xy 95.019092 -282.190745) (xy 95.052859 -282.15218) (xy 95.091807 -282.118855) (xy 95.135132 -282.091461)
			(xy 95.181938 -282.070564) (xy 95.231257 -282.056595) (xy 95.256604 -282.052776) (xy 95.281242 -282.049474)
			(xy 95.453962 -281.750516) (xy 95.44431 -281.727402) (xy 95.43584 -281.705851) (xy 95.423956 -281.661095)
			(xy 95.417989 -281.615174) (xy 95.41764 -281.59202) (xy 95.418138 -281.565371) (xy 95.426081 -281.512667)
			(xy 95.441791 -281.461737) (xy 95.464917 -281.413716) (xy 95.494941 -281.369679) (xy 95.531193 -281.330608)
			(xy 95.572864 -281.297377) (xy 95.619022 -281.270728) (xy 95.668636 -281.251256) (xy 95.720598 -281.239396)
			(xy 95.773748 -281.235413) (xy 95.826898 -281.239396) (xy 95.87886 -281.251256) (xy 95.928474 -281.270728)
			(xy 95.974632 -281.297377) (xy 96.016303 -281.330608) (xy 96.052555 -281.369679) (xy 96.082579 -281.413716)
			(xy 96.105705 -281.461737) (xy 96.121415 -281.512667) (xy 96.129358 -281.565371) (xy 96.129856 -281.59202)
			(xy 96.129412 -281.61766) (xy 96.129266 -281.618669) (xy 96.357938 -281.618669) (xy 96.357938 -281.565371)
			(xy 96.365881 -281.512667) (xy 96.381591 -281.461737) (xy 96.404717 -281.413716) (xy 96.434741 -281.369679)
			(xy 96.470993 -281.330608) (xy 96.512664 -281.297377) (xy 96.558822 -281.270728) (xy 96.608436 -281.251256)
			(xy 96.660398 -281.239396) (xy 96.713548 -281.235413) (xy 96.766698 -281.239396) (xy 96.81866 -281.251256)
			(xy 96.868274 -281.270728) (xy 96.914432 -281.297377) (xy 96.956103 -281.330608) (xy 96.992355 -281.369679)
			(xy 97.022379 -281.413716) (xy 97.045505 -281.461737) (xy 97.061215 -281.512667) (xy 97.069158 -281.565371)
			(xy 97.069656 -281.59202) (xy 97.29724 -281.59202) (xy 97.29769 -281.566392) (xy 97.305022 -281.515663)
			(xy 97.319554 -281.466509) (xy 97.340983 -281.419948) (xy 97.368868 -281.37694) (xy 97.402631 -281.338376)
			(xy 97.441576 -281.305051) (xy 97.484896 -281.277655) (xy 97.531698 -281.256755) (xy 97.581012 -281.242781)
			(xy 97.606358 -281.23896) (xy 97.630996 -281.235658) (xy 97.803462 -280.937208) (xy 97.79381 -280.914094)
			(xy 97.785294 -280.892462) (xy 97.773307 -280.847544) (xy 97.767262 -280.801449) (xy 97.766886 -280.778204)
			(xy 97.767384 -280.751555) (xy 97.775327 -280.698851) (xy 97.791037 -280.647921) (xy 97.814163 -280.5999)
			(xy 97.844187 -280.555863) (xy 97.880439 -280.516792) (xy 97.92211 -280.483561) (xy 97.968268 -280.456912)
			(xy 98.017882 -280.43744) (xy 98.069844 -280.42558) (xy 98.122994 -280.421597) (xy 98.176144 -280.42558)
			(xy 98.228106 -280.43744) (xy 98.27772 -280.456912) (xy 98.323878 -280.483561) (xy 98.365549 -280.516792)
			(xy 98.401801 -280.555863) (xy 98.431825 -280.5999) (xy 98.454951 -280.647921) (xy 98.470661 -280.698851)
			(xy 98.478604 -280.751555) (xy 98.479102 -280.778204) (xy 98.478667 -280.803822) (xy 98.478518 -280.804853)
			(xy 98.707184 -280.804853) (xy 98.707184 -280.751555) (xy 98.715127 -280.698851) (xy 98.730837 -280.647921)
			(xy 98.753963 -280.5999) (xy 98.783987 -280.555863) (xy 98.820239 -280.516792) (xy 98.86191 -280.483561)
			(xy 98.908068 -280.456912) (xy 98.957682 -280.43744) (xy 99.009644 -280.42558) (xy 99.062794 -280.421597)
			(xy 99.115944 -280.42558) (xy 99.167906 -280.43744) (xy 99.21752 -280.456912) (xy 99.263678 -280.483561)
			(xy 99.305349 -280.516792) (xy 99.341601 -280.555863) (xy 99.371625 -280.5999) (xy 99.394751 -280.647921)
			(xy 99.410461 -280.698851) (xy 99.418404 -280.751555) (xy 99.418902 -280.778204) (xy 100.586286 -280.778204)
			(xy 100.586784 -280.751555) (xy 100.594727 -280.698851) (xy 100.610437 -280.647921) (xy 100.633563 -280.5999)
			(xy 100.663587 -280.555863) (xy 100.699839 -280.516792) (xy 100.74151 -280.483561) (xy 100.787668 -280.456912)
			(xy 100.837282 -280.43744) (xy 100.889244 -280.42558) (xy 100.942394 -280.421597) (xy 100.995544 -280.42558)
			(xy 101.047506 -280.43744) (xy 101.09712 -280.456912) (xy 101.143278 -280.483561) (xy 101.184949 -280.516792)
			(xy 101.221201 -280.555863) (xy 101.251225 -280.5999) (xy 101.274351 -280.647921) (xy 101.290061 -280.698851)
			(xy 101.298004 -280.751555) (xy 101.298502 -280.778204) (xy 101.298132 -280.801355) (xy 101.297676 -280.804853)
			(xy 101.526584 -280.804853) (xy 101.526584 -280.751555) (xy 101.534527 -280.698851) (xy 101.550237 -280.647921)
			(xy 101.573363 -280.5999) (xy 101.603387 -280.555863) (xy 101.639639 -280.516792) (xy 101.68131 -280.483561)
			(xy 101.727468 -280.456912) (xy 101.777082 -280.43744) (xy 101.829044 -280.42558) (xy 101.882194 -280.421597)
			(xy 101.935344 -280.42558) (xy 101.987306 -280.43744) (xy 102.03692 -280.456912) (xy 102.083078 -280.483561)
			(xy 102.124749 -280.516792) (xy 102.161001 -280.555863) (xy 102.191025 -280.5999) (xy 102.214151 -280.647921)
			(xy 102.229861 -280.698851) (xy 102.237804 -280.751555) (xy 102.238302 -280.778204) (xy 102.237804 -280.804853)
			(xy 102.466638 -280.804853) (xy 102.466638 -280.751555) (xy 102.474581 -280.698851) (xy 102.490291 -280.647921)
			(xy 102.513417 -280.5999) (xy 102.543441 -280.555863) (xy 102.579693 -280.516792) (xy 102.621364 -280.483561)
			(xy 102.667522 -280.456912) (xy 102.717136 -280.43744) (xy 102.769098 -280.42558) (xy 102.822248 -280.421597)
			(xy 102.875398 -280.42558) (xy 102.92736 -280.43744) (xy 102.976974 -280.456912) (xy 103.023132 -280.483561)
			(xy 103.064803 -280.516792) (xy 103.101055 -280.555863) (xy 103.131079 -280.5999) (xy 103.154205 -280.647921)
			(xy 103.169915 -280.698851) (xy 103.177858 -280.751555) (xy 103.178356 -280.778204) (xy 103.405686 -280.778204)
			(xy 103.406184 -280.751555) (xy 103.414127 -280.698851) (xy 103.429837 -280.647921) (xy 103.452963 -280.5999)
			(xy 103.482987 -280.555863) (xy 103.519239 -280.516792) (xy 103.56091 -280.483561) (xy 103.607068 -280.456912)
			(xy 103.656682 -280.43744) (xy 103.708644 -280.42558) (xy 103.761794 -280.421597) (xy 103.814944 -280.42558)
			(xy 103.866906 -280.43744) (xy 103.91652 -280.456912) (xy 103.962678 -280.483561) (xy 104.004349 -280.516792)
			(xy 104.040601 -280.555863) (xy 104.070625 -280.5999) (xy 104.093751 -280.647921) (xy 104.109461 -280.698851)
			(xy 104.117404 -280.751555) (xy 104.117902 -280.778204) (xy 104.345486 -280.778204) (xy 104.345881 -280.752573)
			(xy 104.353217 -280.70184) (xy 104.367753 -280.652684) (xy 104.389188 -280.606119) (xy 104.417078 -280.56311)
			(xy 104.450848 -280.524545) (xy 104.489799 -280.491222) (xy 104.533127 -280.463828) (xy 104.579935 -280.442931)
			(xy 104.629256 -280.428962) (xy 104.654604 -280.425144) (xy 104.679242 -280.421842) (xy 104.851962 -280.122884)
			(xy 104.842564 -280.09977) (xy 104.834072 -280.078174) (xy 104.822095 -280.033342) (xy 104.816034 -279.987336)
			(xy 104.81564 -279.964134) (xy 104.816138 -279.937485) (xy 104.824081 -279.884781) (xy 104.839791 -279.833851)
			(xy 104.862917 -279.78583) (xy 104.892941 -279.741793) (xy 104.929193 -279.702722) (xy 104.970864 -279.669491)
			(xy 105.017022 -279.642842) (xy 105.066636 -279.62337) (xy 105.118598 -279.61151) (xy 105.171748 -279.607527)
			(xy 105.224898 -279.61151) (xy 105.27686 -279.62337) (xy 105.326474 -279.642842) (xy 105.372632 -279.669491)
			(xy 105.414303 -279.702722) (xy 105.450555 -279.741793) (xy 105.480579 -279.78583) (xy 105.503705 -279.833851)
			(xy 105.519415 -279.884781) (xy 105.527358 -279.937485) (xy 105.527856 -279.964134) (xy 105.527425 -279.989774)
			(xy 105.527279 -279.990783) (xy 105.755938 -279.990783) (xy 105.755938 -279.937485) (xy 105.763881 -279.884781)
			(xy 105.779591 -279.833851) (xy 105.802717 -279.78583) (xy 105.832741 -279.741793) (xy 105.868993 -279.702722)
			(xy 105.910664 -279.669491) (xy 105.956822 -279.642842) (xy 106.006436 -279.62337) (xy 106.058398 -279.61151)
			(xy 106.111548 -279.607527) (xy 106.164698 -279.61151) (xy 106.21666 -279.62337) (xy 106.266274 -279.642842)
			(xy 106.312432 -279.669491) (xy 106.354103 -279.702722) (xy 106.390355 -279.741793) (xy 106.420379 -279.78583)
			(xy 106.443505 -279.833851) (xy 106.459215 -279.884781) (xy 106.467158 -279.937485) (xy 106.467656 -279.964134)
			(xy 106.467158 -279.990783) (xy 106.459215 -280.043487) (xy 106.443505 -280.094417) (xy 106.420379 -280.142438)
			(xy 106.390355 -280.186475) (xy 106.354103 -280.225546) (xy 106.312432 -280.258777) (xy 106.266274 -280.285426)
			(xy 106.21666 -280.304898) (xy 106.164698 -280.316758) (xy 106.111548 -280.320742) (xy 106.058398 -280.316758)
			(xy 106.006436 -280.304898) (xy 105.956822 -280.285426) (xy 105.910664 -280.258777) (xy 105.868993 -280.225546)
			(xy 105.832741 -280.186475) (xy 105.802717 -280.142438) (xy 105.779591 -280.094417) (xy 105.763881 -280.043487)
			(xy 105.755938 -279.990783) (xy 105.527279 -279.990783) (xy 105.520078 -280.040525) (xy 105.505527 -280.089697)
			(xy 105.484073 -280.136273) (xy 105.456159 -280.17929) (xy 105.422362 -280.217857) (xy 105.383383 -280.251177)
			(xy 105.340027 -280.278561) (xy 105.293191 -280.299443) (xy 105.243844 -280.313389) (xy 105.218484 -280.317194)
			(xy 105.193846 -280.320496) (xy 105.021126 -280.6192) (xy 105.030778 -280.642314) (xy 105.039296 -280.663945)
			(xy 105.051282 -280.708864) (xy 105.057327 -280.754959) (xy 105.057702 -280.778204) (xy 105.057204 -280.804853)
			(xy 105.049261 -280.857557) (xy 105.033551 -280.908487) (xy 105.010425 -280.956508) (xy 104.980401 -281.000545)
			(xy 104.944149 -281.039616) (xy 104.902478 -281.072847) (xy 104.85632 -281.099496) (xy 104.806706 -281.118968)
			(xy 104.754744 -281.130828) (xy 104.701594 -281.134812) (xy 104.648444 -281.130828) (xy 104.596482 -281.118968)
			(xy 104.546868 -281.099496) (xy 104.50071 -281.072847) (xy 104.459039 -281.039616) (xy 104.422787 -281.000545)
			(xy 104.392763 -280.956508) (xy 104.369637 -280.908487) (xy 104.353927 -280.857557) (xy 104.345984 -280.804853)
			(xy 104.345486 -280.778204) (xy 104.117902 -280.778204) (xy 104.117532 -280.801355) (xy 104.111545 -280.84727)
			(xy 104.099672 -280.892024) (xy 104.091232 -280.913586) (xy 104.08158 -280.9367) (xy 104.2543 -281.235658)
			(xy 104.278938 -281.23896) (xy 104.304276 -281.242808) (xy 104.353579 -281.256797) (xy 104.400369 -281.277708)
			(xy 104.44368 -281.305107) (xy 104.482617 -281.338429) (xy 104.516378 -281.376987) (xy 104.544265 -281.419985)
			(xy 104.565703 -281.466535) (xy 104.58025 -281.515676) (xy 104.587605 -281.566395) (xy 104.588056 -281.59202)
			(xy 104.587558 -281.618669) (xy 104.816138 -281.618669) (xy 104.816138 -281.565371) (xy 104.824081 -281.512667)
			(xy 104.839791 -281.461737) (xy 104.862917 -281.413716) (xy 104.892941 -281.369679) (xy 104.929193 -281.330608)
			(xy 104.970864 -281.297377) (xy 105.017022 -281.270728) (xy 105.066636 -281.251256) (xy 105.118598 -281.239396)
			(xy 105.171748 -281.235413) (xy 105.224898 -281.239396) (xy 105.27686 -281.251256) (xy 105.326474 -281.270728)
			(xy 105.372632 -281.297377) (xy 105.414303 -281.330608) (xy 105.450555 -281.369679) (xy 105.480579 -281.413716)
			(xy 105.503705 -281.461737) (xy 105.519415 -281.512667) (xy 105.527358 -281.565371) (xy 105.527856 -281.59202)
			(xy 105.527358 -281.618669) (xy 105.519415 -281.671373) (xy 105.503705 -281.722303) (xy 105.480579 -281.770324)
			(xy 105.450555 -281.814361) (xy 105.414303 -281.853432) (xy 105.372632 -281.886663) (xy 105.326474 -281.913312)
			(xy 105.27686 -281.932784) (xy 105.224898 -281.944644) (xy 105.171748 -281.948628) (xy 105.118598 -281.944644)
			(xy 105.066636 -281.932784) (xy 105.017022 -281.913312) (xy 104.970864 -281.886663) (xy 104.929193 -281.853432)
			(xy 104.892941 -281.814361) (xy 104.862917 -281.770324) (xy 104.839791 -281.722303) (xy 104.824081 -281.671373)
			(xy 104.816138 -281.618669) (xy 104.587558 -281.618669) (xy 104.579615 -281.671373) (xy 104.563905 -281.722303)
			(xy 104.540779 -281.770324) (xy 104.510755 -281.814361) (xy 104.474503 -281.853432) (xy 104.432832 -281.886663)
			(xy 104.386674 -281.913312) (xy 104.33706 -281.932784) (xy 104.285098 -281.944644) (xy 104.231948 -281.948628)
			(xy 104.178798 -281.944644) (xy 104.126836 -281.932784) (xy 104.077222 -281.913312) (xy 104.031064 -281.886663)
			(xy 103.989393 -281.853432) (xy 103.953141 -281.814361) (xy 103.923117 -281.770324) (xy 103.899991 -281.722303)
			(xy 103.884281 -281.671373) (xy 103.876338 -281.618669) (xy 103.87584 -281.59202) (xy 103.876213 -281.568775)
			(xy 103.882257 -281.522679) (xy 103.894247 -281.477762) (xy 103.902764 -281.45613) (xy 103.912416 -281.433016)
			(xy 103.73995 -281.134566) (xy 103.715058 -281.131264) (xy 103.689692 -281.127505) (xy 103.640351 -281.113542)
			(xy 103.593522 -281.092647) (xy 103.550172 -281.065253) (xy 103.511199 -281.031927) (xy 103.477408 -280.993356)
			(xy 103.449496 -280.950339) (xy 103.428041 -280.903763) (xy 103.413486 -280.854593) (xy 103.406132 -280.803844)
			(xy 103.405686 -280.778204) (xy 103.178356 -280.778204) (xy 103.177858 -280.804853) (xy 103.169915 -280.857557)
			(xy 103.154205 -280.908487) (xy 103.131079 -280.956508) (xy 103.101055 -281.000545) (xy 103.064803 -281.039616)
			(xy 103.023132 -281.072847) (xy 102.976974 -281.099496) (xy 102.92736 -281.118968) (xy 102.875398 -281.130828)
			(xy 102.822248 -281.134812) (xy 102.769098 -281.130828) (xy 102.717136 -281.118968) (xy 102.667522 -281.099496)
			(xy 102.621364 -281.072847) (xy 102.579693 -281.039616) (xy 102.543441 -281.000545) (xy 102.513417 -280.956508)
			(xy 102.490291 -280.908487) (xy 102.474581 -280.857557) (xy 102.466638 -280.804853) (xy 102.237804 -280.804853)
			(xy 102.229861 -280.857557) (xy 102.214151 -280.908487) (xy 102.191025 -280.956508) (xy 102.161001 -281.000545)
			(xy 102.124749 -281.039616) (xy 102.083078 -281.072847) (xy 102.03692 -281.099496) (xy 101.987306 -281.118968)
			(xy 101.935344 -281.130828) (xy 101.882194 -281.134812) (xy 101.829044 -281.130828) (xy 101.777082 -281.118968)
			(xy 101.727468 -281.099496) (xy 101.68131 -281.072847) (xy 101.639639 -281.039616) (xy 101.603387 -281.000545)
			(xy 101.573363 -280.956508) (xy 101.550237 -280.908487) (xy 101.534527 -280.857557) (xy 101.526584 -280.804853)
			(xy 101.297676 -280.804853) (xy 101.292145 -280.84727) (xy 101.280272 -280.892024) (xy 101.271832 -280.913586)
			(xy 101.26218 -280.9367) (xy 101.4349 -281.235658) (xy 101.459538 -281.23896) (xy 101.484876 -281.242808)
			(xy 101.534179 -281.256797) (xy 101.580969 -281.277708) (xy 101.62428 -281.305107) (xy 101.663217 -281.338429)
			(xy 101.696978 -281.376987) (xy 101.724865 -281.419985) (xy 101.746303 -281.466535) (xy 101.76085 -281.515676)
			(xy 101.768205 -281.566395) (xy 101.768656 -281.59202) (xy 101.768158 -281.618669) (xy 101.760215 -281.671373)
			(xy 101.744505 -281.722303) (xy 101.721379 -281.770324) (xy 101.691355 -281.814361) (xy 101.655103 -281.853432)
			(xy 101.613432 -281.886663) (xy 101.567274 -281.913312) (xy 101.51766 -281.932784) (xy 101.465698 -281.944644)
			(xy 101.412548 -281.948628) (xy 101.359398 -281.944644) (xy 101.307436 -281.932784) (xy 101.257822 -281.913312)
			(xy 101.211664 -281.886663) (xy 101.169993 -281.853432) (xy 101.133741 -281.814361) (xy 101.103717 -281.770324)
			(xy 101.080591 -281.722303) (xy 101.064881 -281.671373) (xy 101.056938 -281.618669) (xy 101.05644 -281.59202)
			(xy 101.056813 -281.568775) (xy 101.062857 -281.522679) (xy 101.074847 -281.477762) (xy 101.083364 -281.45613)
			(xy 101.093016 -281.433016) (xy 100.92055 -281.134566) (xy 100.895658 -281.131264) (xy 100.870292 -281.127505)
			(xy 100.820951 -281.113542) (xy 100.774122 -281.092647) (xy 100.730772 -281.065253) (xy 100.691799 -281.031927)
			(xy 100.658008 -280.993356) (xy 100.630096 -280.950339) (xy 100.608641 -280.903763) (xy 100.594086 -280.854593)
			(xy 100.586732 -280.803844) (xy 100.586286 -280.778204) (xy 99.418902 -280.778204) (xy 99.418404 -280.804853)
			(xy 99.410461 -280.857557) (xy 99.394751 -280.908487) (xy 99.371625 -280.956508) (xy 99.341601 -281.000545)
			(xy 99.305349 -281.039616) (xy 99.263678 -281.072847) (xy 99.21752 -281.099496) (xy 99.167906 -281.118968)
			(xy 99.115944 -281.130828) (xy 99.062794 -281.134812) (xy 99.009644 -281.130828) (xy 98.957682 -281.118968)
			(xy 98.908068 -281.099496) (xy 98.86191 -281.072847) (xy 98.820239 -281.039616) (xy 98.783987 -281.000545)
			(xy 98.753963 -280.956508) (xy 98.730837 -280.908487) (xy 98.715127 -280.857557) (xy 98.707184 -280.804853)
			(xy 98.478518 -280.804853) (xy 98.47135 -280.854534) (xy 98.456838 -280.903672) (xy 98.435432 -280.950222)
			(xy 98.407574 -280.993223) (xy 98.373838 -281.031786) (xy 98.334923 -281.065114) (xy 98.291632 -281.092519)
			(xy 98.24486 -281.113435) (xy 98.195572 -281.12743) (xy 98.170238 -281.131264) (xy 98.145346 -281.134566)
			(xy 97.97288 -281.433016) (xy 97.982532 -281.45613) (xy 97.991052 -281.477761) (xy 98.003039 -281.522679)
			(xy 98.009082 -281.568775) (xy 98.009456 -281.59202) (xy 98.008958 -281.618669) (xy 98.237538 -281.618669)
			(xy 98.237538 -281.565371) (xy 98.245481 -281.512667) (xy 98.261191 -281.461737) (xy 98.284317 -281.413716)
			(xy 98.314341 -281.369679) (xy 98.350593 -281.330608) (xy 98.392264 -281.297377) (xy 98.438422 -281.270728)
			(xy 98.488036 -281.251256) (xy 98.539998 -281.239396) (xy 98.593148 -281.235413) (xy 98.646298 -281.239396)
			(xy 98.69826 -281.251256) (xy 98.747874 -281.270728) (xy 98.794032 -281.297377) (xy 98.835703 -281.330608)
			(xy 98.871955 -281.369679) (xy 98.901979 -281.413716) (xy 98.925105 -281.461737) (xy 98.940815 -281.512667)
			(xy 98.948758 -281.565371) (xy 98.949256 -281.592) (xy 99.176288 -281.592) (xy 99.180272 -281.538845)
			(xy 99.192134 -281.486878) (xy 99.21161 -281.437259) (xy 99.238264 -281.391098) (xy 99.2715 -281.349425)
			(xy 99.310578 -281.313172) (xy 99.354622 -281.283149) (xy 99.402649 -281.260026) (xy 99.453587 -281.24432)
			(xy 99.506296 -281.236382) (xy 99.532948 -281.235912) (xy 99.557963 -281.236313) (xy 99.607502 -281.243304)
			(xy 99.655576 -281.257157) (xy 99.701239 -281.277598) (xy 99.743594 -281.304226) (xy 99.781807 -281.336517)
			(xy 99.815128 -281.373836) (xy 99.829366 -281.394408) (xy 100.17633 -281.394408) (xy 100.190586 -281.373851)
			(xy 100.223911 -281.336543) (xy 100.262125 -281.30426) (xy 100.304477 -281.277636) (xy 100.350135 -281.257195)
			(xy 100.398203 -281.243338) (xy 100.447736 -281.236338) (xy 100.472748 -281.235912) (xy 100.499396 -281.236373)
			(xy 100.552097 -281.244323) (xy 100.603025 -281.260038) (xy 100.651042 -281.283168) (xy 100.695075 -281.313195)
			(xy 100.734142 -281.349448) (xy 100.76737 -281.39112) (xy 100.794016 -281.437278) (xy 100.813486 -281.486891)
			(xy 100.825345 -281.538852) (xy 100.829328 -281.592) (xy 100.825345 -281.645148) (xy 100.813486 -281.697109)
			(xy 100.794016 -281.746723) (xy 100.76737 -281.79288) (xy 100.734142 -281.834552) (xy 100.695075 -281.870805)
			(xy 100.651042 -281.900832) (xy 100.603025 -281.923962) (xy 100.552097 -281.939677) (xy 100.499396 -281.947627)
			(xy 100.472748 -281.948128) (xy 100.447732 -281.947757) (xy 100.39819 -281.940764) (xy 100.350115 -281.926908)
			(xy 100.30445 -281.906463) (xy 100.262096 -281.879829) (xy 100.223884 -281.847532) (xy 100.190566 -281.810207)
			(xy 100.17633 -281.789632) (xy 99.829366 -281.789632) (xy 99.815126 -281.8102) (xy 99.781796 -281.847506)
			(xy 99.743579 -281.879787) (xy 99.701224 -281.906408) (xy 99.655564 -281.926847) (xy 99.607495 -281.940703)
			(xy 99.557961 -281.947703) (xy 99.532948 -281.948128) (xy 99.506296 -281.947618) (xy 99.453587 -281.93968)
			(xy 99.402649 -281.923974) (xy 99.354622 -281.900851) (xy 99.310578 -281.870828) (xy 99.2715 -281.834575)
			(xy 99.238264 -281.792902) (xy 99.21161 -281.746741) (xy 99.192134 -281.697122) (xy 99.180272 -281.645155)
			(xy 99.176288 -281.592) (xy 98.949256 -281.592) (xy 98.949256 -281.59202) (xy 98.948758 -281.618669)
			(xy 98.940815 -281.671373) (xy 98.925105 -281.722303) (xy 98.901979 -281.770324) (xy 98.871955 -281.814361)
			(xy 98.835703 -281.853432) (xy 98.794032 -281.886663) (xy 98.747874 -281.913312) (xy 98.69826 -281.932784)
			(xy 98.646298 -281.944644) (xy 98.593148 -281.948628) (xy 98.539998 -281.944644) (xy 98.488036 -281.932784)
			(xy 98.438422 -281.913312) (xy 98.392264 -281.886663) (xy 98.350593 -281.853432) (xy 98.314341 -281.814361)
			(xy 98.284317 -281.770324) (xy 98.261191 -281.722303) (xy 98.245481 -281.671373) (xy 98.237538 -281.618669)
			(xy 98.008958 -281.618669) (xy 98.001015 -281.671373) (xy 97.985305 -281.722303) (xy 97.962179 -281.770324)
			(xy 97.932155 -281.814361) (xy 97.895903 -281.853432) (xy 97.854232 -281.886663) (xy 97.808074 -281.913312)
			(xy 97.75846 -281.932784) (xy 97.706498 -281.944644) (xy 97.653348 -281.948628) (xy 97.600198 -281.944644)
			(xy 97.548236 -281.932784) (xy 97.498622 -281.913312) (xy 97.452464 -281.886663) (xy 97.410793 -281.853432)
			(xy 97.374541 -281.814361) (xy 97.344517 -281.770324) (xy 97.321391 -281.722303) (xy 97.305681 -281.671373)
			(xy 97.297738 -281.618669) (xy 97.29724 -281.59202) (xy 97.069656 -281.59202) (xy 97.069158 -281.618669)
			(xy 97.061215 -281.671373) (xy 97.045505 -281.722303) (xy 97.022379 -281.770324) (xy 96.992355 -281.814361)
			(xy 96.956103 -281.853432) (xy 96.914432 -281.886663) (xy 96.868274 -281.913312) (xy 96.81866 -281.932784)
			(xy 96.766698 -281.944644) (xy 96.713548 -281.948628) (xy 96.660398 -281.944644) (xy 96.608436 -281.932784)
			(xy 96.558822 -281.913312) (xy 96.512664 -281.886663) (xy 96.470993 -281.853432) (xy 96.434741 -281.814361)
			(xy 96.404717 -281.770324) (xy 96.381591 -281.722303) (xy 96.365881 -281.671373) (xy 96.357938 -281.618669)
			(xy 96.129266 -281.618669) (xy 96.122067 -281.66841) (xy 96.107518 -281.717582) (xy 96.086065 -281.764158)
			(xy 96.058153 -281.807175) (xy 96.024358 -281.845742) (xy 95.98538 -281.879063) (xy 95.942025 -281.906447)
			(xy 95.89519 -281.927328) (xy 95.845844 -281.941275) (xy 95.820484 -281.94508) (xy 95.795592 -281.948382)
			(xy 95.623126 -282.246832) (xy 95.632778 -282.269946) (xy 95.641305 -282.291574) (xy 95.653288 -282.336494)
			(xy 95.659329 -282.382591) (xy 95.659702 -282.405836) (xy 95.887286 -282.405836) (xy 95.887784 -282.379187)
			(xy 95.895727 -282.326483) (xy 95.911437 -282.275553) (xy 95.934563 -282.227532) (xy 95.964587 -282.183495)
			(xy 96.000839 -282.144424) (xy 96.04251 -282.111193) (xy 96.088668 -282.084544) (xy 96.138282 -282.065072)
			(xy 96.190244 -282.053212) (xy 96.243394 -282.049229) (xy 96.296544 -282.053212) (xy 96.348506 -282.065072)
			(xy 96.39812 -282.084544) (xy 96.444278 -282.111193) (xy 96.485949 -282.144424) (xy 96.522201 -282.183495)
			(xy 96.552225 -282.227532) (xy 96.575351 -282.275553) (xy 96.591061 -282.326483) (xy 96.599004 -282.379187)
			(xy 96.599501 -282.4058) (xy 96.826629 -282.4058) (xy 96.830612 -282.352656) (xy 96.84247 -282.3007)
			(xy 96.86194 -282.251091) (xy 96.888586 -282.204938) (xy 96.921813 -282.163272) (xy 96.960879 -282.127024)
			(xy 97.004911 -282.097002) (xy 97.052926 -282.073879) (xy 97.10385 -282.05817) (xy 97.156548 -282.050226)
			(xy 97.183194 -282.049728) (xy 97.208208 -282.050163) (xy 97.257746 -282.057147) (xy 97.305819 -282.070993)
			(xy 97.351482 -282.091429) (xy 97.393838 -282.118051) (xy 97.432052 -282.150338) (xy 97.465374 -282.187654)
			(xy 97.479612 -282.208224) (xy 97.826576 -282.208224) (xy 97.840807 -282.187649) (xy 97.874136 -282.15034)
			(xy 97.912354 -282.118058) (xy 97.954711 -282.091437) (xy 98.000373 -282.070999) (xy 98.048444 -282.057146)
			(xy 98.09798 -282.05015) (xy 98.122994 -282.049728) (xy 98.149648 -282.050129) (xy 98.202361 -282.058073)
			(xy 98.253301 -282.073785) (xy 98.301331 -282.096914) (xy 98.345376 -282.126944) (xy 98.384454 -282.163202)
			(xy 98.417692 -282.20488) (xy 98.444346 -282.251046) (xy 98.463822 -282.300669) (xy 98.475684 -282.352641)
			(xy 98.479668 -282.4058) (xy 98.477668 -282.432485) (xy 98.707184 -282.432485) (xy 98.707184 -282.379187)
			(xy 98.715127 -282.326483) (xy 98.730837 -282.275553) (xy 98.753963 -282.227532) (xy 98.783987 -282.183495)
			(xy 98.820239 -282.144424) (xy 98.86191 -282.111193) (xy 98.908068 -282.084544) (xy 98.957682 -282.065072)
			(xy 99.009644 -282.053212) (xy 99.062794 -282.049229) (xy 99.115944 -282.053212) (xy 99.167906 -282.065072)
			(xy 99.21752 -282.084544) (xy 99.263678 -282.111193) (xy 99.305349 -282.144424) (xy 99.341601 -282.183495)
			(xy 99.371625 -282.227532) (xy 99.394751 -282.275553) (xy 99.410461 -282.326483) (xy 99.418404 -282.379187)
			(xy 99.418902 -282.405836) (xy 99.418404 -282.432485) (xy 99.410461 -282.485189) (xy 99.394751 -282.536119)
			(xy 99.371625 -282.58414) (xy 99.341601 -282.628177) (xy 99.305349 -282.667248) (xy 99.263678 -282.700479)
			(xy 99.21752 -282.727128) (xy 99.167906 -282.7466) (xy 99.115944 -282.75846) (xy 99.062794 -282.762444)
			(xy 99.009644 -282.75846) (xy 98.957682 -282.7466) (xy 98.908068 -282.727128) (xy 98.86191 -282.700479)
			(xy 98.820239 -282.667248) (xy 98.783987 -282.628177) (xy 98.753963 -282.58414) (xy 98.730837 -282.536119)
			(xy 98.715127 -282.485189) (xy 98.707184 -282.432485) (xy 98.477668 -282.432485) (xy 98.475684 -282.458959)
			(xy 98.463822 -282.510931) (xy 98.444346 -282.560554) (xy 98.417692 -282.60672) (xy 98.384454 -282.648398)
			(xy 98.345376 -282.684656) (xy 98.301331 -282.714686) (xy 98.253301 -282.737815) (xy 98.202361 -282.753527)
			(xy 98.149648 -282.761471) (xy 98.122994 -282.761944) (xy 98.097979 -282.761531) (xy 98.04844 -282.754544)
			(xy 98.000366 -282.740695) (xy 97.954702 -282.720257) (xy 97.912346 -282.69363) (xy 97.874133 -282.66134)
			(xy 97.840813 -282.62402) (xy 97.826576 -282.603448) (xy 97.479612 -282.603448) (xy 97.465379 -282.624022)
			(xy 97.432051 -282.661332) (xy 97.393834 -282.693615) (xy 97.351478 -282.720237) (xy 97.305816 -282.740675)
			(xy 97.257744 -282.754527) (xy 97.208208 -282.761522) (xy 97.183194 -282.761944) (xy 97.156548 -282.761374)
			(xy 97.10385 -282.75343) (xy 97.052926 -282.737721) (xy 97.004911 -282.714598) (xy 96.960879 -282.684576)
			(xy 96.921813 -282.648328) (xy 96.888586 -282.606662) (xy 96.86194 -282.560509) (xy 96.84247 -282.5109)
			(xy 96.830612 -282.458944) (xy 96.826629 -282.4058) (xy 96.599501 -282.4058) (xy 96.599502 -282.405836)
			(xy 96.599132 -282.42904) (xy 96.593078 -282.47505) (xy 96.58109 -282.519883) (xy 96.572578 -282.541472)
			(xy 96.56318 -282.564586) (xy 96.7359 -282.863544) (xy 96.760538 -282.866846) (xy 96.785874 -282.870707)
			(xy 96.835176 -282.884696) (xy 96.881965 -282.905605) (xy 96.925275 -282.933003) (xy 96.964212 -282.966324)
			(xy 96.997973 -283.00488) (xy 97.02586 -283.047876) (xy 97.0473 -283.094425) (xy 97.061848 -283.143565)
			(xy 97.069204 -283.194282) (xy 97.069656 -283.219906) (xy 97.069158 -283.246555) (xy 97.297484 -283.246555)
			(xy 97.297484 -283.193257) (xy 97.305427 -283.140553) (xy 97.321137 -283.089623) (xy 97.344263 -283.041602)
			(xy 97.374287 -282.997565) (xy 97.410539 -282.958494) (xy 97.45221 -282.925263) (xy 97.498368 -282.898614)
			(xy 97.547982 -282.879142) (xy 97.599944 -282.867282) (xy 97.653094 -282.863299) (xy 97.706244 -282.867282)
			(xy 97.758206 -282.879142) (xy 97.80782 -282.898614) (xy 97.853978 -282.925263) (xy 97.895649 -282.958494)
			(xy 97.931901 -282.997565) (xy 97.961925 -283.041602) (xy 97.985051 -283.089623) (xy 98.000761 -283.140553)
			(xy 98.008704 -283.193257) (xy 98.009202 -283.219906) (xy 98.008704 -283.246555) (xy 98.237284 -283.246555)
			(xy 98.237284 -283.193257) (xy 98.245227 -283.140553) (xy 98.260937 -283.089623) (xy 98.284063 -283.041602)
			(xy 98.314087 -282.997565) (xy 98.350339 -282.958494) (xy 98.39201 -282.925263) (xy 98.438168 -282.898614)
			(xy 98.487782 -282.879142) (xy 98.539744 -282.867282) (xy 98.592894 -282.863299) (xy 98.646044 -282.867282)
			(xy 98.698006 -282.879142) (xy 98.74762 -282.898614) (xy 98.793778 -282.925263) (xy 98.835449 -282.958494)
			(xy 98.871701 -282.997565) (xy 98.901725 -283.041602) (xy 98.924851 -283.089623) (xy 98.940561 -283.140553)
			(xy 98.948504 -283.193257) (xy 98.949002 -283.219906) (xy 99.17684 -283.219906) (xy 99.177277 -283.194277)
			(xy 99.184611 -283.143548) (xy 99.199145 -283.094394) (xy 99.220576 -283.047833) (xy 99.248462 -283.004825)
			(xy 99.282227 -282.966261) (xy 99.321172 -282.932936) (xy 99.364494 -282.905541) (xy 99.411296 -282.884641)
			(xy 99.460612 -282.870667) (xy 99.485958 -282.866846) (xy 99.510596 -282.863544) (xy 99.683062 -282.565094)
			(xy 99.67341 -282.54198) (xy 99.664897 -282.520302) (xy 99.652895 -282.475302) (xy 99.646853 -282.429123)
			(xy 99.646486 -282.405836) (xy 99.646984 -282.379187) (xy 99.654927 -282.326483) (xy 99.670637 -282.275553)
			(xy 99.693763 -282.227532) (xy 99.723787 -282.183495) (xy 99.760039 -282.144424) (xy 99.80171 -282.111193)
			(xy 99.847868 -282.084544) (xy 99.897482 -282.065072) (xy 99.949444 -282.053212) (xy 100.002594 -282.049229)
			(xy 100.055744 -282.053212) (xy 100.107706 -282.065072) (xy 100.15732 -282.084544) (xy 100.203478 -282.111193)
			(xy 100.245149 -282.144424) (xy 100.281401 -282.183495) (xy 100.311425 -282.227532) (xy 100.334551 -282.275553)
			(xy 100.350261 -282.326483) (xy 100.358204 -282.379187) (xy 100.358702 -282.405836) (xy 100.358296 -282.431455)
			(xy 100.358147 -282.432485) (xy 100.586784 -282.432485) (xy 100.586784 -282.379187) (xy 100.594727 -282.326483)
			(xy 100.610437 -282.275553) (xy 100.633563 -282.227532) (xy 100.663587 -282.183495) (xy 100.699839 -282.144424)
			(xy 100.74151 -282.111193) (xy 100.787668 -282.084544) (xy 100.837282 -282.065072) (xy 100.889244 -282.053212)
			(xy 100.942394 -282.049229) (xy 100.995544 -282.053212) (xy 101.047506 -282.065072) (xy 101.09712 -282.084544)
			(xy 101.143278 -282.111193) (xy 101.184949 -282.144424) (xy 101.221201 -282.183495) (xy 101.251225 -282.227532)
			(xy 101.274351 -282.275553) (xy 101.290061 -282.326483) (xy 101.298004 -282.379187) (xy 101.298502 -282.405836)
			(xy 101.526086 -282.405836) (xy 101.526511 -282.380206) (xy 101.533842 -282.329474) (xy 101.548374 -282.280318)
			(xy 101.569805 -282.233754) (xy 101.597692 -282.190745) (xy 101.631459 -282.15218) (xy 101.670407 -282.118855)
			(xy 101.713732 -282.091461) (xy 101.760538 -282.070564) (xy 101.809857 -282.056595) (xy 101.835204 -282.052776)
			(xy 101.859842 -282.049474) (xy 102.032562 -281.750516) (xy 102.02291 -281.727402) (xy 102.01444 -281.705851)
			(xy 102.002556 -281.661095) (xy 101.996589 -281.615174) (xy 101.99624 -281.59202) (xy 101.996738 -281.565371)
			(xy 102.004681 -281.512667) (xy 102.020391 -281.461737) (xy 102.043517 -281.413716) (xy 102.073541 -281.369679)
			(xy 102.109793 -281.330608) (xy 102.151464 -281.297377) (xy 102.197622 -281.270728) (xy 102.247236 -281.251256)
			(xy 102.299198 -281.239396) (xy 102.352348 -281.235413) (xy 102.405498 -281.239396) (xy 102.45746 -281.251256)
			(xy 102.507074 -281.270728) (xy 102.553232 -281.297377) (xy 102.594903 -281.330608) (xy 102.631155 -281.369679)
			(xy 102.661179 -281.413716) (xy 102.684305 -281.461737) (xy 102.700015 -281.512667) (xy 102.707958 -281.565371)
			(xy 102.708456 -281.59202) (xy 102.708012 -281.61766) (xy 102.707866 -281.618669) (xy 102.936284 -281.618669)
			(xy 102.936284 -281.565371) (xy 102.944227 -281.512667) (xy 102.959937 -281.461737) (xy 102.983063 -281.413716)
			(xy 103.013087 -281.369679) (xy 103.049339 -281.330608) (xy 103.09101 -281.297377) (xy 103.137168 -281.270728)
			(xy 103.186782 -281.251256) (xy 103.238744 -281.239396) (xy 103.291894 -281.235413) (xy 103.345044 -281.239396)
			(xy 103.397006 -281.251256) (xy 103.44662 -281.270728) (xy 103.492778 -281.297377) (xy 103.534449 -281.330608)
			(xy 103.570701 -281.369679) (xy 103.600725 -281.413716) (xy 103.623851 -281.461737) (xy 103.639561 -281.512667)
			(xy 103.647504 -281.565371) (xy 103.648002 -281.59202) (xy 103.647504 -281.618669) (xy 103.639561 -281.671373)
			(xy 103.623851 -281.722303) (xy 103.600725 -281.770324) (xy 103.570701 -281.814361) (xy 103.534449 -281.853432)
			(xy 103.492778 -281.886663) (xy 103.44662 -281.913312) (xy 103.397006 -281.932784) (xy 103.345044 -281.944644)
			(xy 103.291894 -281.948628) (xy 103.238744 -281.944644) (xy 103.186782 -281.932784) (xy 103.137168 -281.913312)
			(xy 103.09101 -281.886663) (xy 103.049339 -281.853432) (xy 103.013087 -281.814361) (xy 102.983063 -281.770324)
			(xy 102.959937 -281.722303) (xy 102.944227 -281.671373) (xy 102.936284 -281.618669) (xy 102.707866 -281.618669)
			(xy 102.700667 -281.66841) (xy 102.686118 -281.717582) (xy 102.664665 -281.764158) (xy 102.636753 -281.807175)
			(xy 102.602958 -281.845742) (xy 102.56398 -281.879063) (xy 102.520625 -281.906447) (xy 102.47379 -281.927328)
			(xy 102.424444 -281.941275) (xy 102.399084 -281.94508) (xy 102.374192 -281.948382) (xy 102.201726 -282.246832)
			(xy 102.211378 -282.269946) (xy 102.219905 -282.291574) (xy 102.231888 -282.336494) (xy 102.237929 -282.382591)
			(xy 102.238302 -282.405836) (xy 102.237804 -282.432485) (xy 102.466638 -282.432485) (xy 102.466638 -282.379187)
			(xy 102.474581 -282.326483) (xy 102.490291 -282.275553) (xy 102.513417 -282.227532) (xy 102.543441 -282.183495)
			(xy 102.579693 -282.144424) (xy 102.621364 -282.111193) (xy 102.667522 -282.084544) (xy 102.717136 -282.065072)
			(xy 102.769098 -282.053212) (xy 102.822248 -282.049229) (xy 102.875398 -282.053212) (xy 102.92736 -282.065072)
			(xy 102.976974 -282.084544) (xy 103.023132 -282.111193) (xy 103.064803 -282.144424) (xy 103.101055 -282.183495)
			(xy 103.131079 -282.227532) (xy 103.154205 -282.275553) (xy 103.169915 -282.326483) (xy 103.177858 -282.379187)
			(xy 103.178356 -282.405836) (xy 103.177858 -282.432485) (xy 103.169915 -282.485189) (xy 103.154205 -282.536119)
			(xy 103.131079 -282.58414) (xy 103.101055 -282.628177) (xy 103.064803 -282.667248) (xy 103.023132 -282.700479)
			(xy 102.976974 -282.727128) (xy 102.92736 -282.7466) (xy 102.875398 -282.75846) (xy 102.822248 -282.762444)
			(xy 102.769098 -282.75846) (xy 102.717136 -282.7466) (xy 102.667522 -282.727128) (xy 102.621364 -282.700479)
			(xy 102.579693 -282.667248) (xy 102.543441 -282.628177) (xy 102.513417 -282.58414) (xy 102.490291 -282.536119)
			(xy 102.474581 -282.485189) (xy 102.466638 -282.432485) (xy 102.237804 -282.432485) (xy 102.229861 -282.485189)
			(xy 102.214151 -282.536119) (xy 102.191025 -282.58414) (xy 102.161001 -282.628177) (xy 102.124749 -282.667248)
			(xy 102.083078 -282.700479) (xy 102.03692 -282.727128) (xy 101.987306 -282.7466) (xy 101.935344 -282.75846)
			(xy 101.882194 -282.762444) (xy 101.829044 -282.75846) (xy 101.777082 -282.7466) (xy 101.727468 -282.727128)
			(xy 101.68131 -282.700479) (xy 101.639639 -282.667248) (xy 101.603387 -282.628177) (xy 101.573363 -282.58414)
			(xy 101.550237 -282.536119) (xy 101.534527 -282.485189) (xy 101.526584 -282.432485) (xy 101.526086 -282.405836)
			(xy 101.298502 -282.405836) (xy 101.298004 -282.432485) (xy 101.290061 -282.485189) (xy 101.274351 -282.536119)
			(xy 101.251225 -282.58414) (xy 101.221201 -282.628177) (xy 101.184949 -282.667248) (xy 101.143278 -282.700479)
			(xy 101.09712 -282.727128) (xy 101.047506 -282.7466) (xy 100.995544 -282.75846) (xy 100.942394 -282.762444)
			(xy 100.889244 -282.75846) (xy 100.837282 -282.7466) (xy 100.787668 -282.727128) (xy 100.74151 -282.700479)
			(xy 100.699839 -282.667248) (xy 100.663587 -282.628177) (xy 100.633563 -282.58414) (xy 100.610437 -282.536119)
			(xy 100.594727 -282.485189) (xy 100.586784 -282.432485) (xy 100.358147 -282.432485) (xy 100.350975 -282.482168)
			(xy 100.336459 -282.531306) (xy 100.315049 -282.577857) (xy 100.287187 -282.620858) (xy 100.253449 -282.65942)
			(xy 100.214531 -282.692748) (xy 100.171237 -282.720153) (xy 100.124463 -282.741068) (xy 100.075173 -282.755062)
			(xy 100.049838 -282.758896) (xy 100.0252 -282.762198) (xy 99.85248 -283.060902) (xy 99.862132 -283.084016)
			(xy 99.870648 -283.105648) (xy 99.882636 -283.150566) (xy 99.888681 -283.196661) (xy 99.889056 -283.219906)
			(xy 99.888558 -283.246555) (xy 100.116884 -283.246555) (xy 100.116884 -283.193257) (xy 100.124827 -283.140553)
			(xy 100.140537 -283.089623) (xy 100.163663 -283.041602) (xy 100.193687 -282.997565) (xy 100.229939 -282.958494)
			(xy 100.27161 -282.925263) (xy 100.317768 -282.898614) (xy 100.367382 -282.879142) (xy 100.419344 -282.867282)
			(xy 100.472494 -282.863299) (xy 100.525644 -282.867282) (xy 100.577606 -282.879142) (xy 100.62722 -282.898614)
			(xy 100.673378 -282.925263) (xy 100.715049 -282.958494) (xy 100.751301 -282.997565) (xy 100.781325 -283.041602)
			(xy 100.804451 -283.089623) (xy 100.820161 -283.140553) (xy 100.828104 -283.193257) (xy 100.828602 -283.2199)
			(xy 101.055874 -283.2199) (xy 101.059858 -283.166743) (xy 101.071721 -283.114774) (xy 101.091197 -283.065153)
			(xy 101.117852 -283.01899) (xy 101.15109 -282.977316) (xy 101.190169 -282.941061) (xy 101.234215 -282.911037)
			(xy 101.282244 -282.887913) (xy 101.333183 -282.872206) (xy 101.385895 -282.864268) (xy 101.412548 -282.863798)
			(xy 101.437572 -282.864258) (xy 101.487128 -282.871259) (xy 101.535215 -282.885131) (xy 101.580885 -282.905599)
			(xy 101.62324 -282.932262) (xy 101.661443 -282.964593) (xy 101.694743 -283.001955) (xy 101.708966 -283.022548)
			(xy 102.05593 -283.022548) (xy 102.070124 -283.001933) (xy 102.103427 -282.964566) (xy 102.141635 -282.932232)
			(xy 102.183993 -282.905566) (xy 102.229669 -282.885095) (xy 102.277761 -282.871221) (xy 102.327321 -282.864219)
			(xy 102.352348 -282.863798) (xy 102.378995 -282.864287) (xy 102.431694 -282.872237) (xy 102.48262 -282.887951)
			(xy 102.530635 -282.91108) (xy 102.574666 -282.941105) (xy 102.613732 -282.977358) (xy 102.646958 -283.019028)
			(xy 102.673604 -283.065184) (xy 102.693073 -283.114795) (xy 102.704931 -283.166754) (xy 102.708914 -283.2199)
			(xy 102.706916 -283.246555) (xy 102.936284 -283.246555) (xy 102.936284 -283.193257) (xy 102.944227 -283.140553)
			(xy 102.959937 -283.089623) (xy 102.983063 -283.041602) (xy 103.013087 -282.997565) (xy 103.049339 -282.958494)
			(xy 103.09101 -282.925263) (xy 103.137168 -282.898614) (xy 103.186782 -282.879142) (xy 103.238744 -282.867282)
			(xy 103.291894 -282.863299) (xy 103.345044 -282.867282) (xy 103.397006 -282.879142) (xy 103.44662 -282.898614)
			(xy 103.492778 -282.925263) (xy 103.534449 -282.958494) (xy 103.570701 -282.997565) (xy 103.600725 -283.041602)
			(xy 103.623851 -283.089623) (xy 103.639561 -283.140553) (xy 103.647504 -283.193257) (xy 103.648002 -283.219906)
			(xy 103.647504 -283.246555) (xy 103.639561 -283.299259) (xy 103.623851 -283.350189) (xy 103.600725 -283.39821)
			(xy 103.570701 -283.442247) (xy 103.534449 -283.481318) (xy 103.492778 -283.514549) (xy 103.44662 -283.541198)
			(xy 103.397006 -283.56067) (xy 103.345044 -283.57253) (xy 103.291894 -283.576514) (xy 103.238744 -283.57253)
			(xy 103.186782 -283.56067) (xy 103.137168 -283.541198) (xy 103.09101 -283.514549) (xy 103.049339 -283.481318)
			(xy 103.013087 -283.442247) (xy 102.983063 -283.39821) (xy 102.959937 -283.350189) (xy 102.944227 -283.299259)
			(xy 102.936284 -283.246555) (xy 102.706916 -283.246555) (xy 102.704931 -283.273046) (xy 102.693073 -283.325005)
			(xy 102.673604 -283.374616) (xy 102.646958 -283.420772) (xy 102.613732 -283.462442) (xy 102.574666 -283.498695)
			(xy 102.530635 -283.52872) (xy 102.48262 -283.551849) (xy 102.431694 -283.567563) (xy 102.378995 -283.575513)
			(xy 102.352348 -283.576014) (xy 102.327324 -283.575552) (xy 102.277769 -283.56855) (xy 102.229682 -283.554679)
			(xy 102.184011 -283.53421) (xy 102.141657 -283.507548) (xy 102.103453 -283.475218) (xy 102.070153 -283.437857)
			(xy 102.05593 -283.417264) (xy 101.708966 -283.417264) (xy 101.694714 -283.437838) (xy 101.66142 -283.475204)
			(xy 101.623223 -283.507541) (xy 101.580874 -283.534211) (xy 101.535208 -283.55469) (xy 101.487125 -283.568573)
			(xy 101.437572 -283.575586) (xy 101.412548 -283.576014) (xy 101.385895 -283.575532) (xy 101.333183 -283.567594)
			(xy 101.282244 -283.551887) (xy 101.234215 -283.528763) (xy 101.190169 -283.498739) (xy 101.15109 -283.462484)
			(xy 101.117852 -283.42081) (xy 101.091197 -283.374647) (xy 101.071721 -283.325026) (xy 101.059858 -283.273057)
			(xy 101.055874 -283.2199) (xy 100.828602 -283.2199) (xy 100.828602 -283.219906) (xy 100.828104 -283.246555)
			(xy 100.820161 -283.299259) (xy 100.804451 -283.350189) (xy 100.781325 -283.39821) (xy 100.751301 -283.442247)
			(xy 100.715049 -283.481318) (xy 100.673378 -283.514549) (xy 100.62722 -283.541198) (xy 100.577606 -283.56067)
			(xy 100.525644 -283.57253) (xy 100.472494 -283.576514) (xy 100.419344 -283.57253) (xy 100.367382 -283.56067)
			(xy 100.317768 -283.541198) (xy 100.27161 -283.514549) (xy 100.229939 -283.481318) (xy 100.193687 -283.442247)
			(xy 100.163663 -283.39821) (xy 100.140537 -283.350189) (xy 100.124827 -283.299259) (xy 100.116884 -283.246555)
			(xy 99.888558 -283.246555) (xy 99.880615 -283.299259) (xy 99.864905 -283.350189) (xy 99.841779 -283.39821)
			(xy 99.811755 -283.442247) (xy 99.775503 -283.481318) (xy 99.733832 -283.514549) (xy 99.687674 -283.541198)
			(xy 99.63806 -283.56067) (xy 99.586098 -283.57253) (xy 99.532948 -283.576514) (xy 99.479798 -283.57253)
			(xy 99.427836 -283.56067) (xy 99.378222 -283.541198) (xy 99.332064 -283.514549) (xy 99.290393 -283.481318)
			(xy 99.254141 -283.442247) (xy 99.224117 -283.39821) (xy 99.200991 -283.350189) (xy 99.185281 -283.299259)
			(xy 99.177338 -283.246555) (xy 99.17684 -283.219906) (xy 98.949002 -283.219906) (xy 98.948504 -283.246555)
			(xy 98.940561 -283.299259) (xy 98.924851 -283.350189) (xy 98.901725 -283.39821) (xy 98.871701 -283.442247)
			(xy 98.835449 -283.481318) (xy 98.793778 -283.514549) (xy 98.74762 -283.541198) (xy 98.698006 -283.56067)
			(xy 98.646044 -283.57253) (xy 98.592894 -283.576514) (xy 98.539744 -283.57253) (xy 98.487782 -283.56067)
			(xy 98.438168 -283.541198) (xy 98.39201 -283.514549) (xy 98.350339 -283.481318) (xy 98.314087 -283.442247)
			(xy 98.284063 -283.39821) (xy 98.260937 -283.350189) (xy 98.245227 -283.299259) (xy 98.237284 -283.246555)
			(xy 98.008704 -283.246555) (xy 98.000761 -283.299259) (xy 97.985051 -283.350189) (xy 97.961925 -283.39821)
			(xy 97.931901 -283.442247) (xy 97.895649 -283.481318) (xy 97.853978 -283.514549) (xy 97.80782 -283.541198)
			(xy 97.758206 -283.56067) (xy 97.706244 -283.57253) (xy 97.653094 -283.576514) (xy 97.599944 -283.57253)
			(xy 97.547982 -283.56067) (xy 97.498368 -283.541198) (xy 97.45221 -283.514549) (xy 97.410539 -283.481318)
			(xy 97.374287 -283.442247) (xy 97.344263 -283.39821) (xy 97.321137 -283.350189) (xy 97.305427 -283.299259)
			(xy 97.297484 -283.246555) (xy 97.069158 -283.246555) (xy 97.061215 -283.299259) (xy 97.045505 -283.350189)
			(xy 97.022379 -283.39821) (xy 96.992355 -283.442247) (xy 96.956103 -283.481318) (xy 96.914432 -283.514549)
			(xy 96.868274 -283.541198) (xy 96.81866 -283.56067) (xy 96.766698 -283.57253) (xy 96.713548 -283.576514)
			(xy 96.660398 -283.57253) (xy 96.608436 -283.56067) (xy 96.558822 -283.541198) (xy 96.512664 -283.514549)
			(xy 96.470993 -283.481318) (xy 96.434741 -283.442247) (xy 96.404717 -283.39821) (xy 96.381591 -283.350189)
			(xy 96.365881 -283.299259) (xy 96.357938 -283.246555) (xy 96.35744 -283.219906) (xy 96.357808 -283.196661)
			(xy 96.363855 -283.150565) (xy 96.375846 -283.105648) (xy 96.384364 -283.084016) (xy 96.394016 -283.060902)
			(xy 96.221296 -282.762198) (xy 96.196658 -282.758896) (xy 96.171298 -282.755106) (xy 96.121959 -282.741144)
			(xy 96.075131 -282.720252) (xy 96.031784 -282.692861) (xy 95.992811 -282.659538) (xy 95.959019 -282.620972)
			(xy 95.931107 -282.577958) (xy 95.90965 -282.531387) (xy 95.895092 -282.48222) (xy 95.887735 -282.431474)
			(xy 95.887286 -282.405836) (xy 95.659702 -282.405836) (xy 95.659204 -282.432485) (xy 95.651261 -282.485189)
			(xy 95.635551 -282.536119) (xy 95.612425 -282.58414) (xy 95.582401 -282.628177) (xy 95.546149 -282.667248)
			(xy 95.504478 -282.700479) (xy 95.45832 -282.727128) (xy 95.408706 -282.7466) (xy 95.356744 -282.75846)
			(xy 95.303594 -282.762444) (xy 95.250444 -282.75846) (xy 95.198482 -282.7466) (xy 95.148868 -282.727128)
			(xy 95.10271 -282.700479) (xy 95.061039 -282.667248) (xy 95.024787 -282.628177) (xy 94.994763 -282.58414)
			(xy 94.971637 -282.536119) (xy 94.955927 -282.485189) (xy 94.947984 -282.432485) (xy 94.947486 -282.405836)
			(xy 94.720156 -282.405836) (xy 94.719658 -282.432485) (xy 94.711715 -282.485189) (xy 94.696005 -282.536119)
			(xy 94.672879 -282.58414) (xy 94.642855 -282.628177) (xy 94.606603 -282.667248) (xy 94.564932 -282.700479)
			(xy 94.518774 -282.727128) (xy 94.46916 -282.7466) (xy 94.417198 -282.75846) (xy 94.364048 -282.762444)
			(xy 94.310898 -282.75846) (xy 94.258936 -282.7466) (xy 94.209322 -282.727128) (xy 94.163164 -282.700479)
			(xy 94.121493 -282.667248) (xy 94.085241 -282.628177) (xy 94.055217 -282.58414) (xy 94.032091 -282.536119)
			(xy 94.016381 -282.485189) (xy 94.008438 -282.432485) (xy 93.779858 -282.432485) (xy 93.771915 -282.485189)
			(xy 93.756205 -282.536119) (xy 93.733079 -282.58414) (xy 93.703055 -282.628177) (xy 93.666803 -282.667248)
			(xy 93.625132 -282.700479) (xy 93.578974 -282.727128) (xy 93.52936 -282.7466) (xy 93.477398 -282.75846)
			(xy 93.424248 -282.762444) (xy 93.371098 -282.75846) (xy 93.319136 -282.7466) (xy 93.269522 -282.727128)
			(xy 93.223364 -282.700479) (xy 93.181693 -282.667248) (xy 93.145441 -282.628177) (xy 93.115417 -282.58414)
			(xy 93.092291 -282.536119) (xy 93.076581 -282.485189) (xy 93.068638 -282.432485) (xy 93.06814 -282.405836)
			(xy 92.840556 -282.405836) (xy 92.840058 -282.432485) (xy 92.832115 -282.485189) (xy 92.816405 -282.536119)
			(xy 92.793279 -282.58414) (xy 92.763255 -282.628177) (xy 92.727003 -282.667248) (xy 92.685332 -282.700479)
			(xy 92.639174 -282.727128) (xy 92.58956 -282.7466) (xy 92.537598 -282.75846) (xy 92.484448 -282.762444)
			(xy 92.431298 -282.75846) (xy 92.379336 -282.7466) (xy 92.329722 -282.727128) (xy 92.283564 -282.700479)
			(xy 92.241893 -282.667248) (xy 92.205641 -282.628177) (xy 92.175617 -282.58414) (xy 92.152491 -282.536119)
			(xy 92.136781 -282.485189) (xy 92.128838 -282.432485) (xy 91.900181 -282.432485) (xy 91.89298 -282.482227)
			(xy 91.878429 -282.531399) (xy 91.856974 -282.577975) (xy 91.829059 -282.620992) (xy 91.795263 -282.659559)
			(xy 91.756283 -282.692879) (xy 91.712927 -282.720263) (xy 91.666091 -282.741145) (xy 91.616744 -282.755091)
			(xy 91.591384 -282.758896) (xy 91.566492 -282.762198) (xy 91.394026 -283.060902) (xy 91.403678 -283.084016)
			(xy 91.412196 -283.105647) (xy 91.424183 -283.150565) (xy 91.430227 -283.196661) (xy 91.430602 -283.219906)
			(xy 91.430104 -283.246555) (xy 91.658684 -283.246555) (xy 91.658684 -283.193257) (xy 91.666627 -283.140553)
			(xy 91.682337 -283.089623) (xy 91.705463 -283.041602) (xy 91.735487 -282.997565) (xy 91.771739 -282.958494)
			(xy 91.81341 -282.925263) (xy 91.859568 -282.898614) (xy 91.909182 -282.879142) (xy 91.961144 -282.867282)
			(xy 92.014294 -282.863299) (xy 92.067444 -282.867282) (xy 92.119406 -282.879142) (xy 92.16902 -282.898614)
			(xy 92.215178 -282.925263) (xy 92.256849 -282.958494) (xy 92.293101 -282.997565) (xy 92.323125 -283.041602)
			(xy 92.346251 -283.089623) (xy 92.361961 -283.140553) (xy 92.369904 -283.193257) (xy 92.370402 -283.2199)
			(xy 92.597498 -283.2199) (xy 92.601481 -283.166752) (xy 92.613341 -283.114791) (xy 92.632812 -283.065178)
			(xy 92.659461 -283.019021) (xy 92.692691 -282.977351) (xy 92.73176 -282.9411) (xy 92.775796 -282.911076)
			(xy 92.823815 -282.887951) (xy 92.874744 -282.87224) (xy 92.927445 -282.864296) (xy 92.954094 -282.863798)
			(xy 92.979119 -282.864223) (xy 93.028676 -282.87123) (xy 93.076764 -282.885108) (xy 93.122435 -282.905583)
			(xy 93.164789 -282.93225) (xy 93.202992 -282.964586) (xy 93.23629 -283.001953) (xy 93.250512 -283.022548)
			(xy 93.597476 -283.022548) (xy 93.611705 -283.001958) (xy 93.645002 -282.964591) (xy 93.683203 -282.932255)
			(xy 93.725556 -282.905586) (xy 93.771226 -282.885111) (xy 93.819313 -282.871232) (xy 93.868869 -282.864223)
			(xy 93.893894 -282.863798) (xy 93.920546 -282.864259) (xy 93.973254 -282.872203) (xy 94.02419 -282.887913)
			(xy 94.072216 -282.91104) (xy 94.116257 -282.941067) (xy 94.155332 -282.977322) (xy 94.188567 -283.018997)
			(xy 94.215219 -283.065159) (xy 94.234693 -283.114778) (xy 94.246555 -283.166745) (xy 94.250538 -283.2199)
			(xy 94.248541 -283.246555) (xy 94.478084 -283.246555) (xy 94.478084 -283.193257) (xy 94.486027 -283.140553)
			(xy 94.501737 -283.089623) (xy 94.524863 -283.041602) (xy 94.554887 -282.997565) (xy 94.591139 -282.958494)
			(xy 94.63281 -282.925263) (xy 94.678968 -282.898614) (xy 94.728582 -282.879142) (xy 94.780544 -282.867282)
			(xy 94.833694 -282.863299) (xy 94.886844 -282.867282) (xy 94.938806 -282.879142) (xy 94.98842 -282.898614)
			(xy 95.034578 -282.925263) (xy 95.076249 -282.958494) (xy 95.112501 -282.997565) (xy 95.142525 -283.041602)
			(xy 95.165651 -283.089623) (xy 95.181361 -283.140553) (xy 95.189304 -283.193257) (xy 95.189802 -283.219906)
			(xy 95.189304 -283.246555) (xy 95.417884 -283.246555) (xy 95.417884 -283.193257) (xy 95.425827 -283.140553)
			(xy 95.441537 -283.089623) (xy 95.464663 -283.041602) (xy 95.494687 -282.997565) (xy 95.530939 -282.958494)
			(xy 95.57261 -282.925263) (xy 95.618768 -282.898614) (xy 95.668382 -282.879142) (xy 95.720344 -282.867282)
			(xy 95.773494 -282.863299) (xy 95.826644 -282.867282) (xy 95.878606 -282.879142) (xy 95.92822 -282.898614)
			(xy 95.974378 -282.925263) (xy 96.016049 -282.958494) (xy 96.052301 -282.997565) (xy 96.082325 -283.041602)
			(xy 96.105451 -283.089623) (xy 96.121161 -283.140553) (xy 96.129104 -283.193257) (xy 96.129602 -283.219906)
			(xy 96.129104 -283.246555) (xy 96.121161 -283.299259) (xy 96.105451 -283.350189) (xy 96.082325 -283.39821)
			(xy 96.052301 -283.442247) (xy 96.016049 -283.481318) (xy 95.974378 -283.514549) (xy 95.92822 -283.541198)
			(xy 95.878606 -283.56067) (xy 95.826644 -283.57253) (xy 95.773494 -283.576514) (xy 95.720344 -283.57253)
			(xy 95.668382 -283.56067) (xy 95.618768 -283.541198) (xy 95.57261 -283.514549) (xy 95.530939 -283.481318)
			(xy 95.494687 -283.442247) (xy 95.464663 -283.39821) (xy 95.441537 -283.350189) (xy 95.425827 -283.299259)
			(xy 95.417884 -283.246555) (xy 95.189304 -283.246555) (xy 95.181361 -283.299259) (xy 95.165651 -283.350189)
			(xy 95.142525 -283.39821) (xy 95.112501 -283.442247) (xy 95.076249 -283.481318) (xy 95.034578 -283.514549)
			(xy 94.98842 -283.541198) (xy 94.938806 -283.56067) (xy 94.886844 -283.57253) (xy 94.833694 -283.576514)
			(xy 94.780544 -283.57253) (xy 94.728582 -283.56067) (xy 94.678968 -283.541198) (xy 94.63281 -283.514549)
			(xy 94.591139 -283.481318) (xy 94.554887 -283.442247) (xy 94.524863 -283.39821) (xy 94.501737 -283.350189)
			(xy 94.486027 -283.299259) (xy 94.478084 -283.246555) (xy 94.248541 -283.246555) (xy 94.246555 -283.273055)
			(xy 94.234693 -283.325022) (xy 94.215219 -283.374641) (xy 94.188567 -283.420803) (xy 94.155332 -283.462478)
			(xy 94.116257 -283.498733) (xy 94.072216 -283.52876) (xy 94.02419 -283.551887) (xy 93.973254 -283.567597)
			(xy 93.920546 -283.575541) (xy 93.893894 -283.576014) (xy 93.868869 -283.575593) (xy 93.819312 -283.568584)
			(xy 93.771224 -283.554705) (xy 93.725553 -283.53423) (xy 93.683199 -283.507562) (xy 93.644997 -283.475226)
			(xy 93.611698 -283.437859) (xy 93.597476 -283.417264) (xy 93.250512 -283.417264) (xy 93.236294 -283.437863)
			(xy 93.202995 -283.475229) (xy 93.164792 -283.507564) (xy 93.122437 -283.534231) (xy 93.076765 -283.554705)
			(xy 93.028677 -283.568583) (xy 92.979119 -283.57559) (xy 92.954094 -283.576014) (xy 92.927445 -283.575504)
			(xy 92.874744 -283.56756) (xy 92.823815 -283.551849) (xy 92.775796 -283.528724) (xy 92.73176 -283.4987)
			(xy 92.692691 -283.462449) (xy 92.659461 -283.420779) (xy 92.632812 -283.374622) (xy 92.613341 -283.325009)
			(xy 92.601481 -283.273048) (xy 92.597498 -283.2199) (xy 92.370402 -283.2199) (xy 92.370402 -283.219906)
			(xy 92.369904 -283.246555) (xy 92.361961 -283.299259) (xy 92.346251 -283.350189) (xy 92.323125 -283.39821)
			(xy 92.293101 -283.442247) (xy 92.256849 -283.481318) (xy 92.215178 -283.514549) (xy 92.16902 -283.541198)
			(xy 92.119406 -283.56067) (xy 92.067444 -283.57253) (xy 92.014294 -283.576514) (xy 91.961144 -283.57253)
			(xy 91.909182 -283.56067) (xy 91.859568 -283.541198) (xy 91.81341 -283.514549) (xy 91.771739 -283.481318)
			(xy 91.735487 -283.442247) (xy 91.705463 -283.39821) (xy 91.682337 -283.350189) (xy 91.666627 -283.299259)
			(xy 91.658684 -283.246555) (xy 91.430104 -283.246555) (xy 91.422161 -283.299259) (xy 91.406451 -283.350189)
			(xy 91.383325 -283.39821) (xy 91.353301 -283.442247) (xy 91.317049 -283.481318) (xy 91.275378 -283.514549)
			(xy 91.22922 -283.541198) (xy 91.179606 -283.56067) (xy 91.127644 -283.57253) (xy 91.074494 -283.576514)
			(xy 91.021344 -283.57253) (xy 90.969382 -283.56067) (xy 90.919768 -283.541198) (xy 90.87361 -283.514549)
			(xy 90.831939 -283.481318) (xy 90.795687 -283.442247) (xy 90.765663 -283.39821) (xy 90.742537 -283.350189)
			(xy 90.726827 -283.299259) (xy 90.718884 -283.246555) (xy 90.718386 -283.219906) (xy 90.490802 -283.219906)
			(xy 90.490304 -283.246555) (xy 90.482361 -283.299259) (xy 90.466651 -283.350189) (xy 90.443525 -283.39821)
			(xy 90.413501 -283.442247) (xy 90.377249 -283.481318) (xy 90.335578 -283.514549) (xy 90.28942 -283.541198)
			(xy 90.239806 -283.56067) (xy 90.187844 -283.57253) (xy 90.134694 -283.576514) (xy 90.081544 -283.57253)
			(xy 90.029582 -283.56067) (xy 89.979968 -283.541198) (xy 89.93381 -283.514549) (xy 89.892139 -283.481318)
			(xy 89.855887 -283.442247) (xy 89.825863 -283.39821) (xy 89.802737 -283.350189) (xy 89.787027 -283.299259)
			(xy 89.779084 -283.246555) (xy 89.550504 -283.246555) (xy 89.542561 -283.299259) (xy 89.526851 -283.350189)
			(xy 89.503725 -283.39821) (xy 89.473701 -283.442247) (xy 89.437449 -283.481318) (xy 89.395778 -283.514549)
			(xy 89.34962 -283.541198) (xy 89.300006 -283.56067) (xy 89.248044 -283.57253) (xy 89.194894 -283.576514)
			(xy 89.141744 -283.57253) (xy 89.089782 -283.56067) (xy 89.040168 -283.541198) (xy 88.99401 -283.514549)
			(xy 88.952339 -283.481318) (xy 88.916087 -283.442247) (xy 88.886063 -283.39821) (xy 88.862937 -283.350189)
			(xy 88.847227 -283.299259) (xy 88.839284 -283.246555) (xy 88.610704 -283.246555) (xy 88.602761 -283.299259)
			(xy 88.587051 -283.350189) (xy 88.563925 -283.39821) (xy 88.533901 -283.442247) (xy 88.497649 -283.481318)
			(xy 88.455978 -283.514549) (xy 88.40982 -283.541198) (xy 88.360206 -283.56067) (xy 88.308244 -283.57253)
			(xy 88.255094 -283.576514) (xy 88.201944 -283.57253) (xy 88.149982 -283.56067) (xy 88.100368 -283.541198)
			(xy 88.05421 -283.514549) (xy 88.012539 -283.481318) (xy 87.976287 -283.442247) (xy 87.946263 -283.39821)
			(xy 87.923137 -283.350189) (xy 87.907427 -283.299259) (xy 87.899484 -283.246555) (xy 87.898986 -283.219906)
			(xy 87.899358 -283.196661) (xy 87.905403 -283.150565) (xy 87.917393 -283.105648) (xy 87.92591 -283.084016)
			(xy 87.935562 -283.060902) (xy 87.762842 -282.762198) (xy 87.738204 -282.758896) (xy 87.712863 -282.755058)
			(xy 87.663557 -282.741071) (xy 87.616765 -282.720163) (xy 87.573452 -282.692764) (xy 87.534512 -282.659441)
			(xy 87.500751 -282.620881) (xy 87.472864 -282.577881) (xy 87.451427 -282.531328) (xy 87.436884 -282.482183)
			(xy 87.429534 -282.431462) (xy 87.429086 -282.405836) (xy 87.201756 -282.405836) (xy 87.201258 -282.432485)
			(xy 87.193315 -282.485189) (xy 87.177605 -282.536119) (xy 87.154479 -282.58414) (xy 87.124455 -282.628177)
			(xy 87.088203 -282.667248) (xy 87.046532 -282.700479) (xy 87.000374 -282.727128) (xy 86.95076 -282.7466)
			(xy 86.898798 -282.75846) (xy 86.845648 -282.762444) (xy 86.792498 -282.75846) (xy 86.740536 -282.7466)
			(xy 86.690922 -282.727128) (xy 86.644764 -282.700479) (xy 86.603093 -282.667248) (xy 86.566841 -282.628177)
			(xy 86.536817 -282.58414) (xy 86.513691 -282.536119) (xy 86.497981 -282.485189) (xy 86.490038 -282.432485)
			(xy 86.48954 -282.405836) (xy 86.262193 -282.405836) (xy 86.258213 -282.458948) (xy 86.246353 -282.51091)
			(xy 86.226881 -282.560523) (xy 86.200232 -282.60668) (xy 86.167001 -282.648349) (xy 86.127931 -282.6846)
			(xy 86.083895 -282.714623) (xy 86.035875 -282.737748) (xy 85.984945 -282.753457) (xy 85.932243 -282.761399)
			(xy 85.905594 -282.761944) (xy 85.876625 -282.761377) (xy 85.819451 -282.752006) (xy 85.764545 -282.733512)
			(xy 85.713352 -282.70638) (xy 85.689948 -282.6893) (xy 85.678429 -282.681126) (xy 85.652128 -282.670858)
			(xy 85.62402 -282.668185) (xy 85.596255 -282.673312) (xy 85.570955 -282.685846) (xy 85.550054 -282.704829)
			(xy 85.535151 -282.72881) (xy 85.527385 -282.755955) (xy 85.52688 -282.770072) (xy 85.52688 -282.873958)
			(xy 85.5599 -282.88615) (xy 85.585072 -282.896054) (xy 85.632331 -282.92237) (xy 85.675067 -282.955529)
			(xy 85.712296 -282.994771) (xy 85.743162 -283.039192) (xy 85.766955 -283.087769) (xy 85.783127 -283.139387)
			(xy 85.791308 -283.192856) (xy 85.791307 -283.246555) (xy 86.019884 -283.246555) (xy 86.019884 -283.193257)
			(xy 86.027827 -283.140553) (xy 86.043537 -283.089623) (xy 86.066663 -283.041602) (xy 86.096687 -282.997565)
			(xy 86.132939 -282.958494) (xy 86.17461 -282.925263) (xy 86.220768 -282.898614) (xy 86.270382 -282.879142)
			(xy 86.322344 -282.867282) (xy 86.375494 -282.863299) (xy 86.428644 -282.867282) (xy 86.480606 -282.879142)
			(xy 86.53022 -282.898614) (xy 86.576378 -282.925263) (xy 86.618049 -282.958494) (xy 86.654301 -282.997565)
			(xy 86.684325 -283.041602) (xy 86.707451 -283.089623) (xy 86.723161 -283.140553) (xy 86.731104 -283.193257)
			(xy 86.731602 -283.219906) (xy 86.731104 -283.246555) (xy 86.959684 -283.246555) (xy 86.959684 -283.193257)
			(xy 86.967627 -283.140553) (xy 86.983337 -283.089623) (xy 87.006463 -283.041602) (xy 87.036487 -282.997565)
			(xy 87.072739 -282.958494) (xy 87.11441 -282.925263) (xy 87.160568 -282.898614) (xy 87.210182 -282.879142)
			(xy 87.262144 -282.867282) (xy 87.315294 -282.863299) (xy 87.368444 -282.867282) (xy 87.420406 -282.879142)
			(xy 87.47002 -282.898614) (xy 87.516178 -282.925263) (xy 87.557849 -282.958494) (xy 87.594101 -282.997565)
			(xy 87.624125 -283.041602) (xy 87.647251 -283.089623) (xy 87.662961 -283.140553) (xy 87.670904 -283.193257)
			(xy 87.671402 -283.219906) (xy 87.670904 -283.246555) (xy 87.662961 -283.299259) (xy 87.647251 -283.350189)
			(xy 87.624125 -283.39821) (xy 87.594101 -283.442247) (xy 87.557849 -283.481318) (xy 87.516178 -283.514549)
			(xy 87.47002 -283.541198) (xy 87.420406 -283.56067) (xy 87.368444 -283.57253) (xy 87.315294 -283.576514)
			(xy 87.262144 -283.57253) (xy 87.210182 -283.56067) (xy 87.160568 -283.541198) (xy 87.11441 -283.514549)
			(xy 87.072739 -283.481318) (xy 87.036487 -283.442247) (xy 87.006463 -283.39821) (xy 86.983337 -283.350189)
			(xy 86.967627 -283.299259) (xy 86.959684 -283.246555) (xy 86.731104 -283.246555) (xy 86.723161 -283.299259)
			(xy 86.707451 -283.350189) (xy 86.684325 -283.39821) (xy 86.654301 -283.442247) (xy 86.618049 -283.481318)
			(xy 86.576378 -283.514549) (xy 86.53022 -283.541198) (xy 86.480606 -283.56067) (xy 86.428644 -283.57253)
			(xy 86.375494 -283.576514) (xy 86.322344 -283.57253) (xy 86.270382 -283.56067) (xy 86.220768 -283.541198)
			(xy 86.17461 -283.514549) (xy 86.132939 -283.481318) (xy 86.096687 -283.442247) (xy 86.066663 -283.39821)
			(xy 86.043537 -283.350189) (xy 86.027827 -283.299259) (xy 86.019884 -283.246555) (xy 85.791307 -283.246555)
			(xy 85.791307 -283.246948) (xy 85.783126 -283.300417) (xy 85.766953 -283.352034) (xy 85.74316 -283.400612)
			(xy 85.712293 -283.445032) (xy 85.675064 -283.484273) (xy 85.632328 -283.517433) (xy 85.585068 -283.543748)
			(xy 85.5599 -283.553662) (xy 85.52688 -283.565854) (xy 85.52688 -284.033722) (xy 86.48954 -284.033722)
			(xy 86.490038 -284.007073) (xy 86.497981 -283.954369) (xy 86.513691 -283.903439) (xy 86.536817 -283.855418)
			(xy 86.566841 -283.811381) (xy 86.603093 -283.77231) (xy 86.644764 -283.739079) (xy 86.690922 -283.71243)
			(xy 86.740536 -283.692958) (xy 86.792498 -283.681098) (xy 86.845648 -283.677115) (xy 86.898798 -283.681098)
			(xy 86.95076 -283.692958) (xy 87.000374 -283.71243) (xy 87.046532 -283.739079) (xy 87.088203 -283.77231)
			(xy 87.124455 -283.811381) (xy 87.154479 -283.855418) (xy 87.177605 -283.903439) (xy 87.193315 -283.954369)
			(xy 87.201258 -284.007073) (xy 87.201756 -284.033722) (xy 87.201397 -284.056968) (xy 87.20095 -284.060371)
			(xy 87.429584 -284.060371) (xy 87.429584 -284.007073) (xy 87.437527 -283.954369) (xy 87.453237 -283.903439)
			(xy 87.476363 -283.855418) (xy 87.506387 -283.811381) (xy 87.542639 -283.77231) (xy 87.58431 -283.739079)
			(xy 87.630468 -283.71243) (xy 87.680082 -283.692958) (xy 87.732044 -283.681098) (xy 87.785194 -283.677115)
			(xy 87.838344 -283.681098) (xy 87.890306 -283.692958) (xy 87.93992 -283.71243) (xy 87.986078 -283.739079)
			(xy 88.027749 -283.77231) (xy 88.064001 -283.811381) (xy 88.094025 -283.855418) (xy 88.117151 -283.903439)
			(xy 88.132861 -283.954369) (xy 88.140804 -284.007073) (xy 88.141302 -284.033722) (xy 88.140804 -284.060371)
			(xy 88.369638 -284.060371) (xy 88.369638 -284.007073) (xy 88.377581 -283.954369) (xy 88.393291 -283.903439)
			(xy 88.416417 -283.855418) (xy 88.446441 -283.811381) (xy 88.482693 -283.77231) (xy 88.524364 -283.739079)
			(xy 88.570522 -283.71243) (xy 88.620136 -283.692958) (xy 88.672098 -283.681098) (xy 88.725248 -283.677115)
			(xy 88.778398 -283.681098) (xy 88.83036 -283.692958) (xy 88.879974 -283.71243) (xy 88.926132 -283.739079)
			(xy 88.967803 -283.77231) (xy 89.004055 -283.811381) (xy 89.034079 -283.855418) (xy 89.057205 -283.903439)
			(xy 89.072915 -283.954369) (xy 89.080858 -284.007073) (xy 89.081356 -284.033722) (xy 89.080858 -284.060371)
			(xy 90.248984 -284.060371) (xy 90.248984 -284.007073) (xy 90.256927 -283.954369) (xy 90.272637 -283.903439)
			(xy 90.295763 -283.855418) (xy 90.325787 -283.811381) (xy 90.362039 -283.77231) (xy 90.40371 -283.739079)
			(xy 90.449868 -283.71243) (xy 90.499482 -283.692958) (xy 90.551444 -283.681098) (xy 90.604594 -283.677115)
			(xy 90.657744 -283.681098) (xy 90.709706 -283.692958) (xy 90.75932 -283.71243) (xy 90.805478 -283.739079)
			(xy 90.847149 -283.77231) (xy 90.883401 -283.811381) (xy 90.913425 -283.855418) (xy 90.936551 -283.903439)
			(xy 90.952261 -283.954369) (xy 90.960204 -284.007073) (xy 90.960702 -284.033722) (xy 90.960204 -284.060371)
			(xy 91.188784 -284.060371) (xy 91.188784 -284.007073) (xy 91.196727 -283.954369) (xy 91.212437 -283.903439)
			(xy 91.235563 -283.855418) (xy 91.265587 -283.811381) (xy 91.301839 -283.77231) (xy 91.34351 -283.739079)
			(xy 91.389668 -283.71243) (xy 91.439282 -283.692958) (xy 91.491244 -283.681098) (xy 91.544394 -283.677115)
			(xy 91.597544 -283.681098) (xy 91.649506 -283.692958) (xy 91.69912 -283.71243) (xy 91.745278 -283.739079)
			(xy 91.786949 -283.77231) (xy 91.823201 -283.811381) (xy 91.853225 -283.855418) (xy 91.876351 -283.903439)
			(xy 91.892061 -283.954369) (xy 91.900004 -284.007073) (xy 91.900502 -284.033722) (xy 91.900004 -284.060371)
			(xy 92.128584 -284.060371) (xy 92.128584 -284.007073) (xy 92.136527 -283.954369) (xy 92.152237 -283.903439)
			(xy 92.175363 -283.855418) (xy 92.205387 -283.811381) (xy 92.241639 -283.77231) (xy 92.28331 -283.739079)
			(xy 92.329468 -283.71243) (xy 92.379082 -283.692958) (xy 92.431044 -283.681098) (xy 92.484194 -283.677115)
			(xy 92.537344 -283.681098) (xy 92.589306 -283.692958) (xy 92.63892 -283.71243) (xy 92.685078 -283.739079)
			(xy 92.726749 -283.77231) (xy 92.763001 -283.811381) (xy 92.793025 -283.855418) (xy 92.816151 -283.903439)
			(xy 92.831861 -283.954369) (xy 92.839804 -284.007073) (xy 92.840302 -284.033722) (xy 92.839804 -284.060371)
			(xy 93.068384 -284.060371) (xy 93.068384 -284.007073) (xy 93.076327 -283.954369) (xy 93.092037 -283.903439)
			(xy 93.115163 -283.855418) (xy 93.145187 -283.811381) (xy 93.181439 -283.77231) (xy 93.22311 -283.739079)
			(xy 93.269268 -283.71243) (xy 93.318882 -283.692958) (xy 93.370844 -283.681098) (xy 93.423994 -283.677115)
			(xy 93.477144 -283.681098) (xy 93.529106 -283.692958) (xy 93.57872 -283.71243) (xy 93.624878 -283.739079)
			(xy 93.666549 -283.77231) (xy 93.702801 -283.811381) (xy 93.732825 -283.855418) (xy 93.755951 -283.903439)
			(xy 93.771661 -283.954369) (xy 93.779604 -284.007073) (xy 93.780102 -284.033722) (xy 93.779604 -284.060371)
			(xy 94.008184 -284.060371) (xy 94.008184 -284.007073) (xy 94.016127 -283.954369) (xy 94.031837 -283.903439)
			(xy 94.054963 -283.855418) (xy 94.084987 -283.811381) (xy 94.121239 -283.77231) (xy 94.16291 -283.739079)
			(xy 94.209068 -283.71243) (xy 94.258682 -283.692958) (xy 94.310644 -283.681098) (xy 94.363794 -283.677115)
			(xy 94.416944 -283.681098) (xy 94.468906 -283.692958) (xy 94.51852 -283.71243) (xy 94.564678 -283.739079)
			(xy 94.606349 -283.77231) (xy 94.642601 -283.811381) (xy 94.672625 -283.855418) (xy 94.695751 -283.903439)
			(xy 94.711461 -283.954369) (xy 94.719404 -284.007073) (xy 94.719902 -284.033722) (xy 94.719404 -284.060371)
			(xy 94.947984 -284.060371) (xy 94.947984 -284.007073) (xy 94.955927 -283.954369) (xy 94.971637 -283.903439)
			(xy 94.994763 -283.855418) (xy 95.024787 -283.811381) (xy 95.061039 -283.77231) (xy 95.10271 -283.739079)
			(xy 95.148868 -283.71243) (xy 95.198482 -283.692958) (xy 95.250444 -283.681098) (xy 95.303594 -283.677115)
			(xy 95.356744 -283.681098) (xy 95.408706 -283.692958) (xy 95.45832 -283.71243) (xy 95.504478 -283.739079)
			(xy 95.546149 -283.77231) (xy 95.582401 -283.811381) (xy 95.612425 -283.855418) (xy 95.635551 -283.903439)
			(xy 95.651261 -283.954369) (xy 95.659204 -284.007073) (xy 95.659702 -284.033722) (xy 95.659204 -284.060371)
			(xy 95.887784 -284.060371) (xy 95.887784 -284.007073) (xy 95.895727 -283.954369) (xy 95.911437 -283.903439)
			(xy 95.934563 -283.855418) (xy 95.964587 -283.811381) (xy 96.000839 -283.77231) (xy 96.04251 -283.739079)
			(xy 96.088668 -283.71243) (xy 96.138282 -283.692958) (xy 96.190244 -283.681098) (xy 96.243394 -283.677115)
			(xy 96.296544 -283.681098) (xy 96.348506 -283.692958) (xy 96.39812 -283.71243) (xy 96.444278 -283.739079)
			(xy 96.485949 -283.77231) (xy 96.522201 -283.811381) (xy 96.552225 -283.855418) (xy 96.575351 -283.903439)
			(xy 96.591061 -283.954369) (xy 96.599004 -284.007073) (xy 96.599502 -284.033722) (xy 96.599004 -284.060371)
			(xy 96.827584 -284.060371) (xy 96.827584 -284.007073) (xy 96.835527 -283.954369) (xy 96.851237 -283.903439)
			(xy 96.874363 -283.855418) (xy 96.904387 -283.811381) (xy 96.940639 -283.77231) (xy 96.98231 -283.739079)
			(xy 97.028468 -283.71243) (xy 97.078082 -283.692958) (xy 97.130044 -283.681098) (xy 97.183194 -283.677115)
			(xy 97.236344 -283.681098) (xy 97.288306 -283.692958) (xy 97.33792 -283.71243) (xy 97.384078 -283.739079)
			(xy 97.425749 -283.77231) (xy 97.462001 -283.811381) (xy 97.492025 -283.855418) (xy 97.515151 -283.903439)
			(xy 97.530861 -283.954369) (xy 97.538804 -284.007073) (xy 97.539302 -284.033722) (xy 97.538804 -284.060371)
			(xy 97.767384 -284.060371) (xy 97.767384 -284.007073) (xy 97.775327 -283.954369) (xy 97.791037 -283.903439)
			(xy 97.814163 -283.855418) (xy 97.844187 -283.811381) (xy 97.880439 -283.77231) (xy 97.92211 -283.739079)
			(xy 97.968268 -283.71243) (xy 98.017882 -283.692958) (xy 98.069844 -283.681098) (xy 98.122994 -283.677115)
			(xy 98.176144 -283.681098) (xy 98.228106 -283.692958) (xy 98.27772 -283.71243) (xy 98.323878 -283.739079)
			(xy 98.365549 -283.77231) (xy 98.401801 -283.811381) (xy 98.431825 -283.855418) (xy 98.454951 -283.903439)
			(xy 98.470661 -283.954369) (xy 98.478604 -284.007073) (xy 98.479102 -284.033722) (xy 98.478604 -284.060371)
			(xy 98.707184 -284.060371) (xy 98.707184 -284.007073) (xy 98.715127 -283.954369) (xy 98.730837 -283.903439)
			(xy 98.753963 -283.855418) (xy 98.783987 -283.811381) (xy 98.820239 -283.77231) (xy 98.86191 -283.739079)
			(xy 98.908068 -283.71243) (xy 98.957682 -283.692958) (xy 99.009644 -283.681098) (xy 99.062794 -283.677115)
			(xy 99.115944 -283.681098) (xy 99.167906 -283.692958) (xy 99.21752 -283.71243) (xy 99.263678 -283.739079)
			(xy 99.305349 -283.77231) (xy 99.341601 -283.811381) (xy 99.371625 -283.855418) (xy 99.394751 -283.903439)
			(xy 99.410461 -283.954369) (xy 99.418404 -284.007073) (xy 99.418902 -284.033722) (xy 99.418404 -284.060371)
			(xy 99.646984 -284.060371) (xy 99.646984 -284.007073) (xy 99.654927 -283.954369) (xy 99.670637 -283.903439)
			(xy 99.693763 -283.855418) (xy 99.723787 -283.811381) (xy 99.760039 -283.77231) (xy 99.80171 -283.739079)
			(xy 99.847868 -283.71243) (xy 99.897482 -283.692958) (xy 99.949444 -283.681098) (xy 100.002594 -283.677115)
			(xy 100.055744 -283.681098) (xy 100.107706 -283.692958) (xy 100.15732 -283.71243) (xy 100.203478 -283.739079)
			(xy 100.245149 -283.77231) (xy 100.281401 -283.811381) (xy 100.311425 -283.855418) (xy 100.334551 -283.903439)
			(xy 100.350261 -283.954369) (xy 100.358204 -284.007073) (xy 100.358702 -284.033722) (xy 100.358204 -284.060371)
			(xy 100.586784 -284.060371) (xy 100.586784 -284.007073) (xy 100.594727 -283.954369) (xy 100.610437 -283.903439)
			(xy 100.633563 -283.855418) (xy 100.663587 -283.811381) (xy 100.699839 -283.77231) (xy 100.74151 -283.739079)
			(xy 100.787668 -283.71243) (xy 100.837282 -283.692958) (xy 100.889244 -283.681098) (xy 100.942394 -283.677115)
			(xy 100.995544 -283.681098) (xy 101.047506 -283.692958) (xy 101.09712 -283.71243) (xy 101.143278 -283.739079)
			(xy 101.184949 -283.77231) (xy 101.221201 -283.811381) (xy 101.251225 -283.855418) (xy 101.274351 -283.903439)
			(xy 101.290061 -283.954369) (xy 101.298004 -284.007073) (xy 101.298502 -284.033722) (xy 101.298004 -284.060371)
			(xy 101.526584 -284.060371) (xy 101.526584 -284.007073) (xy 101.534527 -283.954369) (xy 101.550237 -283.903439)
			(xy 101.573363 -283.855418) (xy 101.603387 -283.811381) (xy 101.639639 -283.77231) (xy 101.68131 -283.739079)
			(xy 101.727468 -283.71243) (xy 101.777082 -283.692958) (xy 101.829044 -283.681098) (xy 101.882194 -283.677115)
			(xy 101.935344 -283.681098) (xy 101.987306 -283.692958) (xy 102.03692 -283.71243) (xy 102.083078 -283.739079)
			(xy 102.124749 -283.77231) (xy 102.161001 -283.811381) (xy 102.191025 -283.855418) (xy 102.214151 -283.903439)
			(xy 102.229861 -283.954369) (xy 102.237804 -284.007073) (xy 102.238302 -284.033722) (xy 102.237804 -284.060371)
			(xy 102.466384 -284.060371) (xy 102.466384 -284.007073) (xy 102.474327 -283.954369) (xy 102.490037 -283.903439)
			(xy 102.513163 -283.855418) (xy 102.543187 -283.811381) (xy 102.579439 -283.77231) (xy 102.62111 -283.739079)
			(xy 102.667268 -283.71243) (xy 102.716882 -283.692958) (xy 102.768844 -283.681098) (xy 102.821994 -283.677115)
			(xy 102.875144 -283.681098) (xy 102.927106 -283.692958) (xy 102.97672 -283.71243) (xy 103.022878 -283.739079)
			(xy 103.064549 -283.77231) (xy 103.100801 -283.811381) (xy 103.130825 -283.855418) (xy 103.153951 -283.903439)
			(xy 103.169661 -283.954369) (xy 103.177604 -284.007073) (xy 103.178102 -284.033722) (xy 103.177604 -284.060371)
			(xy 103.169661 -284.113075) (xy 103.153951 -284.164005) (xy 103.130825 -284.212026) (xy 103.100801 -284.256063)
			(xy 103.064549 -284.295134) (xy 103.022878 -284.328365) (xy 102.97672 -284.355014) (xy 102.927106 -284.374486)
			(xy 102.875144 -284.386346) (xy 102.821994 -284.39033) (xy 102.768844 -284.386346) (xy 102.716882 -284.374486)
			(xy 102.667268 -284.355014) (xy 102.62111 -284.328365) (xy 102.579439 -284.295134) (xy 102.543187 -284.256063)
			(xy 102.513163 -284.212026) (xy 102.490037 -284.164005) (xy 102.474327 -284.113075) (xy 102.466384 -284.060371)
			(xy 102.237804 -284.060371) (xy 102.229861 -284.113075) (xy 102.214151 -284.164005) (xy 102.191025 -284.212026)
			(xy 102.161001 -284.256063) (xy 102.124749 -284.295134) (xy 102.083078 -284.328365) (xy 102.03692 -284.355014)
			(xy 101.987306 -284.374486) (xy 101.935344 -284.386346) (xy 101.882194 -284.39033) (xy 101.829044 -284.386346)
			(xy 101.777082 -284.374486) (xy 101.727468 -284.355014) (xy 101.68131 -284.328365) (xy 101.639639 -284.295134)
			(xy 101.603387 -284.256063) (xy 101.573363 -284.212026) (xy 101.550237 -284.164005) (xy 101.534527 -284.113075)
			(xy 101.526584 -284.060371) (xy 101.298004 -284.060371) (xy 101.290061 -284.113075) (xy 101.274351 -284.164005)
			(xy 101.251225 -284.212026) (xy 101.221201 -284.256063) (xy 101.184949 -284.295134) (xy 101.143278 -284.328365)
			(xy 101.09712 -284.355014) (xy 101.047506 -284.374486) (xy 100.995544 -284.386346) (xy 100.942394 -284.39033)
			(xy 100.889244 -284.386346) (xy 100.837282 -284.374486) (xy 100.787668 -284.355014) (xy 100.74151 -284.328365)
			(xy 100.699839 -284.295134) (xy 100.663587 -284.256063) (xy 100.633563 -284.212026) (xy 100.610437 -284.164005)
			(xy 100.594727 -284.113075) (xy 100.586784 -284.060371) (xy 100.358204 -284.060371) (xy 100.350261 -284.113075)
			(xy 100.334551 -284.164005) (xy 100.311425 -284.212026) (xy 100.281401 -284.256063) (xy 100.245149 -284.295134)
			(xy 100.203478 -284.328365) (xy 100.15732 -284.355014) (xy 100.107706 -284.374486) (xy 100.055744 -284.386346)
			(xy 100.002594 -284.39033) (xy 99.949444 -284.386346) (xy 99.897482 -284.374486) (xy 99.847868 -284.355014)
			(xy 99.80171 -284.328365) (xy 99.760039 -284.295134) (xy 99.723787 -284.256063) (xy 99.693763 -284.212026)
			(xy 99.670637 -284.164005) (xy 99.654927 -284.113075) (xy 99.646984 -284.060371) (xy 99.418404 -284.060371)
			(xy 99.410461 -284.113075) (xy 99.394751 -284.164005) (xy 99.371625 -284.212026) (xy 99.341601 -284.256063)
			(xy 99.305349 -284.295134) (xy 99.263678 -284.328365) (xy 99.21752 -284.355014) (xy 99.167906 -284.374486)
			(xy 99.115944 -284.386346) (xy 99.062794 -284.39033) (xy 99.009644 -284.386346) (xy 98.957682 -284.374486)
			(xy 98.908068 -284.355014) (xy 98.86191 -284.328365) (xy 98.820239 -284.295134) (xy 98.783987 -284.256063)
			(xy 98.753963 -284.212026) (xy 98.730837 -284.164005) (xy 98.715127 -284.113075) (xy 98.707184 -284.060371)
			(xy 98.478604 -284.060371) (xy 98.470661 -284.113075) (xy 98.454951 -284.164005) (xy 98.431825 -284.212026)
			(xy 98.401801 -284.256063) (xy 98.365549 -284.295134) (xy 98.323878 -284.328365) (xy 98.27772 -284.355014)
			(xy 98.228106 -284.374486) (xy 98.176144 -284.386346) (xy 98.122994 -284.39033) (xy 98.069844 -284.386346)
			(xy 98.017882 -284.374486) (xy 97.968268 -284.355014) (xy 97.92211 -284.328365) (xy 97.880439 -284.295134)
			(xy 97.844187 -284.256063) (xy 97.814163 -284.212026) (xy 97.791037 -284.164005) (xy 97.775327 -284.113075)
			(xy 97.767384 -284.060371) (xy 97.538804 -284.060371) (xy 97.530861 -284.113075) (xy 97.515151 -284.164005)
			(xy 97.492025 -284.212026) (xy 97.462001 -284.256063) (xy 97.425749 -284.295134) (xy 97.384078 -284.328365)
			(xy 97.33792 -284.355014) (xy 97.288306 -284.374486) (xy 97.236344 -284.386346) (xy 97.183194 -284.39033)
			(xy 97.130044 -284.386346) (xy 97.078082 -284.374486) (xy 97.028468 -284.355014) (xy 96.98231 -284.328365)
			(xy 96.940639 -284.295134) (xy 96.904387 -284.256063) (xy 96.874363 -284.212026) (xy 96.851237 -284.164005)
			(xy 96.835527 -284.113075) (xy 96.827584 -284.060371) (xy 96.599004 -284.060371) (xy 96.591061 -284.113075)
			(xy 96.575351 -284.164005) (xy 96.552225 -284.212026) (xy 96.522201 -284.256063) (xy 96.485949 -284.295134)
			(xy 96.444278 -284.328365) (xy 96.39812 -284.355014) (xy 96.348506 -284.374486) (xy 96.296544 -284.386346)
			(xy 96.243394 -284.39033) (xy 96.190244 -284.386346) (xy 96.138282 -284.374486) (xy 96.088668 -284.355014)
			(xy 96.04251 -284.328365) (xy 96.000839 -284.295134) (xy 95.964587 -284.256063) (xy 95.934563 -284.212026)
			(xy 95.911437 -284.164005) (xy 95.895727 -284.113075) (xy 95.887784 -284.060371) (xy 95.659204 -284.060371)
			(xy 95.651261 -284.113075) (xy 95.635551 -284.164005) (xy 95.612425 -284.212026) (xy 95.582401 -284.256063)
			(xy 95.546149 -284.295134) (xy 95.504478 -284.328365) (xy 95.45832 -284.355014) (xy 95.408706 -284.374486)
			(xy 95.356744 -284.386346) (xy 95.303594 -284.39033) (xy 95.250444 -284.386346) (xy 95.198482 -284.374486)
			(xy 95.148868 -284.355014) (xy 95.10271 -284.328365) (xy 95.061039 -284.295134) (xy 95.024787 -284.256063)
			(xy 94.994763 -284.212026) (xy 94.971637 -284.164005) (xy 94.955927 -284.113075) (xy 94.947984 -284.060371)
			(xy 94.719404 -284.060371) (xy 94.711461 -284.113075) (xy 94.695751 -284.164005) (xy 94.672625 -284.212026)
			(xy 94.642601 -284.256063) (xy 94.606349 -284.295134) (xy 94.564678 -284.328365) (xy 94.51852 -284.355014)
			(xy 94.468906 -284.374486) (xy 94.416944 -284.386346) (xy 94.363794 -284.39033) (xy 94.310644 -284.386346)
			(xy 94.258682 -284.374486) (xy 94.209068 -284.355014) (xy 94.16291 -284.328365) (xy 94.121239 -284.295134)
			(xy 94.084987 -284.256063) (xy 94.054963 -284.212026) (xy 94.031837 -284.164005) (xy 94.016127 -284.113075)
			(xy 94.008184 -284.060371) (xy 93.779604 -284.060371) (xy 93.771661 -284.113075) (xy 93.755951 -284.164005)
			(xy 93.732825 -284.212026) (xy 93.702801 -284.256063) (xy 93.666549 -284.295134) (xy 93.624878 -284.328365)
			(xy 93.57872 -284.355014) (xy 93.529106 -284.374486) (xy 93.477144 -284.386346) (xy 93.423994 -284.39033)
			(xy 93.370844 -284.386346) (xy 93.318882 -284.374486) (xy 93.269268 -284.355014) (xy 93.22311 -284.328365)
			(xy 93.181439 -284.295134) (xy 93.145187 -284.256063) (xy 93.115163 -284.212026) (xy 93.092037 -284.164005)
			(xy 93.076327 -284.113075) (xy 93.068384 -284.060371) (xy 92.839804 -284.060371) (xy 92.831861 -284.113075)
			(xy 92.816151 -284.164005) (xy 92.793025 -284.212026) (xy 92.763001 -284.256063) (xy 92.726749 -284.295134)
			(xy 92.685078 -284.328365) (xy 92.63892 -284.355014) (xy 92.589306 -284.374486) (xy 92.537344 -284.386346)
			(xy 92.484194 -284.39033) (xy 92.431044 -284.386346) (xy 92.379082 -284.374486) (xy 92.329468 -284.355014)
			(xy 92.28331 -284.328365) (xy 92.241639 -284.295134) (xy 92.205387 -284.256063) (xy 92.175363 -284.212026)
			(xy 92.152237 -284.164005) (xy 92.136527 -284.113075) (xy 92.128584 -284.060371) (xy 91.900004 -284.060371)
			(xy 91.892061 -284.113075) (xy 91.876351 -284.164005) (xy 91.853225 -284.212026) (xy 91.823201 -284.256063)
			(xy 91.786949 -284.295134) (xy 91.745278 -284.328365) (xy 91.69912 -284.355014) (xy 91.649506 -284.374486)
			(xy 91.597544 -284.386346) (xy 91.544394 -284.39033) (xy 91.491244 -284.386346) (xy 91.439282 -284.374486)
			(xy 91.389668 -284.355014) (xy 91.34351 -284.328365) (xy 91.301839 -284.295134) (xy 91.265587 -284.256063)
			(xy 91.235563 -284.212026) (xy 91.212437 -284.164005) (xy 91.196727 -284.113075) (xy 91.188784 -284.060371)
			(xy 90.960204 -284.060371) (xy 90.952261 -284.113075) (xy 90.936551 -284.164005) (xy 90.913425 -284.212026)
			(xy 90.883401 -284.256063) (xy 90.847149 -284.295134) (xy 90.805478 -284.328365) (xy 90.75932 -284.355014)
			(xy 90.709706 -284.374486) (xy 90.657744 -284.386346) (xy 90.604594 -284.39033) (xy 90.551444 -284.386346)
			(xy 90.499482 -284.374486) (xy 90.449868 -284.355014) (xy 90.40371 -284.328365) (xy 90.362039 -284.295134)
			(xy 90.325787 -284.256063) (xy 90.295763 -284.212026) (xy 90.272637 -284.164005) (xy 90.256927 -284.113075)
			(xy 90.248984 -284.060371) (xy 89.080858 -284.060371) (xy 89.072915 -284.113075) (xy 89.057205 -284.164005)
			(xy 89.034079 -284.212026) (xy 89.004055 -284.256063) (xy 88.967803 -284.295134) (xy 88.926132 -284.328365)
			(xy 88.879974 -284.355014) (xy 88.83036 -284.374486) (xy 88.778398 -284.386346) (xy 88.725248 -284.39033)
			(xy 88.672098 -284.386346) (xy 88.620136 -284.374486) (xy 88.570522 -284.355014) (xy 88.524364 -284.328365)
			(xy 88.482693 -284.295134) (xy 88.446441 -284.256063) (xy 88.416417 -284.212026) (xy 88.393291 -284.164005)
			(xy 88.377581 -284.113075) (xy 88.369638 -284.060371) (xy 88.140804 -284.060371) (xy 88.132861 -284.113075)
			(xy 88.117151 -284.164005) (xy 88.094025 -284.212026) (xy 88.064001 -284.256063) (xy 88.027749 -284.295134)
			(xy 87.986078 -284.328365) (xy 87.93992 -284.355014) (xy 87.890306 -284.374486) (xy 87.838344 -284.386346)
			(xy 87.785194 -284.39033) (xy 87.732044 -284.386346) (xy 87.680082 -284.374486) (xy 87.630468 -284.355014)
			(xy 87.58431 -284.328365) (xy 87.542639 -284.295134) (xy 87.506387 -284.256063) (xy 87.476363 -284.212026)
			(xy 87.453237 -284.164005) (xy 87.437527 -284.113075) (xy 87.429584 -284.060371) (xy 87.20095 -284.060371)
			(xy 87.195347 -284.103063) (xy 87.183352 -284.147981) (xy 87.174832 -284.169612) (xy 87.16518 -284.192726)
			(xy 87.337646 -284.491176) (xy 87.362284 -284.494478) (xy 87.387619 -284.498351) (xy 87.436923 -284.512334)
			(xy 87.483714 -284.533239) (xy 87.527026 -284.560634) (xy 87.565965 -284.593953) (xy 87.599727 -284.632509)
			(xy 87.627615 -284.675505) (xy 87.649053 -284.722055) (xy 87.663599 -284.771195) (xy 87.670952 -284.821914)
			(xy 87.671402 -284.847538) (xy 87.670904 -284.874187) (xy 87.662961 -284.926891) (xy 87.647251 -284.977821)
			(xy 87.624125 -285.025842) (xy 87.594101 -285.069879) (xy 87.557849 -285.10895) (xy 87.516178 -285.142181)
			(xy 87.47002 -285.16883) (xy 87.420406 -285.188302) (xy 87.368444 -285.200162) (xy 87.315294 -285.204146)
			(xy 87.262144 -285.200162) (xy 87.210182 -285.188302) (xy 87.160568 -285.16883) (xy 87.11441 -285.142181)
			(xy 87.072739 -285.10895) (xy 87.036487 -285.069879) (xy 87.006463 -285.025842) (xy 86.983337 -284.977821)
			(xy 86.967627 -284.926891) (xy 86.959684 -284.874187) (xy 86.959186 -284.847538) (xy 86.959568 -284.824293)
			(xy 86.965609 -284.778198) (xy 86.977595 -284.73328) (xy 86.98611 -284.711648) (xy 86.995762 -284.688534)
			(xy 86.823296 -284.390084) (xy 86.798658 -284.386782) (xy 86.773309 -284.382994) (xy 86.724002 -284.369)
			(xy 86.677209 -284.348085) (xy 86.633896 -284.32068) (xy 86.594957 -284.287351) (xy 86.561197 -284.248786)
			(xy 86.533311 -284.20578) (xy 86.511877 -284.159223) (xy 86.497335 -284.110074) (xy 86.489987 -284.059349)
			(xy 86.48954 -284.033722) (xy 85.52688 -284.033722) (xy 85.52688 -284.50159) (xy 85.5599 -284.513782)
			(xy 85.585886 -284.524035) (xy 85.634554 -284.551455) (xy 85.678343 -284.586138) (xy 85.716179 -284.627234)
			(xy 85.732112 -284.65018) (xy 86.079076 -284.65018) (xy 86.093297 -284.629583) (xy 86.126593 -284.592212)
			(xy 86.164795 -284.559872) (xy 86.207149 -284.5332) (xy 86.25282 -284.512722) (xy 86.300909 -284.498841)
			(xy 86.350468 -284.491832) (xy 86.375494 -284.49143) (xy 86.402143 -284.491903) (xy 86.454845 -284.499845)
			(xy 86.505774 -284.515554) (xy 86.553794 -284.538679) (xy 86.59783 -284.568701) (xy 86.6369 -284.604952)
			(xy 86.67013 -284.646622) (xy 86.696779 -284.692778) (xy 86.716251 -284.742391) (xy 86.728111 -284.794352)
			(xy 86.732094 -284.8475) (xy 86.728111 -284.900648) (xy 86.716251 -284.952609) (xy 86.696779 -285.002222)
			(xy 86.670131 -285.048378) (xy 86.6369 -285.090048) (xy 86.59783 -285.126299) (xy 86.553794 -285.156321)
			(xy 86.505774 -285.179446) (xy 86.454845 -285.195155) (xy 86.402143 -285.203097) (xy 86.375494 -285.203646)
			(xy 86.350469 -285.203221) (xy 86.300911 -285.196213) (xy 86.252823 -285.182335) (xy 86.207152 -285.161861)
			(xy 86.164796 -285.135195) (xy 86.126592 -285.102861) (xy 86.093291 -285.065496) (xy 86.079076 -285.044896)
			(xy 85.732112 -285.044896) (xy 85.716181 -285.067844) (xy 85.678345 -285.108942) (xy 85.634558 -285.14363)
			(xy 85.585893 -285.171057) (xy 85.5599 -285.181294) (xy 85.52688 -285.193486) (xy 85.52688 -285.297118)
			(xy 85.52733 -285.311252) (xy 85.535063 -285.33844) (xy 85.549958 -285.362464) (xy 85.570872 -285.38148)
			(xy 85.5962 -285.394029) (xy 85.624 -285.399147) (xy 85.652137 -285.396443) (xy 85.678452 -285.386123)
			(xy 85.689948 -285.37789) (xy 85.713354 -285.360811) (xy 85.764544 -285.333673) (xy 85.81945 -285.315174)
			(xy 85.876625 -285.305801) (xy 85.905594 -285.305246) (xy 85.932249 -285.305719) (xy 85.984963 -285.313664)
			(xy 86.035905 -285.329376) (xy 86.083936 -285.352506) (xy 86.127982 -285.382536) (xy 86.167062 -285.418795)
			(xy 86.2003 -285.460474) (xy 86.226955 -285.506642) (xy 86.246431 -285.556266) (xy 86.258294 -285.608239)
			(xy 86.262278 -285.6614) (xy 86.260284 -285.688003) (xy 86.489784 -285.688003) (xy 86.489784 -285.634705)
			(xy 86.497727 -285.582001) (xy 86.513437 -285.531071) (xy 86.536563 -285.48305) (xy 86.566587 -285.439013)
			(xy 86.602839 -285.399942) (xy 86.64451 -285.366711) (xy 86.690668 -285.340062) (xy 86.740282 -285.32059)
			(xy 86.792244 -285.30873) (xy 86.845394 -285.304747) (xy 86.898544 -285.30873) (xy 86.950506 -285.32059)
			(xy 87.00012 -285.340062) (xy 87.046278 -285.366711) (xy 87.087949 -285.399942) (xy 87.124201 -285.439013)
			(xy 87.154225 -285.48305) (xy 87.177351 -285.531071) (xy 87.193061 -285.582001) (xy 87.201004 -285.634705)
			(xy 87.201502 -285.661354) (xy 87.429086 -285.661354) (xy 87.429527 -285.635725) (xy 87.436856 -285.584993)
			(xy 87.451386 -285.535838) (xy 87.472814 -285.489274) (xy 87.500699 -285.446264) (xy 87.534464 -285.407699)
			(xy 87.573411 -285.374374) (xy 87.616735 -285.34698) (xy 87.663539 -285.326082) (xy 87.712857 -285.312113)
			(xy 87.738204 -285.308294) (xy 87.762842 -285.304992) (xy 87.935308 -285.006288) (xy 87.92591 -284.983174)
			(xy 87.917417 -284.961579) (xy 87.905441 -284.916747) (xy 87.89938 -284.87074) (xy 87.898986 -284.847538)
			(xy 87.899484 -284.820889) (xy 87.907427 -284.768185) (xy 87.923137 -284.717255) (xy 87.946263 -284.669234)
			(xy 87.976287 -284.625197) (xy 88.012539 -284.586126) (xy 88.05421 -284.552895) (xy 88.100368 -284.526246)
			(xy 88.149982 -284.506774) (xy 88.201944 -284.494914) (xy 88.255094 -284.490931) (xy 88.308244 -284.494914)
			(xy 88.360206 -284.506774) (xy 88.40982 -284.526246) (xy 88.455978 -284.552895) (xy 88.497649 -284.586126)
			(xy 88.533901 -284.625197) (xy 88.563925 -284.669234) (xy 88.587051 -284.717255) (xy 88.602761 -284.768185)
			(xy 88.610704 -284.820889) (xy 88.611202 -284.847538) (xy 88.610764 -284.873167) (xy 88.610617 -284.874187)
			(xy 88.839284 -284.874187) (xy 88.839284 -284.820889) (xy 88.847227 -284.768185) (xy 88.862937 -284.717255)
			(xy 88.886063 -284.669234) (xy 88.916087 -284.625197) (xy 88.952339 -284.586126) (xy 88.99401 -284.552895)
			(xy 89.040168 -284.526246) (xy 89.089782 -284.506774) (xy 89.141744 -284.494914) (xy 89.194894 -284.490931)
			(xy 89.248044 -284.494914) (xy 89.300006 -284.506774) (xy 89.34962 -284.526246) (xy 89.395778 -284.552895)
			(xy 89.437449 -284.586126) (xy 89.473701 -284.625197) (xy 89.503725 -284.669234) (xy 89.526851 -284.717255)
			(xy 89.542561 -284.768185) (xy 89.550504 -284.820889) (xy 89.551002 -284.847538) (xy 89.550504 -284.874187)
			(xy 89.542561 -284.926891) (xy 89.526851 -284.977821) (xy 89.503725 -285.025842) (xy 89.473701 -285.069879)
			(xy 89.437449 -285.10895) (xy 89.395778 -285.142181) (xy 89.34962 -285.16883) (xy 89.300006 -285.188302)
			(xy 89.248044 -285.200162) (xy 89.194894 -285.204146) (xy 89.141744 -285.200162) (xy 89.089782 -285.188302)
			(xy 89.040168 -285.16883) (xy 88.99401 -285.142181) (xy 88.952339 -285.10895) (xy 88.916087 -285.069879)
			(xy 88.886063 -285.025842) (xy 88.862937 -284.977821) (xy 88.847227 -284.926891) (xy 88.839284 -284.874187)
			(xy 88.610617 -284.874187) (xy 88.603435 -284.923899) (xy 88.588907 -284.973056) (xy 88.567478 -285.01962)
			(xy 88.539593 -285.06263) (xy 88.505827 -285.101196) (xy 88.46688 -285.13452) (xy 88.423555 -285.161915)
			(xy 88.37675 -285.182812) (xy 88.327431 -285.19678) (xy 88.302084 -285.200598) (xy 88.277446 -285.2039)
			(xy 88.10498 -285.502604) (xy 88.114378 -285.525718) (xy 88.122868 -285.547314) (xy 88.134845 -285.592146)
			(xy 88.140907 -285.638152) (xy 88.141302 -285.661354) (xy 88.140804 -285.688003) (xy 88.369384 -285.688003)
			(xy 88.369384 -285.634705) (xy 88.377327 -285.582001) (xy 88.393037 -285.531071) (xy 88.416163 -285.48305)
			(xy 88.446187 -285.439013) (xy 88.482439 -285.399942) (xy 88.52411 -285.366711) (xy 88.570268 -285.340062)
			(xy 88.619882 -285.32059) (xy 88.671844 -285.30873) (xy 88.724994 -285.304747) (xy 88.778144 -285.30873)
			(xy 88.830106 -285.32059) (xy 88.87972 -285.340062) (xy 88.925878 -285.366711) (xy 88.967549 -285.399942)
			(xy 89.003801 -285.439013) (xy 89.033825 -285.48305) (xy 89.056951 -285.531071) (xy 89.072661 -285.582001)
			(xy 89.080604 -285.634705) (xy 89.081102 -285.661354) (xy 89.308686 -285.661354) (xy 89.309184 -285.634705)
			(xy 89.317127 -285.582001) (xy 89.332837 -285.531071) (xy 89.355963 -285.48305) (xy 89.385987 -285.439013)
			(xy 89.422239 -285.399942) (xy 89.46391 -285.366711) (xy 89.510068 -285.340062) (xy 89.559682 -285.32059)
			(xy 89.611644 -285.30873) (xy 89.664794 -285.304747) (xy 89.717944 -285.30873) (xy 89.769906 -285.32059)
			(xy 89.81952 -285.340062) (xy 89.865678 -285.366711) (xy 89.907349 -285.399942) (xy 89.943601 -285.439013)
			(xy 89.973625 -285.48305) (xy 89.996751 -285.531071) (xy 90.012461 -285.582001) (xy 90.020404 -285.634705)
			(xy 90.020902 -285.661354) (xy 90.24874 -285.661354) (xy 90.249221 -285.635727) (xy 90.256549 -285.584999)
			(xy 90.271076 -285.535846) (xy 90.292501 -285.489285) (xy 90.320382 -285.446277) (xy 90.354142 -285.407712)
			(xy 90.393084 -285.374387) (xy 90.436402 -285.346991) (xy 90.483201 -285.32609) (xy 90.532513 -285.312115)
			(xy 90.557858 -285.308294) (xy 90.582496 -285.304992) (xy 90.754962 -285.006542) (xy 90.74531 -284.983428)
			(xy 90.736804 -284.961792) (xy 90.724813 -284.916876) (xy 90.718764 -284.870782) (xy 90.718386 -284.847538)
			(xy 90.718884 -284.820889) (xy 90.726827 -284.768185) (xy 90.742537 -284.717255) (xy 90.765663 -284.669234)
			(xy 90.795687 -284.625197) (xy 90.831939 -284.586126) (xy 90.87361 -284.552895) (xy 90.919768 -284.526246)
			(xy 90.969382 -284.506774) (xy 91.021344 -284.494914) (xy 91.074494 -284.490931) (xy 91.127644 -284.494914)
			(xy 91.179606 -284.506774) (xy 91.22922 -284.526246) (xy 91.275378 -284.552895) (xy 91.317049 -284.586126)
			(xy 91.353301 -284.625197) (xy 91.383325 -284.669234) (xy 91.406451 -284.717255) (xy 91.422161 -284.768185)
			(xy 91.430104 -284.820889) (xy 91.430602 -284.847538) (xy 91.430198 -284.873157) (xy 91.422876 -284.92387)
			(xy 91.40836 -284.973009) (xy 91.38695 -285.019559) (xy 91.359088 -285.06256) (xy 91.325349 -285.101122)
			(xy 91.286431 -285.13445) (xy 91.243138 -285.161855) (xy 91.196363 -285.18277) (xy 91.147073 -285.196764)
			(xy 91.121738 -285.200598) (xy 91.096846 -285.2039) (xy 90.92438 -285.50235) (xy 90.934032 -285.525464)
			(xy 90.942532 -285.547102) (xy 90.954526 -285.592017) (xy 90.960577 -285.63811) (xy 90.960956 -285.661354)
			(xy 91.18854 -285.661354) (xy 91.189038 -285.634705) (xy 91.196981 -285.582001) (xy 91.212691 -285.531071)
			(xy 91.235817 -285.48305) (xy 91.265841 -285.439013) (xy 91.302093 -285.399942) (xy 91.343764 -285.366711)
			(xy 91.389922 -285.340062) (xy 91.439536 -285.32059) (xy 91.491498 -285.30873) (xy 91.544648 -285.304747)
			(xy 91.597798 -285.30873) (xy 91.64976 -285.32059) (xy 91.699374 -285.340062) (xy 91.745532 -285.366711)
			(xy 91.787203 -285.399942) (xy 91.823455 -285.439013) (xy 91.853479 -285.48305) (xy 91.876605 -285.531071)
			(xy 91.892315 -285.582001) (xy 91.900258 -285.634705) (xy 91.900756 -285.661354) (xy 92.128086 -285.661354)
			(xy 92.128527 -285.635725) (xy 92.135856 -285.584993) (xy 92.150386 -285.535838) (xy 92.171814 -285.489274)
			(xy 92.199699 -285.446264) (xy 92.233464 -285.407699) (xy 92.272411 -285.374374) (xy 92.315735 -285.34698)
			(xy 92.362539 -285.326082) (xy 92.411857 -285.312113) (xy 92.437204 -285.308294) (xy 92.461842 -285.304992)
			(xy 92.634562 -285.006034) (xy 92.62491 -284.98292) (xy 92.616445 -284.961367) (xy 92.60456 -284.916612)
			(xy 92.59859 -284.870692) (xy 92.59824 -284.847538) (xy 92.598738 -284.820889) (xy 92.606681 -284.768185)
			(xy 92.622391 -284.717255) (xy 92.645517 -284.669234) (xy 92.675541 -284.625197) (xy 92.711793 -284.586126)
			(xy 92.753464 -284.552895) (xy 92.799622 -284.526246) (xy 92.849236 -284.506774) (xy 92.901198 -284.494914)
			(xy 92.954348 -284.490931) (xy 93.007498 -284.494914) (xy 93.05946 -284.506774) (xy 93.109074 -284.526246)
			(xy 93.155232 -284.552895) (xy 93.196903 -284.586126) (xy 93.233155 -284.625197) (xy 93.263179 -284.669234)
			(xy 93.286305 -284.717255) (xy 93.302015 -284.768185) (xy 93.309958 -284.820889) (xy 93.310456 -284.847538)
			(xy 93.310029 -284.873178) (xy 93.302682 -284.923929) (xy 93.28813 -284.973101) (xy 93.266675 -285.019677)
			(xy 93.23876 -285.062694) (xy 93.204964 -285.101261) (xy 93.165984 -285.134582) (xy 93.122628 -285.161966)
			(xy 93.075791 -285.182847) (xy 93.026444 -285.196793) (xy 93.001084 -285.200598) (xy 92.976192 -285.2039)
			(xy 92.803726 -285.50235) (xy 92.813378 -285.525464) (xy 92.821881 -285.547101) (xy 92.833873 -285.592016)
			(xy 92.839924 -285.63811) (xy 92.840302 -285.661354) (xy 93.067886 -285.661354) (xy 93.068384 -285.634705)
			(xy 93.076327 -285.582001) (xy 93.092037 -285.531071) (xy 93.115163 -285.48305) (xy 93.145187 -285.439013)
			(xy 93.181439 -285.399942) (xy 93.22311 -285.366711) (xy 93.269268 -285.340062) (xy 93.318882 -285.32059)
			(xy 93.370844 -285.30873) (xy 93.423994 -285.304747) (xy 93.477144 -285.30873) (xy 93.529106 -285.32059)
			(xy 93.57872 -285.340062) (xy 93.624878 -285.366711) (xy 93.666549 -285.399942) (xy 93.702801 -285.439013)
			(xy 93.732825 -285.48305) (xy 93.755951 -285.531071) (xy 93.771661 -285.582001) (xy 93.779604 -285.634705)
			(xy 93.780102 -285.661354) (xy 94.007686 -285.661354) (xy 94.008127 -285.635725) (xy 94.015456 -285.584993)
			(xy 94.029986 -285.535838) (xy 94.051414 -285.489274) (xy 94.079299 -285.446264) (xy 94.113064 -285.407699)
			(xy 94.152011 -285.374374) (xy 94.195335 -285.34698) (xy 94.242139 -285.326082) (xy 94.291457 -285.312113)
			(xy 94.316804 -285.308294) (xy 94.341442 -285.304992) (xy 94.514162 -285.006034) (xy 94.50451 -284.98292)
			(xy 94.496045 -284.961367) (xy 94.48416 -284.916612) (xy 94.47819 -284.870692) (xy 94.47784 -284.847538)
			(xy 94.478338 -284.820889) (xy 94.486281 -284.768185) (xy 94.501991 -284.717255) (xy 94.525117 -284.669234)
			(xy 94.555141 -284.625197) (xy 94.591393 -284.586126) (xy 94.633064 -284.552895) (xy 94.679222 -284.526246)
			(xy 94.728836 -284.506774) (xy 94.780798 -284.494914) (xy 94.833948 -284.490931) (xy 94.887098 -284.494914)
			(xy 94.93906 -284.506774) (xy 94.988674 -284.526246) (xy 95.034832 -284.552895) (xy 95.076503 -284.586126)
			(xy 95.112755 -284.625197) (xy 95.142779 -284.669234) (xy 95.165905 -284.717255) (xy 95.181615 -284.768185)
			(xy 95.189558 -284.820889) (xy 95.190056 -284.847538) (xy 95.189629 -284.873178) (xy 95.182282 -284.923929)
			(xy 95.16773 -284.973101) (xy 95.146275 -285.019677) (xy 95.11836 -285.062694) (xy 95.084564 -285.101261)
			(xy 95.045584 -285.134582) (xy 95.002228 -285.161966) (xy 94.955391 -285.182847) (xy 94.906044 -285.196793)
			(xy 94.880684 -285.200598) (xy 94.855792 -285.2039) (xy 94.683326 -285.50235) (xy 94.692978 -285.525464)
			(xy 94.701481 -285.547101) (xy 94.713473 -285.592016) (xy 94.719524 -285.63811) (xy 94.719902 -285.661354)
			(xy 94.947486 -285.661354) (xy 94.947984 -285.634705) (xy 94.955927 -285.582001) (xy 94.971637 -285.531071)
			(xy 94.994763 -285.48305) (xy 95.024787 -285.439013) (xy 95.061039 -285.399942) (xy 95.10271 -285.366711)
			(xy 95.148868 -285.340062) (xy 95.198482 -285.32059) (xy 95.250444 -285.30873) (xy 95.303594 -285.304747)
			(xy 95.356744 -285.30873) (xy 95.408706 -285.32059) (xy 95.45832 -285.340062) (xy 95.504478 -285.366711)
			(xy 95.546149 -285.399942) (xy 95.582401 -285.439013) (xy 95.612425 -285.48305) (xy 95.635551 -285.531071)
			(xy 95.651261 -285.582001) (xy 95.659204 -285.634705) (xy 95.659702 -285.661354) (xy 95.887286 -285.661354)
			(xy 95.887727 -285.635725) (xy 95.895056 -285.584993) (xy 95.909586 -285.535838) (xy 95.931014 -285.489274)
			(xy 95.958899 -285.446264) (xy 95.992664 -285.407699) (xy 96.031611 -285.374374) (xy 96.074935 -285.34698)
			(xy 96.121739 -285.326082) (xy 96.171057 -285.312113) (xy 96.196404 -285.308294) (xy 96.221042 -285.304992)
			(xy 96.393762 -285.006034) (xy 96.38411 -284.98292) (xy 96.375645 -284.961367) (xy 96.36376 -284.916612)
			(xy 96.35779 -284.870692) (xy 96.35744 -284.847538) (xy 96.357938 -284.820889) (xy 96.365881 -284.768185)
			(xy 96.381591 -284.717255) (xy 96.404717 -284.669234) (xy 96.434741 -284.625197) (xy 96.470993 -284.586126)
			(xy 96.512664 -284.552895) (xy 96.558822 -284.526246) (xy 96.608436 -284.506774) (xy 96.660398 -284.494914)
			(xy 96.713548 -284.490931) (xy 96.766698 -284.494914) (xy 96.81866 -284.506774) (xy 96.868274 -284.526246)
			(xy 96.914432 -284.552895) (xy 96.956103 -284.586126) (xy 96.992355 -284.625197) (xy 97.022379 -284.669234)
			(xy 97.045505 -284.717255) (xy 97.061215 -284.768185) (xy 97.069158 -284.820889) (xy 97.069656 -284.847538)
			(xy 97.069229 -284.873178) (xy 97.061882 -284.923929) (xy 97.04733 -284.973101) (xy 97.025875 -285.019677)
			(xy 96.99796 -285.062694) (xy 96.964164 -285.101261) (xy 96.925184 -285.134582) (xy 96.881828 -285.161966)
			(xy 96.834991 -285.182847) (xy 96.785644 -285.196793) (xy 96.760284 -285.200598) (xy 96.735392 -285.2039)
			(xy 96.562926 -285.50235) (xy 96.572578 -285.525464) (xy 96.581081 -285.547101) (xy 96.593073 -285.592016)
			(xy 96.599124 -285.63811) (xy 96.599502 -285.661354) (xy 96.827086 -285.661354) (xy 96.827584 -285.634705)
			(xy 96.835527 -285.582001) (xy 96.851237 -285.531071) (xy 96.874363 -285.48305) (xy 96.904387 -285.439013)
			(xy 96.940639 -285.399942) (xy 96.98231 -285.366711) (xy 97.028468 -285.340062) (xy 97.078082 -285.32059)
			(xy 97.130044 -285.30873) (xy 97.183194 -285.304747) (xy 97.236344 -285.30873) (xy 97.288306 -285.32059)
			(xy 97.33792 -285.340062) (xy 97.384078 -285.366711) (xy 97.425749 -285.399942) (xy 97.462001 -285.439013)
			(xy 97.492025 -285.48305) (xy 97.515151 -285.531071) (xy 97.530861 -285.582001) (xy 97.538804 -285.634705)
			(xy 97.539302 -285.661354) (xy 97.766886 -285.661354) (xy 97.767327 -285.635725) (xy 97.774656 -285.584993)
			(xy 97.789186 -285.535838) (xy 97.810614 -285.489274) (xy 97.838499 -285.446264) (xy 97.872264 -285.407699)
			(xy 97.911211 -285.374374) (xy 97.954535 -285.34698) (xy 98.001339 -285.326082) (xy 98.050657 -285.312113)
			(xy 98.076004 -285.308294) (xy 98.100642 -285.304992) (xy 98.273362 -285.006034) (xy 98.26371 -284.98292)
			(xy 98.255245 -284.961367) (xy 98.24336 -284.916612) (xy 98.23739 -284.870692) (xy 98.23704 -284.847538)
			(xy 98.237538 -284.820889) (xy 98.245481 -284.768185) (xy 98.261191 -284.717255) (xy 98.284317 -284.669234)
			(xy 98.314341 -284.625197) (xy 98.350593 -284.586126) (xy 98.392264 -284.552895) (xy 98.438422 -284.526246)
			(xy 98.488036 -284.506774) (xy 98.539998 -284.494914) (xy 98.593148 -284.490931) (xy 98.646298 -284.494914)
			(xy 98.69826 -284.506774) (xy 98.747874 -284.526246) (xy 98.794032 -284.552895) (xy 98.835703 -284.586126)
			(xy 98.871955 -284.625197) (xy 98.901979 -284.669234) (xy 98.925105 -284.717255) (xy 98.940815 -284.768185)
			(xy 98.948758 -284.820889) (xy 98.949256 -284.847538) (xy 98.948829 -284.873178) (xy 98.941482 -284.923929)
			(xy 98.92693 -284.973101) (xy 98.905475 -285.019677) (xy 98.87756 -285.062694) (xy 98.843764 -285.101261)
			(xy 98.804784 -285.134582) (xy 98.761428 -285.161966) (xy 98.714591 -285.182847) (xy 98.665244 -285.196793)
			(xy 98.639884 -285.200598) (xy 98.614992 -285.2039) (xy 98.442526 -285.50235) (xy 98.452178 -285.525464)
			(xy 98.460681 -285.547101) (xy 98.472673 -285.592016) (xy 98.478724 -285.63811) (xy 98.479102 -285.661354)
			(xy 98.706686 -285.661354) (xy 98.707184 -285.634705) (xy 98.715127 -285.582001) (xy 98.730837 -285.531071)
			(xy 98.753963 -285.48305) (xy 98.783987 -285.439013) (xy 98.820239 -285.399942) (xy 98.86191 -285.366711)
			(xy 98.908068 -285.340062) (xy 98.957682 -285.32059) (xy 99.009644 -285.30873) (xy 99.062794 -285.304747)
			(xy 99.115944 -285.30873) (xy 99.167906 -285.32059) (xy 99.21752 -285.340062) (xy 99.263678 -285.366711)
			(xy 99.305349 -285.399942) (xy 99.341601 -285.439013) (xy 99.371625 -285.48305) (xy 99.394751 -285.531071)
			(xy 99.410461 -285.582001) (xy 99.418404 -285.634705) (xy 99.418902 -285.661354) (xy 99.646486 -285.661354)
			(xy 99.646927 -285.635725) (xy 99.654256 -285.584993) (xy 99.668786 -285.535838) (xy 99.690214 -285.489274)
			(xy 99.718099 -285.446264) (xy 99.751864 -285.407699) (xy 99.790811 -285.374374) (xy 99.834135 -285.34698)
			(xy 99.880939 -285.326082) (xy 99.930257 -285.312113) (xy 99.955604 -285.308294) (xy 99.980242 -285.304992)
			(xy 100.152962 -285.006034) (xy 100.14331 -284.98292) (xy 100.134845 -284.961367) (xy 100.12296 -284.916612)
			(xy 100.11699 -284.870692) (xy 100.11664 -284.847538) (xy 100.117138 -284.820889) (xy 100.125081 -284.768185)
			(xy 100.140791 -284.717255) (xy 100.163917 -284.669234) (xy 100.193941 -284.625197) (xy 100.230193 -284.586126)
			(xy 100.271864 -284.552895) (xy 100.318022 -284.526246) (xy 100.367636 -284.506774) (xy 100.419598 -284.494914)
			(xy 100.472748 -284.490931) (xy 100.525898 -284.494914) (xy 100.57786 -284.506774) (xy 100.627474 -284.526246)
			(xy 100.673632 -284.552895) (xy 100.715303 -284.586126) (xy 100.751555 -284.625197) (xy 100.781579 -284.669234)
			(xy 100.804705 -284.717255) (xy 100.820415 -284.768185) (xy 100.828358 -284.820889) (xy 100.828856 -284.847538)
			(xy 100.828429 -284.873178) (xy 100.828283 -284.874187) (xy 101.056938 -284.874187) (xy 101.056938 -284.820889)
			(xy 101.064881 -284.768185) (xy 101.080591 -284.717255) (xy 101.103717 -284.669234) (xy 101.133741 -284.625197)
			(xy 101.169993 -284.586126) (xy 101.211664 -284.552895) (xy 101.257822 -284.526246) (xy 101.307436 -284.506774)
			(xy 101.359398 -284.494914) (xy 101.412548 -284.490931) (xy 101.465698 -284.494914) (xy 101.51766 -284.506774)
			(xy 101.567274 -284.526246) (xy 101.613432 -284.552895) (xy 101.655103 -284.586126) (xy 101.691355 -284.625197)
			(xy 101.721379 -284.669234) (xy 101.744505 -284.717255) (xy 101.760215 -284.768185) (xy 101.768158 -284.820889)
			(xy 101.768656 -284.847538) (xy 101.768158 -284.874187) (xy 101.760215 -284.926891) (xy 101.744505 -284.977821)
			(xy 101.721379 -285.025842) (xy 101.691355 -285.069879) (xy 101.655103 -285.10895) (xy 101.613432 -285.142181)
			(xy 101.567274 -285.16883) (xy 101.51766 -285.188302) (xy 101.465698 -285.200162) (xy 101.412548 -285.204146)
			(xy 101.359398 -285.200162) (xy 101.307436 -285.188302) (xy 101.257822 -285.16883) (xy 101.211664 -285.142181)
			(xy 101.169993 -285.10895) (xy 101.133741 -285.069879) (xy 101.103717 -285.025842) (xy 101.080591 -284.977821)
			(xy 101.064881 -284.926891) (xy 101.056938 -284.874187) (xy 100.828283 -284.874187) (xy 100.821082 -284.923929)
			(xy 100.80653 -284.973101) (xy 100.785075 -285.019677) (xy 100.75716 -285.062694) (xy 100.723364 -285.101261)
			(xy 100.684384 -285.134582) (xy 100.641028 -285.161966) (xy 100.594191 -285.182847) (xy 100.544844 -285.196793)
			(xy 100.519484 -285.200598) (xy 100.494592 -285.2039) (xy 100.322126 -285.50235) (xy 100.331778 -285.525464)
			(xy 100.340281 -285.547101) (xy 100.352273 -285.592016) (xy 100.358324 -285.63811) (xy 100.358702 -285.661354)
			(xy 100.586286 -285.661354) (xy 100.586784 -285.634705) (xy 100.594727 -285.582001) (xy 100.610437 -285.531071)
			(xy 100.633563 -285.48305) (xy 100.663587 -285.439013) (xy 100.699839 -285.399942) (xy 100.74151 -285.366711)
			(xy 100.787668 -285.340062) (xy 100.837282 -285.32059) (xy 100.889244 -285.30873) (xy 100.942394 -285.304747)
			(xy 100.995544 -285.30873) (xy 101.047506 -285.32059) (xy 101.09712 -285.340062) (xy 101.143278 -285.366711)
			(xy 101.184949 -285.399942) (xy 101.221201 -285.439013) (xy 101.251225 -285.48305) (xy 101.274351 -285.531071)
			(xy 101.290061 -285.582001) (xy 101.298004 -285.634705) (xy 101.298502 -285.661354) (xy 101.526086 -285.661354)
			(xy 101.526527 -285.635725) (xy 101.533856 -285.584993) (xy 101.548386 -285.535838) (xy 101.569814 -285.489274)
			(xy 101.597699 -285.446264) (xy 101.631464 -285.407699) (xy 101.670411 -285.374374) (xy 101.713735 -285.34698)
			(xy 101.760539 -285.326082) (xy 101.809857 -285.312113) (xy 101.835204 -285.308294) (xy 101.859842 -285.304992)
			(xy 102.032562 -285.006034) (xy 102.02291 -284.98292) (xy 102.014445 -284.961367) (xy 102.00256 -284.916612)
			(xy 101.99659 -284.870692) (xy 101.99624 -284.847538) (xy 101.996738 -284.820889) (xy 102.004681 -284.768185)
			(xy 102.020391 -284.717255) (xy 102.043517 -284.669234) (xy 102.073541 -284.625197) (xy 102.109793 -284.586126)
			(xy 102.151464 -284.552895) (xy 102.197622 -284.526246) (xy 102.247236 -284.506774) (xy 102.299198 -284.494914)
			(xy 102.352348 -284.490931) (xy 102.405498 -284.494914) (xy 102.45746 -284.506774) (xy 102.507074 -284.526246)
			(xy 102.553232 -284.552895) (xy 102.594903 -284.586126) (xy 102.631155 -284.625197) (xy 102.661179 -284.669234)
			(xy 102.684305 -284.717255) (xy 102.700015 -284.768185) (xy 102.707958 -284.820889) (xy 102.708456 -284.847538)
			(xy 102.708029 -284.873178) (xy 102.707883 -284.874187) (xy 102.936284 -284.874187) (xy 102.936284 -284.820889)
			(xy 102.944227 -284.768185) (xy 102.959937 -284.717255) (xy 102.983063 -284.669234) (xy 103.013087 -284.625197)
			(xy 103.049339 -284.586126) (xy 103.09101 -284.552895) (xy 103.137168 -284.526246) (xy 103.186782 -284.506774)
			(xy 103.238744 -284.494914) (xy 103.291894 -284.490931) (xy 103.345044 -284.494914) (xy 103.397006 -284.506774)
			(xy 103.44662 -284.526246) (xy 103.492778 -284.552895) (xy 103.534449 -284.586126) (xy 103.570701 -284.625197)
			(xy 103.600725 -284.669234) (xy 103.623851 -284.717255) (xy 103.639561 -284.768185) (xy 103.647504 -284.820889)
			(xy 103.648002 -284.847538) (xy 103.647504 -284.874187) (xy 103.639561 -284.926891) (xy 103.623851 -284.977821)
			(xy 103.600725 -285.025842) (xy 103.570701 -285.069879) (xy 103.534449 -285.10895) (xy 103.492778 -285.142181)
			(xy 103.44662 -285.16883) (xy 103.397006 -285.188302) (xy 103.345044 -285.200162) (xy 103.291894 -285.204146)
			(xy 103.238744 -285.200162) (xy 103.186782 -285.188302) (xy 103.137168 -285.16883) (xy 103.09101 -285.142181)
			(xy 103.049339 -285.10895) (xy 103.013087 -285.069879) (xy 102.983063 -285.025842) (xy 102.959937 -284.977821)
			(xy 102.944227 -284.926891) (xy 102.936284 -284.874187) (xy 102.707883 -284.874187) (xy 102.700682 -284.923929)
			(xy 102.68613 -284.973101) (xy 102.664675 -285.019677) (xy 102.63676 -285.062694) (xy 102.602964 -285.101261)
			(xy 102.563984 -285.134582) (xy 102.520628 -285.161966) (xy 102.473791 -285.182847) (xy 102.424444 -285.196793)
			(xy 102.399084 -285.200598) (xy 102.374192 -285.2039) (xy 102.201726 -285.50235) (xy 102.211378 -285.525464)
			(xy 102.219881 -285.547101) (xy 102.231873 -285.592016) (xy 102.237924 -285.63811) (xy 102.238302 -285.661354)
			(xy 102.465886 -285.661354) (xy 102.466384 -285.634705) (xy 102.474327 -285.582001) (xy 102.490037 -285.531071)
			(xy 102.513163 -285.48305) (xy 102.543187 -285.439013) (xy 102.579439 -285.399942) (xy 102.62111 -285.366711)
			(xy 102.667268 -285.340062) (xy 102.716882 -285.32059) (xy 102.768844 -285.30873) (xy 102.821994 -285.304747)
			(xy 102.875144 -285.30873) (xy 102.927106 -285.32059) (xy 102.97672 -285.340062) (xy 103.022878 -285.366711)
			(xy 103.064549 -285.399942) (xy 103.100801 -285.439013) (xy 103.130825 -285.48305) (xy 103.153951 -285.531071)
			(xy 103.169661 -285.582001) (xy 103.177604 -285.634705) (xy 103.178102 -285.661354) (xy 103.177706 -285.684557)
			(xy 103.171663 -285.730567) (xy 103.159685 -285.7754) (xy 103.151178 -285.79699) (xy 103.14178 -285.820104)
			(xy 103.3145 -286.119062) (xy 103.339138 -286.122364) (xy 103.364477 -286.126208) (xy 103.41378 -286.140198)
			(xy 103.46057 -286.161108) (xy 103.503881 -286.188508) (xy 103.542818 -286.221831) (xy 103.576579 -286.260389)
			(xy 103.604466 -286.303387) (xy 103.625904 -286.349938) (xy 103.640451 -286.39908) (xy 103.647805 -286.449799)
			(xy 103.648256 -286.475424) (xy 103.647758 -286.502073) (xy 103.639815 -286.554777) (xy 103.624105 -286.605707)
			(xy 103.600979 -286.653728) (xy 103.570955 -286.697765) (xy 103.534703 -286.736836) (xy 103.493032 -286.770067)
			(xy 103.446874 -286.796716) (xy 103.39726 -286.816188) (xy 103.345298 -286.828048) (xy 103.292148 -286.832032)
			(xy 103.238998 -286.828048) (xy 103.187036 -286.816188) (xy 103.137422 -286.796716) (xy 103.091264 -286.770067)
			(xy 103.049593 -286.736836) (xy 103.013341 -286.697765) (xy 102.983317 -286.653728) (xy 102.960191 -286.605707)
			(xy 102.944481 -286.554777) (xy 102.936538 -286.502073) (xy 102.93604 -286.475424) (xy 102.936414 -286.452179)
			(xy 102.942458 -286.406083) (xy 102.954447 -286.361166) (xy 102.962964 -286.339534) (xy 102.972616 -286.31642)
			(xy 102.799896 -286.017716) (xy 102.775258 -286.014414) (xy 102.749901 -286.010607) (xy 102.700563 -285.996646)
			(xy 102.653737 -285.975755) (xy 102.61039 -285.948366) (xy 102.571418 -285.915045) (xy 102.537626 -285.87648)
			(xy 102.509713 -285.833469) (xy 102.488255 -285.7869) (xy 102.473695 -285.737735) (xy 102.466336 -285.686991)
			(xy 102.465886 -285.661354) (xy 102.238302 -285.661354) (xy 102.237804 -285.688003) (xy 102.229861 -285.740707)
			(xy 102.214151 -285.791637) (xy 102.191025 -285.839658) (xy 102.161001 -285.883695) (xy 102.124749 -285.922766)
			(xy 102.083078 -285.955997) (xy 102.03692 -285.982646) (xy 101.987306 -286.002118) (xy 101.935344 -286.013978)
			(xy 101.882194 -286.017962) (xy 101.829044 -286.013978) (xy 101.777082 -286.002118) (xy 101.727468 -285.982646)
			(xy 101.68131 -285.955997) (xy 101.639639 -285.922766) (xy 101.603387 -285.883695) (xy 101.573363 -285.839658)
			(xy 101.550237 -285.791637) (xy 101.534527 -285.740707) (xy 101.526584 -285.688003) (xy 101.526086 -285.661354)
			(xy 101.298502 -285.661354) (xy 101.298106 -285.684557) (xy 101.292063 -285.730567) (xy 101.280085 -285.7754)
			(xy 101.271578 -285.79699) (xy 101.26218 -285.820104) (xy 101.4349 -286.119062) (xy 101.459538 -286.122364)
			(xy 101.484877 -286.126208) (xy 101.53418 -286.140198) (xy 101.58097 -286.161108) (xy 101.624281 -286.188508)
			(xy 101.663218 -286.221831) (xy 101.696979 -286.260389) (xy 101.724866 -286.303387) (xy 101.746304 -286.349938)
			(xy 101.760851 -286.39908) (xy 101.768205 -286.449799) (xy 101.768656 -286.475424) (xy 101.768158 -286.502073)
			(xy 101.996484 -286.502073) (xy 101.996484 -286.448775) (xy 102.004427 -286.396071) (xy 102.020137 -286.345141)
			(xy 102.043263 -286.29712) (xy 102.073287 -286.253083) (xy 102.109539 -286.214012) (xy 102.15121 -286.180781)
			(xy 102.197368 -286.154132) (xy 102.246982 -286.13466) (xy 102.298944 -286.1228) (xy 102.352094 -286.118817)
			(xy 102.405244 -286.1228) (xy 102.457206 -286.13466) (xy 102.50682 -286.154132) (xy 102.552978 -286.180781)
			(xy 102.594649 -286.214012) (xy 102.630901 -286.253083) (xy 102.660925 -286.29712) (xy 102.684051 -286.345141)
			(xy 102.699761 -286.396071) (xy 102.707704 -286.448775) (xy 102.708202 -286.475424) (xy 102.707704 -286.502073)
			(xy 102.699761 -286.554777) (xy 102.684051 -286.605707) (xy 102.660925 -286.653728) (xy 102.630901 -286.697765)
			(xy 102.594649 -286.736836) (xy 102.552978 -286.770067) (xy 102.50682 -286.796716) (xy 102.457206 -286.816188)
			(xy 102.405244 -286.828048) (xy 102.352094 -286.832032) (xy 102.298944 -286.828048) (xy 102.246982 -286.816188)
			(xy 102.197368 -286.796716) (xy 102.15121 -286.770067) (xy 102.109539 -286.736836) (xy 102.073287 -286.697765)
			(xy 102.043263 -286.653728) (xy 102.020137 -286.605707) (xy 102.004427 -286.554777) (xy 101.996484 -286.502073)
			(xy 101.768158 -286.502073) (xy 101.760215 -286.554777) (xy 101.744505 -286.605707) (xy 101.721379 -286.653728)
			(xy 101.691355 -286.697765) (xy 101.655103 -286.736836) (xy 101.613432 -286.770067) (xy 101.567274 -286.796716)
			(xy 101.51766 -286.816188) (xy 101.465698 -286.828048) (xy 101.412548 -286.832032) (xy 101.359398 -286.828048)
			(xy 101.307436 -286.816188) (xy 101.257822 -286.796716) (xy 101.211664 -286.770067) (xy 101.169993 -286.736836)
			(xy 101.133741 -286.697765) (xy 101.103717 -286.653728) (xy 101.080591 -286.605707) (xy 101.064881 -286.554777)
			(xy 101.056938 -286.502073) (xy 101.05644 -286.475424) (xy 101.056814 -286.452179) (xy 101.062858 -286.406083)
			(xy 101.074847 -286.361166) (xy 101.083364 -286.339534) (xy 101.093016 -286.31642) (xy 100.920296 -286.017716)
			(xy 100.895658 -286.014414) (xy 100.870301 -286.010607) (xy 100.820963 -285.996646) (xy 100.774137 -285.975755)
			(xy 100.73079 -285.948366) (xy 100.691818 -285.915045) (xy 100.658026 -285.87648) (xy 100.630113 -285.833469)
			(xy 100.608655 -285.7869) (xy 100.594095 -285.737735) (xy 100.586736 -285.686991) (xy 100.586286 -285.661354)
			(xy 100.358702 -285.661354) (xy 100.358204 -285.688003) (xy 100.350261 -285.740707) (xy 100.334551 -285.791637)
			(xy 100.311425 -285.839658) (xy 100.281401 -285.883695) (xy 100.245149 -285.922766) (xy 100.203478 -285.955997)
			(xy 100.15732 -285.982646) (xy 100.107706 -286.002118) (xy 100.055744 -286.013978) (xy 100.002594 -286.017962)
			(xy 99.949444 -286.013978) (xy 99.897482 -286.002118) (xy 99.847868 -285.982646) (xy 99.80171 -285.955997)
			(xy 99.760039 -285.922766) (xy 99.723787 -285.883695) (xy 99.693763 -285.839658) (xy 99.670637 -285.791637)
			(xy 99.654927 -285.740707) (xy 99.646984 -285.688003) (xy 99.646486 -285.661354) (xy 99.418902 -285.661354)
			(xy 99.418506 -285.684557) (xy 99.412463 -285.730567) (xy 99.400485 -285.7754) (xy 99.391978 -285.79699)
			(xy 99.38258 -285.820104) (xy 99.5553 -286.119062) (xy 99.579938 -286.122364) (xy 99.605277 -286.126208)
			(xy 99.65458 -286.140198) (xy 99.70137 -286.161108) (xy 99.744681 -286.188508) (xy 99.783618 -286.221831)
			(xy 99.817379 -286.260389) (xy 99.845266 -286.303387) (xy 99.866704 -286.349938) (xy 99.881251 -286.39908)
			(xy 99.888605 -286.449799) (xy 99.889056 -286.475424) (xy 99.888558 -286.502073) (xy 100.116884 -286.502073)
			(xy 100.116884 -286.448775) (xy 100.124827 -286.396071) (xy 100.140537 -286.345141) (xy 100.163663 -286.29712)
			(xy 100.193687 -286.253083) (xy 100.229939 -286.214012) (xy 100.27161 -286.180781) (xy 100.317768 -286.154132)
			(xy 100.367382 -286.13466) (xy 100.419344 -286.1228) (xy 100.472494 -286.118817) (xy 100.525644 -286.1228)
			(xy 100.577606 -286.13466) (xy 100.62722 -286.154132) (xy 100.673378 -286.180781) (xy 100.715049 -286.214012)
			(xy 100.751301 -286.253083) (xy 100.781325 -286.29712) (xy 100.804451 -286.345141) (xy 100.820161 -286.396071)
			(xy 100.828104 -286.448775) (xy 100.828602 -286.475424) (xy 100.828104 -286.502073) (xy 100.820161 -286.554777)
			(xy 100.804451 -286.605707) (xy 100.781325 -286.653728) (xy 100.751301 -286.697765) (xy 100.715049 -286.736836)
			(xy 100.673378 -286.770067) (xy 100.62722 -286.796716) (xy 100.577606 -286.816188) (xy 100.525644 -286.828048)
			(xy 100.472494 -286.832032) (xy 100.419344 -286.828048) (xy 100.367382 -286.816188) (xy 100.317768 -286.796716)
			(xy 100.27161 -286.770067) (xy 100.229939 -286.736836) (xy 100.193687 -286.697765) (xy 100.163663 -286.653728)
			(xy 100.140537 -286.605707) (xy 100.124827 -286.554777) (xy 100.116884 -286.502073) (xy 99.888558 -286.502073)
			(xy 99.880615 -286.554777) (xy 99.864905 -286.605707) (xy 99.841779 -286.653728) (xy 99.811755 -286.697765)
			(xy 99.775503 -286.736836) (xy 99.733832 -286.770067) (xy 99.687674 -286.796716) (xy 99.63806 -286.816188)
			(xy 99.586098 -286.828048) (xy 99.532948 -286.832032) (xy 99.479798 -286.828048) (xy 99.427836 -286.816188)
			(xy 99.378222 -286.796716) (xy 99.332064 -286.770067) (xy 99.290393 -286.736836) (xy 99.254141 -286.697765)
			(xy 99.224117 -286.653728) (xy 99.200991 -286.605707) (xy 99.185281 -286.554777) (xy 99.177338 -286.502073)
			(xy 99.17684 -286.475424) (xy 99.177214 -286.452179) (xy 99.183258 -286.406083) (xy 99.195247 -286.361166)
			(xy 99.203764 -286.339534) (xy 99.213416 -286.31642) (xy 99.040696 -286.017716) (xy 99.016058 -286.014414)
			(xy 98.990701 -286.010607) (xy 98.941363 -285.996646) (xy 98.894537 -285.975755) (xy 98.85119 -285.948366)
			(xy 98.812218 -285.915045) (xy 98.778426 -285.87648) (xy 98.750513 -285.833469) (xy 98.729055 -285.7869)
			(xy 98.714495 -285.737735) (xy 98.707136 -285.686991) (xy 98.706686 -285.661354) (xy 98.479102 -285.661354)
			(xy 98.478604 -285.688003) (xy 98.470661 -285.740707) (xy 98.454951 -285.791637) (xy 98.431825 -285.839658)
			(xy 98.401801 -285.883695) (xy 98.365549 -285.922766) (xy 98.323878 -285.955997) (xy 98.27772 -285.982646)
			(xy 98.228106 -286.002118) (xy 98.176144 -286.013978) (xy 98.122994 -286.017962) (xy 98.069844 -286.013978)
			(xy 98.017882 -286.002118) (xy 97.968268 -285.982646) (xy 97.92211 -285.955997) (xy 97.880439 -285.922766)
			(xy 97.844187 -285.883695) (xy 97.814163 -285.839658) (xy 97.791037 -285.791637) (xy 97.775327 -285.740707)
			(xy 97.767384 -285.688003) (xy 97.766886 -285.661354) (xy 97.539302 -285.661354) (xy 97.538906 -285.684557)
			(xy 97.532863 -285.730567) (xy 97.520885 -285.7754) (xy 97.512378 -285.79699) (xy 97.50298 -285.820104)
			(xy 97.6757 -286.119062) (xy 97.700338 -286.122364) (xy 97.725677 -286.126208) (xy 97.77498 -286.140198)
			(xy 97.82177 -286.161108) (xy 97.865081 -286.188508) (xy 97.904018 -286.221831) (xy 97.937779 -286.260389)
			(xy 97.965666 -286.303387) (xy 97.987104 -286.349938) (xy 98.001651 -286.39908) (xy 98.009005 -286.449799)
			(xy 98.009456 -286.475424) (xy 98.008958 -286.502073) (xy 98.237284 -286.502073) (xy 98.237284 -286.448775)
			(xy 98.245227 -286.396071) (xy 98.260937 -286.345141) (xy 98.284063 -286.29712) (xy 98.314087 -286.253083)
			(xy 98.350339 -286.214012) (xy 98.39201 -286.180781) (xy 98.438168 -286.154132) (xy 98.487782 -286.13466)
			(xy 98.539744 -286.1228) (xy 98.592894 -286.118817) (xy 98.646044 -286.1228) (xy 98.698006 -286.13466)
			(xy 98.74762 -286.154132) (xy 98.793778 -286.180781) (xy 98.835449 -286.214012) (xy 98.871701 -286.253083)
			(xy 98.901725 -286.29712) (xy 98.924851 -286.345141) (xy 98.940561 -286.396071) (xy 98.948504 -286.448775)
			(xy 98.949002 -286.475424) (xy 98.948504 -286.502073) (xy 98.940561 -286.554777) (xy 98.924851 -286.605707)
			(xy 98.901725 -286.653728) (xy 98.871701 -286.697765) (xy 98.835449 -286.736836) (xy 98.793778 -286.770067)
			(xy 98.74762 -286.796716) (xy 98.698006 -286.816188) (xy 98.646044 -286.828048) (xy 98.592894 -286.832032)
			(xy 98.539744 -286.828048) (xy 98.487782 -286.816188) (xy 98.438168 -286.796716) (xy 98.39201 -286.770067)
			(xy 98.350339 -286.736836) (xy 98.314087 -286.697765) (xy 98.284063 -286.653728) (xy 98.260937 -286.605707)
			(xy 98.245227 -286.554777) (xy 98.237284 -286.502073) (xy 98.008958 -286.502073) (xy 98.001015 -286.554777)
			(xy 97.985305 -286.605707) (xy 97.962179 -286.653728) (xy 97.932155 -286.697765) (xy 97.895903 -286.736836)
			(xy 97.854232 -286.770067) (xy 97.808074 -286.796716) (xy 97.75846 -286.816188) (xy 97.706498 -286.828048)
			(xy 97.653348 -286.832032) (xy 97.600198 -286.828048) (xy 97.548236 -286.816188) (xy 97.498622 -286.796716)
			(xy 97.452464 -286.770067) (xy 97.410793 -286.736836) (xy 97.374541 -286.697765) (xy 97.344517 -286.653728)
			(xy 97.321391 -286.605707) (xy 97.305681 -286.554777) (xy 97.297738 -286.502073) (xy 97.29724 -286.475424)
			(xy 97.297614 -286.452179) (xy 97.303658 -286.406083) (xy 97.315647 -286.361166) (xy 97.324164 -286.339534)
			(xy 97.333816 -286.31642) (xy 97.161096 -286.017716) (xy 97.136458 -286.014414) (xy 97.111101 -286.010607)
			(xy 97.061763 -285.996646) (xy 97.014937 -285.975755) (xy 96.97159 -285.948366) (xy 96.932618 -285.915045)
			(xy 96.898826 -285.87648) (xy 96.870913 -285.833469) (xy 96.849455 -285.7869) (xy 96.834895 -285.737735)
			(xy 96.827536 -285.686991) (xy 96.827086 -285.661354) (xy 96.599502 -285.661354) (xy 96.599004 -285.688003)
			(xy 96.591061 -285.740707) (xy 96.575351 -285.791637) (xy 96.552225 -285.839658) (xy 96.522201 -285.883695)
			(xy 96.485949 -285.922766) (xy 96.444278 -285.955997) (xy 96.39812 -285.982646) (xy 96.348506 -286.002118)
			(xy 96.296544 -286.013978) (xy 96.243394 -286.017962) (xy 96.190244 -286.013978) (xy 96.138282 -286.002118)
			(xy 96.088668 -285.982646) (xy 96.04251 -285.955997) (xy 96.000839 -285.922766) (xy 95.964587 -285.883695)
			(xy 95.934563 -285.839658) (xy 95.911437 -285.791637) (xy 95.895727 -285.740707) (xy 95.887784 -285.688003)
			(xy 95.887286 -285.661354) (xy 95.659702 -285.661354) (xy 95.659306 -285.684557) (xy 95.653263 -285.730567)
			(xy 95.641285 -285.7754) (xy 95.632778 -285.79699) (xy 95.62338 -285.820104) (xy 95.7961 -286.119062)
			(xy 95.820738 -286.122364) (xy 95.846077 -286.126208) (xy 95.89538 -286.140198) (xy 95.94217 -286.161108)
			(xy 95.985481 -286.188508) (xy 96.024418 -286.221831) (xy 96.058179 -286.260389) (xy 96.086066 -286.303387)
			(xy 96.107504 -286.349938) (xy 96.122051 -286.39908) (xy 96.129405 -286.449799) (xy 96.129856 -286.475424)
			(xy 96.129358 -286.502073) (xy 96.357684 -286.502073) (xy 96.357684 -286.448775) (xy 96.365627 -286.396071)
			(xy 96.381337 -286.345141) (xy 96.404463 -286.29712) (xy 96.434487 -286.253083) (xy 96.470739 -286.214012)
			(xy 96.51241 -286.180781) (xy 96.558568 -286.154132) (xy 96.608182 -286.13466) (xy 96.660144 -286.1228)
			(xy 96.713294 -286.118817) (xy 96.766444 -286.1228) (xy 96.818406 -286.13466) (xy 96.86802 -286.154132)
			(xy 96.914178 -286.180781) (xy 96.955849 -286.214012) (xy 96.992101 -286.253083) (xy 97.022125 -286.29712)
			(xy 97.045251 -286.345141) (xy 97.060961 -286.396071) (xy 97.068904 -286.448775) (xy 97.069402 -286.475424)
			(xy 97.068904 -286.502073) (xy 97.060961 -286.554777) (xy 97.045251 -286.605707) (xy 97.022125 -286.653728)
			(xy 96.992101 -286.697765) (xy 96.955849 -286.736836) (xy 96.914178 -286.770067) (xy 96.86802 -286.796716)
			(xy 96.818406 -286.816188) (xy 96.766444 -286.828048) (xy 96.713294 -286.832032) (xy 96.660144 -286.828048)
			(xy 96.608182 -286.816188) (xy 96.558568 -286.796716) (xy 96.51241 -286.770067) (xy 96.470739 -286.736836)
			(xy 96.434487 -286.697765) (xy 96.404463 -286.653728) (xy 96.381337 -286.605707) (xy 96.365627 -286.554777)
			(xy 96.357684 -286.502073) (xy 96.129358 -286.502073) (xy 96.121415 -286.554777) (xy 96.105705 -286.605707)
			(xy 96.082579 -286.653728) (xy 96.052555 -286.697765) (xy 96.016303 -286.736836) (xy 95.974632 -286.770067)
			(xy 95.928474 -286.796716) (xy 95.87886 -286.816188) (xy 95.826898 -286.828048) (xy 95.773748 -286.832032)
			(xy 95.720598 -286.828048) (xy 95.668636 -286.816188) (xy 95.619022 -286.796716) (xy 95.572864 -286.770067)
			(xy 95.531193 -286.736836) (xy 95.494941 -286.697765) (xy 95.464917 -286.653728) (xy 95.441791 -286.605707)
			(xy 95.426081 -286.554777) (xy 95.418138 -286.502073) (xy 95.41764 -286.475424) (xy 95.418014 -286.452179)
			(xy 95.424058 -286.406083) (xy 95.436047 -286.361166) (xy 95.444564 -286.339534) (xy 95.454216 -286.31642)
			(xy 95.281496 -286.017716) (xy 95.256858 -286.014414) (xy 95.231501 -286.010607) (xy 95.182163 -285.996646)
			(xy 95.135337 -285.975755) (xy 95.09199 -285.948366) (xy 95.053018 -285.915045) (xy 95.019226 -285.87648)
			(xy 94.991313 -285.833469) (xy 94.969855 -285.7869) (xy 94.955295 -285.737735) (xy 94.947936 -285.686991)
			(xy 94.947486 -285.661354) (xy 94.719902 -285.661354) (xy 94.719404 -285.688003) (xy 94.711461 -285.740707)
			(xy 94.695751 -285.791637) (xy 94.672625 -285.839658) (xy 94.642601 -285.883695) (xy 94.606349 -285.922766)
			(xy 94.564678 -285.955997) (xy 94.51852 -285.982646) (xy 94.468906 -286.002118) (xy 94.416944 -286.013978)
			(xy 94.363794 -286.017962) (xy 94.310644 -286.013978) (xy 94.258682 -286.002118) (xy 94.209068 -285.982646)
			(xy 94.16291 -285.955997) (xy 94.121239 -285.922766) (xy 94.084987 -285.883695) (xy 94.054963 -285.839658)
			(xy 94.031837 -285.791637) (xy 94.016127 -285.740707) (xy 94.008184 -285.688003) (xy 94.007686 -285.661354)
			(xy 93.780102 -285.661354) (xy 93.779706 -285.684557) (xy 93.773663 -285.730567) (xy 93.761685 -285.7754)
			(xy 93.753178 -285.79699) (xy 93.74378 -285.820104) (xy 93.9165 -286.119062) (xy 93.941138 -286.122364)
			(xy 93.966477 -286.126208) (xy 94.01578 -286.140198) (xy 94.06257 -286.161108) (xy 94.105881 -286.188508)
			(xy 94.144818 -286.221831) (xy 94.178579 -286.260389) (xy 94.206466 -286.303387) (xy 94.227904 -286.349938)
			(xy 94.242451 -286.39908) (xy 94.249805 -286.449799) (xy 94.250256 -286.475424) (xy 94.249758 -286.502073)
			(xy 94.478084 -286.502073) (xy 94.478084 -286.448775) (xy 94.486027 -286.396071) (xy 94.501737 -286.345141)
			(xy 94.524863 -286.29712) (xy 94.554887 -286.253083) (xy 94.591139 -286.214012) (xy 94.63281 -286.180781)
			(xy 94.678968 -286.154132) (xy 94.728582 -286.13466) (xy 94.780544 -286.1228) (xy 94.833694 -286.118817)
			(xy 94.886844 -286.1228) (xy 94.938806 -286.13466) (xy 94.98842 -286.154132) (xy 95.034578 -286.180781)
			(xy 95.076249 -286.214012) (xy 95.112501 -286.253083) (xy 95.142525 -286.29712) (xy 95.165651 -286.345141)
			(xy 95.181361 -286.396071) (xy 95.189304 -286.448775) (xy 95.189802 -286.475424) (xy 95.189304 -286.502073)
			(xy 95.181361 -286.554777) (xy 95.165651 -286.605707) (xy 95.142525 -286.653728) (xy 95.112501 -286.697765)
			(xy 95.076249 -286.736836) (xy 95.034578 -286.770067) (xy 94.98842 -286.796716) (xy 94.938806 -286.816188)
			(xy 94.886844 -286.828048) (xy 94.833694 -286.832032) (xy 94.780544 -286.828048) (xy 94.728582 -286.816188)
			(xy 94.678968 -286.796716) (xy 94.63281 -286.770067) (xy 94.591139 -286.736836) (xy 94.554887 -286.697765)
			(xy 94.524863 -286.653728) (xy 94.501737 -286.605707) (xy 94.486027 -286.554777) (xy 94.478084 -286.502073)
			(xy 94.249758 -286.502073) (xy 94.241815 -286.554777) (xy 94.226105 -286.605707) (xy 94.202979 -286.653728)
			(xy 94.172955 -286.697765) (xy 94.136703 -286.736836) (xy 94.095032 -286.770067) (xy 94.048874 -286.796716)
			(xy 93.99926 -286.816188) (xy 93.947298 -286.828048) (xy 93.894148 -286.832032) (xy 93.840998 -286.828048)
			(xy 93.789036 -286.816188) (xy 93.739422 -286.796716) (xy 93.693264 -286.770067) (xy 93.651593 -286.736836)
			(xy 93.615341 -286.697765) (xy 93.585317 -286.653728) (xy 93.562191 -286.605707) (xy 93.546481 -286.554777)
			(xy 93.538538 -286.502073) (xy 93.53804 -286.475424) (xy 93.538414 -286.452179) (xy 93.544458 -286.406083)
			(xy 93.556447 -286.361166) (xy 93.564964 -286.339534) (xy 93.574616 -286.31642) (xy 93.401896 -286.017716)
			(xy 93.377258 -286.014414) (xy 93.351901 -286.010607) (xy 93.302563 -285.996646) (xy 93.255737 -285.975755)
			(xy 93.21239 -285.948366) (xy 93.173418 -285.915045) (xy 93.139626 -285.87648) (xy 93.111713 -285.833469)
			(xy 93.090255 -285.7869) (xy 93.075695 -285.737735) (xy 93.068336 -285.686991) (xy 93.067886 -285.661354)
			(xy 92.840302 -285.661354) (xy 92.839804 -285.688003) (xy 92.831861 -285.740707) (xy 92.816151 -285.791637)
			(xy 92.793025 -285.839658) (xy 92.763001 -285.883695) (xy 92.726749 -285.922766) (xy 92.685078 -285.955997)
			(xy 92.63892 -285.982646) (xy 92.589306 -286.002118) (xy 92.537344 -286.013978) (xy 92.484194 -286.017962)
			(xy 92.431044 -286.013978) (xy 92.379082 -286.002118) (xy 92.329468 -285.982646) (xy 92.28331 -285.955997)
			(xy 92.241639 -285.922766) (xy 92.205387 -285.883695) (xy 92.175363 -285.839658) (xy 92.152237 -285.791637)
			(xy 92.136527 -285.740707) (xy 92.128584 -285.688003) (xy 92.128086 -285.661354) (xy 91.900756 -285.661354)
			(xy 91.900375 -285.684599) (xy 91.894334 -285.730694) (xy 91.882348 -285.775612) (xy 91.873832 -285.797244)
			(xy 91.86418 -285.820358) (xy 92.0369 -286.119062) (xy 92.061538 -286.122364) (xy 92.086877 -286.126208)
			(xy 92.13618 -286.140198) (xy 92.18297 -286.161108) (xy 92.226281 -286.188508) (xy 92.265218 -286.221831)
			(xy 92.298979 -286.260389) (xy 92.326866 -286.303387) (xy 92.348304 -286.349938) (xy 92.362851 -286.39908)
			(xy 92.370205 -286.449799) (xy 92.370656 -286.475424) (xy 92.370158 -286.502073) (xy 92.598738 -286.502073)
			(xy 92.598738 -286.448775) (xy 92.606681 -286.396071) (xy 92.622391 -286.345141) (xy 92.645517 -286.29712)
			(xy 92.675541 -286.253083) (xy 92.711793 -286.214012) (xy 92.753464 -286.180781) (xy 92.799622 -286.154132)
			(xy 92.849236 -286.13466) (xy 92.901198 -286.1228) (xy 92.954348 -286.118817) (xy 93.007498 -286.1228)
			(xy 93.05946 -286.13466) (xy 93.109074 -286.154132) (xy 93.155232 -286.180781) (xy 93.196903 -286.214012)
			(xy 93.233155 -286.253083) (xy 93.263179 -286.29712) (xy 93.286305 -286.345141) (xy 93.302015 -286.396071)
			(xy 93.309958 -286.448775) (xy 93.310456 -286.475424) (xy 93.309958 -286.502073) (xy 93.302015 -286.554777)
			(xy 93.286305 -286.605707) (xy 93.263179 -286.653728) (xy 93.233155 -286.697765) (xy 93.196903 -286.736836)
			(xy 93.155232 -286.770067) (xy 93.109074 -286.796716) (xy 93.05946 -286.816188) (xy 93.007498 -286.828048)
			(xy 92.954348 -286.832032) (xy 92.901198 -286.828048) (xy 92.849236 -286.816188) (xy 92.799622 -286.796716)
			(xy 92.753464 -286.770067) (xy 92.711793 -286.736836) (xy 92.675541 -286.697765) (xy 92.645517 -286.653728)
			(xy 92.622391 -286.605707) (xy 92.606681 -286.554777) (xy 92.598738 -286.502073) (xy 92.370158 -286.502073)
			(xy 92.362215 -286.554777) (xy 92.346505 -286.605707) (xy 92.323379 -286.653728) (xy 92.293355 -286.697765)
			(xy 92.257103 -286.736836) (xy 92.215432 -286.770067) (xy 92.169274 -286.796716) (xy 92.11966 -286.816188)
			(xy 92.067698 -286.828048) (xy 92.014548 -286.832032) (xy 91.961398 -286.828048) (xy 91.909436 -286.816188)
			(xy 91.859822 -286.796716) (xy 91.813664 -286.770067) (xy 91.771993 -286.736836) (xy 91.735741 -286.697765)
			(xy 91.705717 -286.653728) (xy 91.682591 -286.605707) (xy 91.666881 -286.554777) (xy 91.658938 -286.502073)
			(xy 91.65844 -286.475424) (xy 91.658814 -286.452179) (xy 91.664858 -286.406083) (xy 91.676847 -286.361166)
			(xy 91.685364 -286.339534) (xy 91.695016 -286.31642) (xy 91.522296 -286.017716) (xy 91.497658 -286.014414)
			(xy 91.472315 -286.010595) (xy 91.42301 -285.996603) (xy 91.376218 -285.97569) (xy 91.332907 -285.948288)
			(xy 91.293969 -285.914963) (xy 91.260208 -285.876401) (xy 91.232322 -285.8334) (xy 91.210885 -285.786847)
			(xy 91.196341 -285.737702) (xy 91.188989 -285.68698) (xy 91.18854 -285.661354) (xy 90.960956 -285.661354)
			(xy 90.960458 -285.688003) (xy 90.952515 -285.740707) (xy 90.936805 -285.791637) (xy 90.913679 -285.839658)
			(xy 90.883655 -285.883695) (xy 90.847403 -285.922766) (xy 90.805732 -285.955997) (xy 90.759574 -285.982646)
			(xy 90.70996 -286.002118) (xy 90.657998 -286.013978) (xy 90.604848 -286.017962) (xy 90.551698 -286.013978)
			(xy 90.499736 -286.002118) (xy 90.450122 -285.982646) (xy 90.403964 -285.955997) (xy 90.362293 -285.922766)
			(xy 90.326041 -285.883695) (xy 90.296017 -285.839658) (xy 90.272891 -285.791637) (xy 90.257181 -285.740707)
			(xy 90.249238 -285.688003) (xy 90.24874 -285.661354) (xy 90.020902 -285.661354) (xy 90.020518 -285.684599)
			(xy 90.014477 -285.730694) (xy 90.002493 -285.775612) (xy 89.993978 -285.797244) (xy 89.984326 -285.820358)
			(xy 90.157046 -286.119062) (xy 90.181684 -286.122364) (xy 90.207016 -286.12625) (xy 90.256319 -286.140233)
			(xy 90.303109 -286.161137) (xy 90.346421 -286.188531) (xy 90.38536 -286.221848) (xy 90.419122 -286.260402)
			(xy 90.44701 -286.303397) (xy 90.468449 -286.349944) (xy 90.482996 -286.399084) (xy 90.490351 -286.4498)
			(xy 90.490802 -286.475424) (xy 90.490304 -286.502073) (xy 90.718884 -286.502073) (xy 90.718884 -286.448775)
			(xy 90.726827 -286.396071) (xy 90.742537 -286.345141) (xy 90.765663 -286.29712) (xy 90.795687 -286.253083)
			(xy 90.831939 -286.214012) (xy 90.87361 -286.180781) (xy 90.919768 -286.154132) (xy 90.969382 -286.13466)
			(xy 91.021344 -286.1228) (xy 91.074494 -286.118817) (xy 91.127644 -286.1228) (xy 91.179606 -286.13466)
			(xy 91.22922 -286.154132) (xy 91.275378 -286.180781) (xy 91.317049 -286.214012) (xy 91.353301 -286.253083)
			(xy 91.383325 -286.29712) (xy 91.406451 -286.345141) (xy 91.422161 -286.396071) (xy 91.430104 -286.448775)
			(xy 91.430602 -286.475424) (xy 91.430104 -286.502073) (xy 91.422161 -286.554777) (xy 91.406451 -286.605707)
			(xy 91.383325 -286.653728) (xy 91.353301 -286.697765) (xy 91.317049 -286.736836) (xy 91.275378 -286.770067)
			(xy 91.22922 -286.796716) (xy 91.179606 -286.816188) (xy 91.127644 -286.828048) (xy 91.074494 -286.832032)
			(xy 91.021344 -286.828048) (xy 90.969382 -286.816188) (xy 90.919768 -286.796716) (xy 90.87361 -286.770067)
			(xy 90.831939 -286.736836) (xy 90.795687 -286.697765) (xy 90.765663 -286.653728) (xy 90.742537 -286.605707)
			(xy 90.726827 -286.554777) (xy 90.718884 -286.502073) (xy 90.490304 -286.502073) (xy 90.482361 -286.554777)
			(xy 90.466651 -286.605707) (xy 90.443525 -286.653728) (xy 90.413501 -286.697765) (xy 90.377249 -286.736836)
			(xy 90.335578 -286.770067) (xy 90.28942 -286.796716) (xy 90.239806 -286.816188) (xy 90.187844 -286.828048)
			(xy 90.134694 -286.832032) (xy 90.081544 -286.828048) (xy 90.029582 -286.816188) (xy 89.979968 -286.796716)
			(xy 89.93381 -286.770067) (xy 89.892139 -286.736836) (xy 89.855887 -286.697765) (xy 89.825863 -286.653728)
			(xy 89.802737 -286.605707) (xy 89.787027 -286.554777) (xy 89.779084 -286.502073) (xy 89.778586 -286.475424)
			(xy 89.778963 -286.452179) (xy 89.785007 -286.406084) (xy 89.796994 -286.361166) (xy 89.80551 -286.339534)
			(xy 89.815162 -286.31642) (xy 89.642442 -286.017716) (xy 89.617804 -286.014414) (xy 89.592466 -286.010558)
			(xy 89.543162 -285.996573) (xy 89.49637 -285.975666) (xy 89.453058 -285.948269) (xy 89.414119 -285.914948)
			(xy 89.380357 -285.87639) (xy 89.35247 -285.833392) (xy 89.331032 -285.786841) (xy 89.316487 -285.737699)
			(xy 89.309135 -285.686979) (xy 89.308686 -285.661354) (xy 89.081102 -285.661354) (xy 89.080604 -285.688003)
			(xy 89.072661 -285.740707) (xy 89.056951 -285.791637) (xy 89.033825 -285.839658) (xy 89.003801 -285.883695)
			(xy 88.967549 -285.922766) (xy 88.925878 -285.955997) (xy 88.87972 -285.982646) (xy 88.830106 -286.002118)
			(xy 88.778144 -286.013978) (xy 88.724994 -286.017962) (xy 88.671844 -286.013978) (xy 88.619882 -286.002118)
			(xy 88.570268 -285.982646) (xy 88.52411 -285.955997) (xy 88.482439 -285.922766) (xy 88.446187 -285.883695)
			(xy 88.416163 -285.839658) (xy 88.393037 -285.791637) (xy 88.377327 -285.740707) (xy 88.369384 -285.688003)
			(xy 88.140804 -285.688003) (xy 88.132861 -285.740707) (xy 88.117151 -285.791637) (xy 88.094025 -285.839658)
			(xy 88.064001 -285.883695) (xy 88.027749 -285.922766) (xy 87.986078 -285.955997) (xy 87.93992 -285.982646)
			(xy 87.890306 -286.002118) (xy 87.838344 -286.013978) (xy 87.785194 -286.017962) (xy 87.732044 -286.013978)
			(xy 87.680082 -286.002118) (xy 87.630468 -285.982646) (xy 87.58431 -285.955997) (xy 87.542639 -285.922766)
			(xy 87.506387 -285.883695) (xy 87.476363 -285.839658) (xy 87.453237 -285.791637) (xy 87.437527 -285.740707)
			(xy 87.429584 -285.688003) (xy 87.429086 -285.661354) (xy 87.201502 -285.661354) (xy 87.201004 -285.688003)
			(xy 87.193061 -285.740707) (xy 87.177351 -285.791637) (xy 87.154225 -285.839658) (xy 87.124201 -285.883695)
			(xy 87.087949 -285.922766) (xy 87.046278 -285.955997) (xy 87.00012 -285.982646) (xy 86.950506 -286.002118)
			(xy 86.898544 -286.013978) (xy 86.845394 -286.017962) (xy 86.792244 -286.013978) (xy 86.740282 -286.002118)
			(xy 86.690668 -285.982646) (xy 86.64451 -285.955997) (xy 86.602839 -285.922766) (xy 86.566587 -285.883695)
			(xy 86.536563 -285.839658) (xy 86.513437 -285.791637) (xy 86.497727 -285.740707) (xy 86.489784 -285.688003)
			(xy 86.260284 -285.688003) (xy 86.258294 -285.714561) (xy 86.246431 -285.766534) (xy 86.226955 -285.816158)
			(xy 86.2003 -285.862326) (xy 86.167062 -285.904005) (xy 86.127982 -285.940264) (xy 86.083936 -285.970294)
			(xy 86.035905 -285.993424) (xy 85.984963 -286.009136) (xy 85.932249 -286.017081) (xy 85.905594 -286.017462)
			(xy 85.876625 -286.016895) (xy 85.81945 -286.007525) (xy 85.764544 -285.989031) (xy 85.713351 -285.961901)
			(xy 85.689948 -285.944818) (xy 85.67843 -285.936643) (xy 85.65213 -285.926373) (xy 85.624022 -285.923699)
			(xy 85.596258 -285.928826) (xy 85.570958 -285.941361) (xy 85.55006 -285.960345) (xy 85.535159 -285.984327)
			(xy 85.527397 -286.011473) (xy 85.52688 -286.02559) (xy 85.52688 -286.129476) (xy 85.5599 -286.141668)
			(xy 85.585071 -286.151572) (xy 85.632327 -286.177887) (xy 85.67506 -286.211046) (xy 85.712287 -286.250287)
			(xy 85.74315 -286.294706) (xy 85.766941 -286.343282) (xy 85.783112 -286.394897) (xy 85.791291 -286.448364)
			(xy 85.79129 -286.475424) (xy 86.019386 -286.475424) (xy 86.019884 -286.448775) (xy 86.027827 -286.396071)
			(xy 86.043537 -286.345141) (xy 86.066663 -286.29712) (xy 86.096687 -286.253083) (xy 86.132939 -286.214012)
			(xy 86.17461 -286.180781) (xy 86.220768 -286.154132) (xy 86.270382 -286.13466) (xy 86.322344 -286.1228)
			(xy 86.375494 -286.118817) (xy 86.428644 -286.1228) (xy 86.480606 -286.13466) (xy 86.53022 -286.154132)
			(xy 86.576378 -286.180781) (xy 86.618049 -286.214012) (xy 86.654301 -286.253083) (xy 86.684325 -286.29712)
			(xy 86.707451 -286.345141) (xy 86.723161 -286.396071) (xy 86.731104 -286.448775) (xy 86.731602 -286.4754)
			(xy 86.958717 -286.4754) (xy 86.9627 -286.422255) (xy 86.974559 -286.370296) (xy 86.994029 -286.320686)
			(xy 87.020676 -286.274532) (xy 87.053904 -286.232864) (xy 87.092971 -286.196614) (xy 87.137005 -286.166592)
			(xy 87.185021 -286.143468) (xy 87.235948 -286.127758) (xy 87.288647 -286.119815) (xy 87.315294 -286.119316)
			(xy 87.340308 -286.119756) (xy 87.389845 -286.12674) (xy 87.437918 -286.140586) (xy 87.483581 -286.16102)
			(xy 87.525937 -286.187642) (xy 87.564151 -286.219928) (xy 87.597473 -286.257242) (xy 87.611712 -286.277812)
			(xy 87.958676 -286.277812) (xy 87.972903 -286.257234) (xy 88.006234 -286.219926) (xy 88.044452 -286.187645)
			(xy 88.086809 -286.161024) (xy 88.132472 -286.140586) (xy 88.180544 -286.126734) (xy 88.23008 -286.119738)
			(xy 88.255094 -286.119316) (xy 88.281747 -286.119741) (xy 88.334458 -286.127685) (xy 88.385397 -286.143397)
			(xy 88.433425 -286.166525) (xy 88.477469 -286.196553) (xy 88.516545 -286.23281) (xy 88.549782 -286.274487)
			(xy 88.576435 -286.320651) (xy 88.59591 -286.370273) (xy 88.607772 -286.422243) (xy 88.611756 -286.4754)
			(xy 88.607772 -286.528557) (xy 88.59591 -286.580527) (xy 88.576435 -286.630149) (xy 88.549782 -286.676313)
			(xy 88.516545 -286.71799) (xy 88.477469 -286.754247) (xy 88.433425 -286.784275) (xy 88.385397 -286.807403)
			(xy 88.334458 -286.823115) (xy 88.281747 -286.831059) (xy 88.255094 -286.831532) (xy 88.230079 -286.831124)
			(xy 88.180539 -286.824137) (xy 88.132465 -286.810288) (xy 88.0868 -286.789848) (xy 88.044445 -286.763221)
			(xy 88.006232 -286.730929) (xy 87.972913 -286.693609) (xy 87.958676 -286.673036) (xy 87.611712 -286.673036)
			(xy 87.597507 -286.69363) (xy 87.564172 -286.730935) (xy 87.525948 -286.763214) (xy 87.483587 -286.789832)
			(xy 87.437922 -286.810267) (xy 87.389847 -286.824117) (xy 87.340309 -286.83111) (xy 87.315294 -286.831532)
			(xy 87.288647 -286.830985) (xy 87.235948 -286.823042) (xy 87.185021 -286.807332) (xy 87.137005 -286.784208)
			(xy 87.092971 -286.754186) (xy 87.053904 -286.717936) (xy 87.020676 -286.676268) (xy 86.994029 -286.630114)
			(xy 86.974559 -286.580504) (xy 86.9627 -286.528545) (xy 86.958717 -286.4754) (xy 86.731602 -286.4754)
			(xy 86.731602 -286.475424) (xy 86.731229 -286.498627) (xy 86.725176 -286.544638) (xy 86.713189 -286.589471)
			(xy 86.704678 -286.61106) (xy 86.69528 -286.634174) (xy 86.867746 -286.932878) (xy 86.892638 -286.93618)
			(xy 86.917966 -286.940021) (xy 86.967238 -286.954042) (xy 87.013994 -286.974976) (xy 87.05727 -287.00239)
			(xy 87.096173 -287.035719) (xy 87.129903 -287.074276) (xy 87.157762 -287.117266) (xy 87.179178 -287.163803)
			(xy 87.193708 -287.212927) (xy 87.201054 -287.263626) (xy 87.201502 -287.28924) (xy 87.201004 -287.315889)
			(xy 87.429584 -287.315889) (xy 87.429584 -287.262591) (xy 87.437527 -287.209887) (xy 87.453237 -287.158957)
			(xy 87.476363 -287.110936) (xy 87.506387 -287.066899) (xy 87.542639 -287.027828) (xy 87.58431 -286.994597)
			(xy 87.630468 -286.967948) (xy 87.680082 -286.948476) (xy 87.732044 -286.936616) (xy 87.785194 -286.932633)
			(xy 87.838344 -286.936616) (xy 87.890306 -286.948476) (xy 87.93992 -286.967948) (xy 87.986078 -286.994597)
			(xy 88.027749 -287.027828) (xy 88.064001 -287.066899) (xy 88.094025 -287.110936) (xy 88.117151 -287.158957)
			(xy 88.132861 -287.209887) (xy 88.140804 -287.262591) (xy 88.141302 -287.28924) (xy 88.140804 -287.315889)
			(xy 88.369384 -287.315889) (xy 88.369384 -287.262591) (xy 88.377327 -287.209887) (xy 88.393037 -287.158957)
			(xy 88.416163 -287.110936) (xy 88.446187 -287.066899) (xy 88.482439 -287.027828) (xy 88.52411 -286.994597)
			(xy 88.570268 -286.967948) (xy 88.619882 -286.948476) (xy 88.671844 -286.936616) (xy 88.724994 -286.932633)
			(xy 88.778144 -286.936616) (xy 88.830106 -286.948476) (xy 88.87972 -286.967948) (xy 88.925878 -286.994597)
			(xy 88.967549 -287.027828) (xy 89.003801 -287.066899) (xy 89.033825 -287.110936) (xy 89.056951 -287.158957)
			(xy 89.072661 -287.209887) (xy 89.080604 -287.262591) (xy 89.081102 -287.28924) (xy 89.080604 -287.315889)
			(xy 89.309184 -287.315889) (xy 89.309184 -287.262591) (xy 89.317127 -287.209887) (xy 89.332837 -287.158957)
			(xy 89.355963 -287.110936) (xy 89.385987 -287.066899) (xy 89.422239 -287.027828) (xy 89.46391 -286.994597)
			(xy 89.510068 -286.967948) (xy 89.559682 -286.948476) (xy 89.611644 -286.936616) (xy 89.664794 -286.932633)
			(xy 89.717944 -286.936616) (xy 89.769906 -286.948476) (xy 89.81952 -286.967948) (xy 89.865678 -286.994597)
			(xy 89.907349 -287.027828) (xy 89.943601 -287.066899) (xy 89.973625 -287.110936) (xy 89.996751 -287.158957)
			(xy 90.012461 -287.209887) (xy 90.020404 -287.262591) (xy 90.020902 -287.28924) (xy 90.020404 -287.315889)
			(xy 90.249238 -287.315889) (xy 90.249238 -287.262591) (xy 90.257181 -287.209887) (xy 90.272891 -287.158957)
			(xy 90.296017 -287.110936) (xy 90.326041 -287.066899) (xy 90.362293 -287.027828) (xy 90.403964 -286.994597)
			(xy 90.450122 -286.967948) (xy 90.499736 -286.948476) (xy 90.551698 -286.936616) (xy 90.604848 -286.932633)
			(xy 90.657998 -286.936616) (xy 90.70996 -286.948476) (xy 90.759574 -286.967948) (xy 90.805732 -286.994597)
			(xy 90.847403 -287.027828) (xy 90.883655 -287.066899) (xy 90.913679 -287.110936) (xy 90.936805 -287.158957)
			(xy 90.952515 -287.209887) (xy 90.960458 -287.262591) (xy 90.960956 -287.28924) (xy 90.960458 -287.315889)
			(xy 91.189038 -287.315889) (xy 91.189038 -287.262591) (xy 91.196981 -287.209887) (xy 91.212691 -287.158957)
			(xy 91.235817 -287.110936) (xy 91.265841 -287.066899) (xy 91.302093 -287.027828) (xy 91.343764 -286.994597)
			(xy 91.389922 -286.967948) (xy 91.439536 -286.948476) (xy 91.491498 -286.936616) (xy 91.544648 -286.932633)
			(xy 91.597798 -286.936616) (xy 91.64976 -286.948476) (xy 91.699374 -286.967948) (xy 91.745532 -286.994597)
			(xy 91.787203 -287.027828) (xy 91.823455 -287.066899) (xy 91.853479 -287.110936) (xy 91.876605 -287.158957)
			(xy 91.892315 -287.209887) (xy 91.900258 -287.262591) (xy 91.900756 -287.28924) (xy 91.900258 -287.315889)
			(xy 92.128838 -287.315889) (xy 92.128838 -287.262591) (xy 92.136781 -287.209887) (xy 92.152491 -287.158957)
			(xy 92.175617 -287.110936) (xy 92.205641 -287.066899) (xy 92.241893 -287.027828) (xy 92.283564 -286.994597)
			(xy 92.329722 -286.967948) (xy 92.379336 -286.948476) (xy 92.431298 -286.936616) (xy 92.484448 -286.932633)
			(xy 92.537598 -286.936616) (xy 92.58956 -286.948476) (xy 92.639174 -286.967948) (xy 92.685332 -286.994597)
			(xy 92.727003 -287.027828) (xy 92.763255 -287.066899) (xy 92.793279 -287.110936) (xy 92.816405 -287.158957)
			(xy 92.832115 -287.209887) (xy 92.840058 -287.262591) (xy 92.840556 -287.28924) (xy 92.840058 -287.315889)
			(xy 93.068384 -287.315889) (xy 93.068384 -287.262591) (xy 93.076327 -287.209887) (xy 93.092037 -287.158957)
			(xy 93.115163 -287.110936) (xy 93.145187 -287.066899) (xy 93.181439 -287.027828) (xy 93.22311 -286.994597)
			(xy 93.269268 -286.967948) (xy 93.318882 -286.948476) (xy 93.370844 -286.936616) (xy 93.423994 -286.932633)
			(xy 93.477144 -286.936616) (xy 93.529106 -286.948476) (xy 93.57872 -286.967948) (xy 93.624878 -286.994597)
			(xy 93.666549 -287.027828) (xy 93.702801 -287.066899) (xy 93.732825 -287.110936) (xy 93.755951 -287.158957)
			(xy 93.771661 -287.209887) (xy 93.779604 -287.262591) (xy 93.780102 -287.28924) (xy 93.779604 -287.315889)
			(xy 94.008184 -287.315889) (xy 94.008184 -287.262591) (xy 94.016127 -287.209887) (xy 94.031837 -287.158957)
			(xy 94.054963 -287.110936) (xy 94.084987 -287.066899) (xy 94.121239 -287.027828) (xy 94.16291 -286.994597)
			(xy 94.209068 -286.967948) (xy 94.258682 -286.948476) (xy 94.310644 -286.936616) (xy 94.363794 -286.932633)
			(xy 94.416944 -286.936616) (xy 94.468906 -286.948476) (xy 94.51852 -286.967948) (xy 94.564678 -286.994597)
			(xy 94.606349 -287.027828) (xy 94.642601 -287.066899) (xy 94.672625 -287.110936) (xy 94.695751 -287.158957)
			(xy 94.711461 -287.209887) (xy 94.719404 -287.262591) (xy 94.719902 -287.28924) (xy 94.719404 -287.315889)
			(xy 94.947984 -287.315889) (xy 94.947984 -287.262591) (xy 94.955927 -287.209887) (xy 94.971637 -287.158957)
			(xy 94.994763 -287.110936) (xy 95.024787 -287.066899) (xy 95.061039 -287.027828) (xy 95.10271 -286.994597)
			(xy 95.148868 -286.967948) (xy 95.198482 -286.948476) (xy 95.250444 -286.936616) (xy 95.303594 -286.932633)
			(xy 95.356744 -286.936616) (xy 95.408706 -286.948476) (xy 95.45832 -286.967948) (xy 95.504478 -286.994597)
			(xy 95.546149 -287.027828) (xy 95.582401 -287.066899) (xy 95.612425 -287.110936) (xy 95.635551 -287.158957)
			(xy 95.651261 -287.209887) (xy 95.659204 -287.262591) (xy 95.659702 -287.28924) (xy 95.659204 -287.315889)
			(xy 95.887784 -287.315889) (xy 95.887784 -287.262591) (xy 95.895727 -287.209887) (xy 95.911437 -287.158957)
			(xy 95.934563 -287.110936) (xy 95.964587 -287.066899) (xy 96.000839 -287.027828) (xy 96.04251 -286.994597)
			(xy 96.088668 -286.967948) (xy 96.138282 -286.948476) (xy 96.190244 -286.936616) (xy 96.243394 -286.932633)
			(xy 96.296544 -286.936616) (xy 96.348506 -286.948476) (xy 96.39812 -286.967948) (xy 96.444278 -286.994597)
			(xy 96.485949 -287.027828) (xy 96.522201 -287.066899) (xy 96.552225 -287.110936) (xy 96.575351 -287.158957)
			(xy 96.591061 -287.209887) (xy 96.599004 -287.262591) (xy 96.599502 -287.28924) (xy 96.599004 -287.315889)
			(xy 96.827584 -287.315889) (xy 96.827584 -287.262591) (xy 96.835527 -287.209887) (xy 96.851237 -287.158957)
			(xy 96.874363 -287.110936) (xy 96.904387 -287.066899) (xy 96.940639 -287.027828) (xy 96.98231 -286.994597)
			(xy 97.028468 -286.967948) (xy 97.078082 -286.948476) (xy 97.130044 -286.936616) (xy 97.183194 -286.932633)
			(xy 97.236344 -286.936616) (xy 97.288306 -286.948476) (xy 97.33792 -286.967948) (xy 97.384078 -286.994597)
			(xy 97.425749 -287.027828) (xy 97.462001 -287.066899) (xy 97.492025 -287.110936) (xy 97.515151 -287.158957)
			(xy 97.530861 -287.209887) (xy 97.538804 -287.262591) (xy 97.539302 -287.28924) (xy 97.538804 -287.315889)
			(xy 97.767384 -287.315889) (xy 97.767384 -287.262591) (xy 97.775327 -287.209887) (xy 97.791037 -287.158957)
			(xy 97.814163 -287.110936) (xy 97.844187 -287.066899) (xy 97.880439 -287.027828) (xy 97.92211 -286.994597)
			(xy 97.968268 -286.967948) (xy 98.017882 -286.948476) (xy 98.069844 -286.936616) (xy 98.122994 -286.932633)
			(xy 98.176144 -286.936616) (xy 98.228106 -286.948476) (xy 98.27772 -286.967948) (xy 98.323878 -286.994597)
			(xy 98.365549 -287.027828) (xy 98.401801 -287.066899) (xy 98.431825 -287.110936) (xy 98.454951 -287.158957)
			(xy 98.470661 -287.209887) (xy 98.478604 -287.262591) (xy 98.479102 -287.28924) (xy 98.478604 -287.315889)
			(xy 98.707184 -287.315889) (xy 98.707184 -287.262591) (xy 98.715127 -287.209887) (xy 98.730837 -287.158957)
			(xy 98.753963 -287.110936) (xy 98.783987 -287.066899) (xy 98.820239 -287.027828) (xy 98.86191 -286.994597)
			(xy 98.908068 -286.967948) (xy 98.957682 -286.948476) (xy 99.009644 -286.936616) (xy 99.062794 -286.932633)
			(xy 99.115944 -286.936616) (xy 99.167906 -286.948476) (xy 99.21752 -286.967948) (xy 99.263678 -286.994597)
			(xy 99.305349 -287.027828) (xy 99.341601 -287.066899) (xy 99.371625 -287.110936) (xy 99.394751 -287.158957)
			(xy 99.410461 -287.209887) (xy 99.418404 -287.262591) (xy 99.418902 -287.28924) (xy 99.418404 -287.315889)
			(xy 99.646984 -287.315889) (xy 99.646984 -287.262591) (xy 99.654927 -287.209887) (xy 99.670637 -287.158957)
			(xy 99.693763 -287.110936) (xy 99.723787 -287.066899) (xy 99.760039 -287.027828) (xy 99.80171 -286.994597)
			(xy 99.847868 -286.967948) (xy 99.897482 -286.948476) (xy 99.949444 -286.936616) (xy 100.002594 -286.932633)
			(xy 100.055744 -286.936616) (xy 100.107706 -286.948476) (xy 100.15732 -286.967948) (xy 100.203478 -286.994597)
			(xy 100.245149 -287.027828) (xy 100.281401 -287.066899) (xy 100.311425 -287.110936) (xy 100.334551 -287.158957)
			(xy 100.350261 -287.209887) (xy 100.358204 -287.262591) (xy 100.358702 -287.28924) (xy 100.358204 -287.315889)
			(xy 100.586784 -287.315889) (xy 100.586784 -287.262591) (xy 100.594727 -287.209887) (xy 100.610437 -287.158957)
			(xy 100.633563 -287.110936) (xy 100.663587 -287.066899) (xy 100.699839 -287.027828) (xy 100.74151 -286.994597)
			(xy 100.787668 -286.967948) (xy 100.837282 -286.948476) (xy 100.889244 -286.936616) (xy 100.942394 -286.932633)
			(xy 100.995544 -286.936616) (xy 101.047506 -286.948476) (xy 101.09712 -286.967948) (xy 101.143278 -286.994597)
			(xy 101.184949 -287.027828) (xy 101.221201 -287.066899) (xy 101.251225 -287.110936) (xy 101.274351 -287.158957)
			(xy 101.290061 -287.209887) (xy 101.298004 -287.262591) (xy 101.298502 -287.28924) (xy 101.298004 -287.315889)
			(xy 101.526584 -287.315889) (xy 101.526584 -287.262591) (xy 101.534527 -287.209887) (xy 101.550237 -287.158957)
			(xy 101.573363 -287.110936) (xy 101.603387 -287.066899) (xy 101.639639 -287.027828) (xy 101.68131 -286.994597)
			(xy 101.727468 -286.967948) (xy 101.777082 -286.948476) (xy 101.829044 -286.936616) (xy 101.882194 -286.932633)
			(xy 101.935344 -286.936616) (xy 101.987306 -286.948476) (xy 102.03692 -286.967948) (xy 102.083078 -286.994597)
			(xy 102.124749 -287.027828) (xy 102.161001 -287.066899) (xy 102.191025 -287.110936) (xy 102.214151 -287.158957)
			(xy 102.229861 -287.209887) (xy 102.237804 -287.262591) (xy 102.238302 -287.28924) (xy 102.237804 -287.315889)
			(xy 102.466384 -287.315889) (xy 102.466384 -287.262591) (xy 102.474327 -287.209887) (xy 102.490037 -287.158957)
			(xy 102.513163 -287.110936) (xy 102.543187 -287.066899) (xy 102.579439 -287.027828) (xy 102.62111 -286.994597)
			(xy 102.667268 -286.967948) (xy 102.716882 -286.948476) (xy 102.768844 -286.936616) (xy 102.821994 -286.932633)
			(xy 102.875144 -286.936616) (xy 102.927106 -286.948476) (xy 102.97672 -286.967948) (xy 103.022878 -286.994597)
			(xy 103.064549 -287.027828) (xy 103.100801 -287.066899) (xy 103.130825 -287.110936) (xy 103.153951 -287.158957)
			(xy 103.169661 -287.209887) (xy 103.177604 -287.262591) (xy 103.178102 -287.28924) (xy 103.177604 -287.315889)
			(xy 103.169661 -287.368593) (xy 103.153951 -287.419523) (xy 103.130825 -287.467544) (xy 103.100801 -287.511581)
			(xy 103.064549 -287.550652) (xy 103.022878 -287.583883) (xy 102.97672 -287.610532) (xy 102.927106 -287.630004)
			(xy 102.875144 -287.641864) (xy 102.821994 -287.645848) (xy 102.768844 -287.641864) (xy 102.716882 -287.630004)
			(xy 102.667268 -287.610532) (xy 102.62111 -287.583883) (xy 102.579439 -287.550652) (xy 102.543187 -287.511581)
			(xy 102.513163 -287.467544) (xy 102.490037 -287.419523) (xy 102.474327 -287.368593) (xy 102.466384 -287.315889)
			(xy 102.237804 -287.315889) (xy 102.229861 -287.368593) (xy 102.214151 -287.419523) (xy 102.191025 -287.467544)
			(xy 102.161001 -287.511581) (xy 102.124749 -287.550652) (xy 102.083078 -287.583883) (xy 102.03692 -287.610532)
			(xy 101.987306 -287.630004) (xy 101.935344 -287.641864) (xy 101.882194 -287.645848) (xy 101.829044 -287.641864)
			(xy 101.777082 -287.630004) (xy 101.727468 -287.610532) (xy 101.68131 -287.583883) (xy 101.639639 -287.550652)
			(xy 101.603387 -287.511581) (xy 101.573363 -287.467544) (xy 101.550237 -287.419523) (xy 101.534527 -287.368593)
			(xy 101.526584 -287.315889) (xy 101.298004 -287.315889) (xy 101.290061 -287.368593) (xy 101.274351 -287.419523)
			(xy 101.251225 -287.467544) (xy 101.221201 -287.511581) (xy 101.184949 -287.550652) (xy 101.143278 -287.583883)
			(xy 101.09712 -287.610532) (xy 101.047506 -287.630004) (xy 100.995544 -287.641864) (xy 100.942394 -287.645848)
			(xy 100.889244 -287.641864) (xy 100.837282 -287.630004) (xy 100.787668 -287.610532) (xy 100.74151 -287.583883)
			(xy 100.699839 -287.550652) (xy 100.663587 -287.511581) (xy 100.633563 -287.467544) (xy 100.610437 -287.419523)
			(xy 100.594727 -287.368593) (xy 100.586784 -287.315889) (xy 100.358204 -287.315889) (xy 100.350261 -287.368593)
			(xy 100.334551 -287.419523) (xy 100.311425 -287.467544) (xy 100.281401 -287.511581) (xy 100.245149 -287.550652)
			(xy 100.203478 -287.583883) (xy 100.15732 -287.610532) (xy 100.107706 -287.630004) (xy 100.055744 -287.641864)
			(xy 100.002594 -287.645848) (xy 99.949444 -287.641864) (xy 99.897482 -287.630004) (xy 99.847868 -287.610532)
			(xy 99.80171 -287.583883) (xy 99.760039 -287.550652) (xy 99.723787 -287.511581) (xy 99.693763 -287.467544)
			(xy 99.670637 -287.419523) (xy 99.654927 -287.368593) (xy 99.646984 -287.315889) (xy 99.418404 -287.315889)
			(xy 99.410461 -287.368593) (xy 99.394751 -287.419523) (xy 99.371625 -287.467544) (xy 99.341601 -287.511581)
			(xy 99.305349 -287.550652) (xy 99.263678 -287.583883) (xy 99.21752 -287.610532) (xy 99.167906 -287.630004)
			(xy 99.115944 -287.641864) (xy 99.062794 -287.645848) (xy 99.009644 -287.641864) (xy 98.957682 -287.630004)
			(xy 98.908068 -287.610532) (xy 98.86191 -287.583883) (xy 98.820239 -287.550652) (xy 98.783987 -287.511581)
			(xy 98.753963 -287.467544) (xy 98.730837 -287.419523) (xy 98.715127 -287.368593) (xy 98.707184 -287.315889)
			(xy 98.478604 -287.315889) (xy 98.470661 -287.368593) (xy 98.454951 -287.419523) (xy 98.431825 -287.467544)
			(xy 98.401801 -287.511581) (xy 98.365549 -287.550652) (xy 98.323878 -287.583883) (xy 98.27772 -287.610532)
			(xy 98.228106 -287.630004) (xy 98.176144 -287.641864) (xy 98.122994 -287.645848) (xy 98.069844 -287.641864)
			(xy 98.017882 -287.630004) (xy 97.968268 -287.610532) (xy 97.92211 -287.583883) (xy 97.880439 -287.550652)
			(xy 97.844187 -287.511581) (xy 97.814163 -287.467544) (xy 97.791037 -287.419523) (xy 97.775327 -287.368593)
			(xy 97.767384 -287.315889) (xy 97.538804 -287.315889) (xy 97.530861 -287.368593) (xy 97.515151 -287.419523)
			(xy 97.492025 -287.467544) (xy 97.462001 -287.511581) (xy 97.425749 -287.550652) (xy 97.384078 -287.583883)
			(xy 97.33792 -287.610532) (xy 97.288306 -287.630004) (xy 97.236344 -287.641864) (xy 97.183194 -287.645848)
			(xy 97.130044 -287.641864) (xy 97.078082 -287.630004) (xy 97.028468 -287.610532) (xy 96.98231 -287.583883)
			(xy 96.940639 -287.550652) (xy 96.904387 -287.511581) (xy 96.874363 -287.467544) (xy 96.851237 -287.419523)
			(xy 96.835527 -287.368593) (xy 96.827584 -287.315889) (xy 96.599004 -287.315889) (xy 96.591061 -287.368593)
			(xy 96.575351 -287.419523) (xy 96.552225 -287.467544) (xy 96.522201 -287.511581) (xy 96.485949 -287.550652)
			(xy 96.444278 -287.583883) (xy 96.39812 -287.610532) (xy 96.348506 -287.630004) (xy 96.296544 -287.641864)
			(xy 96.243394 -287.645848) (xy 96.190244 -287.641864) (xy 96.138282 -287.630004) (xy 96.088668 -287.610532)
			(xy 96.04251 -287.583883) (xy 96.000839 -287.550652) (xy 95.964587 -287.511581) (xy 95.934563 -287.467544)
			(xy 95.911437 -287.419523) (xy 95.895727 -287.368593) (xy 95.887784 -287.315889) (xy 95.659204 -287.315889)
			(xy 95.651261 -287.368593) (xy 95.635551 -287.419523) (xy 95.612425 -287.467544) (xy 95.582401 -287.511581)
			(xy 95.546149 -287.550652) (xy 95.504478 -287.583883) (xy 95.45832 -287.610532) (xy 95.408706 -287.630004)
			(xy 95.356744 -287.641864) (xy 95.303594 -287.645848) (xy 95.250444 -287.641864) (xy 95.198482 -287.630004)
			(xy 95.148868 -287.610532) (xy 95.10271 -287.583883) (xy 95.061039 -287.550652) (xy 95.024787 -287.511581)
			(xy 94.994763 -287.467544) (xy 94.971637 -287.419523) (xy 94.955927 -287.368593) (xy 94.947984 -287.315889)
			(xy 94.719404 -287.315889) (xy 94.711461 -287.368593) (xy 94.695751 -287.419523) (xy 94.672625 -287.467544)
			(xy 94.642601 -287.511581) (xy 94.606349 -287.550652) (xy 94.564678 -287.583883) (xy 94.51852 -287.610532)
			(xy 94.468906 -287.630004) (xy 94.416944 -287.641864) (xy 94.363794 -287.645848) (xy 94.310644 -287.641864)
			(xy 94.258682 -287.630004) (xy 94.209068 -287.610532) (xy 94.16291 -287.583883) (xy 94.121239 -287.550652)
			(xy 94.084987 -287.511581) (xy 94.054963 -287.467544) (xy 94.031837 -287.419523) (xy 94.016127 -287.368593)
			(xy 94.008184 -287.315889) (xy 93.779604 -287.315889) (xy 93.771661 -287.368593) (xy 93.755951 -287.419523)
			(xy 93.732825 -287.467544) (xy 93.702801 -287.511581) (xy 93.666549 -287.550652) (xy 93.624878 -287.583883)
			(xy 93.57872 -287.610532) (xy 93.529106 -287.630004) (xy 93.477144 -287.641864) (xy 93.423994 -287.645848)
			(xy 93.370844 -287.641864) (xy 93.318882 -287.630004) (xy 93.269268 -287.610532) (xy 93.22311 -287.583883)
			(xy 93.181439 -287.550652) (xy 93.145187 -287.511581) (xy 93.115163 -287.467544) (xy 93.092037 -287.419523)
			(xy 93.076327 -287.368593) (xy 93.068384 -287.315889) (xy 92.840058 -287.315889) (xy 92.832115 -287.368593)
			(xy 92.816405 -287.419523) (xy 92.793279 -287.467544) (xy 92.763255 -287.511581) (xy 92.727003 -287.550652)
			(xy 92.685332 -287.583883) (xy 92.639174 -287.610532) (xy 92.58956 -287.630004) (xy 92.537598 -287.641864)
			(xy 92.484448 -287.645848) (xy 92.431298 -287.641864) (xy 92.379336 -287.630004) (xy 92.329722 -287.610532)
			(xy 92.283564 -287.583883) (xy 92.241893 -287.550652) (xy 92.205641 -287.511581) (xy 92.175617 -287.467544)
			(xy 92.152491 -287.419523) (xy 92.136781 -287.368593) (xy 92.128838 -287.315889) (xy 91.900258 -287.315889)
			(xy 91.892315 -287.368593) (xy 91.876605 -287.419523) (xy 91.853479 -287.467544) (xy 91.823455 -287.511581)
			(xy 91.787203 -287.550652) (xy 91.745532 -287.583883) (xy 91.699374 -287.610532) (xy 91.64976 -287.630004)
			(xy 91.597798 -287.641864) (xy 91.544648 -287.645848) (xy 91.491498 -287.641864) (xy 91.439536 -287.630004)
			(xy 91.389922 -287.610532) (xy 91.343764 -287.583883) (xy 91.302093 -287.550652) (xy 91.265841 -287.511581)
			(xy 91.235817 -287.467544) (xy 91.212691 -287.419523) (xy 91.196981 -287.368593) (xy 91.189038 -287.315889)
			(xy 90.960458 -287.315889) (xy 90.952515 -287.368593) (xy 90.936805 -287.419523) (xy 90.913679 -287.467544)
			(xy 90.883655 -287.511581) (xy 90.847403 -287.550652) (xy 90.805732 -287.583883) (xy 90.759574 -287.610532)
			(xy 90.70996 -287.630004) (xy 90.657998 -287.641864) (xy 90.604848 -287.645848) (xy 90.551698 -287.641864)
			(xy 90.499736 -287.630004) (xy 90.450122 -287.610532) (xy 90.403964 -287.583883) (xy 90.362293 -287.550652)
			(xy 90.326041 -287.511581) (xy 90.296017 -287.467544) (xy 90.272891 -287.419523) (xy 90.257181 -287.368593)
			(xy 90.249238 -287.315889) (xy 90.020404 -287.315889) (xy 90.012461 -287.368593) (xy 89.996751 -287.419523)
			(xy 89.973625 -287.467544) (xy 89.943601 -287.511581) (xy 89.907349 -287.550652) (xy 89.865678 -287.583883)
			(xy 89.81952 -287.610532) (xy 89.769906 -287.630004) (xy 89.717944 -287.641864) (xy 89.664794 -287.645848)
			(xy 89.611644 -287.641864) (xy 89.559682 -287.630004) (xy 89.510068 -287.610532) (xy 89.46391 -287.583883)
			(xy 89.422239 -287.550652) (xy 89.385987 -287.511581) (xy 89.355963 -287.467544) (xy 89.332837 -287.419523)
			(xy 89.317127 -287.368593) (xy 89.309184 -287.315889) (xy 89.080604 -287.315889) (xy 89.072661 -287.368593)
			(xy 89.056951 -287.419523) (xy 89.033825 -287.467544) (xy 89.003801 -287.511581) (xy 88.967549 -287.550652)
			(xy 88.925878 -287.583883) (xy 88.87972 -287.610532) (xy 88.830106 -287.630004) (xy 88.778144 -287.641864)
			(xy 88.724994 -287.645848) (xy 88.671844 -287.641864) (xy 88.619882 -287.630004) (xy 88.570268 -287.610532)
			(xy 88.52411 -287.583883) (xy 88.482439 -287.550652) (xy 88.446187 -287.511581) (xy 88.416163 -287.467544)
			(xy 88.393037 -287.419523) (xy 88.377327 -287.368593) (xy 88.369384 -287.315889) (xy 88.140804 -287.315889)
			(xy 88.132861 -287.368593) (xy 88.117151 -287.419523) (xy 88.094025 -287.467544) (xy 88.064001 -287.511581)
			(xy 88.027749 -287.550652) (xy 87.986078 -287.583883) (xy 87.93992 -287.610532) (xy 87.890306 -287.630004)
			(xy 87.838344 -287.641864) (xy 87.785194 -287.645848) (xy 87.732044 -287.641864) (xy 87.680082 -287.630004)
			(xy 87.630468 -287.610532) (xy 87.58431 -287.583883) (xy 87.542639 -287.550652) (xy 87.506387 -287.511581)
			(xy 87.476363 -287.467544) (xy 87.453237 -287.419523) (xy 87.437527 -287.368593) (xy 87.429584 -287.315889)
			(xy 87.201004 -287.315889) (xy 87.193061 -287.368593) (xy 87.177351 -287.419523) (xy 87.154225 -287.467544)
			(xy 87.124201 -287.511581) (xy 87.087949 -287.550652) (xy 87.046278 -287.583883) (xy 87.00012 -287.610532)
			(xy 86.950506 -287.630004) (xy 86.898544 -287.641864) (xy 86.845394 -287.645848) (xy 86.792244 -287.641864)
			(xy 86.740282 -287.630004) (xy 86.690668 -287.610532) (xy 86.64451 -287.583883) (xy 86.602839 -287.550652)
			(xy 86.566587 -287.511581) (xy 86.536563 -287.467544) (xy 86.513437 -287.419523) (xy 86.497727 -287.368593)
			(xy 86.489784 -287.315889) (xy 86.489286 -287.28924) (xy 86.489681 -287.266037) (xy 86.495725 -287.220027)
			(xy 86.507703 -287.175194) (xy 86.51621 -287.153604) (xy 86.525608 -287.13049) (xy 86.353142 -286.831786)
			(xy 86.32825 -286.828484) (xy 86.302931 -286.824591) (xy 86.253664 -286.810571) (xy 86.206912 -286.789641)
			(xy 86.16364 -286.762232) (xy 86.124738 -286.728909) (xy 86.091008 -286.690358) (xy 86.063147 -286.647375)
			(xy 86.041727 -286.600845) (xy 86.027191 -286.551728) (xy 86.019839 -286.501035) (xy 86.019386 -286.475424)
			(xy 85.79129 -286.475424) (xy 85.79129 -286.502453) (xy 85.783109 -286.55592) (xy 85.766935 -286.607534)
			(xy 85.743142 -286.656109) (xy 85.712276 -286.700526) (xy 85.675048 -286.739765) (xy 85.632313 -286.772922)
			(xy 85.585056 -286.799235) (xy 85.5599 -286.80918) (xy 85.52688 -286.821372) (xy 85.52688 -287.597088)
			(xy 86.059497 -288.129705) (xy 86.959684 -288.129705) (xy 86.959684 -288.076407) (xy 86.967627 -288.023703)
			(xy 86.983337 -287.972773) (xy 87.006463 -287.924752) (xy 87.036487 -287.880715) (xy 87.072739 -287.841644)
			(xy 87.11441 -287.808413) (xy 87.160568 -287.781764) (xy 87.210182 -287.762292) (xy 87.262144 -287.750432)
			(xy 87.315294 -287.746449) (xy 87.368444 -287.750432) (xy 87.420406 -287.762292) (xy 87.47002 -287.781764)
			(xy 87.516178 -287.808413) (xy 87.557849 -287.841644) (xy 87.594101 -287.880715) (xy 87.624125 -287.924752)
			(xy 87.647251 -287.972773) (xy 87.662961 -288.023703) (xy 87.670904 -288.076407) (xy 87.671402 -288.103056)
			(xy 87.670904 -288.129705) (xy 87.662961 -288.182409) (xy 87.647251 -288.233339) (xy 87.624125 -288.28136)
			(xy 87.594101 -288.325397) (xy 87.557849 -288.364468) (xy 87.516178 -288.397699) (xy 87.47002 -288.424348)
			(xy 87.420406 -288.44382) (xy 87.368444 -288.45568) (xy 87.315294 -288.459664) (xy 87.262144 -288.45568)
			(xy 87.210182 -288.44382) (xy 87.160568 -288.424348) (xy 87.11441 -288.397699) (xy 87.072739 -288.364468)
			(xy 87.036487 -288.325397) (xy 87.006463 -288.28136) (xy 86.983337 -288.233339) (xy 86.967627 -288.182409)
			(xy 86.959684 -288.129705) (xy 86.059497 -288.129705) (xy 86.7664 -288.836608) (xy 87.436452 -288.836608)
		)
		(stroke
			(width 0)
			(type solid)
		)
		(fill yes)
		(layer "In15.Cu")
		(net "PVCCFA_EHV_FIVRA_CPU1")
	)
	(gr_poly
		(pts
			(xy 335.38795 -288.802318) (xy 335.396774 -288.777816) (xy 335.420566 -288.731493) (xy 335.450852 -288.689129)
			(xy 335.486985 -288.651628) (xy 335.528195 -288.619789) (xy 335.573604 -288.594293) (xy 335.622241 -288.575683)
			(xy 335.673071 -288.564356) (xy 335.725008 -288.560553) (xy 335.776945 -288.564356) (xy 335.827775 -288.575683)
			(xy 335.876412 -288.594293) (xy 335.921821 -288.619789) (xy 335.963031 -288.651628) (xy 335.999164 -288.689129)
			(xy 336.02945 -288.731493) (xy 336.053242 -288.777816) (xy 336.062066 -288.802318) (xy 336.07375 -288.836608)
			(xy 336.316066 -288.836608) (xy 336.32775 -288.802318) (xy 336.337386 -288.775735) (xy 336.363854 -288.725772)
			(xy 336.39788 -288.680617) (xy 336.438611 -288.641402) (xy 336.485024 -288.609111) (xy 336.535954 -288.584556)
			(xy 336.590123 -288.568351) (xy 336.618072 -288.564066) (xy 336.642964 -288.560764) (xy 336.81543 -288.26206)
			(xy 336.805778 -288.238946) (xy 336.797264 -288.217314) (xy 336.78528 -288.172396) (xy 336.77924 -288.126301)
			(xy 336.778854 -288.103056) (xy 336.779352 -288.076407) (xy 336.787295 -288.023703) (xy 336.803005 -287.972773)
			(xy 336.826131 -287.924752) (xy 336.856155 -287.880715) (xy 336.892407 -287.841644) (xy 336.934078 -287.808413)
			(xy 336.980236 -287.781764) (xy 337.02985 -287.762292) (xy 337.081812 -287.750432) (xy 337.134962 -287.746449)
			(xy 337.188112 -287.750432) (xy 337.240074 -287.762292) (xy 337.289688 -287.781764) (xy 337.335846 -287.808413)
			(xy 337.377517 -287.841644) (xy 337.413769 -287.880715) (xy 337.443793 -287.924752) (xy 337.466919 -287.972773)
			(xy 337.482629 -288.023703) (xy 337.490572 -288.076407) (xy 337.49107 -288.103056) (xy 337.490621 -288.128682)
			(xy 337.483269 -288.179404) (xy 337.468724 -288.228549) (xy 337.447288 -288.275103) (xy 337.419402 -288.318105)
			(xy 337.385641 -288.356667) (xy 337.346704 -288.389993) (xy 337.303392 -288.417396) (xy 337.256601 -288.43831)
			(xy 337.207296 -288.452303) (xy 337.181952 -288.456116) (xy 337.157314 -288.459418) (xy 336.984594 -288.75863)
			(xy 336.994246 -288.781744) (xy 337.001866 -288.802318) (xy 337.01355 -288.836608) (xy 337.255866 -288.836608)
			(xy 337.26755 -288.802318) (xy 337.276374 -288.777816) (xy 337.300166 -288.731493) (xy 337.330452 -288.689129)
			(xy 337.366585 -288.651628) (xy 337.407795 -288.619789) (xy 337.453204 -288.594293) (xy 337.501841 -288.575683)
			(xy 337.552671 -288.564356) (xy 337.604608 -288.560553) (xy 337.656545 -288.564356) (xy 337.707375 -288.575683)
			(xy 337.756012 -288.594293) (xy 337.801421 -288.619789) (xy 337.842631 -288.651628) (xy 337.878764 -288.689129)
			(xy 337.90905 -288.731493) (xy 337.932842 -288.777816) (xy 337.941666 -288.802318) (xy 337.95335 -288.836608)
			(xy 338.196174 -288.836608) (xy 338.207858 -288.802318) (xy 338.217485 -288.775748) (xy 338.243928 -288.725808)
			(xy 338.277921 -288.680665) (xy 338.318612 -288.641453) (xy 338.36498 -288.609153) (xy 338.415865 -288.584574)
			(xy 338.46999 -288.568334) (xy 338.497926 -288.564066) (xy 338.522564 -288.560764) (xy 338.69503 -288.26206)
			(xy 338.685378 -288.238946) (xy 338.676864 -288.217314) (xy 338.66488 -288.172396) (xy 338.65884 -288.126301)
			(xy 338.658454 -288.103056) (xy 338.658952 -288.076407) (xy 338.666895 -288.023703) (xy 338.682605 -287.972773)
			(xy 338.705731 -287.924752) (xy 338.735755 -287.880715) (xy 338.772007 -287.841644) (xy 338.813678 -287.808413)
			(xy 338.859836 -287.781764) (xy 338.90945 -287.762292) (xy 338.961412 -287.750432) (xy 339.014562 -287.746449)
			(xy 339.067712 -287.750432) (xy 339.119674 -287.762292) (xy 339.169288 -287.781764) (xy 339.215446 -287.808413)
			(xy 339.257117 -287.841644) (xy 339.293369 -287.880715) (xy 339.323393 -287.924752) (xy 339.346519 -287.972773)
			(xy 339.362229 -288.023703) (xy 339.370172 -288.076407) (xy 339.37067 -288.103056) (xy 339.370221 -288.128682)
			(xy 339.362869 -288.179404) (xy 339.348324 -288.228549) (xy 339.326888 -288.275103) (xy 339.299002 -288.318105)
			(xy 339.265241 -288.356667) (xy 339.226304 -288.389993) (xy 339.182992 -288.417396) (xy 339.136201 -288.43831)
			(xy 339.086896 -288.452303) (xy 339.061552 -288.456116) (xy 339.036914 -288.459418) (xy 338.864448 -288.758122)
			(xy 338.8741 -288.781236) (xy 338.881974 -288.802318) (xy 338.893658 -288.836608) (xy 339.135974 -288.836608)
			(xy 339.147658 -288.802318) (xy 339.156482 -288.777816) (xy 339.180274 -288.731493) (xy 339.21056 -288.689129)
			(xy 339.246693 -288.651628) (xy 339.287903 -288.619789) (xy 339.333312 -288.594293) (xy 339.381949 -288.575683)
			(xy 339.432779 -288.564356) (xy 339.484716 -288.560553) (xy 339.536653 -288.564356) (xy 339.587483 -288.575683)
			(xy 339.63612 -288.594293) (xy 339.681529 -288.619789) (xy 339.722739 -288.651628) (xy 339.758872 -288.689129)
			(xy 339.789158 -288.731493) (xy 339.81295 -288.777816) (xy 339.821774 -288.802318) (xy 339.833458 -288.836608)
			(xy 340.075774 -288.836608) (xy 340.087458 -288.802318) (xy 340.097085 -288.775748) (xy 340.123528 -288.725808)
			(xy 340.157521 -288.680665) (xy 340.198212 -288.641453) (xy 340.24458 -288.609153) (xy 340.295465 -288.584574)
			(xy 340.34959 -288.568334) (xy 340.377526 -288.564066) (xy 340.402164 -288.560764) (xy 340.574884 -288.26206)
			(xy 340.565232 -288.238946) (xy 340.556717 -288.217314) (xy 340.544732 -288.172396) (xy 340.538691 -288.126301)
			(xy 340.538308 -288.103056) (xy 340.538806 -288.076407) (xy 340.546749 -288.023703) (xy 340.562459 -287.972773)
			(xy 340.585585 -287.924752) (xy 340.615609 -287.880715) (xy 340.651861 -287.841644) (xy 340.693532 -287.808413)
			(xy 340.73969 -287.781764) (xy 340.789304 -287.762292) (xy 340.841266 -287.750432) (xy 340.894416 -287.746449)
			(xy 340.947566 -287.750432) (xy 340.999528 -287.762292) (xy 341.049142 -287.781764) (xy 341.0953 -287.808413)
			(xy 341.136971 -287.841644) (xy 341.173223 -287.880715) (xy 341.203247 -287.924752) (xy 341.226373 -287.972773)
			(xy 341.242083 -288.023703) (xy 341.250026 -288.076407) (xy 341.250524 -288.103056) (xy 341.250075 -288.128681)
			(xy 341.242722 -288.179401) (xy 341.228177 -288.228544) (xy 341.20674 -288.275095) (xy 341.178852 -288.318093)
			(xy 341.145091 -288.356652) (xy 341.106152 -288.389974) (xy 341.06284 -288.417371) (xy 341.016049 -288.43828)
			(xy 340.966745 -288.452266) (xy 340.941406 -288.456116) (xy 340.916768 -288.459418) (xy 340.744048 -288.758122)
			(xy 340.7537 -288.781236) (xy 340.761574 -288.802318) (xy 340.773258 -288.836608) (xy 341.015574 -288.836608)
			(xy 341.027258 -288.802318) (xy 341.036082 -288.777816) (xy 341.059874 -288.731493) (xy 341.09016 -288.689129)
			(xy 341.126293 -288.651628) (xy 341.167503 -288.619789) (xy 341.212912 -288.594293) (xy 341.261549 -288.575683)
			(xy 341.312379 -288.564356) (xy 341.364316 -288.560553) (xy 341.416253 -288.564356) (xy 341.467083 -288.575683)
			(xy 341.51572 -288.594293) (xy 341.561129 -288.619789) (xy 341.602339 -288.651628) (xy 341.638472 -288.689129)
			(xy 341.668758 -288.731493) (xy 341.69255 -288.777816) (xy 341.701374 -288.802318) (xy 341.713058 -288.836608)
			(xy 341.955374 -288.836608) (xy 341.967058 -288.802318) (xy 341.976685 -288.775748) (xy 342.003128 -288.725808)
			(xy 342.037121 -288.680665) (xy 342.077812 -288.641453) (xy 342.12418 -288.609153) (xy 342.175065 -288.584574)
			(xy 342.22919 -288.568334) (xy 342.257126 -288.564066) (xy 342.281764 -288.560764) (xy 342.454484 -288.26206)
			(xy 342.444832 -288.238946) (xy 342.436317 -288.217314) (xy 342.424332 -288.172396) (xy 342.418291 -288.126301)
			(xy 342.417908 -288.103056) (xy 342.418406 -288.076407) (xy 342.426349 -288.023703) (xy 342.442059 -287.972773)
			(xy 342.465185 -287.924752) (xy 342.495209 -287.880715) (xy 342.531461 -287.841644) (xy 342.573132 -287.808413)
			(xy 342.61929 -287.781764) (xy 342.668904 -287.762292) (xy 342.720866 -287.750432) (xy 342.774016 -287.746449)
			(xy 342.827166 -287.750432) (xy 342.879128 -287.762292) (xy 342.928742 -287.781764) (xy 342.9749 -287.808413)
			(xy 343.016571 -287.841644) (xy 343.052823 -287.880715) (xy 343.082847 -287.924752) (xy 343.105973 -287.972773)
			(xy 343.121683 -288.023703) (xy 343.129626 -288.076407) (xy 343.130124 -288.103056) (xy 343.129675 -288.128681)
			(xy 343.122322 -288.179401) (xy 343.107777 -288.228544) (xy 343.08634 -288.275095) (xy 343.058452 -288.318093)
			(xy 343.024691 -288.356652) (xy 342.985752 -288.389974) (xy 342.94244 -288.417371) (xy 342.895649 -288.43828)
			(xy 342.846345 -288.452266) (xy 342.821006 -288.456116) (xy 342.796368 -288.459418) (xy 342.623648 -288.758122)
			(xy 342.6333 -288.781236) (xy 342.641174 -288.802318) (xy 342.652858 -288.836608) (xy 342.895174 -288.836608)
			(xy 342.906858 -288.802318) (xy 342.915682 -288.777816) (xy 342.939474 -288.731493) (xy 342.96976 -288.689129)
			(xy 343.005893 -288.651628) (xy 343.047103 -288.619789) (xy 343.092512 -288.594293) (xy 343.141149 -288.575683)
			(xy 343.191979 -288.564356) (xy 343.243916 -288.560553) (xy 343.295853 -288.564356) (xy 343.346683 -288.575683)
			(xy 343.39532 -288.594293) (xy 343.440729 -288.619789) (xy 343.481939 -288.651628) (xy 343.518072 -288.689129)
			(xy 343.548358 -288.731493) (xy 343.57215 -288.777816) (xy 343.580974 -288.802318) (xy 343.592658 -288.836608)
			(xy 343.834974 -288.836608) (xy 343.846658 -288.802318) (xy 343.856285 -288.775748) (xy 343.882728 -288.725808)
			(xy 343.916721 -288.680665) (xy 343.957412 -288.641453) (xy 344.00378 -288.609153) (xy 344.054665 -288.584574)
			(xy 344.10879 -288.568334) (xy 344.136726 -288.564066) (xy 344.161364 -288.560764) (xy 344.334084 -288.26206)
			(xy 344.324432 -288.238946) (xy 344.315917 -288.217314) (xy 344.303932 -288.172396) (xy 344.297891 -288.126301)
			(xy 344.297508 -288.103056) (xy 344.298006 -288.076407) (xy 344.305949 -288.023703) (xy 344.321659 -287.972773)
			(xy 344.344785 -287.924752) (xy 344.374809 -287.880715) (xy 344.411061 -287.841644) (xy 344.452732 -287.808413)
			(xy 344.49889 -287.781764) (xy 344.548504 -287.762292) (xy 344.600466 -287.750432) (xy 344.653616 -287.746449)
			(xy 344.706766 -287.750432) (xy 344.758728 -287.762292) (xy 344.808342 -287.781764) (xy 344.8545 -287.808413)
			(xy 344.896171 -287.841644) (xy 344.932423 -287.880715) (xy 344.962447 -287.924752) (xy 344.985573 -287.972773)
			(xy 345.001283 -288.023703) (xy 345.009226 -288.076407) (xy 345.009724 -288.103056) (xy 345.009275 -288.128681)
			(xy 345.001922 -288.179401) (xy 344.987377 -288.228544) (xy 344.96594 -288.275095) (xy 344.938052 -288.318093)
			(xy 344.904291 -288.356652) (xy 344.865352 -288.389974) (xy 344.82204 -288.417371) (xy 344.775249 -288.43828)
			(xy 344.725945 -288.452266) (xy 344.700606 -288.456116) (xy 344.675968 -288.459418) (xy 344.503248 -288.758122)
			(xy 344.5129 -288.781236) (xy 344.520774 -288.802318) (xy 344.532458 -288.836608) (xy 344.774774 -288.836608)
			(xy 344.786458 -288.802318) (xy 344.795282 -288.777816) (xy 344.819074 -288.731493) (xy 344.84936 -288.689129)
			(xy 344.885493 -288.651628) (xy 344.926703 -288.619789) (xy 344.972112 -288.594293) (xy 345.020749 -288.575683)
			(xy 345.071579 -288.564356) (xy 345.123516 -288.560553) (xy 345.175453 -288.564356) (xy 345.226283 -288.575683)
			(xy 345.27492 -288.594293) (xy 345.320329 -288.619789) (xy 345.361539 -288.651628) (xy 345.397672 -288.689129)
			(xy 345.427958 -288.731493) (xy 345.45175 -288.777816) (xy 345.460574 -288.802318) (xy 345.472258 -288.836608)
			(xy 345.714574 -288.836608) (xy 345.726258 -288.802318) (xy 345.735885 -288.775748) (xy 345.762328 -288.725808)
			(xy 345.796321 -288.680665) (xy 345.837012 -288.641453) (xy 345.88338 -288.609153) (xy 345.934265 -288.584574)
			(xy 345.98839 -288.568334) (xy 346.016326 -288.564066) (xy 346.040964 -288.560764) (xy 346.213684 -288.26206)
			(xy 346.204032 -288.238946) (xy 346.195517 -288.217314) (xy 346.183532 -288.172396) (xy 346.177491 -288.126301)
			(xy 346.177108 -288.103056) (xy 346.177606 -288.076407) (xy 346.185549 -288.023703) (xy 346.201259 -287.972773)
			(xy 346.224385 -287.924752) (xy 346.254409 -287.880715) (xy 346.290661 -287.841644) (xy 346.332332 -287.808413)
			(xy 346.37849 -287.781764) (xy 346.428104 -287.762292) (xy 346.480066 -287.750432) (xy 346.533216 -287.746449)
			(xy 346.586366 -287.750432) (xy 346.638328 -287.762292) (xy 346.687942 -287.781764) (xy 346.7341 -287.808413)
			(xy 346.775771 -287.841644) (xy 346.812023 -287.880715) (xy 346.842047 -287.924752) (xy 346.865173 -287.972773)
			(xy 346.880883 -288.023703) (xy 346.888826 -288.076407) (xy 346.889324 -288.103056) (xy 346.888875 -288.128681)
			(xy 346.881522 -288.179401) (xy 346.866977 -288.228544) (xy 346.84554 -288.275095) (xy 346.817652 -288.318093)
			(xy 346.783891 -288.356652) (xy 346.744952 -288.389974) (xy 346.70164 -288.417371) (xy 346.654849 -288.43828)
			(xy 346.605545 -288.452266) (xy 346.580206 -288.456116) (xy 346.555568 -288.459418) (xy 346.382848 -288.758122)
			(xy 346.3925 -288.781236) (xy 346.400374 -288.802318) (xy 346.412058 -288.836608) (xy 346.654374 -288.836608)
			(xy 346.666058 -288.802318) (xy 346.674882 -288.777816) (xy 346.698674 -288.731493) (xy 346.72896 -288.689129)
			(xy 346.765093 -288.651628) (xy 346.806303 -288.619789) (xy 346.851712 -288.594293) (xy 346.900349 -288.575683)
			(xy 346.951179 -288.564356) (xy 347.003116 -288.560553) (xy 347.055053 -288.564356) (xy 347.105883 -288.575683)
			(xy 347.15452 -288.594293) (xy 347.199929 -288.619789) (xy 347.241139 -288.651628) (xy 347.277272 -288.689129)
			(xy 347.307558 -288.731493) (xy 347.33135 -288.777816) (xy 347.340174 -288.802318) (xy 347.351858 -288.836608)
			(xy 347.594174 -288.836608) (xy 347.605858 -288.802318) (xy 347.615485 -288.775748) (xy 347.641928 -288.725808)
			(xy 347.675921 -288.680665) (xy 347.716612 -288.641453) (xy 347.76298 -288.609153) (xy 347.813865 -288.584574)
			(xy 347.86799 -288.568334) (xy 347.895926 -288.564066) (xy 347.920564 -288.560764) (xy 348.093284 -288.26206)
			(xy 348.083632 -288.238946) (xy 348.075117 -288.217314) (xy 348.063132 -288.172396) (xy 348.057091 -288.126301)
			(xy 348.056708 -288.103056) (xy 348.057206 -288.076407) (xy 348.065149 -288.023703) (xy 348.080859 -287.972773)
			(xy 348.103985 -287.924752) (xy 348.134009 -287.880715) (xy 348.170261 -287.841644) (xy 348.211932 -287.808413)
			(xy 348.25809 -287.781764) (xy 348.307704 -287.762292) (xy 348.359666 -287.750432) (xy 348.412816 -287.746449)
			(xy 348.465966 -287.750432) (xy 348.517928 -287.762292) (xy 348.567542 -287.781764) (xy 348.6137 -287.808413)
			(xy 348.655371 -287.841644) (xy 348.691623 -287.880715) (xy 348.721647 -287.924752) (xy 348.744773 -287.972773)
			(xy 348.760483 -288.023703) (xy 348.768426 -288.076407) (xy 348.768924 -288.103056) (xy 348.768475 -288.128681)
			(xy 348.761122 -288.179401) (xy 348.746577 -288.228544) (xy 348.72514 -288.275095) (xy 348.697252 -288.318093)
			(xy 348.663491 -288.356652) (xy 348.624552 -288.389974) (xy 348.58124 -288.417371) (xy 348.534449 -288.43828)
			(xy 348.485145 -288.452266) (xy 348.459806 -288.456116) (xy 348.435168 -288.459418) (xy 348.262448 -288.758122)
			(xy 348.2721 -288.781236) (xy 348.279974 -288.802318) (xy 348.291658 -288.836608) (xy 348.533974 -288.836608)
			(xy 348.545658 -288.802318) (xy 348.554482 -288.777816) (xy 348.578274 -288.731493) (xy 348.60856 -288.689129)
			(xy 348.644693 -288.651628) (xy 348.685903 -288.619789) (xy 348.731312 -288.594293) (xy 348.779949 -288.575683)
			(xy 348.830779 -288.564356) (xy 348.882716 -288.560553) (xy 348.934653 -288.564356) (xy 348.985483 -288.575683)
			(xy 349.03412 -288.594293) (xy 349.079529 -288.619789) (xy 349.120739 -288.651628) (xy 349.156872 -288.689129)
			(xy 349.187158 -288.731493) (xy 349.21095 -288.777816) (xy 349.219774 -288.802318) (xy 349.231458 -288.836608)
			(xy 349.473774 -288.836608) (xy 349.485458 -288.802318) (xy 349.495085 -288.775748) (xy 349.521528 -288.725808)
			(xy 349.555521 -288.680665) (xy 349.596212 -288.641453) (xy 349.64258 -288.609153) (xy 349.693465 -288.584574)
			(xy 349.74759 -288.568334) (xy 349.775526 -288.564066) (xy 349.800164 -288.560764) (xy 349.972884 -288.26206)
			(xy 349.963232 -288.238946) (xy 349.954717 -288.217314) (xy 349.942732 -288.172396) (xy 349.936691 -288.126301)
			(xy 349.936308 -288.103056) (xy 349.936806 -288.076407) (xy 349.944749 -288.023703) (xy 349.960459 -287.972773)
			(xy 349.983585 -287.924752) (xy 350.013609 -287.880715) (xy 350.049861 -287.841644) (xy 350.091532 -287.808413)
			(xy 350.13769 -287.781764) (xy 350.187304 -287.762292) (xy 350.239266 -287.750432) (xy 350.292416 -287.746449)
			(xy 350.345566 -287.750432) (xy 350.397528 -287.762292) (xy 350.447142 -287.781764) (xy 350.4933 -287.808413)
			(xy 350.534971 -287.841644) (xy 350.571223 -287.880715) (xy 350.601247 -287.924752) (xy 350.624373 -287.972773)
			(xy 350.640083 -288.023703) (xy 350.648026 -288.076407) (xy 350.648524 -288.103056) (xy 350.648075 -288.128681)
			(xy 350.640722 -288.179401) (xy 350.626177 -288.228544) (xy 350.60474 -288.275095) (xy 350.576852 -288.318093)
			(xy 350.543091 -288.356652) (xy 350.504152 -288.389974) (xy 350.46084 -288.417371) (xy 350.414049 -288.43828)
			(xy 350.364745 -288.452266) (xy 350.339406 -288.456116) (xy 350.314768 -288.459418) (xy 350.142048 -288.758122)
			(xy 350.1517 -288.781236) (xy 350.159574 -288.802318) (xy 350.171258 -288.836608) (xy 350.413574 -288.836608)
			(xy 350.425258 -288.802318) (xy 350.434082 -288.777816) (xy 350.457874 -288.731493) (xy 350.48816 -288.689129)
			(xy 350.524293 -288.651628) (xy 350.565503 -288.619789) (xy 350.610912 -288.594293) (xy 350.659549 -288.575683)
			(xy 350.710379 -288.564356) (xy 350.762316 -288.560553) (xy 350.814253 -288.564356) (xy 350.865083 -288.575683)
			(xy 350.91372 -288.594293) (xy 350.959129 -288.619789) (xy 351.000339 -288.651628) (xy 351.036472 -288.689129)
			(xy 351.066758 -288.731493) (xy 351.09055 -288.777816) (xy 351.099374 -288.802318) (xy 351.111058 -288.836608)
			(xy 351.353374 -288.836608) (xy 351.365058 -288.802318) (xy 351.374385 -288.776503) (xy 351.399844 -288.727876)
			(xy 351.432463 -288.683733) (xy 351.47147 -288.645118) (xy 351.515941 -288.612947) (xy 351.564822 -288.587981)
			(xy 351.616955 -288.570813) (xy 351.64395 -288.565844) (xy 351.660206 -288.56305) (xy 351.70364 -288.519616)
			(xy 351.852484 -288.26206) (xy 351.842832 -288.238946) (xy 351.834317 -288.217314) (xy 351.822332 -288.172396)
			(xy 351.816291 -288.126301) (xy 351.815908 -288.103056) (xy 351.816495 -288.073886) (xy 351.826007 -288.016327)
			(xy 351.844768 -287.961087) (xy 351.872278 -287.909641) (xy 351.889568 -287.88614) (xy 351.889568 -287.73882)
			(xy 351.889049 -287.723887) (xy 351.880424 -287.695294) (xy 351.863904 -287.670413) (xy 351.840899 -287.651367)
			(xy 351.813372 -287.639782) (xy 351.783671 -287.636645) (xy 351.768918 -287.638998) (xy 351.752316 -287.641987)
			(xy 351.71873 -287.645166) (xy 351.701862 -287.645348) (xy 351.675212 -287.644848) (xy 351.622507 -287.636898)
			(xy 351.571575 -287.621183) (xy 351.523554 -287.598053) (xy 351.479517 -287.568025) (xy 351.440447 -287.531769)
			(xy 351.407216 -287.490095) (xy 351.380567 -287.443934) (xy 351.361095 -287.394317) (xy 351.349235 -287.342352)
			(xy 351.345252 -287.2892) (xy 351.349235 -287.236048) (xy 351.361095 -287.184083) (xy 351.380567 -287.134466)
			(xy 351.407216 -287.088305) (xy 351.440447 -287.046631) (xy 351.479517 -287.010375) (xy 351.523554 -286.980347)
			(xy 351.571575 -286.957217) (xy 351.622507 -286.941502) (xy 351.675212 -286.933552) (xy 351.701862 -286.933132)
			(xy 351.718729 -286.933329) (xy 351.752314 -286.936505) (xy 351.768918 -286.939482) (xy 351.783682 -286.941772)
			(xy 351.813383 -286.93866) (xy 351.840914 -286.927093) (xy 351.863925 -286.908058) (xy 351.880448 -286.883183)
			(xy 351.889073 -286.854592) (xy 351.889568 -286.83966) (xy 351.889568 -286.692594) (xy 351.874106 -286.671731)
			(xy 351.848749 -286.626416) (xy 351.830242 -286.577899) (xy 351.818978 -286.527208) (xy 351.815194 -286.475419)
			(xy 351.818972 -286.423629) (xy 351.830231 -286.372938) (xy 351.848733 -286.324418) (xy 351.874085 -286.279101)
			(xy 351.889568 -286.258254) (xy 351.889568 -286.110934) (xy 351.88905 -286.096) (xy 351.880428 -286.067403)
			(xy 351.863909 -286.042518) (xy 351.840903 -286.023469) (xy 351.813373 -286.011882) (xy 351.78367 -286.008746)
			(xy 351.768918 -286.011112) (xy 351.752316 -286.014101) (xy 351.71873 -286.017279) (xy 351.701862 -286.017462)
			(xy 351.67388 -286.016939) (xy 351.618606 -286.008178) (xy 351.565382 -285.990878) (xy 351.515521 -285.965465)
			(xy 351.470249 -285.932565) (xy 351.43068 -285.892988) (xy 351.397791 -285.847708) (xy 351.37239 -285.79784)
			(xy 351.355103 -285.744613) (xy 351.346355 -285.689336) (xy 351.345754 -285.661354) (xy 351.346202 -285.635728)
			(xy 351.353554 -285.585006) (xy 351.368097 -285.535861) (xy 351.389534 -285.489307) (xy 351.41742 -285.446306)
			(xy 351.451181 -285.407745) (xy 351.49012 -285.37442) (xy 351.533432 -285.347019) (xy 351.580223 -285.326107)
			(xy 351.629529 -285.312117) (xy 351.654872 -285.308294) (xy 351.67951 -285.304992) (xy 351.85223 -285.006034)
			(xy 351.842578 -284.98292) (xy 351.834136 -284.961359) (xy 351.822259 -284.916604) (xy 351.816267 -284.87069)
			(xy 351.815908 -284.847538) (xy 351.816497 -284.818369) (xy 351.826011 -284.760811) (xy 351.844774 -284.705573)
			(xy 351.872286 -284.654129) (xy 351.889568 -284.630622) (xy 351.889568 -284.483302) (xy 351.889046 -284.468371)
			(xy 351.880418 -284.439782) (xy 351.863898 -284.414906) (xy 351.840894 -284.395864) (xy 351.81337 -284.384281)
			(xy 351.783673 -284.381145) (xy 351.768918 -284.38348) (xy 351.752316 -284.386468) (xy 351.71873 -284.389646)
			(xy 351.701862 -284.38983) (xy 351.675213 -284.38933) (xy 351.622511 -284.381381) (xy 351.571582 -284.365666)
			(xy 351.523563 -284.342538) (xy 351.479528 -284.312511) (xy 351.44046 -284.276256) (xy 351.407231 -284.234585)
			(xy 351.380583 -284.188426) (xy 351.361112 -284.138811) (xy 351.349253 -284.086849) (xy 351.34527 -284.0337)
			(xy 351.349253 -283.980551) (xy 351.361112 -283.928589) (xy 351.380583 -283.878974) (xy 351.407231 -283.832815)
			(xy 351.44046 -283.791144) (xy 351.479528 -283.754889) (xy 351.523563 -283.724862) (xy 351.571582 -283.701734)
			(xy 351.622511 -283.686019) (xy 351.675213 -283.67807) (xy 351.701862 -283.677614) (xy 351.718729 -283.677811)
			(xy 351.752314 -283.680987) (xy 351.768918 -283.683964) (xy 351.783681 -283.686255) (xy 351.81338 -283.683143)
			(xy 351.84091 -283.671575) (xy 351.863918 -283.652539) (xy 351.880438 -283.627663) (xy 351.889057 -283.599073)
			(xy 351.889568 -283.584142) (xy 351.889568 -283.494988) (xy 351.91446 -283.470096) (xy 351.88779 -283.43479)
			(xy 351.870822 -283.411446) (xy 351.843871 -283.360418) (xy 351.825501 -283.305712) (xy 351.816194 -283.24876)
			(xy 351.815654 -283.219906) (xy 351.816202 -283.191922) (xy 351.824957 -283.136641) (xy 351.84225 -283.083411)
			(xy 351.867657 -283.033541) (xy 351.900553 -282.98826) (xy 351.940126 -282.948681) (xy 351.985404 -282.91578)
			(xy 352.03527 -282.890367) (xy 352.088499 -282.873067) (xy 352.143778 -282.864306) (xy 352.171762 -282.863798)
			(xy 352.199241 -282.864306) (xy 352.253545 -282.872753) (xy 352.305905 -282.889452) (xy 352.355072 -282.914006)
			(xy 352.399879 -282.945829) (xy 352.41992 -282.964636) (xy 352.501454 -282.883102) (xy 352.510741 -282.873143)
			(xy 352.524151 -282.849456) (xy 352.530832 -282.823068) (xy 352.530311 -282.795853) (xy 352.522624 -282.769741)
			(xy 352.508317 -282.746584) (xy 352.488405 -282.728025) (xy 352.476562 -282.721304) (xy 352.450478 -282.707012)
			(xy 352.403058 -282.671116) (xy 352.362256 -282.627845) (xy 352.345244 -282.603448) (xy 351.99828 -282.603448)
			(xy 351.984044 -282.624023) (xy 351.950726 -282.661347) (xy 351.912513 -282.693644) (xy 351.870159 -282.720277)
			(xy 351.824495 -282.740723) (xy 351.776419 -282.754579) (xy 351.726878 -282.761573) (xy 351.701862 -282.761944)
			(xy 351.675212 -282.761444) (xy 351.622508 -282.753494) (xy 351.571577 -282.737779) (xy 351.523556 -282.71465)
			(xy 351.479519 -282.684622) (xy 351.440449 -282.648366) (xy 351.407219 -282.606692) (xy 351.380571 -282.560532)
			(xy 351.361099 -282.510916) (xy 351.349239 -282.458951) (xy 351.345256 -282.4058) (xy 351.349239 -282.352649)
			(xy 351.361099 -282.300684) (xy 351.380571 -282.251068) (xy 351.407219 -282.204908) (xy 351.440449 -282.163234)
			(xy 351.479519 -282.126978) (xy 351.523556 -282.09695) (xy 351.571577 -282.073821) (xy 351.622508 -282.058106)
			(xy 351.675212 -282.050156) (xy 351.701862 -282.049728) (xy 351.726874 -282.050154) (xy 351.776405 -282.057157)
			(xy 351.824471 -282.071015) (xy 351.870128 -282.091457) (xy 351.912478 -282.118082) (xy 351.95069 -282.150366)
			(xy 351.984013 -282.187675) (xy 351.99828 -282.208224) (xy 352.345244 -282.208224) (xy 352.359482 -282.187652)
			(xy 352.392802 -282.150332) (xy 352.431015 -282.118041) (xy 352.47337 -282.091412) (xy 352.519034 -282.070971)
			(xy 352.567108 -282.05712) (xy 352.616647 -282.050129) (xy 352.641662 -282.049728) (xy 352.669367 -282.050253)
			(xy 352.72411 -282.058833) (xy 352.776862 -282.075792) (xy 352.826349 -282.100719) (xy 352.871375 -282.133014)
			(xy 352.910854 -282.171896) (xy 352.943831 -282.216425) (xy 352.95713 -282.240736) (xy 352.963801 -282.252626)
			(xy 352.982327 -282.272614) (xy 353.00549 -282.286975) (xy 353.031631 -282.29468) (xy 353.05888 -282.295178)
			(xy 353.085285 -282.288433) (xy 353.108957 -282.274929) (xy 353.118928 -282.265628) (xy 353.705414 -281.679142)
			(xy 353.700842 -281.653234) (xy 353.698344 -281.638054) (xy 353.695669 -281.607403) (xy 353.695508 -281.59202)
			(xy 353.696027 -281.564034) (xy 353.70478 -281.508751) (xy 353.722075 -281.455518) (xy 353.747484 -281.405646)
			(xy 353.780383 -281.360364) (xy 353.819961 -281.320785) (xy 353.865243 -281.287886) (xy 353.915114 -281.262476)
			(xy 353.968347 -281.245181) (xy 354.02363 -281.236427) (xy 354.051616 -281.235912) (xy 354.066999 -281.236091)
			(xy 354.097648 -281.238761) (xy 354.11283 -281.241246) (xy 354.138738 -281.245818) (xy 354.241608 -281.142948)
			(xy 354.25183 -281.131911) (xy 354.265913 -281.105347) (xy 354.271653 -281.075833) (xy 354.268553 -281.045927)
			(xy 354.25688 -281.018218) (xy 354.247704 -281.006296) (xy 354.241634 -280.998948) (xy 354.230197 -280.983701)
			(xy 354.224844 -280.975816) (xy 353.87788 -280.975816) (xy 353.863641 -280.996387) (xy 353.83032 -281.033706)
			(xy 353.792106 -281.065996) (xy 353.749752 -281.092624) (xy 353.704089 -281.113065) (xy 353.656015 -281.126919)
			(xy 353.606477 -281.133911) (xy 353.581462 -281.134312) (xy 353.554814 -281.133812) (xy 353.502115 -281.125863)
			(xy 353.451188 -281.11015) (xy 353.403172 -281.087022) (xy 353.359139 -281.056997) (xy 353.320073 -281.020744)
			(xy 353.286846 -280.979074) (xy 353.260199 -280.932918) (xy 353.24073 -280.883306) (xy 353.228871 -280.831347)
			(xy 353.224888 -280.7782) (xy 353.228871 -280.725053) (xy 353.24073 -280.673094) (xy 353.260199 -280.623482)
			(xy 353.286846 -280.577326) (xy 353.320073 -280.535656) (xy 353.359139 -280.499403) (xy 353.403172 -280.469378)
			(xy 353.451188 -280.44625) (xy 353.502115 -280.430537) (xy 353.554814 -280.422588) (xy 353.581462 -280.422096)
			(xy 353.606474 -280.422522) (xy 353.656007 -280.429524) (xy 353.704074 -280.443382) (xy 353.749731 -280.463823)
			(xy 353.792083 -280.490446) (xy 353.830297 -280.522728) (xy 353.863623 -280.560036) (xy 353.87788 -280.580592)
			(xy 354.224844 -280.580592) (xy 354.239083 -280.560021) (xy 354.272404 -280.522705) (xy 354.310618 -280.490416)
			(xy 354.352973 -280.46379) (xy 354.398636 -280.443351) (xy 354.44671 -280.429501) (xy 354.496248 -280.422511)
			(xy 354.521262 -280.422096) (xy 354.546025 -280.422519) (xy 354.595074 -280.42937) (xy 354.642702 -280.442947)
			(xy 354.687992 -280.462988) (xy 354.73007 -280.489106) (xy 354.749354 -280.504646) (xy 354.761249 -280.513863)
			(xy 354.78896 -280.525553) (xy 354.818876 -280.52865) (xy 354.848394 -280.522883) (xy 354.874944 -280.508755)
			(xy 354.886006 -280.49855) (xy 355.874828 -279.509728) (xy 355.874828 -278.690324) (xy 355.83749 -278.67991)
			(xy 355.812702 -278.672688) (xy 355.765365 -278.652075) (xy 355.721505 -278.624836) (xy 355.682043 -278.591544)
			(xy 355.647807 -278.552897) (xy 355.619517 -278.509708) (xy 355.597766 -278.462884) (xy 355.583011 -278.413407)
			(xy 355.575562 -278.362317) (xy 355.575108 -278.336502) (xy 355.575483 -278.313257) (xy 355.581528 -278.267162)
			(xy 355.593515 -278.222244) (xy 355.602032 -278.200612) (xy 355.611684 -278.177498) (xy 355.438964 -277.878794)
			(xy 355.414326 -277.875492) (xy 355.388966 -277.871688) (xy 355.339618 -277.857742) (xy 355.292781 -277.836862)
			(xy 355.249423 -277.809478) (xy 355.210443 -277.776158) (xy 355.176646 -277.73759) (xy 355.148731 -277.694573)
			(xy 355.127276 -277.647997) (xy 355.112725 -277.598824) (xy 355.105378 -277.548072) (xy 355.104954 -277.522432)
			(xy 355.105501 -277.494446) (xy 355.114251 -277.439163) (xy 355.131543 -277.385929) (xy 355.156948 -277.336056)
			(xy 355.189843 -277.290771) (xy 355.229417 -277.251189) (xy 355.274696 -277.218285) (xy 355.324564 -277.192869)
			(xy 355.377795 -277.175568) (xy 355.433076 -277.166806) (xy 355.461062 -277.166324) (xy 355.487803 -277.166803)
			(xy 355.540683 -277.174805) (xy 355.591769 -277.190634) (xy 355.639909 -277.213933) (xy 355.684018 -277.244177)
			(xy 355.703886 -277.262082) (xy 355.715035 -277.271801) (xy 355.741521 -277.284937) (xy 355.770658 -277.289941)
			(xy 355.800008 -277.286393) (xy 355.827114 -277.27459) (xy 355.849706 -277.25552) (xy 355.865892 -277.230781)
			(xy 355.874318 -277.202443) (xy 355.874828 -277.18766) (xy 355.874828 -277.062438) (xy 355.83749 -277.052024)
			(xy 355.811245 -277.04436) (xy 355.761309 -277.022098) (xy 355.715364 -276.992462) (xy 355.674492 -276.956148)
			(xy 355.639654 -276.914011) (xy 355.611669 -276.867043) (xy 355.591196 -276.816347) (xy 355.578716 -276.763117)
			(xy 355.574522 -276.708604) (xy 355.578714 -276.654092) (xy 355.591193 -276.600861) (xy 355.611665 -276.550165)
			(xy 355.639649 -276.503196) (xy 355.674486 -276.461058) (xy 355.715357 -276.424743) (xy 355.761301 -276.395106)
			(xy 355.811237 -276.372843) (xy 355.83749 -276.365208) (xy 355.874828 -276.354794) (xy 355.874828 -276.229572)
			(xy 355.874325 -276.214793) (xy 355.865867 -276.186472) (xy 355.849666 -276.161751) (xy 355.827072 -276.142693)
			(xy 355.799974 -276.13089) (xy 355.770632 -276.127327) (xy 355.741496 -276.132302) (xy 355.714998 -276.145398)
			(xy 355.703886 -276.15515) (xy 355.68401 -276.173043) (xy 355.639896 -276.203272) (xy 355.591757 -276.226562)
			(xy 355.540675 -276.242389) (xy 355.487801 -276.250398) (xy 355.461062 -276.250908) (xy 355.436049 -276.250483)
			(xy 355.386515 -276.243484) (xy 355.338445 -276.229629) (xy 355.292785 -276.20919) (xy 355.25043 -276.182569)
			(xy 355.212213 -276.150287) (xy 355.178884 -276.11298) (xy 355.164644 -276.092412) (xy 354.81768 -276.092412)
			(xy 354.803441 -276.112984) (xy 354.77012 -276.150302) (xy 354.731907 -276.182593) (xy 354.689552 -276.209221)
			(xy 354.643889 -276.229663) (xy 354.595816 -276.243516) (xy 354.546277 -276.250509) (xy 354.521262 -276.250908)
			(xy 354.494615 -276.250408) (xy 354.441916 -276.242459) (xy 354.39099 -276.226746) (xy 354.342974 -276.203618)
			(xy 354.298942 -276.173593) (xy 354.259876 -276.137341) (xy 354.226649 -276.095672) (xy 354.200003 -276.049516)
			(xy 354.180533 -275.999905) (xy 354.168675 -275.947946) (xy 354.164692 -275.8948) (xy 354.168675 -275.841654)
			(xy 354.180533 -275.789695) (xy 354.200003 -275.740084) (xy 354.226649 -275.693928) (xy 354.259876 -275.652259)
			(xy 354.298942 -275.616007) (xy 354.342974 -275.585982) (xy 354.39099 -275.562854) (xy 354.441916 -275.547141)
			(xy 354.494615 -275.539192) (xy 354.521262 -275.538692) (xy 354.546274 -275.539118) (xy 354.595807 -275.54612)
			(xy 354.643874 -275.559978) (xy 354.689532 -275.580419) (xy 354.731884 -275.607042) (xy 354.770098 -275.639324)
			(xy 354.803424 -275.676631) (xy 354.81768 -275.697188) (xy 355.164644 -275.697188) (xy 355.178883 -275.676618)
			(xy 355.212205 -275.639301) (xy 355.250419 -275.607013) (xy 355.292774 -275.580388) (xy 355.338437 -275.559949)
			(xy 355.38651 -275.546099) (xy 355.436048 -275.539109) (xy 355.461062 -275.538692) (xy 355.487803 -275.539171)
			(xy 355.540684 -275.547172) (xy 355.591771 -275.563) (xy 355.639912 -275.586298) (xy 355.684023 -275.61654)
			(xy 355.703886 -275.63445) (xy 355.71504 -275.644164) (xy 355.741529 -275.657292) (xy 355.770668 -275.662291)
			(xy 355.800018 -275.658742) (xy 355.827125 -275.646942) (xy 355.849722 -275.627877) (xy 355.865918 -275.603144)
			(xy 355.874358 -275.57481) (xy 355.874828 -275.560028) (xy 355.874828 -275.434552) (xy 355.83749 -275.424138)
			(xy 355.811244 -275.416474) (xy 355.761305 -275.394212) (xy 355.715359 -275.364575) (xy 355.674485 -275.32826)
			(xy 355.639645 -275.286122) (xy 355.611659 -275.239152) (xy 355.591184 -275.188455) (xy 355.578703 -275.135223)
			(xy 355.574509 -275.080708) (xy 355.5787 -275.026193) (xy 355.591179 -274.97296) (xy 355.611652 -274.922262)
			(xy 355.639636 -274.875291) (xy 355.674474 -274.833151) (xy 355.715346 -274.796835) (xy 355.761292 -274.767196)
			(xy 355.811229 -274.744931) (xy 355.83749 -274.737322) (xy 355.874828 -274.726908) (xy 355.874828 -274.013168)
			(xy 355.488748 -273.627088) (xy 355.302058 -273.627088) (xy 355.28844 -273.650382) (xy 355.255273 -273.692939)
			(xy 355.216064 -273.730005) (xy 355.171711 -273.760731) (xy 355.123231 -273.784412) (xy 355.071732 -273.800508)
			(xy 355.018394 -273.808649) (xy 354.964438 -273.808649) (xy 354.9111 -273.800508) (xy 354.859601 -273.784412)
			(xy 354.811121 -273.760731) (xy 354.766768 -273.730005) (xy 354.727559 -273.692939) (xy 354.694392 -273.650382)
			(xy 354.680774 -273.627088) (xy 354.362258 -273.627088) (xy 354.34864 -273.650382) (xy 354.315473 -273.692939)
			(xy 354.276264 -273.730005) (xy 354.231911 -273.760731) (xy 354.183431 -273.784412) (xy 354.131932 -273.800508)
			(xy 354.078594 -273.808649) (xy 354.024638 -273.808649) (xy 353.9713 -273.800508) (xy 353.919801 -273.784412)
			(xy 353.871321 -273.760731) (xy 353.826968 -273.730005) (xy 353.787759 -273.692939) (xy 353.754592 -273.650382)
			(xy 353.740974 -273.627088) (xy 352.482658 -273.627088) (xy 352.46904 -273.650382) (xy 352.435873 -273.692939)
			(xy 352.396664 -273.730005) (xy 352.352311 -273.760731) (xy 352.303831 -273.784412) (xy 352.252332 -273.800508)
			(xy 352.198994 -273.808649) (xy 352.145038 -273.808649) (xy 352.0917 -273.800508) (xy 352.040201 -273.784412)
			(xy 351.991721 -273.760731) (xy 351.947368 -273.730005) (xy 351.908159 -273.692939) (xy 351.874992 -273.650382)
			(xy 351.861374 -273.627088) (xy 351.542604 -273.627088) (xy 351.528986 -273.650382) (xy 351.495819 -273.692939)
			(xy 351.45661 -273.730005) (xy 351.412257 -273.760731) (xy 351.363777 -273.784412) (xy 351.312278 -273.800508)
			(xy 351.25894 -273.808649) (xy 351.204984 -273.808649) (xy 351.151646 -273.800508) (xy 351.100147 -273.784412)
			(xy 351.051667 -273.760731) (xy 351.007314 -273.730005) (xy 350.968105 -273.692939) (xy 350.934938 -273.650382)
			(xy 350.92132 -273.627088) (xy 350.603058 -273.627088) (xy 350.58944 -273.650382) (xy 350.556273 -273.692939)
			(xy 350.517064 -273.730005) (xy 350.472711 -273.760731) (xy 350.424231 -273.784412) (xy 350.372732 -273.800508)
			(xy 350.319394 -273.808649) (xy 350.265438 -273.808649) (xy 350.2121 -273.800508) (xy 350.160601 -273.784412)
			(xy 350.112121 -273.760731) (xy 350.067768 -273.730005) (xy 350.028559 -273.692939) (xy 349.995392 -273.650382)
			(xy 349.981774 -273.627088) (xy 349.663004 -273.627088) (xy 349.649386 -273.650382) (xy 349.616219 -273.692939)
			(xy 349.57701 -273.730005) (xy 349.532657 -273.760731) (xy 349.484177 -273.784412) (xy 349.432678 -273.800508)
			(xy 349.37934 -273.808649) (xy 349.325384 -273.808649) (xy 349.272046 -273.800508) (xy 349.220547 -273.784412)
			(xy 349.172067 -273.760731) (xy 349.127714 -273.730005) (xy 349.088505 -273.692939) (xy 349.055338 -273.650382)
			(xy 349.04172 -273.627088) (xy 348.723458 -273.627088) (xy 348.70984 -273.650382) (xy 348.676673 -273.692939)
			(xy 348.637464 -273.730005) (xy 348.593111 -273.760731) (xy 348.544631 -273.784412) (xy 348.493132 -273.800508)
			(xy 348.439794 -273.808649) (xy 348.385838 -273.808649) (xy 348.3325 -273.800508) (xy 348.281001 -273.784412)
			(xy 348.232521 -273.760731) (xy 348.188168 -273.730005) (xy 348.148959 -273.692939) (xy 348.115792 -273.650382)
			(xy 348.102174 -273.627088) (xy 347.783658 -273.627088) (xy 347.77004 -273.650382) (xy 347.736873 -273.692939)
			(xy 347.697664 -273.730005) (xy 347.653311 -273.760731) (xy 347.604831 -273.784412) (xy 347.553332 -273.800508)
			(xy 347.499994 -273.808649) (xy 347.446038 -273.808649) (xy 347.3927 -273.800508) (xy 347.341201 -273.784412)
			(xy 347.292721 -273.760731) (xy 347.248368 -273.730005) (xy 347.209159 -273.692939) (xy 347.175992 -273.650382)
			(xy 347.162374 -273.627088) (xy 346.843858 -273.627088) (xy 346.83024 -273.650382) (xy 346.797073 -273.692939)
			(xy 346.757864 -273.730005) (xy 346.713511 -273.760731) (xy 346.665031 -273.784412) (xy 346.613532 -273.800508)
			(xy 346.560194 -273.808649) (xy 346.506238 -273.808649) (xy 346.4529 -273.800508) (xy 346.401401 -273.784412)
			(xy 346.352921 -273.760731) (xy 346.308568 -273.730005) (xy 346.269359 -273.692939) (xy 346.236192 -273.650382)
			(xy 346.222574 -273.627088) (xy 345.904058 -273.627088) (xy 345.89044 -273.650382) (xy 345.857273 -273.692939)
			(xy 345.818064 -273.730005) (xy 345.773711 -273.760731) (xy 345.725231 -273.784412) (xy 345.673732 -273.800508)
			(xy 345.620394 -273.808649) (xy 345.566438 -273.808649) (xy 345.5131 -273.800508) (xy 345.461601 -273.784412)
			(xy 345.413121 -273.760731) (xy 345.368768 -273.730005) (xy 345.329559 -273.692939) (xy 345.296392 -273.650382)
			(xy 345.282774 -273.627088) (xy 344.964258 -273.627088) (xy 344.95064 -273.650382) (xy 344.917473 -273.692939)
			(xy 344.878264 -273.730005) (xy 344.833911 -273.760731) (xy 344.785431 -273.784412) (xy 344.733932 -273.800508)
			(xy 344.680594 -273.808649) (xy 344.626638 -273.808649) (xy 344.5733 -273.800508) (xy 344.521801 -273.784412)
			(xy 344.473321 -273.760731) (xy 344.428968 -273.730005) (xy 344.389759 -273.692939) (xy 344.356592 -273.650382)
			(xy 344.342974 -273.627088) (xy 344.024458 -273.627088) (xy 344.01084 -273.650382) (xy 343.977673 -273.692939)
			(xy 343.938464 -273.730005) (xy 343.894111 -273.760731) (xy 343.845631 -273.784412) (xy 343.794132 -273.800508)
			(xy 343.740794 -273.808649) (xy 343.686838 -273.808649) (xy 343.6335 -273.800508) (xy 343.582001 -273.784412)
			(xy 343.533521 -273.760731) (xy 343.489168 -273.730005) (xy 343.449959 -273.692939) (xy 343.416792 -273.650382)
			(xy 343.403174 -273.627088) (xy 343.084404 -273.627088) (xy 343.070786 -273.650382) (xy 343.037619 -273.692939)
			(xy 342.99841 -273.730005) (xy 342.954057 -273.760731) (xy 342.905577 -273.784412) (xy 342.854078 -273.800508)
			(xy 342.80074 -273.808649) (xy 342.746784 -273.808649) (xy 342.693446 -273.800508) (xy 342.641947 -273.784412)
			(xy 342.593467 -273.760731) (xy 342.549114 -273.730005) (xy 342.509905 -273.692939) (xy 342.476738 -273.650382)
			(xy 342.46312 -273.627088) (xy 342.144858 -273.627088) (xy 342.13124 -273.650382) (xy 342.098073 -273.692939)
			(xy 342.058864 -273.730005) (xy 342.014511 -273.760731) (xy 341.966031 -273.784412) (xy 341.914532 -273.800508)
			(xy 341.861194 -273.808649) (xy 341.807238 -273.808649) (xy 341.7539 -273.800508) (xy 341.702401 -273.784412)
			(xy 341.653921 -273.760731) (xy 341.609568 -273.730005) (xy 341.570359 -273.692939) (xy 341.537192 -273.650382)
			(xy 341.523574 -273.627088) (xy 341.205058 -273.627088) (xy 341.19144 -273.650382) (xy 341.158273 -273.692939)
			(xy 341.119064 -273.730005) (xy 341.074711 -273.760731) (xy 341.026231 -273.784412) (xy 340.974732 -273.800508)
			(xy 340.921394 -273.808649) (xy 340.867438 -273.808649) (xy 340.8141 -273.800508) (xy 340.762601 -273.784412)
			(xy 340.714121 -273.760731) (xy 340.669768 -273.730005) (xy 340.630559 -273.692939) (xy 340.597392 -273.650382)
			(xy 340.583774 -273.627088) (xy 340.265258 -273.627088) (xy 340.25164 -273.650382) (xy 340.218473 -273.692939)
			(xy 340.179264 -273.730005) (xy 340.134911 -273.760731) (xy 340.086431 -273.784412) (xy 340.034932 -273.800508)
			(xy 339.981594 -273.808649) (xy 339.927638 -273.808649) (xy 339.8743 -273.800508) (xy 339.822801 -273.784412)
			(xy 339.774321 -273.760731) (xy 339.729968 -273.730005) (xy 339.690759 -273.692939) (xy 339.657592 -273.650382)
			(xy 339.643974 -273.627088) (xy 339.325458 -273.627088) (xy 339.31184 -273.650382) (xy 339.278673 -273.692939)
			(xy 339.239464 -273.730005) (xy 339.195111 -273.760731) (xy 339.146631 -273.784412) (xy 339.095132 -273.800508)
			(xy 339.041794 -273.808649) (xy 338.987838 -273.808649) (xy 338.9345 -273.800508) (xy 338.883001 -273.784412)
			(xy 338.834521 -273.760731) (xy 338.790168 -273.730005) (xy 338.750959 -273.692939) (xy 338.717792 -273.650382)
			(xy 338.704174 -273.627088) (xy 338.385404 -273.627088) (xy 338.371786 -273.650382) (xy 338.338619 -273.692939)
			(xy 338.29941 -273.730005) (xy 338.255057 -273.760731) (xy 338.206577 -273.784412) (xy 338.155078 -273.800508)
			(xy 338.10174 -273.808649) (xy 338.047784 -273.808649) (xy 337.994446 -273.800508) (xy 337.942947 -273.784412)
			(xy 337.894467 -273.760731) (xy 337.850114 -273.730005) (xy 337.810905 -273.692939) (xy 337.777738 -273.650382)
			(xy 337.76412 -273.627088) (xy 337.445604 -273.627088) (xy 337.431986 -273.650382) (xy 337.398819 -273.692939)
			(xy 337.35961 -273.730005) (xy 337.315257 -273.760731) (xy 337.266777 -273.784412) (xy 337.215278 -273.800508)
			(xy 337.16194 -273.808649) (xy 337.107984 -273.808649) (xy 337.054646 -273.800508) (xy 337.003147 -273.784412)
			(xy 336.954667 -273.760731) (xy 336.910314 -273.730005) (xy 336.871105 -273.692939) (xy 336.837938 -273.650382)
			(xy 336.82432 -273.627088) (xy 336.505804 -273.627088) (xy 336.492181 -273.650379) (xy 336.459007 -273.69293)
			(xy 336.419796 -273.729994) (xy 336.375445 -273.760721) (xy 336.326969 -273.78441) (xy 336.275474 -273.800518)
			(xy 336.222139 -273.808678) (xy 336.195162 -273.809206) (xy 336.164061 -273.808563) (xy 336.102807 -273.797745)
			(xy 336.044365 -273.776446) (xy 336.017108 -273.761454) (xy 335.983326 -273.74215) (xy 335.909666 -273.81581)
			(xy 335.899459 -273.826741) (xy 335.88533 -273.853082) (xy 335.879444 -273.882388) (xy 335.882308 -273.912142)
			(xy 335.893675 -273.939788) (xy 335.912569 -273.962951) (xy 335.924652 -273.971766) (xy 335.944995 -273.986051)
			(xy 335.981894 -274.019355) (xy 336.013809 -274.057463) (xy 336.040119 -274.099635) (xy 336.060315 -274.145054)
			(xy 336.074005 -274.192838) (xy 336.080923 -274.242061) (xy 336.08137 -274.266914) (xy 336.080873 -274.293563)
			(xy 336.309452 -274.293563) (xy 336.309452 -274.240265) (xy 336.317395 -274.187561) (xy 336.333105 -274.136631)
			(xy 336.356231 -274.08861) (xy 336.386255 -274.044573) (xy 336.422507 -274.005502) (xy 336.464178 -273.972271)
			(xy 336.510336 -273.945622) (xy 336.55995 -273.92615) (xy 336.611912 -273.91429) (xy 336.665062 -273.910307)
			(xy 336.718212 -273.91429) (xy 336.770174 -273.92615) (xy 336.819788 -273.945622) (xy 336.865946 -273.972271)
			(xy 336.907617 -274.005502) (xy 336.943869 -274.044573) (xy 336.973893 -274.08861) (xy 336.997019 -274.136631)
			(xy 337.012729 -274.187561) (xy 337.020672 -274.240265) (xy 337.02117 -274.266914) (xy 337.020672 -274.293563)
			(xy 337.249252 -274.293563) (xy 337.249252 -274.240265) (xy 337.257195 -274.187561) (xy 337.272905 -274.136631)
			(xy 337.296031 -274.08861) (xy 337.326055 -274.044573) (xy 337.362307 -274.005502) (xy 337.403978 -273.972271)
			(xy 337.450136 -273.945622) (xy 337.49975 -273.92615) (xy 337.551712 -273.91429) (xy 337.604862 -273.910307)
			(xy 337.658012 -273.91429) (xy 337.709974 -273.92615) (xy 337.759588 -273.945622) (xy 337.805746 -273.972271)
			(xy 337.847417 -274.005502) (xy 337.883669 -274.044573) (xy 337.913693 -274.08861) (xy 337.936819 -274.136631)
			(xy 337.952529 -274.187561) (xy 337.960472 -274.240265) (xy 337.96097 -274.266914) (xy 337.960472 -274.293563)
			(xy 338.189052 -274.293563) (xy 338.189052 -274.240265) (xy 338.196995 -274.187561) (xy 338.212705 -274.136631)
			(xy 338.235831 -274.08861) (xy 338.265855 -274.044573) (xy 338.302107 -274.005502) (xy 338.343778 -273.972271)
			(xy 338.389936 -273.945622) (xy 338.43955 -273.92615) (xy 338.491512 -273.91429) (xy 338.544662 -273.910307)
			(xy 338.597812 -273.91429) (xy 338.649774 -273.92615) (xy 338.699388 -273.945622) (xy 338.745546 -273.972271)
			(xy 338.787217 -274.005502) (xy 338.823469 -274.044573) (xy 338.853493 -274.08861) (xy 338.876619 -274.136631)
			(xy 338.892329 -274.187561) (xy 338.900272 -274.240265) (xy 338.90077 -274.266914) (xy 338.900272 -274.293563)
			(xy 339.129106 -274.293563) (xy 339.129106 -274.240265) (xy 339.137049 -274.187561) (xy 339.152759 -274.136631)
			(xy 339.175885 -274.08861) (xy 339.205909 -274.044573) (xy 339.242161 -274.005502) (xy 339.283832 -273.972271)
			(xy 339.32999 -273.945622) (xy 339.379604 -273.92615) (xy 339.431566 -273.91429) (xy 339.484716 -273.910307)
			(xy 339.537866 -273.91429) (xy 339.589828 -273.92615) (xy 339.639442 -273.945622) (xy 339.6856 -273.972271)
			(xy 339.727271 -274.005502) (xy 339.763523 -274.044573) (xy 339.793547 -274.08861) (xy 339.816673 -274.136631)
			(xy 339.832383 -274.187561) (xy 339.840326 -274.240265) (xy 339.840824 -274.266914) (xy 339.840326 -274.293563)
			(xy 340.068652 -274.293563) (xy 340.068652 -274.240265) (xy 340.076595 -274.187561) (xy 340.092305 -274.136631)
			(xy 340.115431 -274.08861) (xy 340.145455 -274.044573) (xy 340.181707 -274.005502) (xy 340.223378 -273.972271)
			(xy 340.269536 -273.945622) (xy 340.31915 -273.92615) (xy 340.371112 -273.91429) (xy 340.424262 -273.910307)
			(xy 340.477412 -273.91429) (xy 340.529374 -273.92615) (xy 340.578988 -273.945622) (xy 340.625146 -273.972271)
			(xy 340.666817 -274.005502) (xy 340.703069 -274.044573) (xy 340.733093 -274.08861) (xy 340.756219 -274.136631)
			(xy 340.771929 -274.187561) (xy 340.779872 -274.240265) (xy 340.78037 -274.266914) (xy 340.779872 -274.293563)
			(xy 341.008452 -274.293563) (xy 341.008452 -274.240265) (xy 341.016395 -274.187561) (xy 341.032105 -274.136631)
			(xy 341.055231 -274.08861) (xy 341.085255 -274.044573) (xy 341.121507 -274.005502) (xy 341.163178 -273.972271)
			(xy 341.209336 -273.945622) (xy 341.25895 -273.92615) (xy 341.310912 -273.91429) (xy 341.364062 -273.910307)
			(xy 341.417212 -273.91429) (xy 341.469174 -273.92615) (xy 341.518788 -273.945622) (xy 341.564946 -273.972271)
			(xy 341.606617 -274.005502) (xy 341.642869 -274.044573) (xy 341.672893 -274.08861) (xy 341.696019 -274.136631)
			(xy 341.711729 -274.187561) (xy 341.719672 -274.240265) (xy 341.72017 -274.266914) (xy 341.719672 -274.293563)
			(xy 341.948252 -274.293563) (xy 341.948252 -274.240265) (xy 341.956195 -274.187561) (xy 341.971905 -274.136631)
			(xy 341.995031 -274.08861) (xy 342.025055 -274.044573) (xy 342.061307 -274.005502) (xy 342.102978 -273.972271)
			(xy 342.149136 -273.945622) (xy 342.19875 -273.92615) (xy 342.250712 -273.91429) (xy 342.303862 -273.910307)
			(xy 342.357012 -273.91429) (xy 342.408974 -273.92615) (xy 342.458588 -273.945622) (xy 342.504746 -273.972271)
			(xy 342.546417 -274.005502) (xy 342.582669 -274.044573) (xy 342.612693 -274.08861) (xy 342.635819 -274.136631)
			(xy 342.651529 -274.187561) (xy 342.659472 -274.240265) (xy 342.65997 -274.266914) (xy 342.659472 -274.293563)
			(xy 342.888052 -274.293563) (xy 342.888052 -274.240265) (xy 342.895995 -274.187561) (xy 342.911705 -274.136631)
			(xy 342.934831 -274.08861) (xy 342.964855 -274.044573) (xy 343.001107 -274.005502) (xy 343.042778 -273.972271)
			(xy 343.088936 -273.945622) (xy 343.13855 -273.92615) (xy 343.190512 -273.91429) (xy 343.243662 -273.910307)
			(xy 343.296812 -273.91429) (xy 343.348774 -273.92615) (xy 343.398388 -273.945622) (xy 343.444546 -273.972271)
			(xy 343.486217 -274.005502) (xy 343.522469 -274.044573) (xy 343.552493 -274.08861) (xy 343.575619 -274.136631)
			(xy 343.591329 -274.187561) (xy 343.599272 -274.240265) (xy 343.59977 -274.266914) (xy 343.599272 -274.293563)
			(xy 343.827852 -274.293563) (xy 343.827852 -274.240265) (xy 343.835795 -274.187561) (xy 343.851505 -274.136631)
			(xy 343.874631 -274.08861) (xy 343.904655 -274.044573) (xy 343.940907 -274.005502) (xy 343.982578 -273.972271)
			(xy 344.028736 -273.945622) (xy 344.07835 -273.92615) (xy 344.130312 -273.91429) (xy 344.183462 -273.910307)
			(xy 344.236612 -273.91429) (xy 344.288574 -273.92615) (xy 344.338188 -273.945622) (xy 344.384346 -273.972271)
			(xy 344.426017 -274.005502) (xy 344.462269 -274.044573) (xy 344.492293 -274.08861) (xy 344.515419 -274.136631)
			(xy 344.531129 -274.187561) (xy 344.539072 -274.240265) (xy 344.53957 -274.266914) (xy 344.539072 -274.293563)
			(xy 344.767652 -274.293563) (xy 344.767652 -274.240265) (xy 344.775595 -274.187561) (xy 344.791305 -274.136631)
			(xy 344.814431 -274.08861) (xy 344.844455 -274.044573) (xy 344.880707 -274.005502) (xy 344.922378 -273.972271)
			(xy 344.968536 -273.945622) (xy 345.01815 -273.92615) (xy 345.070112 -273.91429) (xy 345.123262 -273.910307)
			(xy 345.176412 -273.91429) (xy 345.228374 -273.92615) (xy 345.277988 -273.945622) (xy 345.324146 -273.972271)
			(xy 345.365817 -274.005502) (xy 345.402069 -274.044573) (xy 345.432093 -274.08861) (xy 345.455219 -274.136631)
			(xy 345.470929 -274.187561) (xy 345.478872 -274.240265) (xy 345.47937 -274.266914) (xy 345.478872 -274.293563)
			(xy 345.707452 -274.293563) (xy 345.707452 -274.240265) (xy 345.715395 -274.187561) (xy 345.731105 -274.136631)
			(xy 345.754231 -274.08861) (xy 345.784255 -274.044573) (xy 345.820507 -274.005502) (xy 345.862178 -273.972271)
			(xy 345.908336 -273.945622) (xy 345.95795 -273.92615) (xy 346.009912 -273.91429) (xy 346.063062 -273.910307)
			(xy 346.116212 -273.91429) (xy 346.168174 -273.92615) (xy 346.217788 -273.945622) (xy 346.263946 -273.972271)
			(xy 346.305617 -274.005502) (xy 346.341869 -274.044573) (xy 346.371893 -274.08861) (xy 346.395019 -274.136631)
			(xy 346.410729 -274.187561) (xy 346.418672 -274.240265) (xy 346.41917 -274.266914) (xy 346.418672 -274.293563)
			(xy 346.647252 -274.293563) (xy 346.647252 -274.240265) (xy 346.655195 -274.187561) (xy 346.670905 -274.136631)
			(xy 346.694031 -274.08861) (xy 346.724055 -274.044573) (xy 346.760307 -274.005502) (xy 346.801978 -273.972271)
			(xy 346.848136 -273.945622) (xy 346.89775 -273.92615) (xy 346.949712 -273.91429) (xy 347.002862 -273.910307)
			(xy 347.056012 -273.91429) (xy 347.107974 -273.92615) (xy 347.157588 -273.945622) (xy 347.203746 -273.972271)
			(xy 347.245417 -274.005502) (xy 347.281669 -274.044573) (xy 347.311693 -274.08861) (xy 347.334819 -274.136631)
			(xy 347.350529 -274.187561) (xy 347.358472 -274.240265) (xy 347.35897 -274.266914) (xy 347.358472 -274.293563)
			(xy 347.587052 -274.293563) (xy 347.587052 -274.240265) (xy 347.594995 -274.187561) (xy 347.610705 -274.136631)
			(xy 347.633831 -274.08861) (xy 347.663855 -274.044573) (xy 347.700107 -274.005502) (xy 347.741778 -273.972271)
			(xy 347.787936 -273.945622) (xy 347.83755 -273.92615) (xy 347.889512 -273.91429) (xy 347.942662 -273.910307)
			(xy 347.995812 -273.91429) (xy 348.047774 -273.92615) (xy 348.097388 -273.945622) (xy 348.143546 -273.972271)
			(xy 348.185217 -274.005502) (xy 348.221469 -274.044573) (xy 348.251493 -274.08861) (xy 348.274619 -274.136631)
			(xy 348.290329 -274.187561) (xy 348.298272 -274.240265) (xy 348.29877 -274.266914) (xy 348.298272 -274.293563)
			(xy 348.526852 -274.293563) (xy 348.526852 -274.240265) (xy 348.534795 -274.187561) (xy 348.550505 -274.136631)
			(xy 348.573631 -274.08861) (xy 348.603655 -274.044573) (xy 348.639907 -274.005502) (xy 348.681578 -273.972271)
			(xy 348.727736 -273.945622) (xy 348.77735 -273.92615) (xy 348.829312 -273.91429) (xy 348.882462 -273.910307)
			(xy 348.935612 -273.91429) (xy 348.987574 -273.92615) (xy 349.037188 -273.945622) (xy 349.083346 -273.972271)
			(xy 349.125017 -274.005502) (xy 349.161269 -274.044573) (xy 349.191293 -274.08861) (xy 349.214419 -274.136631)
			(xy 349.230129 -274.187561) (xy 349.238072 -274.240265) (xy 349.23857 -274.266914) (xy 349.238072 -274.293563)
			(xy 349.466652 -274.293563) (xy 349.466652 -274.240265) (xy 349.474595 -274.187561) (xy 349.490305 -274.136631)
			(xy 349.513431 -274.08861) (xy 349.543455 -274.044573) (xy 349.579707 -274.005502) (xy 349.621378 -273.972271)
			(xy 349.667536 -273.945622) (xy 349.71715 -273.92615) (xy 349.769112 -273.91429) (xy 349.822262 -273.910307)
			(xy 349.875412 -273.91429) (xy 349.927374 -273.92615) (xy 349.976988 -273.945622) (xy 350.023146 -273.972271)
			(xy 350.064817 -274.005502) (xy 350.101069 -274.044573) (xy 350.131093 -274.08861) (xy 350.154219 -274.136631)
			(xy 350.169929 -274.187561) (xy 350.177872 -274.240265) (xy 350.17837 -274.266914) (xy 350.177872 -274.293563)
			(xy 350.406452 -274.293563) (xy 350.406452 -274.240265) (xy 350.414395 -274.187561) (xy 350.430105 -274.136631)
			(xy 350.453231 -274.08861) (xy 350.483255 -274.044573) (xy 350.519507 -274.005502) (xy 350.561178 -273.972271)
			(xy 350.607336 -273.945622) (xy 350.65695 -273.92615) (xy 350.708912 -273.91429) (xy 350.762062 -273.910307)
			(xy 350.815212 -273.91429) (xy 350.867174 -273.92615) (xy 350.916788 -273.945622) (xy 350.962946 -273.972271)
			(xy 351.004617 -274.005502) (xy 351.040869 -274.044573) (xy 351.070893 -274.08861) (xy 351.094019 -274.136631)
			(xy 351.109729 -274.187561) (xy 351.117672 -274.240265) (xy 351.11817 -274.266914) (xy 351.345754 -274.266914)
			(xy 351.346252 -274.240265) (xy 351.354195 -274.187561) (xy 351.369905 -274.136631) (xy 351.393031 -274.08861)
			(xy 351.423055 -274.044573) (xy 351.459307 -274.005502) (xy 351.500978 -273.972271) (xy 351.547136 -273.945622)
			(xy 351.59675 -273.92615) (xy 351.648712 -273.91429) (xy 351.701862 -273.910307) (xy 351.755012 -273.91429)
			(xy 351.806974 -273.92615) (xy 351.856588 -273.945622) (xy 351.902746 -273.972271) (xy 351.944417 -274.005502)
			(xy 351.980669 -274.044573) (xy 352.010693 -274.08861) (xy 352.033819 -274.136631) (xy 352.049529 -274.187561)
			(xy 352.057472 -274.240265) (xy 352.05797 -274.266914) (xy 352.057605 -274.290066) (xy 352.057149 -274.293563)
			(xy 352.286052 -274.293563) (xy 352.286052 -274.240265) (xy 352.293995 -274.187561) (xy 352.309705 -274.136631)
			(xy 352.332831 -274.08861) (xy 352.362855 -274.044573) (xy 352.399107 -274.005502) (xy 352.440778 -273.972271)
			(xy 352.486936 -273.945622) (xy 352.53655 -273.92615) (xy 352.588512 -273.91429) (xy 352.641662 -273.910307)
			(xy 352.694812 -273.91429) (xy 352.746774 -273.92615) (xy 352.796388 -273.945622) (xy 352.842546 -273.972271)
			(xy 352.884217 -274.005502) (xy 352.920469 -274.044573) (xy 352.950493 -274.08861) (xy 352.973619 -274.136631)
			(xy 352.989329 -274.187561) (xy 352.997272 -274.240265) (xy 352.99777 -274.266914) (xy 352.997272 -274.293563)
			(xy 354.165652 -274.293563) (xy 354.165652 -274.240265) (xy 354.173595 -274.187561) (xy 354.189305 -274.136631)
			(xy 354.212431 -274.08861) (xy 354.242455 -274.044573) (xy 354.278707 -274.005502) (xy 354.320378 -273.972271)
			(xy 354.366536 -273.945622) (xy 354.41615 -273.92615) (xy 354.468112 -273.91429) (xy 354.521262 -273.910307)
			(xy 354.574412 -273.91429) (xy 354.626374 -273.92615) (xy 354.675988 -273.945622) (xy 354.722146 -273.972271)
			(xy 354.763817 -274.005502) (xy 354.800069 -274.044573) (xy 354.830093 -274.08861) (xy 354.853219 -274.136631)
			(xy 354.868929 -274.187561) (xy 354.876872 -274.240265) (xy 354.87737 -274.266914) (xy 354.876872 -274.293563)
			(xy 354.868929 -274.346267) (xy 354.853219 -274.397197) (xy 354.830093 -274.445218) (xy 354.800069 -274.489255)
			(xy 354.763817 -274.528326) (xy 354.722146 -274.561557) (xy 354.675988 -274.588206) (xy 354.626374 -274.607678)
			(xy 354.574412 -274.619538) (xy 354.521262 -274.623522) (xy 354.468112 -274.619538) (xy 354.41615 -274.607678)
			(xy 354.366536 -274.588206) (xy 354.320378 -274.561557) (xy 354.278707 -274.528326) (xy 354.242455 -274.489255)
			(xy 354.212431 -274.445218) (xy 354.189305 -274.397197) (xy 354.173595 -274.346267) (xy 354.165652 -274.293563)
			(xy 352.997272 -274.293563) (xy 352.989329 -274.346267) (xy 352.973619 -274.397197) (xy 352.950493 -274.445218)
			(xy 352.920469 -274.489255) (xy 352.884217 -274.528326) (xy 352.842546 -274.561557) (xy 352.796388 -274.588206)
			(xy 352.746774 -274.607678) (xy 352.694812 -274.619538) (xy 352.641662 -274.623522) (xy 352.588512 -274.619538)
			(xy 352.53655 -274.607678) (xy 352.486936 -274.588206) (xy 352.440778 -274.561557) (xy 352.399107 -274.528326)
			(xy 352.362855 -274.489255) (xy 352.332831 -274.445218) (xy 352.309705 -274.397197) (xy 352.293995 -274.346267)
			(xy 352.286052 -274.293563) (xy 352.057149 -274.293563) (xy 352.051616 -274.33598) (xy 352.039741 -274.380735)
			(xy 352.0313 -274.402296) (xy 352.021648 -274.42541) (xy 352.194368 -274.724368) (xy 352.219006 -274.72767)
			(xy 352.244342 -274.731533) (xy 352.293646 -274.745519) (xy 352.340436 -274.766426) (xy 352.383747 -274.793823)
			(xy 352.422686 -274.827143) (xy 352.456447 -274.8657) (xy 352.484335 -274.908697) (xy 352.505773 -274.955246)
			(xy 352.52032 -275.004387) (xy 352.527674 -275.055106) (xy 352.528124 -275.08073) (xy 352.527626 -275.107379)
			(xy 352.519683 -275.160083) (xy 352.503973 -275.211013) (xy 352.480847 -275.259034) (xy 352.450823 -275.303071)
			(xy 352.414571 -275.342142) (xy 352.3729 -275.375373) (xy 352.326742 -275.402022) (xy 352.277128 -275.421494)
			(xy 352.225166 -275.433354) (xy 352.172016 -275.437338) (xy 352.118866 -275.433354) (xy 352.066904 -275.421494)
			(xy 352.01729 -275.402022) (xy 351.971132 -275.375373) (xy 351.929461 -275.342142) (xy 351.893209 -275.303071)
			(xy 351.863185 -275.259034) (xy 351.840059 -275.211013) (xy 351.824349 -275.160083) (xy 351.816406 -275.107379)
			(xy 351.815908 -275.08073) (xy 351.816286 -275.057485) (xy 351.822329 -275.01139) (xy 351.834316 -274.966472)
			(xy 351.842832 -274.94484) (xy 351.852484 -274.921726) (xy 351.680018 -274.623276) (xy 351.655126 -274.619974)
			(xy 351.629771 -274.616152) (xy 351.58043 -274.602198) (xy 351.533601 -274.581312) (xy 351.490252 -274.553927)
			(xy 351.451277 -274.520608) (xy 351.417484 -274.482044) (xy 351.38957 -274.439033) (xy 351.368113 -274.392463)
			(xy 351.353557 -274.343297) (xy 351.346201 -274.292552) (xy 351.345754 -274.266914) (xy 351.11817 -274.266914)
			(xy 351.117672 -274.293563) (xy 351.109729 -274.346267) (xy 351.094019 -274.397197) (xy 351.070893 -274.445218)
			(xy 351.040869 -274.489255) (xy 351.004617 -274.528326) (xy 350.962946 -274.561557) (xy 350.916788 -274.588206)
			(xy 350.867174 -274.607678) (xy 350.815212 -274.619538) (xy 350.762062 -274.623522) (xy 350.708912 -274.619538)
			(xy 350.65695 -274.607678) (xy 350.607336 -274.588206) (xy 350.561178 -274.561557) (xy 350.519507 -274.528326)
			(xy 350.483255 -274.489255) (xy 350.453231 -274.445218) (xy 350.430105 -274.397197) (xy 350.414395 -274.346267)
			(xy 350.406452 -274.293563) (xy 350.177872 -274.293563) (xy 350.169929 -274.346267) (xy 350.154219 -274.397197)
			(xy 350.131093 -274.445218) (xy 350.101069 -274.489255) (xy 350.064817 -274.528326) (xy 350.023146 -274.561557)
			(xy 349.976988 -274.588206) (xy 349.927374 -274.607678) (xy 349.875412 -274.619538) (xy 349.822262 -274.623522)
			(xy 349.769112 -274.619538) (xy 349.71715 -274.607678) (xy 349.667536 -274.588206) (xy 349.621378 -274.561557)
			(xy 349.579707 -274.528326) (xy 349.543455 -274.489255) (xy 349.513431 -274.445218) (xy 349.490305 -274.397197)
			(xy 349.474595 -274.346267) (xy 349.466652 -274.293563) (xy 349.238072 -274.293563) (xy 349.230129 -274.346267)
			(xy 349.214419 -274.397197) (xy 349.191293 -274.445218) (xy 349.161269 -274.489255) (xy 349.125017 -274.528326)
			(xy 349.083346 -274.561557) (xy 349.037188 -274.588206) (xy 348.987574 -274.607678) (xy 348.935612 -274.619538)
			(xy 348.882462 -274.623522) (xy 348.829312 -274.619538) (xy 348.77735 -274.607678) (xy 348.727736 -274.588206)
			(xy 348.681578 -274.561557) (xy 348.639907 -274.528326) (xy 348.603655 -274.489255) (xy 348.573631 -274.445218)
			(xy 348.550505 -274.397197) (xy 348.534795 -274.346267) (xy 348.526852 -274.293563) (xy 348.298272 -274.293563)
			(xy 348.290329 -274.346267) (xy 348.274619 -274.397197) (xy 348.251493 -274.445218) (xy 348.221469 -274.489255)
			(xy 348.185217 -274.528326) (xy 348.143546 -274.561557) (xy 348.097388 -274.588206) (xy 348.047774 -274.607678)
			(xy 347.995812 -274.619538) (xy 347.942662 -274.623522) (xy 347.889512 -274.619538) (xy 347.83755 -274.607678)
			(xy 347.787936 -274.588206) (xy 347.741778 -274.561557) (xy 347.700107 -274.528326) (xy 347.663855 -274.489255)
			(xy 347.633831 -274.445218) (xy 347.610705 -274.397197) (xy 347.594995 -274.346267) (xy 347.587052 -274.293563)
			(xy 347.358472 -274.293563) (xy 347.350529 -274.346267) (xy 347.334819 -274.397197) (xy 347.311693 -274.445218)
			(xy 347.281669 -274.489255) (xy 347.245417 -274.528326) (xy 347.203746 -274.561557) (xy 347.157588 -274.588206)
			(xy 347.107974 -274.607678) (xy 347.056012 -274.619538) (xy 347.002862 -274.623522) (xy 346.949712 -274.619538)
			(xy 346.89775 -274.607678) (xy 346.848136 -274.588206) (xy 346.801978 -274.561557) (xy 346.760307 -274.528326)
			(xy 346.724055 -274.489255) (xy 346.694031 -274.445218) (xy 346.670905 -274.397197) (xy 346.655195 -274.346267)
			(xy 346.647252 -274.293563) (xy 346.418672 -274.293563) (xy 346.410729 -274.346267) (xy 346.395019 -274.397197)
			(xy 346.371893 -274.445218) (xy 346.341869 -274.489255) (xy 346.305617 -274.528326) (xy 346.263946 -274.561557)
			(xy 346.217788 -274.588206) (xy 346.168174 -274.607678) (xy 346.116212 -274.619538) (xy 346.063062 -274.623522)
			(xy 346.009912 -274.619538) (xy 345.95795 -274.607678) (xy 345.908336 -274.588206) (xy 345.862178 -274.561557)
			(xy 345.820507 -274.528326) (xy 345.784255 -274.489255) (xy 345.754231 -274.445218) (xy 345.731105 -274.397197)
			(xy 345.715395 -274.346267) (xy 345.707452 -274.293563) (xy 345.478872 -274.293563) (xy 345.470929 -274.346267)
			(xy 345.455219 -274.397197) (xy 345.432093 -274.445218) (xy 345.402069 -274.489255) (xy 345.365817 -274.528326)
			(xy 345.324146 -274.561557) (xy 345.277988 -274.588206) (xy 345.228374 -274.607678) (xy 345.176412 -274.619538)
			(xy 345.123262 -274.623522) (xy 345.070112 -274.619538) (xy 345.01815 -274.607678) (xy 344.968536 -274.588206)
			(xy 344.922378 -274.561557) (xy 344.880707 -274.528326) (xy 344.844455 -274.489255) (xy 344.814431 -274.445218)
			(xy 344.791305 -274.397197) (xy 344.775595 -274.346267) (xy 344.767652 -274.293563) (xy 344.539072 -274.293563)
			(xy 344.531129 -274.346267) (xy 344.515419 -274.397197) (xy 344.492293 -274.445218) (xy 344.462269 -274.489255)
			(xy 344.426017 -274.528326) (xy 344.384346 -274.561557) (xy 344.338188 -274.588206) (xy 344.288574 -274.607678)
			(xy 344.236612 -274.619538) (xy 344.183462 -274.623522) (xy 344.130312 -274.619538) (xy 344.07835 -274.607678)
			(xy 344.028736 -274.588206) (xy 343.982578 -274.561557) (xy 343.940907 -274.528326) (xy 343.904655 -274.489255)
			(xy 343.874631 -274.445218) (xy 343.851505 -274.397197) (xy 343.835795 -274.346267) (xy 343.827852 -274.293563)
			(xy 343.599272 -274.293563) (xy 343.591329 -274.346267) (xy 343.575619 -274.397197) (xy 343.552493 -274.445218)
			(xy 343.522469 -274.489255) (xy 343.486217 -274.528326) (xy 343.444546 -274.561557) (xy 343.398388 -274.588206)
			(xy 343.348774 -274.607678) (xy 343.296812 -274.619538) (xy 343.243662 -274.623522) (xy 343.190512 -274.619538)
			(xy 343.13855 -274.607678) (xy 343.088936 -274.588206) (xy 343.042778 -274.561557) (xy 343.001107 -274.528326)
			(xy 342.964855 -274.489255) (xy 342.934831 -274.445218) (xy 342.911705 -274.397197) (xy 342.895995 -274.346267)
			(xy 342.888052 -274.293563) (xy 342.659472 -274.293563) (xy 342.651529 -274.346267) (xy 342.635819 -274.397197)
			(xy 342.612693 -274.445218) (xy 342.582669 -274.489255) (xy 342.546417 -274.528326) (xy 342.504746 -274.561557)
			(xy 342.458588 -274.588206) (xy 342.408974 -274.607678) (xy 342.357012 -274.619538) (xy 342.303862 -274.623522)
			(xy 342.250712 -274.619538) (xy 342.19875 -274.607678) (xy 342.149136 -274.588206) (xy 342.102978 -274.561557)
			(xy 342.061307 -274.528326) (xy 342.025055 -274.489255) (xy 341.995031 -274.445218) (xy 341.971905 -274.397197)
			(xy 341.956195 -274.346267) (xy 341.948252 -274.293563) (xy 341.719672 -274.293563) (xy 341.711729 -274.346267)
			(xy 341.696019 -274.397197) (xy 341.672893 -274.445218) (xy 341.642869 -274.489255) (xy 341.606617 -274.528326)
			(xy 341.564946 -274.561557) (xy 341.518788 -274.588206) (xy 341.469174 -274.607678) (xy 341.417212 -274.619538)
			(xy 341.364062 -274.623522) (xy 341.310912 -274.619538) (xy 341.25895 -274.607678) (xy 341.209336 -274.588206)
			(xy 341.163178 -274.561557) (xy 341.121507 -274.528326) (xy 341.085255 -274.489255) (xy 341.055231 -274.445218)
			(xy 341.032105 -274.397197) (xy 341.016395 -274.346267) (xy 341.008452 -274.293563) (xy 340.779872 -274.293563)
			(xy 340.771929 -274.346267) (xy 340.756219 -274.397197) (xy 340.733093 -274.445218) (xy 340.703069 -274.489255)
			(xy 340.666817 -274.528326) (xy 340.625146 -274.561557) (xy 340.578988 -274.588206) (xy 340.529374 -274.607678)
			(xy 340.477412 -274.619538) (xy 340.424262 -274.623522) (xy 340.371112 -274.619538) (xy 340.31915 -274.607678)
			(xy 340.269536 -274.588206) (xy 340.223378 -274.561557) (xy 340.181707 -274.528326) (xy 340.145455 -274.489255)
			(xy 340.115431 -274.445218) (xy 340.092305 -274.397197) (xy 340.076595 -274.346267) (xy 340.068652 -274.293563)
			(xy 339.840326 -274.293563) (xy 339.832383 -274.346267) (xy 339.816673 -274.397197) (xy 339.793547 -274.445218)
			(xy 339.763523 -274.489255) (xy 339.727271 -274.528326) (xy 339.6856 -274.561557) (xy 339.639442 -274.588206)
			(xy 339.589828 -274.607678) (xy 339.537866 -274.619538) (xy 339.484716 -274.623522) (xy 339.431566 -274.619538)
			(xy 339.379604 -274.607678) (xy 339.32999 -274.588206) (xy 339.283832 -274.561557) (xy 339.242161 -274.528326)
			(xy 339.205909 -274.489255) (xy 339.175885 -274.445218) (xy 339.152759 -274.397197) (xy 339.137049 -274.346267)
			(xy 339.129106 -274.293563) (xy 338.900272 -274.293563) (xy 338.892329 -274.346267) (xy 338.876619 -274.397197)
			(xy 338.853493 -274.445218) (xy 338.823469 -274.489255) (xy 338.787217 -274.528326) (xy 338.745546 -274.561557)
			(xy 338.699388 -274.588206) (xy 338.649774 -274.607678) (xy 338.597812 -274.619538) (xy 338.544662 -274.623522)
			(xy 338.491512 -274.619538) (xy 338.43955 -274.607678) (xy 338.389936 -274.588206) (xy 338.343778 -274.561557)
			(xy 338.302107 -274.528326) (xy 338.265855 -274.489255) (xy 338.235831 -274.445218) (xy 338.212705 -274.397197)
			(xy 338.196995 -274.346267) (xy 338.189052 -274.293563) (xy 337.960472 -274.293563) (xy 337.952529 -274.346267)
			(xy 337.936819 -274.397197) (xy 337.913693 -274.445218) (xy 337.883669 -274.489255) (xy 337.847417 -274.528326)
			(xy 337.805746 -274.561557) (xy 337.759588 -274.588206) (xy 337.709974 -274.607678) (xy 337.658012 -274.619538)
			(xy 337.604862 -274.623522) (xy 337.551712 -274.619538) (xy 337.49975 -274.607678) (xy 337.450136 -274.588206)
			(xy 337.403978 -274.561557) (xy 337.362307 -274.528326) (xy 337.326055 -274.489255) (xy 337.296031 -274.445218)
			(xy 337.272905 -274.397197) (xy 337.257195 -274.346267) (xy 337.249252 -274.293563) (xy 337.020672 -274.293563)
			(xy 337.012729 -274.346267) (xy 336.997019 -274.397197) (xy 336.973893 -274.445218) (xy 336.943869 -274.489255)
			(xy 336.907617 -274.528326) (xy 336.865946 -274.561557) (xy 336.819788 -274.588206) (xy 336.770174 -274.607678)
			(xy 336.718212 -274.619538) (xy 336.665062 -274.623522) (xy 336.611912 -274.619538) (xy 336.55995 -274.607678)
			(xy 336.510336 -274.588206) (xy 336.464178 -274.561557) (xy 336.422507 -274.528326) (xy 336.386255 -274.489255)
			(xy 336.356231 -274.445218) (xy 336.333105 -274.397197) (xy 336.317395 -274.346267) (xy 336.309452 -274.293563)
			(xy 336.080873 -274.293563) (xy 336.080848 -274.294898) (xy 336.072091 -274.350175) (xy 336.054793 -274.403402)
			(xy 336.029382 -274.453268) (xy 335.996482 -274.498544) (xy 335.956904 -274.538116) (xy 335.911623 -274.571009)
			(xy 335.861754 -274.596413) (xy 335.808525 -274.613703) (xy 335.753246 -274.622452) (xy 335.725262 -274.623022)
			(xy 335.700406 -274.622594) (xy 335.651176 -274.615691) (xy 335.603383 -274.602009) (xy 335.557958 -274.581815)
			(xy 335.515781 -274.555501) (xy 335.477674 -274.523578) (xy 335.444374 -274.486666) (xy 335.430114 -274.466304)
			(xy 335.4213 -274.454234) (xy 335.39811 -274.435404) (xy 335.370468 -274.424074) (xy 335.340733 -274.421212)
			(xy 335.311438 -274.427059) (xy 335.285081 -274.441119) (xy 335.274158 -274.451318) (xy 335.174082 -274.551394)
			(xy 335.163833 -274.562477) (xy 335.14974 -274.589154) (xy 335.144056 -274.618785) (xy 335.147277 -274.648783)
			(xy 335.159122 -274.676532) (xy 335.178558 -274.699608) (xy 335.203888 -274.716) (xy 335.232901 -274.724275)
			(xy 335.247996 -274.724622) (xy 335.255108 -274.724622) (xy 335.282185 -274.725128) (xy 335.335715 -274.73333)
			(xy 335.387386 -274.749542) (xy 335.436006 -274.773392) (xy 335.480454 -274.804329) (xy 335.519704 -274.84164)
			(xy 335.552853 -274.884465) (xy 335.579134 -274.931814) (xy 335.597942 -274.982598) (xy 335.608844 -275.035644)
			(xy 335.611588 -275.089729) (xy 335.609793 -275.107379) (xy 335.839552 -275.107379) (xy 335.839552 -275.054081)
			(xy 335.847495 -275.001377) (xy 335.863205 -274.950447) (xy 335.886331 -274.902426) (xy 335.916355 -274.858389)
			(xy 335.952607 -274.819318) (xy 335.994278 -274.786087) (xy 336.040436 -274.759438) (xy 336.09005 -274.739966)
			(xy 336.142012 -274.728106) (xy 336.195162 -274.724123) (xy 336.248312 -274.728106) (xy 336.300274 -274.739966)
			(xy 336.349888 -274.759438) (xy 336.396046 -274.786087) (xy 336.437717 -274.819318) (xy 336.473969 -274.858389)
			(xy 336.503993 -274.902426) (xy 336.527119 -274.950447) (xy 336.542829 -275.001377) (xy 336.550772 -275.054081)
			(xy 336.55127 -275.08073) (xy 336.550772 -275.107379) (xy 336.779352 -275.107379) (xy 336.779352 -275.054081)
			(xy 336.787295 -275.001377) (xy 336.803005 -274.950447) (xy 336.826131 -274.902426) (xy 336.856155 -274.858389)
			(xy 336.892407 -274.819318) (xy 336.934078 -274.786087) (xy 336.980236 -274.759438) (xy 337.02985 -274.739966)
			(xy 337.081812 -274.728106) (xy 337.134962 -274.724123) (xy 337.188112 -274.728106) (xy 337.240074 -274.739966)
			(xy 337.289688 -274.759438) (xy 337.335846 -274.786087) (xy 337.377517 -274.819318) (xy 337.413769 -274.858389)
			(xy 337.443793 -274.902426) (xy 337.466919 -274.950447) (xy 337.482629 -275.001377) (xy 337.490572 -275.054081)
			(xy 337.49107 -275.08073) (xy 337.490572 -275.107379) (xy 337.719152 -275.107379) (xy 337.719152 -275.054081)
			(xy 337.727095 -275.001377) (xy 337.742805 -274.950447) (xy 337.765931 -274.902426) (xy 337.795955 -274.858389)
			(xy 337.832207 -274.819318) (xy 337.873878 -274.786087) (xy 337.920036 -274.759438) (xy 337.96965 -274.739966)
			(xy 338.021612 -274.728106) (xy 338.074762 -274.724123) (xy 338.127912 -274.728106) (xy 338.179874 -274.739966)
			(xy 338.229488 -274.759438) (xy 338.275646 -274.786087) (xy 338.317317 -274.819318) (xy 338.353569 -274.858389)
			(xy 338.383593 -274.902426) (xy 338.406719 -274.950447) (xy 338.422429 -275.001377) (xy 338.430372 -275.054081)
			(xy 338.43087 -275.08073) (xy 338.430372 -275.107379) (xy 338.659206 -275.107379) (xy 338.659206 -275.054081)
			(xy 338.667149 -275.001377) (xy 338.682859 -274.950447) (xy 338.705985 -274.902426) (xy 338.736009 -274.858389)
			(xy 338.772261 -274.819318) (xy 338.813932 -274.786087) (xy 338.86009 -274.759438) (xy 338.909704 -274.739966)
			(xy 338.961666 -274.728106) (xy 339.014816 -274.724123) (xy 339.067966 -274.728106) (xy 339.119928 -274.739966)
			(xy 339.169542 -274.759438) (xy 339.2157 -274.786087) (xy 339.257371 -274.819318) (xy 339.293623 -274.858389)
			(xy 339.323647 -274.902426) (xy 339.346773 -274.950447) (xy 339.362483 -275.001377) (xy 339.370426 -275.054081)
			(xy 339.370924 -275.08073) (xy 339.370426 -275.107379) (xy 339.598752 -275.107379) (xy 339.598752 -275.054081)
			(xy 339.606695 -275.001377) (xy 339.622405 -274.950447) (xy 339.645531 -274.902426) (xy 339.675555 -274.858389)
			(xy 339.711807 -274.819318) (xy 339.753478 -274.786087) (xy 339.799636 -274.759438) (xy 339.84925 -274.739966)
			(xy 339.901212 -274.728106) (xy 339.954362 -274.724123) (xy 340.007512 -274.728106) (xy 340.059474 -274.739966)
			(xy 340.109088 -274.759438) (xy 340.155246 -274.786087) (xy 340.196917 -274.819318) (xy 340.233169 -274.858389)
			(xy 340.263193 -274.902426) (xy 340.286319 -274.950447) (xy 340.302029 -275.001377) (xy 340.309972 -275.054081)
			(xy 340.31047 -275.08073) (xy 340.309972 -275.107379) (xy 340.538806 -275.107379) (xy 340.538806 -275.054081)
			(xy 340.546749 -275.001377) (xy 340.562459 -274.950447) (xy 340.585585 -274.902426) (xy 340.615609 -274.858389)
			(xy 340.651861 -274.819318) (xy 340.693532 -274.786087) (xy 340.73969 -274.759438) (xy 340.789304 -274.739966)
			(xy 340.841266 -274.728106) (xy 340.894416 -274.724123) (xy 340.947566 -274.728106) (xy 340.999528 -274.739966)
			(xy 341.049142 -274.759438) (xy 341.0953 -274.786087) (xy 341.136971 -274.819318) (xy 341.173223 -274.858389)
			(xy 341.203247 -274.902426) (xy 341.226373 -274.950447) (xy 341.242083 -275.001377) (xy 341.250026 -275.054081)
			(xy 341.250524 -275.08073) (xy 341.250026 -275.107379) (xy 341.478606 -275.107379) (xy 341.478606 -275.054081)
			(xy 341.486549 -275.001377) (xy 341.502259 -274.950447) (xy 341.525385 -274.902426) (xy 341.555409 -274.858389)
			(xy 341.591661 -274.819318) (xy 341.633332 -274.786087) (xy 341.67949 -274.759438) (xy 341.729104 -274.739966)
			(xy 341.781066 -274.728106) (xy 341.834216 -274.724123) (xy 341.887366 -274.728106) (xy 341.939328 -274.739966)
			(xy 341.988942 -274.759438) (xy 342.0351 -274.786087) (xy 342.076771 -274.819318) (xy 342.113023 -274.858389)
			(xy 342.143047 -274.902426) (xy 342.166173 -274.950447) (xy 342.181883 -275.001377) (xy 342.189826 -275.054081)
			(xy 342.190324 -275.08073) (xy 342.189826 -275.107379) (xy 342.418406 -275.107379) (xy 342.418406 -275.054081)
			(xy 342.426349 -275.001377) (xy 342.442059 -274.950447) (xy 342.465185 -274.902426) (xy 342.495209 -274.858389)
			(xy 342.531461 -274.819318) (xy 342.573132 -274.786087) (xy 342.61929 -274.759438) (xy 342.668904 -274.739966)
			(xy 342.720866 -274.728106) (xy 342.774016 -274.724123) (xy 342.827166 -274.728106) (xy 342.879128 -274.739966)
			(xy 342.928742 -274.759438) (xy 342.9749 -274.786087) (xy 343.016571 -274.819318) (xy 343.052823 -274.858389)
			(xy 343.082847 -274.902426) (xy 343.105973 -274.950447) (xy 343.121683 -275.001377) (xy 343.129626 -275.054081)
			(xy 343.130124 -275.08073) (xy 343.129626 -275.107379) (xy 343.358206 -275.107379) (xy 343.358206 -275.054081)
			(xy 343.366149 -275.001377) (xy 343.381859 -274.950447) (xy 343.404985 -274.902426) (xy 343.435009 -274.858389)
			(xy 343.471261 -274.819318) (xy 343.512932 -274.786087) (xy 343.55909 -274.759438) (xy 343.608704 -274.739966)
			(xy 343.660666 -274.728106) (xy 343.713816 -274.724123) (xy 343.766966 -274.728106) (xy 343.818928 -274.739966)
			(xy 343.868542 -274.759438) (xy 343.9147 -274.786087) (xy 343.956371 -274.819318) (xy 343.992623 -274.858389)
			(xy 344.022647 -274.902426) (xy 344.045773 -274.950447) (xy 344.061483 -275.001377) (xy 344.069426 -275.054081)
			(xy 344.069924 -275.08073) (xy 344.069426 -275.107379) (xy 344.298006 -275.107379) (xy 344.298006 -275.054081)
			(xy 344.305949 -275.001377) (xy 344.321659 -274.950447) (xy 344.344785 -274.902426) (xy 344.374809 -274.858389)
			(xy 344.411061 -274.819318) (xy 344.452732 -274.786087) (xy 344.49889 -274.759438) (xy 344.548504 -274.739966)
			(xy 344.600466 -274.728106) (xy 344.653616 -274.724123) (xy 344.706766 -274.728106) (xy 344.758728 -274.739966)
			(xy 344.808342 -274.759438) (xy 344.8545 -274.786087) (xy 344.896171 -274.819318) (xy 344.932423 -274.858389)
			(xy 344.962447 -274.902426) (xy 344.985573 -274.950447) (xy 345.001283 -275.001377) (xy 345.009226 -275.054081)
			(xy 345.009724 -275.08073) (xy 345.009226 -275.107379) (xy 345.237806 -275.107379) (xy 345.237806 -275.054081)
			(xy 345.245749 -275.001377) (xy 345.261459 -274.950447) (xy 345.284585 -274.902426) (xy 345.314609 -274.858389)
			(xy 345.350861 -274.819318) (xy 345.392532 -274.786087) (xy 345.43869 -274.759438) (xy 345.488304 -274.739966)
			(xy 345.540266 -274.728106) (xy 345.593416 -274.724123) (xy 345.646566 -274.728106) (xy 345.698528 -274.739966)
			(xy 345.748142 -274.759438) (xy 345.7943 -274.786087) (xy 345.835971 -274.819318) (xy 345.872223 -274.858389)
			(xy 345.902247 -274.902426) (xy 345.925373 -274.950447) (xy 345.941083 -275.001377) (xy 345.949026 -275.054081)
			(xy 345.949524 -275.08073) (xy 345.949026 -275.107379) (xy 346.177352 -275.107379) (xy 346.177352 -275.054081)
			(xy 346.185295 -275.001377) (xy 346.201005 -274.950447) (xy 346.224131 -274.902426) (xy 346.254155 -274.858389)
			(xy 346.290407 -274.819318) (xy 346.332078 -274.786087) (xy 346.378236 -274.759438) (xy 346.42785 -274.739966)
			(xy 346.479812 -274.728106) (xy 346.532962 -274.724123) (xy 346.586112 -274.728106) (xy 346.638074 -274.739966)
			(xy 346.687688 -274.759438) (xy 346.733846 -274.786087) (xy 346.775517 -274.819318) (xy 346.811769 -274.858389)
			(xy 346.841793 -274.902426) (xy 346.864919 -274.950447) (xy 346.880629 -275.001377) (xy 346.888572 -275.054081)
			(xy 346.88907 -275.08073) (xy 346.888572 -275.107379) (xy 347.117406 -275.107379) (xy 347.117406 -275.054081)
			(xy 347.125349 -275.001377) (xy 347.141059 -274.950447) (xy 347.164185 -274.902426) (xy 347.194209 -274.858389)
			(xy 347.230461 -274.819318) (xy 347.272132 -274.786087) (xy 347.31829 -274.759438) (xy 347.367904 -274.739966)
			(xy 347.419866 -274.728106) (xy 347.473016 -274.724123) (xy 347.526166 -274.728106) (xy 347.578128 -274.739966)
			(xy 347.627742 -274.759438) (xy 347.6739 -274.786087) (xy 347.715571 -274.819318) (xy 347.751823 -274.858389)
			(xy 347.781847 -274.902426) (xy 347.804973 -274.950447) (xy 347.820683 -275.001377) (xy 347.828626 -275.054081)
			(xy 347.829124 -275.08073) (xy 347.828626 -275.107379) (xy 348.057206 -275.107379) (xy 348.057206 -275.054081)
			(xy 348.065149 -275.001377) (xy 348.080859 -274.950447) (xy 348.103985 -274.902426) (xy 348.134009 -274.858389)
			(xy 348.170261 -274.819318) (xy 348.211932 -274.786087) (xy 348.25809 -274.759438) (xy 348.307704 -274.739966)
			(xy 348.359666 -274.728106) (xy 348.412816 -274.724123) (xy 348.465966 -274.728106) (xy 348.517928 -274.739966)
			(xy 348.567542 -274.759438) (xy 348.6137 -274.786087) (xy 348.655371 -274.819318) (xy 348.691623 -274.858389)
			(xy 348.721647 -274.902426) (xy 348.744773 -274.950447) (xy 348.760483 -275.001377) (xy 348.768426 -275.054081)
			(xy 348.768923 -275.0807) (xy 349.935798 -275.0807) (xy 349.939781 -275.02755) (xy 349.951642 -274.975587)
			(xy 349.971115 -274.925972) (xy 349.997765 -274.879814) (xy 350.030997 -274.838143) (xy 350.070069 -274.801892)
			(xy 350.114108 -274.771868) (xy 350.16213 -274.748744) (xy 350.213062 -274.733036) (xy 350.265766 -274.725094)
			(xy 350.292416 -274.724622) (xy 350.317442 -274.72502) (xy 350.367001 -274.732031) (xy 350.41509 -274.745912)
			(xy 350.460761 -274.766391) (xy 350.503115 -274.793063) (xy 350.541317 -274.825404) (xy 350.574613 -274.862775)
			(xy 350.588834 -274.883372) (xy 350.935798 -274.883372) (xy 350.950021 -274.862777) (xy 350.983318 -274.825409)
			(xy 351.02152 -274.793072) (xy 351.063874 -274.766404) (xy 351.109545 -274.745929) (xy 351.157633 -274.732052)
			(xy 351.207191 -274.725045) (xy 351.232216 -274.724622) (xy 351.258867 -274.725061) (xy 351.311573 -274.733007)
			(xy 351.362506 -274.74872) (xy 351.410528 -274.771848) (xy 351.454567 -274.801875) (xy 351.493639 -274.83813)
			(xy 351.526871 -274.879804) (xy 351.553521 -274.925965) (xy 351.572994 -274.975582) (xy 351.584854 -275.027547)
			(xy 351.588838 -275.0807) (xy 351.584854 -275.133853) (xy 351.572994 -275.185818) (xy 351.553521 -275.235435)
			(xy 351.526871 -275.281596) (xy 351.493639 -275.32327) (xy 351.454567 -275.359525) (xy 351.410528 -275.389552)
			(xy 351.362506 -275.41268) (xy 351.311573 -275.428393) (xy 351.258867 -275.436339) (xy 351.232216 -275.436838)
			(xy 351.207192 -275.43639) (xy 351.157636 -275.429384) (xy 351.10955 -275.415509) (xy 351.063879 -275.395038)
			(xy 351.021525 -275.368375) (xy 350.983322 -275.336043) (xy 350.950022 -275.298681) (xy 350.935798 -275.278088)
			(xy 350.588834 -275.278088) (xy 350.57461 -275.298682) (xy 350.541311 -275.336047) (xy 350.503108 -275.368382)
			(xy 350.460754 -275.395049) (xy 350.415084 -275.415524) (xy 350.366997 -275.429403) (xy 350.317441 -275.436413)
			(xy 350.292416 -275.436838) (xy 350.265766 -275.436306) (xy 350.213062 -275.428364) (xy 350.16213 -275.412656)
			(xy 350.114108 -275.389532) (xy 350.070069 -275.359508) (xy 350.030997 -275.323257) (xy 349.997765 -275.281586)
			(xy 349.971115 -275.235428) (xy 349.951642 -275.185813) (xy 349.939781 -275.13385) (xy 349.935798 -275.0807)
			(xy 348.768923 -275.0807) (xy 348.768924 -275.08073) (xy 348.768426 -275.107379) (xy 348.760483 -275.160083)
			(xy 348.744773 -275.211013) (xy 348.721647 -275.259034) (xy 348.691623 -275.303071) (xy 348.655371 -275.342142)
			(xy 348.6137 -275.375373) (xy 348.567542 -275.402022) (xy 348.517928 -275.421494) (xy 348.465966 -275.433354)
			(xy 348.412816 -275.437338) (xy 348.359666 -275.433354) (xy 348.307704 -275.421494) (xy 348.25809 -275.402022)
			(xy 348.211932 -275.375373) (xy 348.170261 -275.342142) (xy 348.134009 -275.303071) (xy 348.103985 -275.259034)
			(xy 348.080859 -275.211013) (xy 348.065149 -275.160083) (xy 348.057206 -275.107379) (xy 347.828626 -275.107379)
			(xy 347.820683 -275.160083) (xy 347.804973 -275.211013) (xy 347.781847 -275.259034) (xy 347.751823 -275.303071)
			(xy 347.715571 -275.342142) (xy 347.6739 -275.375373) (xy 347.627742 -275.402022) (xy 347.578128 -275.421494)
			(xy 347.526166 -275.433354) (xy 347.473016 -275.437338) (xy 347.419866 -275.433354) (xy 347.367904 -275.421494)
			(xy 347.31829 -275.402022) (xy 347.272132 -275.375373) (xy 347.230461 -275.342142) (xy 347.194209 -275.303071)
			(xy 347.164185 -275.259034) (xy 347.141059 -275.211013) (xy 347.125349 -275.160083) (xy 347.117406 -275.107379)
			(xy 346.888572 -275.107379) (xy 346.880629 -275.160083) (xy 346.864919 -275.211013) (xy 346.841793 -275.259034)
			(xy 346.811769 -275.303071) (xy 346.775517 -275.342142) (xy 346.733846 -275.375373) (xy 346.687688 -275.402022)
			(xy 346.638074 -275.421494) (xy 346.586112 -275.433354) (xy 346.532962 -275.437338) (xy 346.479812 -275.433354)
			(xy 346.42785 -275.421494) (xy 346.378236 -275.402022) (xy 346.332078 -275.375373) (xy 346.290407 -275.342142)
			(xy 346.254155 -275.303071) (xy 346.224131 -275.259034) (xy 346.201005 -275.211013) (xy 346.185295 -275.160083)
			(xy 346.177352 -275.107379) (xy 345.949026 -275.107379) (xy 345.941083 -275.160083) (xy 345.925373 -275.211013)
			(xy 345.902247 -275.259034) (xy 345.872223 -275.303071) (xy 345.835971 -275.342142) (xy 345.7943 -275.375373)
			(xy 345.748142 -275.402022) (xy 345.698528 -275.421494) (xy 345.646566 -275.433354) (xy 345.593416 -275.437338)
			(xy 345.540266 -275.433354) (xy 345.488304 -275.421494) (xy 345.43869 -275.402022) (xy 345.392532 -275.375373)
			(xy 345.350861 -275.342142) (xy 345.314609 -275.303071) (xy 345.284585 -275.259034) (xy 345.261459 -275.211013)
			(xy 345.245749 -275.160083) (xy 345.237806 -275.107379) (xy 345.009226 -275.107379) (xy 345.001283 -275.160083)
			(xy 344.985573 -275.211013) (xy 344.962447 -275.259034) (xy 344.932423 -275.303071) (xy 344.896171 -275.342142)
			(xy 344.8545 -275.375373) (xy 344.808342 -275.402022) (xy 344.758728 -275.421494) (xy 344.706766 -275.433354)
			(xy 344.653616 -275.437338) (xy 344.600466 -275.433354) (xy 344.548504 -275.421494) (xy 344.49889 -275.402022)
			(xy 344.452732 -275.375373) (xy 344.411061 -275.342142) (xy 344.374809 -275.303071) (xy 344.344785 -275.259034)
			(xy 344.321659 -275.211013) (xy 344.305949 -275.160083) (xy 344.298006 -275.107379) (xy 344.069426 -275.107379)
			(xy 344.061483 -275.160083) (xy 344.045773 -275.211013) (xy 344.022647 -275.259034) (xy 343.992623 -275.303071)
			(xy 343.956371 -275.342142) (xy 343.9147 -275.375373) (xy 343.868542 -275.402022) (xy 343.818928 -275.421494)
			(xy 343.766966 -275.433354) (xy 343.713816 -275.437338) (xy 343.660666 -275.433354) (xy 343.608704 -275.421494)
			(xy 343.55909 -275.402022) (xy 343.512932 -275.375373) (xy 343.471261 -275.342142) (xy 343.435009 -275.303071)
			(xy 343.404985 -275.259034) (xy 343.381859 -275.211013) (xy 343.366149 -275.160083) (xy 343.358206 -275.107379)
			(xy 343.129626 -275.107379) (xy 343.121683 -275.160083) (xy 343.105973 -275.211013) (xy 343.082847 -275.259034)
			(xy 343.052823 -275.303071) (xy 343.016571 -275.342142) (xy 342.9749 -275.375373) (xy 342.928742 -275.402022)
			(xy 342.879128 -275.421494) (xy 342.827166 -275.433354) (xy 342.774016 -275.437338) (xy 342.720866 -275.433354)
			(xy 342.668904 -275.421494) (xy 342.61929 -275.402022) (xy 342.573132 -275.375373) (xy 342.531461 -275.342142)
			(xy 342.495209 -275.303071) (xy 342.465185 -275.259034) (xy 342.442059 -275.211013) (xy 342.426349 -275.160083)
			(xy 342.418406 -275.107379) (xy 342.189826 -275.107379) (xy 342.181883 -275.160083) (xy 342.166173 -275.211013)
			(xy 342.143047 -275.259034) (xy 342.113023 -275.303071) (xy 342.076771 -275.342142) (xy 342.0351 -275.375373)
			(xy 341.988942 -275.402022) (xy 341.939328 -275.421494) (xy 341.887366 -275.433354) (xy 341.834216 -275.437338)
			(xy 341.781066 -275.433354) (xy 341.729104 -275.421494) (xy 341.67949 -275.402022) (xy 341.633332 -275.375373)
			(xy 341.591661 -275.342142) (xy 341.555409 -275.303071) (xy 341.525385 -275.259034) (xy 341.502259 -275.211013)
			(xy 341.486549 -275.160083) (xy 341.478606 -275.107379) (xy 341.250026 -275.107379) (xy 341.242083 -275.160083)
			(xy 341.226373 -275.211013) (xy 341.203247 -275.259034) (xy 341.173223 -275.303071) (xy 341.136971 -275.342142)
			(xy 341.0953 -275.375373) (xy 341.049142 -275.402022) (xy 340.999528 -275.421494) (xy 340.947566 -275.433354)
			(xy 340.894416 -275.437338) (xy 340.841266 -275.433354) (xy 340.789304 -275.421494) (xy 340.73969 -275.402022)
			(xy 340.693532 -275.375373) (xy 340.651861 -275.342142) (xy 340.615609 -275.303071) (xy 340.585585 -275.259034)
			(xy 340.562459 -275.211013) (xy 340.546749 -275.160083) (xy 340.538806 -275.107379) (xy 340.309972 -275.107379)
			(xy 340.302029 -275.160083) (xy 340.286319 -275.211013) (xy 340.263193 -275.259034) (xy 340.233169 -275.303071)
			(xy 340.196917 -275.342142) (xy 340.155246 -275.375373) (xy 340.109088 -275.402022) (xy 340.059474 -275.421494)
			(xy 340.007512 -275.433354) (xy 339.954362 -275.437338) (xy 339.901212 -275.433354) (xy 339.84925 -275.421494)
			(xy 339.799636 -275.402022) (xy 339.753478 -275.375373) (xy 339.711807 -275.342142) (xy 339.675555 -275.303071)
			(xy 339.645531 -275.259034) (xy 339.622405 -275.211013) (xy 339.606695 -275.160083) (xy 339.598752 -275.107379)
			(xy 339.370426 -275.107379) (xy 339.362483 -275.160083) (xy 339.346773 -275.211013) (xy 339.323647 -275.259034)
			(xy 339.293623 -275.303071) (xy 339.257371 -275.342142) (xy 339.2157 -275.375373) (xy 339.169542 -275.402022)
			(xy 339.119928 -275.421494) (xy 339.067966 -275.433354) (xy 339.014816 -275.437338) (xy 338.961666 -275.433354)
			(xy 338.909704 -275.421494) (xy 338.86009 -275.402022) (xy 338.813932 -275.375373) (xy 338.772261 -275.342142)
			(xy 338.736009 -275.303071) (xy 338.705985 -275.259034) (xy 338.682859 -275.211013) (xy 338.667149 -275.160083)
			(xy 338.659206 -275.107379) (xy 338.430372 -275.107379) (xy 338.422429 -275.160083) (xy 338.406719 -275.211013)
			(xy 338.383593 -275.259034) (xy 338.353569 -275.303071) (xy 338.317317 -275.342142) (xy 338.275646 -275.375373)
			(xy 338.229488 -275.402022) (xy 338.179874 -275.421494) (xy 338.127912 -275.433354) (xy 338.074762 -275.437338)
			(xy 338.021612 -275.433354) (xy 337.96965 -275.421494) (xy 337.920036 -275.402022) (xy 337.873878 -275.375373)
			(xy 337.832207 -275.342142) (xy 337.795955 -275.303071) (xy 337.765931 -275.259034) (xy 337.742805 -275.211013)
			(xy 337.727095 -275.160083) (xy 337.719152 -275.107379) (xy 337.490572 -275.107379) (xy 337.482629 -275.160083)
			(xy 337.466919 -275.211013) (xy 337.443793 -275.259034) (xy 337.413769 -275.303071) (xy 337.377517 -275.342142)
			(xy 337.335846 -275.375373) (xy 337.289688 -275.402022) (xy 337.240074 -275.421494) (xy 337.188112 -275.433354)
			(xy 337.134962 -275.437338) (xy 337.081812 -275.433354) (xy 337.02985 -275.421494) (xy 336.980236 -275.402022)
			(xy 336.934078 -275.375373) (xy 336.892407 -275.342142) (xy 336.856155 -275.303071) (xy 336.826131 -275.259034)
			(xy 336.803005 -275.211013) (xy 336.787295 -275.160083) (xy 336.779352 -275.107379) (xy 336.550772 -275.107379)
			(xy 336.542829 -275.160083) (xy 336.527119 -275.211013) (xy 336.503993 -275.259034) (xy 336.473969 -275.303071)
			(xy 336.437717 -275.342142) (xy 336.396046 -275.375373) (xy 336.349888 -275.402022) (xy 336.300274 -275.421494)
			(xy 336.248312 -275.433354) (xy 336.195162 -275.437338) (xy 336.142012 -275.433354) (xy 336.09005 -275.421494)
			(xy 336.040436 -275.402022) (xy 335.994278 -275.375373) (xy 335.952607 -275.342142) (xy 335.916355 -275.303071)
			(xy 335.886331 -275.259034) (xy 335.863205 -275.211013) (xy 335.847495 -275.160083) (xy 335.839552 -275.107379)
			(xy 335.609793 -275.107379) (xy 335.60611 -275.143606) (xy 335.592537 -275.196032) (xy 335.571182 -275.245798)
			(xy 335.542537 -275.291757) (xy 335.507263 -275.332848) (xy 335.466174 -275.368124) (xy 335.420217 -275.396772)
			(xy 335.370453 -275.41813) (xy 335.318027 -275.431706) (xy 335.264151 -275.437187) (xy 335.210066 -275.434447)
			(xy 335.157019 -275.423549) (xy 335.106234 -275.404743) (xy 335.058883 -275.378465) (xy 335.016057 -275.345319)
			(xy 334.978743 -275.306071) (xy 334.947803 -275.261625) (xy 334.92395 -275.213006) (xy 334.907735 -275.161337)
			(xy 334.89953 -275.107807) (xy 334.899 -275.08073) (xy 334.899 -275.073618) (xy 334.898765 -275.058501)
			(xy 334.890524 -275.029428) (xy 334.874133 -275.00404) (xy 334.85103 -274.984563) (xy 334.823236 -274.972701)
			(xy 334.793189 -274.969495) (xy 334.763518 -274.975226) (xy 334.736825 -274.98939) (xy 334.725772 -274.999704)
			(xy 334.65897 -275.066506) (xy 334.658716 -275.086826) (xy 334.657764 -275.113193) (xy 334.648767 -275.165179)
			(xy 334.631927 -275.215178) (xy 334.607639 -275.262014) (xy 334.576475 -275.304585) (xy 334.539168 -275.34189)
			(xy 334.496595 -275.373051) (xy 334.449757 -275.397336) (xy 334.399757 -275.414173) (xy 334.34777 -275.423166)
			(xy 334.321404 -275.424138) (xy 334.301084 -275.424392) (xy 333.804027 -275.921449) (xy 335.369398 -275.921449)
			(xy 335.369398 -275.868151) (xy 335.377341 -275.815447) (xy 335.393051 -275.764517) (xy 335.416177 -275.716496)
			(xy 335.446201 -275.672459) (xy 335.482453 -275.633388) (xy 335.524124 -275.600157) (xy 335.570282 -275.573508)
			(xy 335.619896 -275.554036) (xy 335.671858 -275.542176) (xy 335.725008 -275.538193) (xy 335.778158 -275.542176)
			(xy 335.83012 -275.554036) (xy 335.879734 -275.573508) (xy 335.925892 -275.600157) (xy 335.967563 -275.633388)
			(xy 336.003815 -275.672459) (xy 336.033839 -275.716496) (xy 336.056965 -275.764517) (xy 336.072675 -275.815447)
			(xy 336.080618 -275.868151) (xy 336.081116 -275.8948) (xy 336.080618 -275.921449) (xy 336.309452 -275.921449)
			(xy 336.309452 -275.868151) (xy 336.317395 -275.815447) (xy 336.333105 -275.764517) (xy 336.356231 -275.716496)
			(xy 336.386255 -275.672459) (xy 336.422507 -275.633388) (xy 336.464178 -275.600157) (xy 336.510336 -275.573508)
			(xy 336.55995 -275.554036) (xy 336.611912 -275.542176) (xy 336.665062 -275.538193) (xy 336.718212 -275.542176)
			(xy 336.770174 -275.554036) (xy 336.819788 -275.573508) (xy 336.865946 -275.600157) (xy 336.907617 -275.633388)
			(xy 336.943869 -275.672459) (xy 336.973893 -275.716496) (xy 336.997019 -275.764517) (xy 337.012729 -275.815447)
			(xy 337.020672 -275.868151) (xy 337.02117 -275.8948) (xy 337.020672 -275.921449) (xy 337.249252 -275.921449)
			(xy 337.249252 -275.868151) (xy 337.257195 -275.815447) (xy 337.272905 -275.764517) (xy 337.296031 -275.716496)
			(xy 337.326055 -275.672459) (xy 337.362307 -275.633388) (xy 337.403978 -275.600157) (xy 337.450136 -275.573508)
			(xy 337.49975 -275.554036) (xy 337.551712 -275.542176) (xy 337.604862 -275.538193) (xy 337.658012 -275.542176)
			(xy 337.709974 -275.554036) (xy 337.759588 -275.573508) (xy 337.805746 -275.600157) (xy 337.847417 -275.633388)
			(xy 337.883669 -275.672459) (xy 337.913693 -275.716496) (xy 337.936819 -275.764517) (xy 337.952529 -275.815447)
			(xy 337.960472 -275.868151) (xy 337.96097 -275.8948) (xy 337.960472 -275.921449) (xy 338.189052 -275.921449)
			(xy 338.189052 -275.868151) (xy 338.196995 -275.815447) (xy 338.212705 -275.764517) (xy 338.235831 -275.716496)
			(xy 338.265855 -275.672459) (xy 338.302107 -275.633388) (xy 338.343778 -275.600157) (xy 338.389936 -275.573508)
			(xy 338.43955 -275.554036) (xy 338.491512 -275.542176) (xy 338.544662 -275.538193) (xy 338.597812 -275.542176)
			(xy 338.649774 -275.554036) (xy 338.699388 -275.573508) (xy 338.745546 -275.600157) (xy 338.787217 -275.633388)
			(xy 338.823469 -275.672459) (xy 338.853493 -275.716496) (xy 338.876619 -275.764517) (xy 338.892329 -275.815447)
			(xy 338.900272 -275.868151) (xy 338.90077 -275.8948) (xy 338.900272 -275.921449) (xy 339.128852 -275.921449)
			(xy 339.128852 -275.868151) (xy 339.136795 -275.815447) (xy 339.152505 -275.764517) (xy 339.175631 -275.716496)
			(xy 339.205655 -275.672459) (xy 339.241907 -275.633388) (xy 339.283578 -275.600157) (xy 339.329736 -275.573508)
			(xy 339.37935 -275.554036) (xy 339.431312 -275.542176) (xy 339.484462 -275.538193) (xy 339.537612 -275.542176)
			(xy 339.589574 -275.554036) (xy 339.639188 -275.573508) (xy 339.685346 -275.600157) (xy 339.727017 -275.633388)
			(xy 339.763269 -275.672459) (xy 339.793293 -275.716496) (xy 339.816419 -275.764517) (xy 339.832129 -275.815447)
			(xy 339.840072 -275.868151) (xy 339.84057 -275.8948) (xy 339.840072 -275.921449) (xy 340.068652 -275.921449)
			(xy 340.068652 -275.868151) (xy 340.076595 -275.815447) (xy 340.092305 -275.764517) (xy 340.115431 -275.716496)
			(xy 340.145455 -275.672459) (xy 340.181707 -275.633388) (xy 340.223378 -275.600157) (xy 340.269536 -275.573508)
			(xy 340.31915 -275.554036) (xy 340.371112 -275.542176) (xy 340.424262 -275.538193) (xy 340.477412 -275.542176)
			(xy 340.529374 -275.554036) (xy 340.578988 -275.573508) (xy 340.625146 -275.600157) (xy 340.666817 -275.633388)
			(xy 340.703069 -275.672459) (xy 340.733093 -275.716496) (xy 340.756219 -275.764517) (xy 340.771929 -275.815447)
			(xy 340.779872 -275.868151) (xy 340.78037 -275.8948) (xy 340.779872 -275.921449) (xy 341.008452 -275.921449)
			(xy 341.008452 -275.868151) (xy 341.016395 -275.815447) (xy 341.032105 -275.764517) (xy 341.055231 -275.716496)
			(xy 341.085255 -275.672459) (xy 341.121507 -275.633388) (xy 341.163178 -275.600157) (xy 341.209336 -275.573508)
			(xy 341.25895 -275.554036) (xy 341.310912 -275.542176) (xy 341.364062 -275.538193) (xy 341.417212 -275.542176)
			(xy 341.469174 -275.554036) (xy 341.518788 -275.573508) (xy 341.564946 -275.600157) (xy 341.606617 -275.633388)
			(xy 341.642869 -275.672459) (xy 341.672893 -275.716496) (xy 341.696019 -275.764517) (xy 341.711729 -275.815447)
			(xy 341.719672 -275.868151) (xy 341.72017 -275.8948) (xy 341.719672 -275.921449) (xy 341.948506 -275.921449)
			(xy 341.948506 -275.868151) (xy 341.956449 -275.815447) (xy 341.972159 -275.764517) (xy 341.995285 -275.716496)
			(xy 342.025309 -275.672459) (xy 342.061561 -275.633388) (xy 342.103232 -275.600157) (xy 342.14939 -275.573508)
			(xy 342.199004 -275.554036) (xy 342.250966 -275.542176) (xy 342.304116 -275.538193) (xy 342.357266 -275.542176)
			(xy 342.409228 -275.554036) (xy 342.458842 -275.573508) (xy 342.505 -275.600157) (xy 342.546671 -275.633388)
			(xy 342.582923 -275.672459) (xy 342.612947 -275.716496) (xy 342.636073 -275.764517) (xy 342.651783 -275.815447)
			(xy 342.659726 -275.868151) (xy 342.660224 -275.8948) (xy 342.659726 -275.921449) (xy 342.888052 -275.921449)
			(xy 342.888052 -275.868151) (xy 342.895995 -275.815447) (xy 342.911705 -275.764517) (xy 342.934831 -275.716496)
			(xy 342.964855 -275.672459) (xy 343.001107 -275.633388) (xy 343.042778 -275.600157) (xy 343.088936 -275.573508)
			(xy 343.13855 -275.554036) (xy 343.190512 -275.542176) (xy 343.243662 -275.538193) (xy 343.296812 -275.542176)
			(xy 343.348774 -275.554036) (xy 343.398388 -275.573508) (xy 343.444546 -275.600157) (xy 343.486217 -275.633388)
			(xy 343.522469 -275.672459) (xy 343.552493 -275.716496) (xy 343.575619 -275.764517) (xy 343.591329 -275.815447)
			(xy 343.599272 -275.868151) (xy 343.59977 -275.8948) (xy 343.599272 -275.921449) (xy 343.827852 -275.921449)
			(xy 343.827852 -275.868151) (xy 343.835795 -275.815447) (xy 343.851505 -275.764517) (xy 343.874631 -275.716496)
			(xy 343.904655 -275.672459) (xy 343.940907 -275.633388) (xy 343.982578 -275.600157) (xy 344.028736 -275.573508)
			(xy 344.07835 -275.554036) (xy 344.130312 -275.542176) (xy 344.183462 -275.538193) (xy 344.236612 -275.542176)
			(xy 344.288574 -275.554036) (xy 344.338188 -275.573508) (xy 344.384346 -275.600157) (xy 344.426017 -275.633388)
			(xy 344.462269 -275.672459) (xy 344.492293 -275.716496) (xy 344.515419 -275.764517) (xy 344.531129 -275.815447)
			(xy 344.539072 -275.868151) (xy 344.53957 -275.8948) (xy 344.539072 -275.921449) (xy 344.767652 -275.921449)
			(xy 344.767652 -275.868151) (xy 344.775595 -275.815447) (xy 344.791305 -275.764517) (xy 344.814431 -275.716496)
			(xy 344.844455 -275.672459) (xy 344.880707 -275.633388) (xy 344.922378 -275.600157) (xy 344.968536 -275.573508)
			(xy 345.01815 -275.554036) (xy 345.070112 -275.542176) (xy 345.123262 -275.538193) (xy 345.176412 -275.542176)
			(xy 345.228374 -275.554036) (xy 345.277988 -275.573508) (xy 345.324146 -275.600157) (xy 345.365817 -275.633388)
			(xy 345.402069 -275.672459) (xy 345.432093 -275.716496) (xy 345.455219 -275.764517) (xy 345.470929 -275.815447)
			(xy 345.478872 -275.868151) (xy 345.47937 -275.8948) (xy 345.478872 -275.921449) (xy 345.707452 -275.921449)
			(xy 345.707452 -275.868151) (xy 345.715395 -275.815447) (xy 345.731105 -275.764517) (xy 345.754231 -275.716496)
			(xy 345.784255 -275.672459) (xy 345.820507 -275.633388) (xy 345.862178 -275.600157) (xy 345.908336 -275.573508)
			(xy 345.95795 -275.554036) (xy 346.009912 -275.542176) (xy 346.063062 -275.538193) (xy 346.116212 -275.542176)
			(xy 346.168174 -275.554036) (xy 346.217788 -275.573508) (xy 346.263946 -275.600157) (xy 346.305617 -275.633388)
			(xy 346.341869 -275.672459) (xy 346.371893 -275.716496) (xy 346.395019 -275.764517) (xy 346.410729 -275.815447)
			(xy 346.418672 -275.868151) (xy 346.41917 -275.8948) (xy 346.418672 -275.921449) (xy 346.647252 -275.921449)
			(xy 346.647252 -275.868151) (xy 346.655195 -275.815447) (xy 346.670905 -275.764517) (xy 346.694031 -275.716496)
			(xy 346.724055 -275.672459) (xy 346.760307 -275.633388) (xy 346.801978 -275.600157) (xy 346.848136 -275.573508)
			(xy 346.89775 -275.554036) (xy 346.949712 -275.542176) (xy 347.002862 -275.538193) (xy 347.056012 -275.542176)
			(xy 347.107974 -275.554036) (xy 347.157588 -275.573508) (xy 347.203746 -275.600157) (xy 347.245417 -275.633388)
			(xy 347.281669 -275.672459) (xy 347.311693 -275.716496) (xy 347.334819 -275.764517) (xy 347.350529 -275.815447)
			(xy 347.358472 -275.868151) (xy 347.35897 -275.8948) (xy 347.358472 -275.921449) (xy 347.587052 -275.921449)
			(xy 347.587052 -275.868151) (xy 347.594995 -275.815447) (xy 347.610705 -275.764517) (xy 347.633831 -275.716496)
			(xy 347.663855 -275.672459) (xy 347.700107 -275.633388) (xy 347.741778 -275.600157) (xy 347.787936 -275.573508)
			(xy 347.83755 -275.554036) (xy 347.889512 -275.542176) (xy 347.942662 -275.538193) (xy 347.995812 -275.542176)
			(xy 348.047774 -275.554036) (xy 348.097388 -275.573508) (xy 348.143546 -275.600157) (xy 348.185217 -275.633388)
			(xy 348.221469 -275.672459) (xy 348.251493 -275.716496) (xy 348.274619 -275.764517) (xy 348.290329 -275.815447)
			(xy 348.298272 -275.868151) (xy 348.29877 -275.8948) (xy 348.298272 -275.921449) (xy 348.527106 -275.921449)
			(xy 348.527106 -275.868151) (xy 348.535049 -275.815447) (xy 348.550759 -275.764517) (xy 348.573885 -275.716496)
			(xy 348.603909 -275.672459) (xy 348.640161 -275.633388) (xy 348.681832 -275.600157) (xy 348.72799 -275.573508)
			(xy 348.777604 -275.554036) (xy 348.829566 -275.542176) (xy 348.882716 -275.538193) (xy 348.935866 -275.542176)
			(xy 348.987828 -275.554036) (xy 349.037442 -275.573508) (xy 349.0836 -275.600157) (xy 349.125271 -275.633388)
			(xy 349.161523 -275.672459) (xy 349.191547 -275.716496) (xy 349.214673 -275.764517) (xy 349.230383 -275.815447)
			(xy 349.238326 -275.868151) (xy 349.238824 -275.8948) (xy 349.238326 -275.921449) (xy 349.466652 -275.921449)
			(xy 349.466652 -275.868151) (xy 349.474595 -275.815447) (xy 349.490305 -275.764517) (xy 349.513431 -275.716496)
			(xy 349.543455 -275.672459) (xy 349.579707 -275.633388) (xy 349.621378 -275.600157) (xy 349.667536 -275.573508)
			(xy 349.71715 -275.554036) (xy 349.769112 -275.542176) (xy 349.822262 -275.538193) (xy 349.875412 -275.542176)
			(xy 349.927374 -275.554036) (xy 349.976988 -275.573508) (xy 350.023146 -275.600157) (xy 350.064817 -275.633388)
			(xy 350.101069 -275.672459) (xy 350.131093 -275.716496) (xy 350.154219 -275.764517) (xy 350.169929 -275.815447)
			(xy 350.177872 -275.868151) (xy 350.17837 -275.8948) (xy 350.177872 -275.921449) (xy 350.169929 -275.974153)
			(xy 350.154219 -276.025083) (xy 350.131093 -276.073104) (xy 350.101069 -276.117141) (xy 350.064817 -276.156212)
			(xy 350.023146 -276.189443) (xy 349.976988 -276.216092) (xy 349.927374 -276.235564) (xy 349.875412 -276.247424)
			(xy 349.822262 -276.251408) (xy 349.769112 -276.247424) (xy 349.71715 -276.235564) (xy 349.667536 -276.216092)
			(xy 349.621378 -276.189443) (xy 349.579707 -276.156212) (xy 349.543455 -276.117141) (xy 349.513431 -276.073104)
			(xy 349.490305 -276.025083) (xy 349.474595 -275.974153) (xy 349.466652 -275.921449) (xy 349.238326 -275.921449)
			(xy 349.230383 -275.974153) (xy 349.214673 -276.025083) (xy 349.191547 -276.073104) (xy 349.161523 -276.117141)
			(xy 349.125271 -276.156212) (xy 349.0836 -276.189443) (xy 349.037442 -276.216092) (xy 348.987828 -276.235564)
			(xy 348.935866 -276.247424) (xy 348.882716 -276.251408) (xy 348.829566 -276.247424) (xy 348.777604 -276.235564)
			(xy 348.72799 -276.216092) (xy 348.681832 -276.189443) (xy 348.640161 -276.156212) (xy 348.603909 -276.117141)
			(xy 348.573885 -276.073104) (xy 348.550759 -276.025083) (xy 348.535049 -275.974153) (xy 348.527106 -275.921449)
			(xy 348.298272 -275.921449) (xy 348.290329 -275.974153) (xy 348.274619 -276.025083) (xy 348.251493 -276.073104)
			(xy 348.221469 -276.117141) (xy 348.185217 -276.156212) (xy 348.143546 -276.189443) (xy 348.097388 -276.216092)
			(xy 348.047774 -276.235564) (xy 347.995812 -276.247424) (xy 347.942662 -276.251408) (xy 347.889512 -276.247424)
			(xy 347.83755 -276.235564) (xy 347.787936 -276.216092) (xy 347.741778 -276.189443) (xy 347.700107 -276.156212)
			(xy 347.663855 -276.117141) (xy 347.633831 -276.073104) (xy 347.610705 -276.025083) (xy 347.594995 -275.974153)
			(xy 347.587052 -275.921449) (xy 347.358472 -275.921449) (xy 347.350529 -275.974153) (xy 347.334819 -276.025083)
			(xy 347.311693 -276.073104) (xy 347.281669 -276.117141) (xy 347.245417 -276.156212) (xy 347.203746 -276.189443)
			(xy 347.157588 -276.216092) (xy 347.107974 -276.235564) (xy 347.056012 -276.247424) (xy 347.002862 -276.251408)
			(xy 346.949712 -276.247424) (xy 346.89775 -276.235564) (xy 346.848136 -276.216092) (xy 346.801978 -276.189443)
			(xy 346.760307 -276.156212) (xy 346.724055 -276.117141) (xy 346.694031 -276.073104) (xy 346.670905 -276.025083)
			(xy 346.655195 -275.974153) (xy 346.647252 -275.921449) (xy 346.418672 -275.921449) (xy 346.410729 -275.974153)
			(xy 346.395019 -276.025083) (xy 346.371893 -276.073104) (xy 346.341869 -276.117141) (xy 346.305617 -276.156212)
			(xy 346.263946 -276.189443) (xy 346.217788 -276.216092) (xy 346.168174 -276.235564) (xy 346.116212 -276.247424)
			(xy 346.063062 -276.251408) (xy 346.009912 -276.247424) (xy 345.95795 -276.235564) (xy 345.908336 -276.216092)
			(xy 345.862178 -276.189443) (xy 345.820507 -276.156212) (xy 345.784255 -276.117141) (xy 345.754231 -276.073104)
			(xy 345.731105 -276.025083) (xy 345.715395 -275.974153) (xy 345.707452 -275.921449) (xy 345.478872 -275.921449)
			(xy 345.470929 -275.974153) (xy 345.455219 -276.025083) (xy 345.432093 -276.073104) (xy 345.402069 -276.117141)
			(xy 345.365817 -276.156212) (xy 345.324146 -276.189443) (xy 345.277988 -276.216092) (xy 345.228374 -276.235564)
			(xy 345.176412 -276.247424) (xy 345.123262 -276.251408) (xy 345.070112 -276.247424) (xy 345.01815 -276.235564)
			(xy 344.968536 -276.216092) (xy 344.922378 -276.189443) (xy 344.880707 -276.156212) (xy 344.844455 -276.117141)
			(xy 344.814431 -276.073104) (xy 344.791305 -276.025083) (xy 344.775595 -275.974153) (xy 344.767652 -275.921449)
			(xy 344.539072 -275.921449) (xy 344.531129 -275.974153) (xy 344.515419 -276.025083) (xy 344.492293 -276.073104)
			(xy 344.462269 -276.117141) (xy 344.426017 -276.156212) (xy 344.384346 -276.189443) (xy 344.338188 -276.216092)
			(xy 344.288574 -276.235564) (xy 344.236612 -276.247424) (xy 344.183462 -276.251408) (xy 344.130312 -276.247424)
			(xy 344.07835 -276.235564) (xy 344.028736 -276.216092) (xy 343.982578 -276.189443) (xy 343.940907 -276.156212)
			(xy 343.904655 -276.117141) (xy 343.874631 -276.073104) (xy 343.851505 -276.025083) (xy 343.835795 -275.974153)
			(xy 343.827852 -275.921449) (xy 343.599272 -275.921449) (xy 343.591329 -275.974153) (xy 343.575619 -276.025083)
			(xy 343.552493 -276.073104) (xy 343.522469 -276.117141) (xy 343.486217 -276.156212) (xy 343.444546 -276.189443)
			(xy 343.398388 -276.216092) (xy 343.348774 -276.235564) (xy 343.296812 -276.247424) (xy 343.243662 -276.251408)
			(xy 343.190512 -276.247424) (xy 343.13855 -276.235564) (xy 343.088936 -276.216092) (xy 343.042778 -276.189443)
			(xy 343.001107 -276.156212) (xy 342.964855 -276.117141) (xy 342.934831 -276.073104) (xy 342.911705 -276.025083)
			(xy 342.895995 -275.974153) (xy 342.888052 -275.921449) (xy 342.659726 -275.921449) (xy 342.651783 -275.974153)
			(xy 342.636073 -276.025083) (xy 342.612947 -276.073104) (xy 342.582923 -276.117141) (xy 342.546671 -276.156212)
			(xy 342.505 -276.189443) (xy 342.458842 -276.216092) (xy 342.409228 -276.235564) (xy 342.357266 -276.247424)
			(xy 342.304116 -276.251408) (xy 342.250966 -276.247424) (xy 342.199004 -276.235564) (xy 342.14939 -276.216092)
			(xy 342.103232 -276.189443) (xy 342.061561 -276.156212) (xy 342.025309 -276.117141) (xy 341.995285 -276.073104)
			(xy 341.972159 -276.025083) (xy 341.956449 -275.974153) (xy 341.948506 -275.921449) (xy 341.719672 -275.921449)
			(xy 341.711729 -275.974153) (xy 341.696019 -276.025083) (xy 341.672893 -276.073104) (xy 341.642869 -276.117141)
			(xy 341.606617 -276.156212) (xy 341.564946 -276.189443) (xy 341.518788 -276.216092) (xy 341.469174 -276.235564)
			(xy 341.417212 -276.247424) (xy 341.364062 -276.251408) (xy 341.310912 -276.247424) (xy 341.25895 -276.235564)
			(xy 341.209336 -276.216092) (xy 341.163178 -276.189443) (xy 341.121507 -276.156212) (xy 341.085255 -276.117141)
			(xy 341.055231 -276.073104) (xy 341.032105 -276.025083) (xy 341.016395 -275.974153) (xy 341.008452 -275.921449)
			(xy 340.779872 -275.921449) (xy 340.771929 -275.974153) (xy 340.756219 -276.025083) (xy 340.733093 -276.073104)
			(xy 340.703069 -276.117141) (xy 340.666817 -276.156212) (xy 340.625146 -276.189443) (xy 340.578988 -276.216092)
			(xy 340.529374 -276.235564) (xy 340.477412 -276.247424) (xy 340.424262 -276.251408) (xy 340.371112 -276.247424)
			(xy 340.31915 -276.235564) (xy 340.269536 -276.216092) (xy 340.223378 -276.189443) (xy 340.181707 -276.156212)
			(xy 340.145455 -276.117141) (xy 340.115431 -276.073104) (xy 340.092305 -276.025083) (xy 340.076595 -275.974153)
			(xy 340.068652 -275.921449) (xy 339.840072 -275.921449) (xy 339.832129 -275.974153) (xy 339.816419 -276.025083)
			(xy 339.793293 -276.073104) (xy 339.763269 -276.117141) (xy 339.727017 -276.156212) (xy 339.685346 -276.189443)
			(xy 339.639188 -276.216092) (xy 339.589574 -276.235564) (xy 339.537612 -276.247424) (xy 339.484462 -276.251408)
			(xy 339.431312 -276.247424) (xy 339.37935 -276.235564) (xy 339.329736 -276.216092) (xy 339.283578 -276.189443)
			(xy 339.241907 -276.156212) (xy 339.205655 -276.117141) (xy 339.175631 -276.073104) (xy 339.152505 -276.025083)
			(xy 339.136795 -275.974153) (xy 339.128852 -275.921449) (xy 338.900272 -275.921449) (xy 338.892329 -275.974153)
			(xy 338.876619 -276.025083) (xy 338.853493 -276.073104) (xy 338.823469 -276.117141) (xy 338.787217 -276.156212)
			(xy 338.745546 -276.189443) (xy 338.699388 -276.216092) (xy 338.649774 -276.235564) (xy 338.597812 -276.247424)
			(xy 338.544662 -276.251408) (xy 338.491512 -276.247424) (xy 338.43955 -276.235564) (xy 338.389936 -276.216092)
			(xy 338.343778 -276.189443) (xy 338.302107 -276.156212) (xy 338.265855 -276.117141) (xy 338.235831 -276.073104)
			(xy 338.212705 -276.025083) (xy 338.196995 -275.974153) (xy 338.189052 -275.921449) (xy 337.960472 -275.921449)
			(xy 337.952529 -275.974153) (xy 337.936819 -276.025083) (xy 337.913693 -276.073104) (xy 337.883669 -276.117141)
			(xy 337.847417 -276.156212) (xy 337.805746 -276.189443) (xy 337.759588 -276.216092) (xy 337.709974 -276.235564)
			(xy 337.658012 -276.247424) (xy 337.604862 -276.251408) (xy 337.551712 -276.247424) (xy 337.49975 -276.235564)
			(xy 337.450136 -276.216092) (xy 337.403978 -276.189443) (xy 337.362307 -276.156212) (xy 337.326055 -276.117141)
			(xy 337.296031 -276.073104) (xy 337.272905 -276.025083) (xy 337.257195 -275.974153) (xy 337.249252 -275.921449)
			(xy 337.020672 -275.921449) (xy 337.012729 -275.974153) (xy 336.997019 -276.025083) (xy 336.973893 -276.073104)
			(xy 336.943869 -276.117141) (xy 336.907617 -276.156212) (xy 336.865946 -276.189443) (xy 336.819788 -276.216092)
			(xy 336.770174 -276.235564) (xy 336.718212 -276.247424) (xy 336.665062 -276.251408) (xy 336.611912 -276.247424)
			(xy 336.55995 -276.235564) (xy 336.510336 -276.216092) (xy 336.464178 -276.189443) (xy 336.422507 -276.156212)
			(xy 336.386255 -276.117141) (xy 336.356231 -276.073104) (xy 336.333105 -276.025083) (xy 336.317395 -275.974153)
			(xy 336.309452 -275.921449) (xy 336.080618 -275.921449) (xy 336.072675 -275.974153) (xy 336.056965 -276.025083)
			(xy 336.033839 -276.073104) (xy 336.003815 -276.117141) (xy 335.967563 -276.156212) (xy 335.925892 -276.189443)
			(xy 335.879734 -276.216092) (xy 335.83012 -276.235564) (xy 335.778158 -276.247424) (xy 335.725008 -276.251408)
			(xy 335.671858 -276.247424) (xy 335.619896 -276.235564) (xy 335.570282 -276.216092) (xy 335.524124 -276.189443)
			(xy 335.482453 -276.156212) (xy 335.446201 -276.117141) (xy 335.416177 -276.073104) (xy 335.393051 -276.025083)
			(xy 335.377341 -275.974153) (xy 335.369398 -275.921449) (xy 333.804027 -275.921449) (xy 333.466948 -276.258528)
			(xy 333.466948 -276.735265) (xy 335.839552 -276.735265) (xy 335.839552 -276.681967) (xy 335.847495 -276.629263)
			(xy 335.863205 -276.578333) (xy 335.886331 -276.530312) (xy 335.916355 -276.486275) (xy 335.952607 -276.447204)
			(xy 335.994278 -276.413973) (xy 336.040436 -276.387324) (xy 336.09005 -276.367852) (xy 336.142012 -276.355992)
			(xy 336.195162 -276.352009) (xy 336.248312 -276.355992) (xy 336.300274 -276.367852) (xy 336.349888 -276.387324)
			(xy 336.396046 -276.413973) (xy 336.437717 -276.447204) (xy 336.473969 -276.486275) (xy 336.503993 -276.530312)
			(xy 336.527119 -276.578333) (xy 336.542829 -276.629263) (xy 336.550772 -276.681967) (xy 336.55127 -276.708616)
			(xy 336.550772 -276.735265) (xy 336.779352 -276.735265) (xy 336.779352 -276.681967) (xy 336.787295 -276.629263)
			(xy 336.803005 -276.578333) (xy 336.826131 -276.530312) (xy 336.856155 -276.486275) (xy 336.892407 -276.447204)
			(xy 336.934078 -276.413973) (xy 336.980236 -276.387324) (xy 337.02985 -276.367852) (xy 337.081812 -276.355992)
			(xy 337.134962 -276.352009) (xy 337.188112 -276.355992) (xy 337.240074 -276.367852) (xy 337.289688 -276.387324)
			(xy 337.335846 -276.413973) (xy 337.377517 -276.447204) (xy 337.413769 -276.486275) (xy 337.443793 -276.530312)
			(xy 337.466919 -276.578333) (xy 337.482629 -276.629263) (xy 337.490572 -276.681967) (xy 337.49107 -276.708616)
			(xy 337.490572 -276.735265) (xy 337.719152 -276.735265) (xy 337.719152 -276.681967) (xy 337.727095 -276.629263)
			(xy 337.742805 -276.578333) (xy 337.765931 -276.530312) (xy 337.795955 -276.486275) (xy 337.832207 -276.447204)
			(xy 337.873878 -276.413973) (xy 337.920036 -276.387324) (xy 337.96965 -276.367852) (xy 338.021612 -276.355992)
			(xy 338.074762 -276.352009) (xy 338.127912 -276.355992) (xy 338.179874 -276.367852) (xy 338.229488 -276.387324)
			(xy 338.275646 -276.413973) (xy 338.317317 -276.447204) (xy 338.353569 -276.486275) (xy 338.383593 -276.530312)
			(xy 338.406719 -276.578333) (xy 338.422429 -276.629263) (xy 338.430372 -276.681967) (xy 338.43087 -276.708616)
			(xy 338.430372 -276.735265) (xy 338.658952 -276.735265) (xy 338.658952 -276.681967) (xy 338.666895 -276.629263)
			(xy 338.682605 -276.578333) (xy 338.705731 -276.530312) (xy 338.735755 -276.486275) (xy 338.772007 -276.447204)
			(xy 338.813678 -276.413973) (xy 338.859836 -276.387324) (xy 338.90945 -276.367852) (xy 338.961412 -276.355992)
			(xy 339.014562 -276.352009) (xy 339.067712 -276.355992) (xy 339.119674 -276.367852) (xy 339.169288 -276.387324)
			(xy 339.215446 -276.413973) (xy 339.257117 -276.447204) (xy 339.293369 -276.486275) (xy 339.323393 -276.530312)
			(xy 339.346519 -276.578333) (xy 339.362229 -276.629263) (xy 339.370172 -276.681967) (xy 339.37067 -276.708616)
			(xy 339.370172 -276.735265) (xy 339.599006 -276.735265) (xy 339.599006 -276.681967) (xy 339.606949 -276.629263)
			(xy 339.622659 -276.578333) (xy 339.645785 -276.530312) (xy 339.675809 -276.486275) (xy 339.712061 -276.447204)
			(xy 339.753732 -276.413973) (xy 339.79989 -276.387324) (xy 339.849504 -276.367852) (xy 339.901466 -276.355992)
			(xy 339.954616 -276.352009) (xy 340.007766 -276.355992) (xy 340.059728 -276.367852) (xy 340.109342 -276.387324)
			(xy 340.1555 -276.413973) (xy 340.197171 -276.447204) (xy 340.233423 -276.486275) (xy 340.263447 -276.530312)
			(xy 340.286573 -276.578333) (xy 340.302283 -276.629263) (xy 340.310226 -276.681967) (xy 340.310724 -276.708616)
			(xy 340.310226 -276.735265) (xy 340.538806 -276.735265) (xy 340.538806 -276.681967) (xy 340.546749 -276.629263)
			(xy 340.562459 -276.578333) (xy 340.585585 -276.530312) (xy 340.615609 -276.486275) (xy 340.651861 -276.447204)
			(xy 340.693532 -276.413973) (xy 340.73969 -276.387324) (xy 340.789304 -276.367852) (xy 340.841266 -276.355992)
			(xy 340.894416 -276.352009) (xy 340.947566 -276.355992) (xy 340.999528 -276.367852) (xy 341.049142 -276.387324)
			(xy 341.0953 -276.413973) (xy 341.136971 -276.447204) (xy 341.173223 -276.486275) (xy 341.203247 -276.530312)
			(xy 341.226373 -276.578333) (xy 341.242083 -276.629263) (xy 341.250026 -276.681967) (xy 341.250524 -276.708616)
			(xy 341.250026 -276.735265) (xy 341.478606 -276.735265) (xy 341.478606 -276.681967) (xy 341.486549 -276.629263)
			(xy 341.502259 -276.578333) (xy 341.525385 -276.530312) (xy 341.555409 -276.486275) (xy 341.591661 -276.447204)
			(xy 341.633332 -276.413973) (xy 341.67949 -276.387324) (xy 341.729104 -276.367852) (xy 341.781066 -276.355992)
			(xy 341.834216 -276.352009) (xy 341.887366 -276.355992) (xy 341.939328 -276.367852) (xy 341.988942 -276.387324)
			(xy 342.0351 -276.413973) (xy 342.076771 -276.447204) (xy 342.113023 -276.486275) (xy 342.143047 -276.530312)
			(xy 342.166173 -276.578333) (xy 342.181883 -276.629263) (xy 342.189826 -276.681967) (xy 342.190324 -276.708616)
			(xy 342.189826 -276.735265) (xy 342.418406 -276.735265) (xy 342.418406 -276.681967) (xy 342.426349 -276.629263)
			(xy 342.442059 -276.578333) (xy 342.465185 -276.530312) (xy 342.495209 -276.486275) (xy 342.531461 -276.447204)
			(xy 342.573132 -276.413973) (xy 342.61929 -276.387324) (xy 342.668904 -276.367852) (xy 342.720866 -276.355992)
			(xy 342.774016 -276.352009) (xy 342.827166 -276.355992) (xy 342.879128 -276.367852) (xy 342.928742 -276.387324)
			(xy 342.9749 -276.413973) (xy 343.016571 -276.447204) (xy 343.052823 -276.486275) (xy 343.082847 -276.530312)
			(xy 343.105973 -276.578333) (xy 343.121683 -276.629263) (xy 343.129626 -276.681967) (xy 343.130124 -276.708616)
			(xy 343.129626 -276.735265) (xy 343.358206 -276.735265) (xy 343.358206 -276.681967) (xy 343.366149 -276.629263)
			(xy 343.381859 -276.578333) (xy 343.404985 -276.530312) (xy 343.435009 -276.486275) (xy 343.471261 -276.447204)
			(xy 343.512932 -276.413973) (xy 343.55909 -276.387324) (xy 343.608704 -276.367852) (xy 343.660666 -276.355992)
			(xy 343.713816 -276.352009) (xy 343.766966 -276.355992) (xy 343.818928 -276.367852) (xy 343.868542 -276.387324)
			(xy 343.9147 -276.413973) (xy 343.956371 -276.447204) (xy 343.992623 -276.486275) (xy 344.022647 -276.530312)
			(xy 344.045773 -276.578333) (xy 344.061483 -276.629263) (xy 344.069426 -276.681967) (xy 344.069924 -276.708616)
			(xy 344.069426 -276.735265) (xy 344.298006 -276.735265) (xy 344.298006 -276.681967) (xy 344.305949 -276.629263)
			(xy 344.321659 -276.578333) (xy 344.344785 -276.530312) (xy 344.374809 -276.486275) (xy 344.411061 -276.447204)
			(xy 344.452732 -276.413973) (xy 344.49889 -276.387324) (xy 344.548504 -276.367852) (xy 344.600466 -276.355992)
			(xy 344.653616 -276.352009) (xy 344.706766 -276.355992) (xy 344.758728 -276.367852) (xy 344.808342 -276.387324)
			(xy 344.8545 -276.413973) (xy 344.896171 -276.447204) (xy 344.932423 -276.486275) (xy 344.962447 -276.530312)
			(xy 344.985573 -276.578333) (xy 345.001283 -276.629263) (xy 345.009226 -276.681967) (xy 345.009724 -276.708616)
			(xy 345.009226 -276.735265) (xy 345.237552 -276.735265) (xy 345.237552 -276.681967) (xy 345.245495 -276.629263)
			(xy 345.261205 -276.578333) (xy 345.284331 -276.530312) (xy 345.314355 -276.486275) (xy 345.350607 -276.447204)
			(xy 345.392278 -276.413973) (xy 345.438436 -276.387324) (xy 345.48805 -276.367852) (xy 345.540012 -276.355992)
			(xy 345.593162 -276.352009) (xy 345.646312 -276.355992) (xy 345.698274 -276.367852) (xy 345.747888 -276.387324)
			(xy 345.794046 -276.413973) (xy 345.835717 -276.447204) (xy 345.871969 -276.486275) (xy 345.901993 -276.530312)
			(xy 345.925119 -276.578333) (xy 345.940829 -276.629263) (xy 345.948772 -276.681967) (xy 345.94927 -276.708616)
			(xy 345.948772 -276.735265) (xy 346.177606 -276.735265) (xy 346.177606 -276.681967) (xy 346.185549 -276.629263)
			(xy 346.201259 -276.578333) (xy 346.224385 -276.530312) (xy 346.254409 -276.486275) (xy 346.290661 -276.447204)
			(xy 346.332332 -276.413973) (xy 346.37849 -276.387324) (xy 346.428104 -276.367852) (xy 346.480066 -276.355992)
			(xy 346.533216 -276.352009) (xy 346.586366 -276.355992) (xy 346.638328 -276.367852) (xy 346.687942 -276.387324)
			(xy 346.7341 -276.413973) (xy 346.775771 -276.447204) (xy 346.812023 -276.486275) (xy 346.842047 -276.530312)
			(xy 346.865173 -276.578333) (xy 346.880883 -276.629263) (xy 346.888826 -276.681967) (xy 346.889324 -276.708616)
			(xy 346.888826 -276.735265) (xy 347.117406 -276.735265) (xy 347.117406 -276.681967) (xy 347.125349 -276.629263)
			(xy 347.141059 -276.578333) (xy 347.164185 -276.530312) (xy 347.194209 -276.486275) (xy 347.230461 -276.447204)
			(xy 347.272132 -276.413973) (xy 347.31829 -276.387324) (xy 347.367904 -276.367852) (xy 347.419866 -276.355992)
			(xy 347.473016 -276.352009) (xy 347.526166 -276.355992) (xy 347.578128 -276.367852) (xy 347.627742 -276.387324)
			(xy 347.6739 -276.413973) (xy 347.715571 -276.447204) (xy 347.751823 -276.486275) (xy 347.781847 -276.530312)
			(xy 347.804973 -276.578333) (xy 347.820683 -276.629263) (xy 347.828626 -276.681967) (xy 347.829124 -276.708616)
			(xy 347.828626 -276.735265) (xy 348.057206 -276.735265) (xy 348.057206 -276.681967) (xy 348.065149 -276.629263)
			(xy 348.080859 -276.578333) (xy 348.103985 -276.530312) (xy 348.134009 -276.486275) (xy 348.170261 -276.447204)
			(xy 348.211932 -276.413973) (xy 348.25809 -276.387324) (xy 348.307704 -276.367852) (xy 348.359666 -276.355992)
			(xy 348.412816 -276.352009) (xy 348.465966 -276.355992) (xy 348.517928 -276.367852) (xy 348.567542 -276.387324)
			(xy 348.6137 -276.413973) (xy 348.655371 -276.447204) (xy 348.691623 -276.486275) (xy 348.721647 -276.530312)
			(xy 348.744773 -276.578333) (xy 348.760483 -276.629263) (xy 348.768426 -276.681967) (xy 348.768924 -276.708616)
			(xy 348.768426 -276.735265) (xy 348.997006 -276.735265) (xy 348.997006 -276.681967) (xy 349.004949 -276.629263)
			(xy 349.020659 -276.578333) (xy 349.043785 -276.530312) (xy 349.073809 -276.486275) (xy 349.110061 -276.447204)
			(xy 349.151732 -276.413973) (xy 349.19789 -276.387324) (xy 349.247504 -276.367852) (xy 349.299466 -276.355992)
			(xy 349.352616 -276.352009) (xy 349.405766 -276.355992) (xy 349.457728 -276.367852) (xy 349.507342 -276.387324)
			(xy 349.5535 -276.413973) (xy 349.595171 -276.447204) (xy 349.631423 -276.486275) (xy 349.661447 -276.530312)
			(xy 349.684573 -276.578333) (xy 349.700283 -276.629263) (xy 349.708226 -276.681967) (xy 349.708724 -276.708616)
			(xy 349.936054 -276.708616) (xy 349.936488 -276.682987) (xy 349.943822 -276.632257) (xy 349.958354 -276.583103)
			(xy 349.979785 -276.53654) (xy 350.007671 -276.493532) (xy 350.041437 -276.454967) (xy 350.080383 -276.421643)
			(xy 350.123706 -276.394248) (xy 350.170509 -276.373348) (xy 350.219826 -276.359376) (xy 350.245172 -276.355556)
			(xy 350.26981 -276.352254) (xy 350.442276 -276.05355) (xy 350.432878 -276.030436) (xy 350.424372 -276.008846)
			(xy 350.412401 -275.964011) (xy 350.406346 -275.918002) (xy 350.405954 -275.8948) (xy 350.406452 -275.868151)
			(xy 350.414395 -275.815447) (xy 350.430105 -275.764517) (xy 350.453231 -275.716496) (xy 350.483255 -275.672459)
			(xy 350.519507 -275.633388) (xy 350.561178 -275.600157) (xy 350.607336 -275.573508) (xy 350.65695 -275.554036)
			(xy 350.708912 -275.542176) (xy 350.762062 -275.538193) (xy 350.815212 -275.542176) (xy 350.867174 -275.554036)
			(xy 350.916788 -275.573508) (xy 350.962946 -275.600157) (xy 351.004617 -275.633388) (xy 351.040869 -275.672459)
			(xy 351.070893 -275.716496) (xy 351.094019 -275.764517) (xy 351.109729 -275.815447) (xy 351.117672 -275.868151)
			(xy 351.11817 -275.8948) (xy 351.11773 -275.920428) (xy 351.117582 -275.921449) (xy 351.346252 -275.921449)
			(xy 351.346252 -275.868151) (xy 351.354195 -275.815447) (xy 351.369905 -275.764517) (xy 351.393031 -275.716496)
			(xy 351.423055 -275.672459) (xy 351.459307 -275.633388) (xy 351.500978 -275.600157) (xy 351.547136 -275.573508)
			(xy 351.59675 -275.554036) (xy 351.648712 -275.542176) (xy 351.701862 -275.538193) (xy 351.755012 -275.542176)
			(xy 351.806974 -275.554036) (xy 351.856588 -275.573508) (xy 351.902746 -275.600157) (xy 351.944417 -275.633388)
			(xy 351.980669 -275.672459) (xy 352.010693 -275.716496) (xy 352.033819 -275.764517) (xy 352.049529 -275.815447)
			(xy 352.057472 -275.868151) (xy 352.05797 -275.8948) (xy 352.285554 -275.8948) (xy 352.285973 -275.869171)
			(xy 352.293309 -275.81844) (xy 352.307844 -275.769285) (xy 352.329276 -275.722723) (xy 352.357165 -275.679715)
			(xy 352.390931 -275.64115) (xy 352.429879 -275.607826) (xy 352.473203 -275.580431) (xy 352.520008 -275.559532)
			(xy 352.569325 -275.54556) (xy 352.594672 -275.54174) (xy 352.61931 -275.538438) (xy 352.79203 -275.23948)
			(xy 352.782632 -275.216366) (xy 352.774138 -275.194771) (xy 352.762162 -275.149939) (xy 352.756102 -275.103932)
			(xy 352.755708 -275.08073) (xy 352.756206 -275.054081) (xy 352.764149 -275.001377) (xy 352.779859 -274.950447)
			(xy 352.802985 -274.902426) (xy 352.833009 -274.858389) (xy 352.869261 -274.819318) (xy 352.910932 -274.786087)
			(xy 352.95709 -274.759438) (xy 353.006704 -274.739966) (xy 353.058666 -274.728106) (xy 353.111816 -274.724123)
			(xy 353.164966 -274.728106) (xy 353.216928 -274.739966) (xy 353.266542 -274.759438) (xy 353.3127 -274.786087)
			(xy 353.354371 -274.819318) (xy 353.390623 -274.858389) (xy 353.420647 -274.902426) (xy 353.443773 -274.950447)
			(xy 353.459483 -275.001377) (xy 353.467426 -275.054081) (xy 353.467924 -275.08073) (xy 353.467431 -275.106367)
			(xy 353.467285 -275.107379) (xy 353.695752 -275.107379) (xy 353.695752 -275.054081) (xy 353.703695 -275.001377)
			(xy 353.719405 -274.950447) (xy 353.742531 -274.902426) (xy 353.772555 -274.858389) (xy 353.808807 -274.819318)
			(xy 353.850478 -274.786087) (xy 353.896636 -274.759438) (xy 353.94625 -274.739966) (xy 353.998212 -274.728106)
			(xy 354.051362 -274.724123) (xy 354.104512 -274.728106) (xy 354.156474 -274.739966) (xy 354.206088 -274.759438)
			(xy 354.252246 -274.786087) (xy 354.293917 -274.819318) (xy 354.330169 -274.858389) (xy 354.360193 -274.902426)
			(xy 354.383319 -274.950447) (xy 354.399029 -275.001377) (xy 354.406972 -275.054081) (xy 354.40747 -275.08073)
			(xy 354.406972 -275.107379) (xy 354.635806 -275.107379) (xy 354.635806 -275.054081) (xy 354.643749 -275.001377)
			(xy 354.659459 -274.950447) (xy 354.682585 -274.902426) (xy 354.712609 -274.858389) (xy 354.748861 -274.819318)
			(xy 354.790532 -274.786087) (xy 354.83669 -274.759438) (xy 354.886304 -274.739966) (xy 354.938266 -274.728106)
			(xy 354.991416 -274.724123) (xy 355.044566 -274.728106) (xy 355.096528 -274.739966) (xy 355.146142 -274.759438)
			(xy 355.1923 -274.786087) (xy 355.233971 -274.819318) (xy 355.270223 -274.858389) (xy 355.300247 -274.902426)
			(xy 355.323373 -274.950447) (xy 355.339083 -275.001377) (xy 355.347026 -275.054081) (xy 355.347524 -275.08073)
			(xy 355.347026 -275.107379) (xy 355.339083 -275.160083) (xy 355.323373 -275.211013) (xy 355.300247 -275.259034)
			(xy 355.270223 -275.303071) (xy 355.233971 -275.342142) (xy 355.1923 -275.375373) (xy 355.146142 -275.402022)
			(xy 355.096528 -275.421494) (xy 355.044566 -275.433354) (xy 354.991416 -275.437338) (xy 354.938266 -275.433354)
			(xy 354.886304 -275.421494) (xy 354.83669 -275.402022) (xy 354.790532 -275.375373) (xy 354.748861 -275.342142)
			(xy 354.712609 -275.303071) (xy 354.682585 -275.259034) (xy 354.659459 -275.211013) (xy 354.643749 -275.160083)
			(xy 354.635806 -275.107379) (xy 354.406972 -275.107379) (xy 354.399029 -275.160083) (xy 354.383319 -275.211013)
			(xy 354.360193 -275.259034) (xy 354.330169 -275.303071) (xy 354.293917 -275.342142) (xy 354.252246 -275.375373)
			(xy 354.206088 -275.402022) (xy 354.156474 -275.421494) (xy 354.104512 -275.433354) (xy 354.051362 -275.437338)
			(xy 353.998212 -275.433354) (xy 353.94625 -275.421494) (xy 353.896636 -275.402022) (xy 353.850478 -275.375373)
			(xy 353.808807 -275.342142) (xy 353.772555 -275.303071) (xy 353.742531 -275.259034) (xy 353.719405 -275.211013)
			(xy 353.703695 -275.160083) (xy 353.695752 -275.107379) (xy 353.467285 -275.107379) (xy 353.460086 -275.157113)
			(xy 353.445539 -275.20628) (xy 353.42409 -275.252852) (xy 353.396182 -275.295867) (xy 353.362394 -275.334433)
			(xy 353.323423 -275.367754) (xy 353.280075 -275.395141) (xy 353.233248 -275.416027) (xy 353.183908 -275.429981)
			(xy 353.158552 -275.43379) (xy 353.133914 -275.437092) (xy 352.961194 -275.735796) (xy 352.970846 -275.75891)
			(xy 352.979361 -275.780542) (xy 352.991349 -275.82546) (xy 352.997394 -275.871555) (xy 352.99777 -275.8948)
			(xy 352.997272 -275.921449) (xy 353.226106 -275.921449) (xy 353.226106 -275.868151) (xy 353.234049 -275.815447)
			(xy 353.249759 -275.764517) (xy 353.272885 -275.716496) (xy 353.302909 -275.672459) (xy 353.339161 -275.633388)
			(xy 353.380832 -275.600157) (xy 353.42699 -275.573508) (xy 353.476604 -275.554036) (xy 353.528566 -275.542176)
			(xy 353.581716 -275.538193) (xy 353.634866 -275.542176) (xy 353.686828 -275.554036) (xy 353.736442 -275.573508)
			(xy 353.7826 -275.600157) (xy 353.824271 -275.633388) (xy 353.860523 -275.672459) (xy 353.890547 -275.716496)
			(xy 353.913673 -275.764517) (xy 353.929383 -275.815447) (xy 353.937326 -275.868151) (xy 353.937824 -275.8948)
			(xy 353.937326 -275.921449) (xy 353.929383 -275.974153) (xy 353.913673 -276.025083) (xy 353.890547 -276.073104)
			(xy 353.860523 -276.117141) (xy 353.824271 -276.156212) (xy 353.7826 -276.189443) (xy 353.736442 -276.216092)
			(xy 353.686828 -276.235564) (xy 353.634866 -276.247424) (xy 353.581716 -276.251408) (xy 353.528566 -276.247424)
			(xy 353.476604 -276.235564) (xy 353.42699 -276.216092) (xy 353.380832 -276.189443) (xy 353.339161 -276.156212)
			(xy 353.302909 -276.117141) (xy 353.272885 -276.073104) (xy 353.249759 -276.025083) (xy 353.234049 -275.974153)
			(xy 353.226106 -275.921449) (xy 352.997272 -275.921449) (xy 352.989329 -275.974153) (xy 352.973619 -276.025083)
			(xy 352.950493 -276.073104) (xy 352.920469 -276.117141) (xy 352.884217 -276.156212) (xy 352.842546 -276.189443)
			(xy 352.796388 -276.216092) (xy 352.746774 -276.235564) (xy 352.694812 -276.247424) (xy 352.641662 -276.251408)
			(xy 352.588512 -276.247424) (xy 352.53655 -276.235564) (xy 352.486936 -276.216092) (xy 352.440778 -276.189443)
			(xy 352.399107 -276.156212) (xy 352.362855 -276.117141) (xy 352.332831 -276.073104) (xy 352.309705 -276.025083)
			(xy 352.293995 -275.974153) (xy 352.286052 -275.921449) (xy 352.285554 -275.8948) (xy 352.05797 -275.8948)
			(xy 352.057472 -275.921449) (xy 352.049529 -275.974153) (xy 352.033819 -276.025083) (xy 352.010693 -276.073104)
			(xy 351.980669 -276.117141) (xy 351.944417 -276.156212) (xy 351.902746 -276.189443) (xy 351.856588 -276.216092)
			(xy 351.806974 -276.235564) (xy 351.755012 -276.247424) (xy 351.701862 -276.251408) (xy 351.648712 -276.247424)
			(xy 351.59675 -276.235564) (xy 351.547136 -276.216092) (xy 351.500978 -276.189443) (xy 351.459307 -276.156212)
			(xy 351.423055 -276.117141) (xy 351.393031 -276.073104) (xy 351.369905 -276.025083) (xy 351.354195 -275.974153)
			(xy 351.346252 -275.921449) (xy 351.117582 -275.921449) (xy 351.110395 -275.971157) (xy 351.095861 -276.02031)
			(xy 351.07443 -276.066872) (xy 351.046544 -276.109879) (xy 351.01278 -276.148443) (xy 350.973835 -276.181767)
			(xy 350.930514 -276.209163) (xy 350.883712 -276.230064) (xy 350.834398 -276.244038) (xy 350.809052 -276.24786)
			(xy 350.78416 -276.251162) (xy 350.611694 -276.549612) (xy 350.621346 -276.572726) (xy 350.629866 -276.594357)
			(xy 350.641852 -276.639275) (xy 350.647895 -276.685371) (xy 350.64827 -276.708616) (xy 350.876108 -276.708616)
			(xy 350.876606 -276.681967) (xy 350.884549 -276.629263) (xy 350.900259 -276.578333) (xy 350.923385 -276.530312)
			(xy 350.953409 -276.486275) (xy 350.989661 -276.447204) (xy 351.031332 -276.413973) (xy 351.07749 -276.387324)
			(xy 351.127104 -276.367852) (xy 351.179066 -276.355992) (xy 351.232216 -276.352009) (xy 351.285366 -276.355992)
			(xy 351.337328 -276.367852) (xy 351.386942 -276.387324) (xy 351.4331 -276.413973) (xy 351.474771 -276.447204)
			(xy 351.511023 -276.486275) (xy 351.541047 -276.530312) (xy 351.564173 -276.578333) (xy 351.579883 -276.629263)
			(xy 351.587826 -276.681967) (xy 351.588324 -276.7086) (xy 351.815384 -276.7086) (xy 351.819367 -276.655448)
			(xy 351.831228 -276.603483) (xy 351.850702 -276.553866) (xy 351.877353 -276.507706) (xy 351.910587 -276.466034)
			(xy 351.949661 -276.429781) (xy 351.993701 -276.399756) (xy 352.041725 -276.376631) (xy 352.092659 -276.360922)
			(xy 352.145365 -276.35298) (xy 352.172016 -276.352508) (xy 352.19703 -276.352935) (xy 352.246568 -276.359922)
			(xy 352.294641 -276.37377) (xy 352.340304 -276.394207) (xy 352.382659 -276.420831) (xy 352.420874 -276.453118)
			(xy 352.454195 -276.490434) (xy 352.468434 -276.511004) (xy 352.815398 -276.511004) (xy 352.829609 -276.490414)
			(xy 352.862942 -276.453107) (xy 352.901164 -276.420827) (xy 352.943524 -276.394207) (xy 352.989189 -276.373772)
			(xy 353.037263 -276.359922) (xy 353.086801 -276.352929) (xy 353.111816 -276.352508) (xy 353.138466 -276.352975)
			(xy 353.19117 -276.360921) (xy 353.242101 -276.376633) (xy 353.290121 -276.39976) (xy 353.334158 -276.429786)
			(xy 353.373229 -276.46604) (xy 353.40646 -276.507712) (xy 353.433109 -276.553871) (xy 353.452581 -276.603486)
			(xy 353.464441 -276.65545) (xy 353.468424 -276.7086) (xy 353.466426 -276.735265) (xy 353.695752 -276.735265)
			(xy 353.695752 -276.681967) (xy 353.703695 -276.629263) (xy 353.719405 -276.578333) (xy 353.742531 -276.530312)
			(xy 353.772555 -276.486275) (xy 353.808807 -276.447204) (xy 353.850478 -276.413973) (xy 353.896636 -276.387324)
			(xy 353.94625 -276.367852) (xy 353.998212 -276.355992) (xy 354.051362 -276.352009) (xy 354.104512 -276.355992)
			(xy 354.156474 -276.367852) (xy 354.206088 -276.387324) (xy 354.252246 -276.413973) (xy 354.293917 -276.447204)
			(xy 354.330169 -276.486275) (xy 354.360193 -276.530312) (xy 354.383319 -276.578333) (xy 354.399029 -276.629263)
			(xy 354.406972 -276.681967) (xy 354.40747 -276.708616) (xy 354.406972 -276.735265) (xy 354.399029 -276.787969)
			(xy 354.383319 -276.838899) (xy 354.360193 -276.88692) (xy 354.330169 -276.930957) (xy 354.293917 -276.970028)
			(xy 354.252246 -277.003259) (xy 354.206088 -277.029908) (xy 354.156474 -277.04938) (xy 354.104512 -277.06124)
			(xy 354.051362 -277.065224) (xy 353.998212 -277.06124) (xy 353.94625 -277.04938) (xy 353.896636 -277.029908)
			(xy 353.850478 -277.003259) (xy 353.808807 -276.970028) (xy 353.772555 -276.930957) (xy 353.742531 -276.88692)
			(xy 353.719405 -276.838899) (xy 353.703695 -276.787969) (xy 353.695752 -276.735265) (xy 353.466426 -276.735265)
			(xy 353.464441 -276.76175) (xy 353.452581 -276.813714) (xy 353.433109 -276.863329) (xy 353.40646 -276.909488)
			(xy 353.373229 -276.95116) (xy 353.334158 -276.987414) (xy 353.290121 -277.01744) (xy 353.242101 -277.040567)
			(xy 353.19117 -277.056279) (xy 353.138466 -277.064225) (xy 353.111816 -277.064724) (xy 353.086801 -277.064303)
			(xy 353.037262 -277.057319) (xy 352.989188 -277.043472) (xy 352.943523 -277.023035) (xy 352.901168 -276.996409)
			(xy 352.862954 -276.964119) (xy 352.829635 -276.9268) (xy 352.815398 -276.906228) (xy 352.468434 -276.906228)
			(xy 352.454213 -276.92681) (xy 352.42088 -276.964116) (xy 352.38266 -276.996396) (xy 352.340302 -277.023016)
			(xy 352.294638 -277.043452) (xy 352.246566 -277.057305) (xy 352.19703 -277.064301) (xy 352.172016 -277.064724)
			(xy 352.145365 -277.06422) (xy 352.092659 -277.056278) (xy 352.041725 -277.040569) (xy 351.993701 -277.017444)
			(xy 351.949661 -276.987419) (xy 351.910587 -276.951166) (xy 351.877353 -276.909494) (xy 351.850702 -276.863334)
			(xy 351.831228 -276.813717) (xy 351.819367 -276.761752) (xy 351.815384 -276.7086) (xy 351.588324 -276.7086)
			(xy 351.588324 -276.708616) (xy 351.587959 -276.731861) (xy 351.58191 -276.777957) (xy 351.569918 -276.822874)
			(xy 351.5614 -276.844506) (xy 351.551748 -276.86762) (xy 351.724214 -277.16607) (xy 351.748852 -277.169372)
			(xy 351.774194 -277.173197) (xy 351.823498 -277.187189) (xy 351.870289 -277.208102) (xy 351.913599 -277.235504)
			(xy 351.952537 -277.268829) (xy 351.986297 -277.307389) (xy 352.014184 -277.35039) (xy 352.035621 -277.396942)
			(xy 352.050167 -277.446086) (xy 352.05752 -277.496807) (xy 352.05797 -277.522432) (xy 352.057472 -277.549081)
			(xy 352.286052 -277.549081) (xy 352.286052 -277.495783) (xy 352.293995 -277.443079) (xy 352.309705 -277.392149)
			(xy 352.332831 -277.344128) (xy 352.362855 -277.300091) (xy 352.399107 -277.26102) (xy 352.440778 -277.227789)
			(xy 352.486936 -277.20114) (xy 352.53655 -277.181668) (xy 352.588512 -277.169808) (xy 352.641662 -277.165825)
			(xy 352.694812 -277.169808) (xy 352.746774 -277.181668) (xy 352.796388 -277.20114) (xy 352.842546 -277.227789)
			(xy 352.884217 -277.26102) (xy 352.920469 -277.300091) (xy 352.950493 -277.344128) (xy 352.973619 -277.392149)
			(xy 352.989329 -277.443079) (xy 352.997272 -277.495783) (xy 352.99777 -277.522432) (xy 352.997272 -277.549081)
			(xy 353.225852 -277.549081) (xy 353.225852 -277.495783) (xy 353.233795 -277.443079) (xy 353.249505 -277.392149)
			(xy 353.272631 -277.344128) (xy 353.302655 -277.300091) (xy 353.338907 -277.26102) (xy 353.380578 -277.227789)
			(xy 353.426736 -277.20114) (xy 353.47635 -277.181668) (xy 353.528312 -277.169808) (xy 353.581462 -277.165825)
			(xy 353.634612 -277.169808) (xy 353.686574 -277.181668) (xy 353.736188 -277.20114) (xy 353.782346 -277.227789)
			(xy 353.824017 -277.26102) (xy 353.860269 -277.300091) (xy 353.890293 -277.344128) (xy 353.913419 -277.392149)
			(xy 353.929129 -277.443079) (xy 353.937072 -277.495783) (xy 353.93757 -277.522432) (xy 354.165154 -277.522432)
			(xy 354.165603 -277.496803) (xy 354.172934 -277.446074) (xy 354.187464 -277.39692) (xy 354.208893 -277.350358)
			(xy 354.236778 -277.307349) (xy 354.270542 -277.268785) (xy 354.309487 -277.23546) (xy 354.352808 -277.208065)
			(xy 354.399611 -277.187165) (xy 354.448926 -277.173192) (xy 354.474272 -277.169372) (xy 354.49891 -277.16607)
			(xy 354.67163 -276.867112) (xy 354.661978 -276.843998) (xy 354.653505 -276.822448) (xy 354.641623 -276.777691)
			(xy 354.635656 -276.73177) (xy 354.635308 -276.708616) (xy 354.635806 -276.681967) (xy 354.643749 -276.629263)
			(xy 354.659459 -276.578333) (xy 354.682585 -276.530312) (xy 354.712609 -276.486275) (xy 354.748861 -276.447204)
			(xy 354.790532 -276.413973) (xy 354.83669 -276.387324) (xy 354.886304 -276.367852) (xy 354.938266 -276.355992)
			(xy 354.991416 -276.352009) (xy 355.044566 -276.355992) (xy 355.096528 -276.367852) (xy 355.146142 -276.387324)
			(xy 355.1923 -276.413973) (xy 355.233971 -276.447204) (xy 355.270223 -276.486275) (xy 355.300247 -276.530312)
			(xy 355.323373 -276.578333) (xy 355.339083 -276.629263) (xy 355.347026 -276.681967) (xy 355.347524 -276.708616)
			(xy 355.347018 -276.734253) (xy 355.339675 -276.784998) (xy 355.32513 -276.834165) (xy 355.303682 -276.880737)
			(xy 355.275776 -276.923751) (xy 355.241989 -276.962318) (xy 355.203019 -276.99564) (xy 355.159673 -277.023027)
			(xy 355.112846 -277.043913) (xy 355.063508 -277.057867) (xy 355.038152 -277.061676) (xy 355.01326 -277.064978)
			(xy 354.840794 -277.363428) (xy 354.850446 -277.386542) (xy 354.858971 -277.408171) (xy 354.870955 -277.45309)
			(xy 354.876996 -277.499187) (xy 354.87737 -277.522432) (xy 354.876872 -277.549081) (xy 354.868929 -277.601785)
			(xy 354.853219 -277.652715) (xy 354.830093 -277.700736) (xy 354.800069 -277.744773) (xy 354.763817 -277.783844)
			(xy 354.722146 -277.817075) (xy 354.675988 -277.843724) (xy 354.626374 -277.863196) (xy 354.574412 -277.875056)
			(xy 354.521262 -277.87904) (xy 354.468112 -277.875056) (xy 354.41615 -277.863196) (xy 354.366536 -277.843724)
			(xy 354.320378 -277.817075) (xy 354.278707 -277.783844) (xy 354.242455 -277.744773) (xy 354.212431 -277.700736)
			(xy 354.189305 -277.652715) (xy 354.173595 -277.601785) (xy 354.165652 -277.549081) (xy 354.165154 -277.522432)
			(xy 353.93757 -277.522432) (xy 353.937072 -277.549081) (xy 353.929129 -277.601785) (xy 353.913419 -277.652715)
			(xy 353.890293 -277.700736) (xy 353.860269 -277.744773) (xy 353.824017 -277.783844) (xy 353.782346 -277.817075)
			(xy 353.736188 -277.843724) (xy 353.686574 -277.863196) (xy 353.634612 -277.875056) (xy 353.581462 -277.87904)
			(xy 353.528312 -277.875056) (xy 353.47635 -277.863196) (xy 353.426736 -277.843724) (xy 353.380578 -277.817075)
			(xy 353.338907 -277.783844) (xy 353.302655 -277.744773) (xy 353.272631 -277.700736) (xy 353.249505 -277.652715)
			(xy 353.233795 -277.601785) (xy 353.225852 -277.549081) (xy 352.997272 -277.549081) (xy 352.989329 -277.601785)
			(xy 352.973619 -277.652715) (xy 352.950493 -277.700736) (xy 352.920469 -277.744773) (xy 352.884217 -277.783844)
			(xy 352.842546 -277.817075) (xy 352.796388 -277.843724) (xy 352.746774 -277.863196) (xy 352.694812 -277.875056)
			(xy 352.641662 -277.87904) (xy 352.588512 -277.875056) (xy 352.53655 -277.863196) (xy 352.486936 -277.843724)
			(xy 352.440778 -277.817075) (xy 352.399107 -277.783844) (xy 352.362855 -277.744773) (xy 352.332831 -277.700736)
			(xy 352.309705 -277.652715) (xy 352.293995 -277.601785) (xy 352.286052 -277.549081) (xy 352.057472 -277.549081)
			(xy 352.049529 -277.601785) (xy 352.033819 -277.652715) (xy 352.010693 -277.700736) (xy 351.980669 -277.744773)
			(xy 351.944417 -277.783844) (xy 351.902746 -277.817075) (xy 351.856588 -277.843724) (xy 351.806974 -277.863196)
			(xy 351.755012 -277.875056) (xy 351.701862 -277.87904) (xy 351.648712 -277.875056) (xy 351.59675 -277.863196)
			(xy 351.547136 -277.843724) (xy 351.500978 -277.817075) (xy 351.459307 -277.783844) (xy 351.423055 -277.744773)
			(xy 351.393031 -277.700736) (xy 351.369905 -277.652715) (xy 351.354195 -277.601785) (xy 351.346252 -277.549081)
			(xy 351.345754 -277.522432) (xy 351.346136 -277.499187) (xy 351.352178 -277.453092) (xy 351.364163 -277.408174)
			(xy 351.372678 -277.386542) (xy 351.38233 -277.363428) (xy 351.209864 -277.064978) (xy 351.184972 -277.061676)
			(xy 351.159655 -277.057773) (xy 351.110387 -277.043756) (xy 351.063635 -277.022828) (xy 351.020361 -276.99542)
			(xy 350.981459 -276.962098) (xy 350.947729 -276.923549) (xy 350.919867 -276.880566) (xy 350.898448 -276.834037)
			(xy 350.883912 -276.78492) (xy 350.87656 -276.734227) (xy 350.876108 -276.708616) (xy 350.64827 -276.708616)
			(xy 350.647772 -276.735265) (xy 350.639829 -276.787969) (xy 350.624119 -276.838899) (xy 350.600993 -276.88692)
			(xy 350.570969 -276.930957) (xy 350.534717 -276.970028) (xy 350.493046 -277.003259) (xy 350.446888 -277.029908)
			(xy 350.397274 -277.04938) (xy 350.345312 -277.06124) (xy 350.292162 -277.065224) (xy 350.239012 -277.06124)
			(xy 350.18705 -277.04938) (xy 350.137436 -277.029908) (xy 350.091278 -277.003259) (xy 350.049607 -276.970028)
			(xy 350.013355 -276.930957) (xy 349.983331 -276.88692) (xy 349.960205 -276.838899) (xy 349.944495 -276.787969)
			(xy 349.936552 -276.735265) (xy 349.936054 -276.708616) (xy 349.708724 -276.708616) (xy 349.708226 -276.735265)
			(xy 349.700283 -276.787969) (xy 349.684573 -276.838899) (xy 349.661447 -276.88692) (xy 349.631423 -276.930957)
			(xy 349.595171 -276.970028) (xy 349.5535 -277.003259) (xy 349.507342 -277.029908) (xy 349.457728 -277.04938)
			(xy 349.405766 -277.06124) (xy 349.352616 -277.065224) (xy 349.299466 -277.06124) (xy 349.247504 -277.04938)
			(xy 349.19789 -277.029908) (xy 349.151732 -277.003259) (xy 349.110061 -276.970028) (xy 349.073809 -276.930957)
			(xy 349.043785 -276.88692) (xy 349.020659 -276.838899) (xy 349.004949 -276.787969) (xy 348.997006 -276.735265)
			(xy 348.768426 -276.735265) (xy 348.760483 -276.787969) (xy 348.744773 -276.838899) (xy 348.721647 -276.88692)
			(xy 348.691623 -276.930957) (xy 348.655371 -276.970028) (xy 348.6137 -277.003259) (xy 348.567542 -277.029908)
			(xy 348.517928 -277.04938) (xy 348.465966 -277.06124) (xy 348.412816 -277.065224) (xy 348.359666 -277.06124)
			(xy 348.307704 -277.04938) (xy 348.25809 -277.029908) (xy 348.211932 -277.003259) (xy 348.170261 -276.970028)
			(xy 348.134009 -276.930957) (xy 348.103985 -276.88692) (xy 348.080859 -276.838899) (xy 348.065149 -276.787969)
			(xy 348.057206 -276.735265) (xy 347.828626 -276.735265) (xy 347.820683 -276.787969) (xy 347.804973 -276.838899)
			(xy 347.781847 -276.88692) (xy 347.751823 -276.930957) (xy 347.715571 -276.970028) (xy 347.6739 -277.003259)
			(xy 347.627742 -277.029908) (xy 347.578128 -277.04938) (xy 347.526166 -277.06124) (xy 347.473016 -277.065224)
			(xy 347.419866 -277.06124) (xy 347.367904 -277.04938) (xy 347.31829 -277.029908) (xy 347.272132 -277.003259)
			(xy 347.230461 -276.970028) (xy 347.194209 -276.930957) (xy 347.164185 -276.88692) (xy 347.141059 -276.838899)
			(xy 347.125349 -276.787969) (xy 347.117406 -276.735265) (xy 346.888826 -276.735265) (xy 346.880883 -276.787969)
			(xy 346.865173 -276.838899) (xy 346.842047 -276.88692) (xy 346.812023 -276.930957) (xy 346.775771 -276.970028)
			(xy 346.7341 -277.003259) (xy 346.687942 -277.029908) (xy 346.638328 -277.04938) (xy 346.586366 -277.06124)
			(xy 346.533216 -277.065224) (xy 346.480066 -277.06124) (xy 346.428104 -277.04938) (xy 346.37849 -277.029908)
			(xy 346.332332 -277.003259) (xy 346.290661 -276.970028) (xy 346.254409 -276.930957) (xy 346.224385 -276.88692)
			(xy 346.201259 -276.838899) (xy 346.185549 -276.787969) (xy 346.177606 -276.735265) (xy 345.948772 -276.735265)
			(xy 345.940829 -276.787969) (xy 345.925119 -276.838899) (xy 345.901993 -276.88692) (xy 345.871969 -276.930957)
			(xy 345.835717 -276.970028) (xy 345.794046 -277.003259) (xy 345.747888 -277.029908) (xy 345.698274 -277.04938)
			(xy 345.646312 -277.06124) (xy 345.593162 -277.065224) (xy 345.540012 -277.06124) (xy 345.48805 -277.04938)
			(xy 345.438436 -277.029908) (xy 345.392278 -277.003259) (xy 345.350607 -276.970028) (xy 345.314355 -276.930957)
			(xy 345.284331 -276.88692) (xy 345.261205 -276.838899) (xy 345.245495 -276.787969) (xy 345.237552 -276.735265)
			(xy 345.009226 -276.735265) (xy 345.001283 -276.787969) (xy 344.985573 -276.838899) (xy 344.962447 -276.88692)
			(xy 344.932423 -276.930957) (xy 344.896171 -276.970028) (xy 344.8545 -277.003259) (xy 344.808342 -277.029908)
			(xy 344.758728 -277.04938) (xy 344.706766 -277.06124) (xy 344.653616 -277.065224) (xy 344.600466 -277.06124)
			(xy 344.548504 -277.04938) (xy 344.49889 -277.029908) (xy 344.452732 -277.003259) (xy 344.411061 -276.970028)
			(xy 344.374809 -276.930957) (xy 344.344785 -276.88692) (xy 344.321659 -276.838899) (xy 344.305949 -276.787969)
			(xy 344.298006 -276.735265) (xy 344.069426 -276.735265) (xy 344.061483 -276.787969) (xy 344.045773 -276.838899)
			(xy 344.022647 -276.88692) (xy 343.992623 -276.930957) (xy 343.956371 -276.970028) (xy 343.9147 -277.003259)
			(xy 343.868542 -277.029908) (xy 343.818928 -277.04938) (xy 343.766966 -277.06124) (xy 343.713816 -277.065224)
			(xy 343.660666 -277.06124) (xy 343.608704 -277.04938) (xy 343.55909 -277.029908) (xy 343.512932 -277.003259)
			(xy 343.471261 -276.970028) (xy 343.435009 -276.930957) (xy 343.404985 -276.88692) (xy 343.381859 -276.838899)
			(xy 343.366149 -276.787969) (xy 343.358206 -276.735265) (xy 343.129626 -276.735265) (xy 343.121683 -276.787969)
			(xy 343.105973 -276.838899) (xy 343.082847 -276.88692) (xy 343.052823 -276.930957) (xy 343.016571 -276.970028)
			(xy 342.9749 -277.003259) (xy 342.928742 -277.029908) (xy 342.879128 -277.04938) (xy 342.827166 -277.06124)
			(xy 342.774016 -277.065224) (xy 342.720866 -277.06124) (xy 342.668904 -277.04938) (xy 342.61929 -277.029908)
			(xy 342.573132 -277.003259) (xy 342.531461 -276.970028) (xy 342.495209 -276.930957) (xy 342.465185 -276.88692)
			(xy 342.442059 -276.838899) (xy 342.426349 -276.787969) (xy 342.418406 -276.735265) (xy 342.189826 -276.735265)
			(xy 342.181883 -276.787969) (xy 342.166173 -276.838899) (xy 342.143047 -276.88692) (xy 342.113023 -276.930957)
			(xy 342.076771 -276.970028) (xy 342.0351 -277.003259) (xy 341.988942 -277.029908) (xy 341.939328 -277.04938)
			(xy 341.887366 -277.06124) (xy 341.834216 -277.065224) (xy 341.781066 -277.06124) (xy 341.729104 -277.04938)
			(xy 341.67949 -277.029908) (xy 341.633332 -277.003259) (xy 341.591661 -276.970028) (xy 341.555409 -276.930957)
			(xy 341.525385 -276.88692) (xy 341.502259 -276.838899) (xy 341.486549 -276.787969) (xy 341.478606 -276.735265)
			(xy 341.250026 -276.735265) (xy 341.242083 -276.787969) (xy 341.226373 -276.838899) (xy 341.203247 -276.88692)
			(xy 341.173223 -276.930957) (xy 341.136971 -276.970028) (xy 341.0953 -277.003259) (xy 341.049142 -277.029908)
			(xy 340.999528 -277.04938) (xy 340.947566 -277.06124) (xy 340.894416 -277.065224) (xy 340.841266 -277.06124)
			(xy 340.789304 -277.04938) (xy 340.73969 -277.029908) (xy 340.693532 -277.003259) (xy 340.651861 -276.970028)
			(xy 340.615609 -276.930957) (xy 340.585585 -276.88692) (xy 340.562459 -276.838899) (xy 340.546749 -276.787969)
			(xy 340.538806 -276.735265) (xy 340.310226 -276.735265) (xy 340.302283 -276.787969) (xy 340.286573 -276.838899)
			(xy 340.263447 -276.88692) (xy 340.233423 -276.930957) (xy 340.197171 -276.970028) (xy 340.1555 -277.003259)
			(xy 340.109342 -277.029908) (xy 340.059728 -277.04938) (xy 340.007766 -277.06124) (xy 339.954616 -277.065224)
			(xy 339.901466 -277.06124) (xy 339.849504 -277.04938) (xy 339.79989 -277.029908) (xy 339.753732 -277.003259)
			(xy 339.712061 -276.970028) (xy 339.675809 -276.930957) (xy 339.645785 -276.88692) (xy 339.622659 -276.838899)
			(xy 339.606949 -276.787969) (xy 339.599006 -276.735265) (xy 339.370172 -276.735265) (xy 339.362229 -276.787969)
			(xy 339.346519 -276.838899) (xy 339.323393 -276.88692) (xy 339.293369 -276.930957) (xy 339.257117 -276.970028)
			(xy 339.215446 -277.003259) (xy 339.169288 -277.029908) (xy 339.119674 -277.04938) (xy 339.067712 -277.06124)
			(xy 339.014562 -277.065224) (xy 338.961412 -277.06124) (xy 338.90945 -277.04938) (xy 338.859836 -277.029908)
			(xy 338.813678 -277.003259) (xy 338.772007 -276.970028) (xy 338.735755 -276.930957) (xy 338.705731 -276.88692)
			(xy 338.682605 -276.838899) (xy 338.666895 -276.787969) (xy 338.658952 -276.735265) (xy 338.430372 -276.735265)
			(xy 338.422429 -276.787969) (xy 338.406719 -276.838899) (xy 338.383593 -276.88692) (xy 338.353569 -276.930957)
			(xy 338.317317 -276.970028) (xy 338.275646 -277.003259) (xy 338.229488 -277.029908) (xy 338.179874 -277.04938)
			(xy 338.127912 -277.06124) (xy 338.074762 -277.065224) (xy 338.021612 -277.06124) (xy 337.96965 -277.04938)
			(xy 337.920036 -277.029908) (xy 337.873878 -277.003259) (xy 337.832207 -276.970028) (xy 337.795955 -276.930957)
			(xy 337.765931 -276.88692) (xy 337.742805 -276.838899) (xy 337.727095 -276.787969) (xy 337.719152 -276.735265)
			(xy 337.490572 -276.735265) (xy 337.482629 -276.787969) (xy 337.466919 -276.838899) (xy 337.443793 -276.88692)
			(xy 337.413769 -276.930957) (xy 337.377517 -276.970028) (xy 337.335846 -277.003259) (xy 337.289688 -277.029908)
			(xy 337.240074 -277.04938) (xy 337.188112 -277.06124) (xy 337.134962 -277.065224) (xy 337.081812 -277.06124)
			(xy 337.02985 -277.04938) (xy 336.980236 -277.029908) (xy 336.934078 -277.003259) (xy 336.892407 -276.970028)
			(xy 336.856155 -276.930957) (xy 336.826131 -276.88692) (xy 336.803005 -276.838899) (xy 336.787295 -276.787969)
			(xy 336.779352 -276.735265) (xy 336.550772 -276.735265) (xy 336.542829 -276.787969) (xy 336.527119 -276.838899)
			(xy 336.503993 -276.88692) (xy 336.473969 -276.930957) (xy 336.437717 -276.970028) (xy 336.396046 -277.003259)
			(xy 336.349888 -277.029908) (xy 336.300274 -277.04938) (xy 336.248312 -277.06124) (xy 336.195162 -277.065224)
			(xy 336.142012 -277.06124) (xy 336.09005 -277.04938) (xy 336.040436 -277.029908) (xy 335.994278 -277.003259)
			(xy 335.952607 -276.970028) (xy 335.916355 -276.930957) (xy 335.886331 -276.88692) (xy 335.863205 -276.838899)
			(xy 335.847495 -276.787969) (xy 335.839552 -276.735265) (xy 333.466948 -276.735265) (xy 333.466948 -277.270951)
			(xy 334.886036 -277.270951) (xy 334.886036 -277.217653) (xy 334.893979 -277.164949) (xy 334.909689 -277.114019)
			(xy 334.932815 -277.065998) (xy 334.962839 -277.021961) (xy 334.999091 -276.98289) (xy 335.040762 -276.949659)
			(xy 335.08692 -276.92301) (xy 335.136534 -276.903538) (xy 335.188496 -276.891678) (xy 335.241646 -276.887695)
			(xy 335.294796 -276.891678) (xy 335.346758 -276.903538) (xy 335.396372 -276.92301) (xy 335.44253 -276.949659)
			(xy 335.484201 -276.98289) (xy 335.520453 -277.021961) (xy 335.550477 -277.065998) (xy 335.573603 -277.114019)
			(xy 335.589313 -277.164949) (xy 335.597256 -277.217653) (xy 335.597754 -277.244302) (xy 335.597256 -277.270951)
			(xy 335.589313 -277.323655) (xy 335.573603 -277.374585) (xy 335.550477 -277.422606) (xy 335.520453 -277.466643)
			(xy 335.484201 -277.505714) (xy 335.44253 -277.538945) (xy 335.424534 -277.549335) (xy 336.309198 -277.549335)
			(xy 336.309198 -277.496037) (xy 336.317141 -277.443333) (xy 336.332851 -277.392403) (xy 336.355977 -277.344382)
			(xy 336.386001 -277.300345) (xy 336.422253 -277.261274) (xy 336.463924 -277.228043) (xy 336.510082 -277.201394)
			(xy 336.559696 -277.181922) (xy 336.611658 -277.170062) (xy 336.664808 -277.166079) (xy 336.717958 -277.170062)
			(xy 336.76992 -277.181922) (xy 336.819534 -277.201394) (xy 336.865692 -277.228043) (xy 336.907363 -277.261274)
			(xy 336.943615 -277.300345) (xy 336.973639 -277.344382) (xy 336.996765 -277.392403) (xy 337.012475 -277.443333)
			(xy 337.020418 -277.496037) (xy 337.020916 -277.522686) (xy 337.020423 -277.549081) (xy 337.249252 -277.549081)
			(xy 337.249252 -277.495783) (xy 337.257195 -277.443079) (xy 337.272905 -277.392149) (xy 337.296031 -277.344128)
			(xy 337.326055 -277.300091) (xy 337.362307 -277.26102) (xy 337.403978 -277.227789) (xy 337.450136 -277.20114)
			(xy 337.49975 -277.181668) (xy 337.551712 -277.169808) (xy 337.604862 -277.165825) (xy 337.658012 -277.169808)
			(xy 337.709974 -277.181668) (xy 337.759588 -277.20114) (xy 337.805746 -277.227789) (xy 337.847417 -277.26102)
			(xy 337.883669 -277.300091) (xy 337.913693 -277.344128) (xy 337.936819 -277.392149) (xy 337.952529 -277.443079)
			(xy 337.960472 -277.495783) (xy 337.96097 -277.522432) (xy 337.960472 -277.549081) (xy 338.189306 -277.549081)
			(xy 338.189306 -277.495783) (xy 338.197249 -277.443079) (xy 338.212959 -277.392149) (xy 338.236085 -277.344128)
			(xy 338.266109 -277.300091) (xy 338.302361 -277.26102) (xy 338.344032 -277.227789) (xy 338.39019 -277.20114)
			(xy 338.439804 -277.181668) (xy 338.491766 -277.169808) (xy 338.544916 -277.165825) (xy 338.598066 -277.169808)
			(xy 338.650028 -277.181668) (xy 338.699642 -277.20114) (xy 338.7458 -277.227789) (xy 338.787471 -277.26102)
			(xy 338.823723 -277.300091) (xy 338.853747 -277.344128) (xy 338.876873 -277.392149) (xy 338.892583 -277.443079)
			(xy 338.900526 -277.495783) (xy 338.901024 -277.522432) (xy 338.900526 -277.549081) (xy 339.128852 -277.549081)
			(xy 339.128852 -277.495783) (xy 339.136795 -277.443079) (xy 339.152505 -277.392149) (xy 339.175631 -277.344128)
			(xy 339.205655 -277.300091) (xy 339.241907 -277.26102) (xy 339.283578 -277.227789) (xy 339.329736 -277.20114)
			(xy 339.37935 -277.181668) (xy 339.431312 -277.169808) (xy 339.484462 -277.165825) (xy 339.537612 -277.169808)
			(xy 339.589574 -277.181668) (xy 339.639188 -277.20114) (xy 339.685346 -277.227789) (xy 339.727017 -277.26102)
			(xy 339.763269 -277.300091) (xy 339.793293 -277.344128) (xy 339.816419 -277.392149) (xy 339.832129 -277.443079)
			(xy 339.840072 -277.495783) (xy 339.84057 -277.522432) (xy 339.840072 -277.549081) (xy 340.068652 -277.549081)
			(xy 340.068652 -277.495783) (xy 340.076595 -277.443079) (xy 340.092305 -277.392149) (xy 340.115431 -277.344128)
			(xy 340.145455 -277.300091) (xy 340.181707 -277.26102) (xy 340.223378 -277.227789) (xy 340.269536 -277.20114)
			(xy 340.31915 -277.181668) (xy 340.371112 -277.169808) (xy 340.424262 -277.165825) (xy 340.477412 -277.169808)
			(xy 340.529374 -277.181668) (xy 340.578988 -277.20114) (xy 340.625146 -277.227789) (xy 340.666817 -277.26102)
			(xy 340.703069 -277.300091) (xy 340.733093 -277.344128) (xy 340.756219 -277.392149) (xy 340.771929 -277.443079)
			(xy 340.779872 -277.495783) (xy 340.78037 -277.522432) (xy 340.779872 -277.549081) (xy 341.008452 -277.549081)
			(xy 341.008452 -277.495783) (xy 341.016395 -277.443079) (xy 341.032105 -277.392149) (xy 341.055231 -277.344128)
			(xy 341.085255 -277.300091) (xy 341.121507 -277.26102) (xy 341.163178 -277.227789) (xy 341.209336 -277.20114)
			(xy 341.25895 -277.181668) (xy 341.310912 -277.169808) (xy 341.364062 -277.165825) (xy 341.417212 -277.169808)
			(xy 341.469174 -277.181668) (xy 341.518788 -277.20114) (xy 341.564946 -277.227789) (xy 341.606617 -277.26102)
			(xy 341.642869 -277.300091) (xy 341.672893 -277.344128) (xy 341.696019 -277.392149) (xy 341.711729 -277.443079)
			(xy 341.719672 -277.495783) (xy 341.72017 -277.522432) (xy 341.719672 -277.549081) (xy 341.948252 -277.549081)
			(xy 341.948252 -277.495783) (xy 341.956195 -277.443079) (xy 341.971905 -277.392149) (xy 341.995031 -277.344128)
			(xy 342.025055 -277.300091) (xy 342.061307 -277.26102) (xy 342.102978 -277.227789) (xy 342.149136 -277.20114)
			(xy 342.19875 -277.181668) (xy 342.250712 -277.169808) (xy 342.303862 -277.165825) (xy 342.357012 -277.169808)
			(xy 342.408974 -277.181668) (xy 342.458588 -277.20114) (xy 342.504746 -277.227789) (xy 342.546417 -277.26102)
			(xy 342.582669 -277.300091) (xy 342.612693 -277.344128) (xy 342.635819 -277.392149) (xy 342.651529 -277.443079)
			(xy 342.659472 -277.495783) (xy 342.65997 -277.522432) (xy 342.659472 -277.549081) (xy 342.888052 -277.549081)
			(xy 342.888052 -277.495783) (xy 342.895995 -277.443079) (xy 342.911705 -277.392149) (xy 342.934831 -277.344128)
			(xy 342.964855 -277.300091) (xy 343.001107 -277.26102) (xy 343.042778 -277.227789) (xy 343.088936 -277.20114)
			(xy 343.13855 -277.181668) (xy 343.190512 -277.169808) (xy 343.243662 -277.165825) (xy 343.296812 -277.169808)
			(xy 343.348774 -277.181668) (xy 343.398388 -277.20114) (xy 343.444546 -277.227789) (xy 343.486217 -277.26102)
			(xy 343.522469 -277.300091) (xy 343.552493 -277.344128) (xy 343.575619 -277.392149) (xy 343.591329 -277.443079)
			(xy 343.599272 -277.495783) (xy 343.59977 -277.522432) (xy 343.599272 -277.549081) (xy 343.827852 -277.549081)
			(xy 343.827852 -277.495783) (xy 343.835795 -277.443079) (xy 343.851505 -277.392149) (xy 343.874631 -277.344128)
			(xy 343.904655 -277.300091) (xy 343.940907 -277.26102) (xy 343.982578 -277.227789) (xy 344.028736 -277.20114)
			(xy 344.07835 -277.181668) (xy 344.130312 -277.169808) (xy 344.183462 -277.165825) (xy 344.236612 -277.169808)
			(xy 344.288574 -277.181668) (xy 344.338188 -277.20114) (xy 344.384346 -277.227789) (xy 344.426017 -277.26102)
			(xy 344.462269 -277.300091) (xy 344.492293 -277.344128) (xy 344.515419 -277.392149) (xy 344.531129 -277.443079)
			(xy 344.539072 -277.495783) (xy 344.53957 -277.522432) (xy 344.539072 -277.549081) (xy 344.767652 -277.549081)
			(xy 344.767652 -277.495783) (xy 344.775595 -277.443079) (xy 344.791305 -277.392149) (xy 344.814431 -277.344128)
			(xy 344.844455 -277.300091) (xy 344.880707 -277.26102) (xy 344.922378 -277.227789) (xy 344.968536 -277.20114)
			(xy 345.01815 -277.181668) (xy 345.070112 -277.169808) (xy 345.123262 -277.165825) (xy 345.176412 -277.169808)
			(xy 345.228374 -277.181668) (xy 345.277988 -277.20114) (xy 345.324146 -277.227789) (xy 345.365817 -277.26102)
			(xy 345.402069 -277.300091) (xy 345.432093 -277.344128) (xy 345.455219 -277.392149) (xy 345.470929 -277.443079)
			(xy 345.478872 -277.495783) (xy 345.47937 -277.522432) (xy 345.478872 -277.549081) (xy 345.707452 -277.549081)
			(xy 345.707452 -277.495783) (xy 345.715395 -277.443079) (xy 345.731105 -277.392149) (xy 345.754231 -277.344128)
			(xy 345.784255 -277.300091) (xy 345.820507 -277.26102) (xy 345.862178 -277.227789) (xy 345.908336 -277.20114)
			(xy 345.95795 -277.181668) (xy 346.009912 -277.169808) (xy 346.063062 -277.165825) (xy 346.116212 -277.169808)
			(xy 346.168174 -277.181668) (xy 346.217788 -277.20114) (xy 346.263946 -277.227789) (xy 346.305617 -277.26102)
			(xy 346.341869 -277.300091) (xy 346.371893 -277.344128) (xy 346.395019 -277.392149) (xy 346.410729 -277.443079)
			(xy 346.418672 -277.495783) (xy 346.41917 -277.522432) (xy 346.418672 -277.549081) (xy 346.647252 -277.549081)
			(xy 346.647252 -277.495783) (xy 346.655195 -277.443079) (xy 346.670905 -277.392149) (xy 346.694031 -277.344128)
			(xy 346.724055 -277.300091) (xy 346.760307 -277.26102) (xy 346.801978 -277.227789) (xy 346.848136 -277.20114)
			(xy 346.89775 -277.181668) (xy 346.949712 -277.169808) (xy 347.002862 -277.165825) (xy 347.056012 -277.169808)
			(xy 347.107974 -277.181668) (xy 347.157588 -277.20114) (xy 347.203746 -277.227789) (xy 347.245417 -277.26102)
			(xy 347.281669 -277.300091) (xy 347.311693 -277.344128) (xy 347.334819 -277.392149) (xy 347.350529 -277.443079)
			(xy 347.358472 -277.495783) (xy 347.35897 -277.522432) (xy 347.358472 -277.549081) (xy 347.587052 -277.549081)
			(xy 347.587052 -277.495783) (xy 347.594995 -277.443079) (xy 347.610705 -277.392149) (xy 347.633831 -277.344128)
			(xy 347.663855 -277.300091) (xy 347.700107 -277.26102) (xy 347.741778 -277.227789) (xy 347.787936 -277.20114)
			(xy 347.83755 -277.181668) (xy 347.889512 -277.169808) (xy 347.942662 -277.165825) (xy 347.995812 -277.169808)
			(xy 348.047774 -277.181668) (xy 348.097388 -277.20114) (xy 348.143546 -277.227789) (xy 348.185217 -277.26102)
			(xy 348.221469 -277.300091) (xy 348.251493 -277.344128) (xy 348.274619 -277.392149) (xy 348.290329 -277.443079)
			(xy 348.298272 -277.495783) (xy 348.29877 -277.522432) (xy 348.298272 -277.549081) (xy 348.526852 -277.549081)
			(xy 348.526852 -277.495783) (xy 348.534795 -277.443079) (xy 348.550505 -277.392149) (xy 348.573631 -277.344128)
			(xy 348.603655 -277.300091) (xy 348.639907 -277.26102) (xy 348.681578 -277.227789) (xy 348.727736 -277.20114)
			(xy 348.77735 -277.181668) (xy 348.829312 -277.169808) (xy 348.882462 -277.165825) (xy 348.935612 -277.169808)
			(xy 348.987574 -277.181668) (xy 349.037188 -277.20114) (xy 349.083346 -277.227789) (xy 349.125017 -277.26102)
			(xy 349.161269 -277.300091) (xy 349.191293 -277.344128) (xy 349.214419 -277.392149) (xy 349.230129 -277.443079)
			(xy 349.238072 -277.495783) (xy 349.23857 -277.522432) (xy 349.238072 -277.549081) (xy 349.466906 -277.549081)
			(xy 349.466906 -277.495783) (xy 349.474849 -277.443079) (xy 349.490559 -277.392149) (xy 349.513685 -277.344128)
			(xy 349.543709 -277.300091) (xy 349.579961 -277.26102) (xy 349.621632 -277.227789) (xy 349.66779 -277.20114)
			(xy 349.717404 -277.181668) (xy 349.769366 -277.169808) (xy 349.822516 -277.165825) (xy 349.875666 -277.169808)
			(xy 349.927628 -277.181668) (xy 349.977242 -277.20114) (xy 350.0234 -277.227789) (xy 350.065071 -277.26102)
			(xy 350.101323 -277.300091) (xy 350.131347 -277.344128) (xy 350.154473 -277.392149) (xy 350.170183 -277.443079)
			(xy 350.178126 -277.495783) (xy 350.178624 -277.522432) (xy 350.178126 -277.549081) (xy 350.170183 -277.601785)
			(xy 350.154473 -277.652715) (xy 350.131347 -277.700736) (xy 350.101323 -277.744773) (xy 350.065071 -277.783844)
			(xy 350.0234 -277.817075) (xy 349.977242 -277.843724) (xy 349.927628 -277.863196) (xy 349.875666 -277.875056)
			(xy 349.822516 -277.87904) (xy 349.769366 -277.875056) (xy 349.717404 -277.863196) (xy 349.66779 -277.843724)
			(xy 349.621632 -277.817075) (xy 349.579961 -277.783844) (xy 349.543709 -277.744773) (xy 349.513685 -277.700736)
			(xy 349.490559 -277.652715) (xy 349.474849 -277.601785) (xy 349.466906 -277.549081) (xy 349.238072 -277.549081)
			(xy 349.230129 -277.601785) (xy 349.214419 -277.652715) (xy 349.191293 -277.700736) (xy 349.161269 -277.744773)
			(xy 349.125017 -277.783844) (xy 349.083346 -277.817075) (xy 349.037188 -277.843724) (xy 348.987574 -277.863196)
			(xy 348.935612 -277.875056) (xy 348.882462 -277.87904) (xy 348.829312 -277.875056) (xy 348.77735 -277.863196)
			(xy 348.727736 -277.843724) (xy 348.681578 -277.817075) (xy 348.639907 -277.783844) (xy 348.603655 -277.744773)
			(xy 348.573631 -277.700736) (xy 348.550505 -277.652715) (xy 348.534795 -277.601785) (xy 348.526852 -277.549081)
			(xy 348.298272 -277.549081) (xy 348.290329 -277.601785) (xy 348.274619 -277.652715) (xy 348.251493 -277.700736)
			(xy 348.221469 -277.744773) (xy 348.185217 -277.783844) (xy 348.143546 -277.817075) (xy 348.097388 -277.843724)
			(xy 348.047774 -277.863196) (xy 347.995812 -277.875056) (xy 347.942662 -277.87904) (xy 347.889512 -277.875056)
			(xy 347.83755 -277.863196) (xy 347.787936 -277.843724) (xy 347.741778 -277.817075) (xy 347.700107 -277.783844)
			(xy 347.663855 -277.744773) (xy 347.633831 -277.700736) (xy 347.610705 -277.652715) (xy 347.594995 -277.601785)
			(xy 347.587052 -277.549081) (xy 347.358472 -277.549081) (xy 347.350529 -277.601785) (xy 347.334819 -277.652715)
			(xy 347.311693 -277.700736) (xy 347.281669 -277.744773) (xy 347.245417 -277.783844) (xy 347.203746 -277.817075)
			(xy 347.157588 -277.843724) (xy 347.107974 -277.863196) (xy 347.056012 -277.875056) (xy 347.002862 -277.87904)
			(xy 346.949712 -277.875056) (xy 346.89775 -277.863196) (xy 346.848136 -277.843724) (xy 346.801978 -277.817075)
			(xy 346.760307 -277.783844) (xy 346.724055 -277.744773) (xy 346.694031 -277.700736) (xy 346.670905 -277.652715)
			(xy 346.655195 -277.601785) (xy 346.647252 -277.549081) (xy 346.418672 -277.549081) (xy 346.410729 -277.601785)
			(xy 346.395019 -277.652715) (xy 346.371893 -277.700736) (xy 346.341869 -277.744773) (xy 346.305617 -277.783844)
			(xy 346.263946 -277.817075) (xy 346.217788 -277.843724) (xy 346.168174 -277.863196) (xy 346.116212 -277.875056)
			(xy 346.063062 -277.87904) (xy 346.009912 -277.875056) (xy 345.95795 -277.863196) (xy 345.908336 -277.843724)
			(xy 345.862178 -277.817075) (xy 345.820507 -277.783844) (xy 345.784255 -277.744773) (xy 345.754231 -277.700736)
			(xy 345.731105 -277.652715) (xy 345.715395 -277.601785) (xy 345.707452 -277.549081) (xy 345.478872 -277.549081)
			(xy 345.470929 -277.601785) (xy 345.455219 -277.652715) (xy 345.432093 -277.700736) (xy 345.402069 -277.744773)
			(xy 345.365817 -277.783844) (xy 345.324146 -277.817075) (xy 345.277988 -277.843724) (xy 345.228374 -277.863196)
			(xy 345.176412 -277.875056) (xy 345.123262 -277.87904) (xy 345.070112 -277.875056) (xy 345.01815 -277.863196)
			(xy 344.968536 -277.843724) (xy 344.922378 -277.817075) (xy 344.880707 -277.783844) (xy 344.844455 -277.744773)
			(xy 344.814431 -277.700736) (xy 344.791305 -277.652715) (xy 344.775595 -277.601785) (xy 344.767652 -277.549081)
			(xy 344.539072 -277.549081) (xy 344.531129 -277.601785) (xy 344.515419 -277.652715) (xy 344.492293 -277.700736)
			(xy 344.462269 -277.744773) (xy 344.426017 -277.783844) (xy 344.384346 -277.817075) (xy 344.338188 -277.843724)
			(xy 344.288574 -277.863196) (xy 344.236612 -277.875056) (xy 344.183462 -277.87904) (xy 344.130312 -277.875056)
			(xy 344.07835 -277.863196) (xy 344.028736 -277.843724) (xy 343.982578 -277.817075) (xy 343.940907 -277.783844)
			(xy 343.904655 -277.744773) (xy 343.874631 -277.700736) (xy 343.851505 -277.652715) (xy 343.835795 -277.601785)
			(xy 343.827852 -277.549081) (xy 343.599272 -277.549081) (xy 343.591329 -277.601785) (xy 343.575619 -277.652715)
			(xy 343.552493 -277.700736) (xy 343.522469 -277.744773) (xy 343.486217 -277.783844) (xy 343.444546 -277.817075)
			(xy 343.398388 -277.843724) (xy 343.348774 -277.863196) (xy 343.296812 -277.875056) (xy 343.243662 -277.87904)
			(xy 343.190512 -277.875056) (xy 343.13855 -277.863196) (xy 343.088936 -277.843724) (xy 343.042778 -277.817075)
			(xy 343.001107 -277.783844) (xy 342.964855 -277.744773) (xy 342.934831 -277.700736) (xy 342.911705 -277.652715)
			(xy 342.895995 -277.601785) (xy 342.888052 -277.549081) (xy 342.659472 -277.549081) (xy 342.651529 -277.601785)
			(xy 342.635819 -277.652715) (xy 342.612693 -277.700736) (xy 342.582669 -277.744773) (xy 342.546417 -277.783844)
			(xy 342.504746 -277.817075) (xy 342.458588 -277.843724) (xy 342.408974 -277.863196) (xy 342.357012 -277.875056)
			(xy 342.303862 -277.87904) (xy 342.250712 -277.875056) (xy 342.19875 -277.863196) (xy 342.149136 -277.843724)
			(xy 342.102978 -277.817075) (xy 342.061307 -277.783844) (xy 342.025055 -277.744773) (xy 341.995031 -277.700736)
			(xy 341.971905 -277.652715) (xy 341.956195 -277.601785) (xy 341.948252 -277.549081) (xy 341.719672 -277.549081)
			(xy 341.711729 -277.601785) (xy 341.696019 -277.652715) (xy 341.672893 -277.700736) (xy 341.642869 -277.744773)
			(xy 341.606617 -277.783844) (xy 341.564946 -277.817075) (xy 341.518788 -277.843724) (xy 341.469174 -277.863196)
			(xy 341.417212 -277.875056) (xy 341.364062 -277.87904) (xy 341.310912 -277.875056) (xy 341.25895 -277.863196)
			(xy 341.209336 -277.843724) (xy 341.163178 -277.817075) (xy 341.121507 -277.783844) (xy 341.085255 -277.744773)
			(xy 341.055231 -277.700736) (xy 341.032105 -277.652715) (xy 341.016395 -277.601785) (xy 341.008452 -277.549081)
			(xy 340.779872 -277.549081) (xy 340.771929 -277.601785) (xy 340.756219 -277.652715) (xy 340.733093 -277.700736)
			(xy 340.703069 -277.744773) (xy 340.666817 -277.783844) (xy 340.625146 -277.817075) (xy 340.578988 -277.843724)
			(xy 340.529374 -277.863196) (xy 340.477412 -277.875056) (xy 340.424262 -277.87904) (xy 340.371112 -277.875056)
			(xy 340.31915 -277.863196) (xy 340.269536 -277.843724) (xy 340.223378 -277.817075) (xy 340.181707 -277.783844)
			(xy 340.145455 -277.744773) (xy 340.115431 -277.700736) (xy 340.092305 -277.652715) (xy 340.076595 -277.601785)
			(xy 340.068652 -277.549081) (xy 339.840072 -277.549081) (xy 339.832129 -277.601785) (xy 339.816419 -277.652715)
			(xy 339.793293 -277.700736) (xy 339.763269 -277.744773) (xy 339.727017 -277.783844) (xy 339.685346 -277.817075)
			(xy 339.639188 -277.843724) (xy 339.589574 -277.863196) (xy 339.537612 -277.875056) (xy 339.484462 -277.87904)
			(xy 339.431312 -277.875056) (xy 339.37935 -277.863196) (xy 339.329736 -277.843724) (xy 339.283578 -277.817075)
			(xy 339.241907 -277.783844) (xy 339.205655 -277.744773) (xy 339.175631 -277.700736) (xy 339.152505 -277.652715)
			(xy 339.136795 -277.601785) (xy 339.128852 -277.549081) (xy 338.900526 -277.549081) (xy 338.892583 -277.601785)
			(xy 338.876873 -277.652715) (xy 338.853747 -277.700736) (xy 338.823723 -277.744773) (xy 338.787471 -277.783844)
			(xy 338.7458 -277.817075) (xy 338.699642 -277.843724) (xy 338.650028 -277.863196) (xy 338.598066 -277.875056)
			(xy 338.544916 -277.87904) (xy 338.491766 -277.875056) (xy 338.439804 -277.863196) (xy 338.39019 -277.843724)
			(xy 338.344032 -277.817075) (xy 338.302361 -277.783844) (xy 338.266109 -277.744773) (xy 338.236085 -277.700736)
			(xy 338.212959 -277.652715) (xy 338.197249 -277.601785) (xy 338.189306 -277.549081) (xy 337.960472 -277.549081)
			(xy 337.952529 -277.601785) (xy 337.936819 -277.652715) (xy 337.913693 -277.700736) (xy 337.883669 -277.744773)
			(xy 337.847417 -277.783844) (xy 337.805746 -277.817075) (xy 337.759588 -277.843724) (xy 337.709974 -277.863196)
			(xy 337.658012 -277.875056) (xy 337.604862 -277.87904) (xy 337.551712 -277.875056) (xy 337.49975 -277.863196)
			(xy 337.450136 -277.843724) (xy 337.403978 -277.817075) (xy 337.362307 -277.783844) (xy 337.326055 -277.744773)
			(xy 337.296031 -277.700736) (xy 337.272905 -277.652715) (xy 337.257195 -277.601785) (xy 337.249252 -277.549081)
			(xy 337.020423 -277.549081) (xy 337.020418 -277.549335) (xy 337.012475 -277.602039) (xy 336.996765 -277.652969)
			(xy 336.973639 -277.70099) (xy 336.943615 -277.745027) (xy 336.907363 -277.784098) (xy 336.865692 -277.817329)
			(xy 336.819534 -277.843978) (xy 336.76992 -277.86345) (xy 336.717958 -277.87531) (xy 336.664808 -277.879294)
			(xy 336.611658 -277.87531) (xy 336.559696 -277.86345) (xy 336.510082 -277.843978) (xy 336.463924 -277.817329)
			(xy 336.422253 -277.784098) (xy 336.386001 -277.745027) (xy 336.355977 -277.70099) (xy 336.332851 -277.652969)
			(xy 336.317141 -277.602039) (xy 336.309198 -277.549335) (xy 335.424534 -277.549335) (xy 335.396372 -277.565594)
			(xy 335.346758 -277.585066) (xy 335.294796 -277.596926) (xy 335.241646 -277.60091) (xy 335.188496 -277.596926)
			(xy 335.136534 -277.585066) (xy 335.08692 -277.565594) (xy 335.040762 -277.538945) (xy 334.999091 -277.505714)
			(xy 334.962839 -277.466643) (xy 334.932815 -277.422606) (xy 334.909689 -277.374585) (xy 334.893979 -277.323655)
			(xy 334.886036 -277.270951) (xy 333.466948 -277.270951) (xy 333.466948 -278.336502) (xy 333.971649 -278.336502)
			(xy 333.975679 -278.284004) (xy 333.987676 -278.232736) (xy 334.007359 -278.183901) (xy 334.034265 -278.138642)
			(xy 334.067765 -278.098021) (xy 334.107073 -278.06299) (xy 334.151268 -278.03437) (xy 334.199313 -278.012831)
			(xy 334.250084 -277.998879) (xy 334.302389 -277.992841) (xy 334.355003 -277.994858) (xy 334.406693 -278.004882)
			(xy 334.456246 -278.02268) (xy 334.502502 -278.047833) (xy 334.544376 -278.079752) (xy 334.580888 -278.11769)
			(xy 334.61118 -278.160756) (xy 334.634543 -278.207941) (xy 334.650429 -278.25814) (xy 334.658466 -278.310176)
			(xy 334.65897 -278.336502) (xy 334.658466 -278.362828) (xy 334.658416 -278.363151) (xy 338.658952 -278.363151)
			(xy 338.658952 -278.309853) (xy 338.666895 -278.257149) (xy 338.682605 -278.206219) (xy 338.705731 -278.158198)
			(xy 338.735755 -278.114161) (xy 338.772007 -278.07509) (xy 338.813678 -278.041859) (xy 338.859836 -278.01521)
			(xy 338.90945 -277.995738) (xy 338.961412 -277.983878) (xy 339.014562 -277.979895) (xy 339.067712 -277.983878)
			(xy 339.119674 -277.995738) (xy 339.169288 -278.01521) (xy 339.215446 -278.041859) (xy 339.257117 -278.07509)
			(xy 339.293369 -278.114161) (xy 339.323393 -278.158198) (xy 339.346519 -278.206219) (xy 339.362229 -278.257149)
			(xy 339.370172 -278.309853) (xy 339.37067 -278.336502) (xy 339.370172 -278.363151) (xy 339.599006 -278.363151)
			(xy 339.599006 -278.309853) (xy 339.606949 -278.257149) (xy 339.622659 -278.206219) (xy 339.645785 -278.158198)
			(xy 339.675809 -278.114161) (xy 339.712061 -278.07509) (xy 339.753732 -278.041859) (xy 339.79989 -278.01521)
			(xy 339.849504 -277.995738) (xy 339.901466 -277.983878) (xy 339.954616 -277.979895) (xy 340.007766 -277.983878)
			(xy 340.059728 -277.995738) (xy 340.109342 -278.01521) (xy 340.1555 -278.041859) (xy 340.197171 -278.07509)
			(xy 340.233423 -278.114161) (xy 340.263447 -278.158198) (xy 340.286573 -278.206219) (xy 340.302283 -278.257149)
			(xy 340.310226 -278.309853) (xy 340.310724 -278.336502) (xy 340.310226 -278.363151) (xy 340.538806 -278.363151)
			(xy 340.538806 -278.309853) (xy 340.546749 -278.257149) (xy 340.562459 -278.206219) (xy 340.585585 -278.158198)
			(xy 340.615609 -278.114161) (xy 340.651861 -278.07509) (xy 340.693532 -278.041859) (xy 340.73969 -278.01521)
			(xy 340.789304 -277.995738) (xy 340.841266 -277.983878) (xy 340.894416 -277.979895) (xy 340.947566 -277.983878)
			(xy 340.999528 -277.995738) (xy 341.049142 -278.01521) (xy 341.0953 -278.041859) (xy 341.136971 -278.07509)
			(xy 341.173223 -278.114161) (xy 341.203247 -278.158198) (xy 341.226373 -278.206219) (xy 341.242083 -278.257149)
			(xy 341.250026 -278.309853) (xy 341.250524 -278.336502) (xy 341.250026 -278.363151) (xy 341.478606 -278.363151)
			(xy 341.478606 -278.309853) (xy 341.486549 -278.257149) (xy 341.502259 -278.206219) (xy 341.525385 -278.158198)
			(xy 341.555409 -278.114161) (xy 341.591661 -278.07509) (xy 341.633332 -278.041859) (xy 341.67949 -278.01521)
			(xy 341.729104 -277.995738) (xy 341.781066 -277.983878) (xy 341.834216 -277.979895) (xy 341.887366 -277.983878)
			(xy 341.939328 -277.995738) (xy 341.988942 -278.01521) (xy 342.0351 -278.041859) (xy 342.076771 -278.07509)
			(xy 342.113023 -278.114161) (xy 342.143047 -278.158198) (xy 342.166173 -278.206219) (xy 342.181883 -278.257149)
			(xy 342.189826 -278.309853) (xy 342.190324 -278.336502) (xy 342.189826 -278.363151) (xy 342.418406 -278.363151)
			(xy 342.418406 -278.309853) (xy 342.426349 -278.257149) (xy 342.442059 -278.206219) (xy 342.465185 -278.158198)
			(xy 342.495209 -278.114161) (xy 342.531461 -278.07509) (xy 342.573132 -278.041859) (xy 342.61929 -278.01521)
			(xy 342.668904 -277.995738) (xy 342.720866 -277.983878) (xy 342.774016 -277.979895) (xy 342.827166 -277.983878)
			(xy 342.879128 -277.995738) (xy 342.928742 -278.01521) (xy 342.9749 -278.041859) (xy 343.016571 -278.07509)
			(xy 343.052823 -278.114161) (xy 343.082847 -278.158198) (xy 343.105973 -278.206219) (xy 343.121683 -278.257149)
			(xy 343.129626 -278.309853) (xy 343.130124 -278.336502) (xy 343.129626 -278.363151) (xy 345.237806 -278.363151)
			(xy 345.237806 -278.309853) (xy 345.245749 -278.257149) (xy 345.261459 -278.206219) (xy 345.284585 -278.158198)
			(xy 345.314609 -278.114161) (xy 345.350861 -278.07509) (xy 345.392532 -278.041859) (xy 345.43869 -278.01521)
			(xy 345.488304 -277.995738) (xy 345.540266 -277.983878) (xy 345.593416 -277.979895) (xy 345.646566 -277.983878)
			(xy 345.698528 -277.995738) (xy 345.748142 -278.01521) (xy 345.7943 -278.041859) (xy 345.835971 -278.07509)
			(xy 345.872223 -278.114161) (xy 345.902247 -278.158198) (xy 345.925373 -278.206219) (xy 345.941083 -278.257149)
			(xy 345.949026 -278.309853) (xy 345.949524 -278.336502) (xy 345.949026 -278.363151) (xy 346.177606 -278.363151)
			(xy 346.177606 -278.309853) (xy 346.185549 -278.257149) (xy 346.201259 -278.206219) (xy 346.224385 -278.158198)
			(xy 346.254409 -278.114161) (xy 346.290661 -278.07509) (xy 346.332332 -278.041859) (xy 346.37849 -278.01521)
			(xy 346.428104 -277.995738) (xy 346.480066 -277.983878) (xy 346.533216 -277.979895) (xy 346.586366 -277.983878)
			(xy 346.638328 -277.995738) (xy 346.687942 -278.01521) (xy 346.7341 -278.041859) (xy 346.775771 -278.07509)
			(xy 346.812023 -278.114161) (xy 346.842047 -278.158198) (xy 346.865173 -278.206219) (xy 346.880883 -278.257149)
			(xy 346.888826 -278.309853) (xy 346.889324 -278.336502) (xy 346.888826 -278.363151) (xy 347.117406 -278.363151)
			(xy 347.117406 -278.309853) (xy 347.125349 -278.257149) (xy 347.141059 -278.206219) (xy 347.164185 -278.158198)
			(xy 347.194209 -278.114161) (xy 347.230461 -278.07509) (xy 347.272132 -278.041859) (xy 347.31829 -278.01521)
			(xy 347.367904 -277.995738) (xy 347.419866 -277.983878) (xy 347.473016 -277.979895) (xy 347.526166 -277.983878)
			(xy 347.578128 -277.995738) (xy 347.627742 -278.01521) (xy 347.6739 -278.041859) (xy 347.715571 -278.07509)
			(xy 347.751823 -278.114161) (xy 347.781847 -278.158198) (xy 347.804973 -278.206219) (xy 347.820683 -278.257149)
			(xy 347.828626 -278.309853) (xy 347.829124 -278.336502) (xy 347.828626 -278.363151) (xy 348.057206 -278.363151)
			(xy 348.057206 -278.309853) (xy 348.065149 -278.257149) (xy 348.080859 -278.206219) (xy 348.103985 -278.158198)
			(xy 348.134009 -278.114161) (xy 348.170261 -278.07509) (xy 348.211932 -278.041859) (xy 348.25809 -278.01521)
			(xy 348.307704 -277.995738) (xy 348.359666 -277.983878) (xy 348.412816 -277.979895) (xy 348.465966 -277.983878)
			(xy 348.517928 -277.995738) (xy 348.567542 -278.01521) (xy 348.6137 -278.041859) (xy 348.655371 -278.07509)
			(xy 348.691623 -278.114161) (xy 348.721647 -278.158198) (xy 348.744773 -278.206219) (xy 348.760483 -278.257149)
			(xy 348.768426 -278.309853) (xy 348.768924 -278.336502) (xy 348.768426 -278.363151) (xy 348.996752 -278.363151)
			(xy 348.996752 -278.309853) (xy 349.004695 -278.257149) (xy 349.020405 -278.206219) (xy 349.043531 -278.158198)
			(xy 349.073555 -278.114161) (xy 349.109807 -278.07509) (xy 349.151478 -278.041859) (xy 349.197636 -278.01521)
			(xy 349.24725 -277.995738) (xy 349.299212 -277.983878) (xy 349.352362 -277.979895) (xy 349.405512 -277.983878)
			(xy 349.457474 -277.995738) (xy 349.507088 -278.01521) (xy 349.553246 -278.041859) (xy 349.594917 -278.07509)
			(xy 349.631169 -278.114161) (xy 349.661193 -278.158198) (xy 349.684319 -278.206219) (xy 349.700029 -278.257149)
			(xy 349.707972 -278.309853) (xy 349.70847 -278.336502) (xy 349.707972 -278.363151) (xy 349.936806 -278.363151)
			(xy 349.936806 -278.309853) (xy 349.944749 -278.257149) (xy 349.960459 -278.206219) (xy 349.983585 -278.158198)
			(xy 350.013609 -278.114161) (xy 350.049861 -278.07509) (xy 350.091532 -278.041859) (xy 350.13769 -278.01521)
			(xy 350.187304 -277.995738) (xy 350.239266 -277.983878) (xy 350.292416 -277.979895) (xy 350.345566 -277.983878)
			(xy 350.397528 -277.995738) (xy 350.447142 -278.01521) (xy 350.4933 -278.041859) (xy 350.534971 -278.07509)
			(xy 350.571223 -278.114161) (xy 350.601247 -278.158198) (xy 350.624373 -278.206219) (xy 350.640083 -278.257149)
			(xy 350.648026 -278.309853) (xy 350.648524 -278.336502) (xy 350.648026 -278.363151) (xy 350.876606 -278.363151)
			(xy 350.876606 -278.309853) (xy 350.884549 -278.257149) (xy 350.900259 -278.206219) (xy 350.923385 -278.158198)
			(xy 350.953409 -278.114161) (xy 350.989661 -278.07509) (xy 351.031332 -278.041859) (xy 351.07749 -278.01521)
			(xy 351.127104 -277.995738) (xy 351.179066 -277.983878) (xy 351.232216 -277.979895) (xy 351.285366 -277.983878)
			(xy 351.337328 -277.995738) (xy 351.386942 -278.01521) (xy 351.4331 -278.041859) (xy 351.474771 -278.07509)
			(xy 351.511023 -278.114161) (xy 351.541047 -278.158198) (xy 351.564173 -278.206219) (xy 351.579883 -278.257149)
			(xy 351.587826 -278.309853) (xy 351.588324 -278.336502) (xy 351.587826 -278.363151) (xy 351.816406 -278.363151)
			(xy 351.816406 -278.309853) (xy 351.824349 -278.257149) (xy 351.840059 -278.206219) (xy 351.863185 -278.158198)
			(xy 351.893209 -278.114161) (xy 351.929461 -278.07509) (xy 351.971132 -278.041859) (xy 352.01729 -278.01521)
			(xy 352.066904 -277.995738) (xy 352.118866 -277.983878) (xy 352.172016 -277.979895) (xy 352.225166 -277.983878)
			(xy 352.277128 -277.995738) (xy 352.326742 -278.01521) (xy 352.3729 -278.041859) (xy 352.414571 -278.07509)
			(xy 352.450823 -278.114161) (xy 352.480847 -278.158198) (xy 352.503973 -278.206219) (xy 352.519683 -278.257149)
			(xy 352.527626 -278.309853) (xy 352.528124 -278.336502) (xy 352.527626 -278.363151) (xy 352.755952 -278.363151)
			(xy 352.755952 -278.309853) (xy 352.763895 -278.257149) (xy 352.779605 -278.206219) (xy 352.802731 -278.158198)
			(xy 352.832755 -278.114161) (xy 352.869007 -278.07509) (xy 352.910678 -278.041859) (xy 352.956836 -278.01521)
			(xy 353.00645 -277.995738) (xy 353.058412 -277.983878) (xy 353.111562 -277.979895) (xy 353.164712 -277.983878)
			(xy 353.216674 -277.995738) (xy 353.266288 -278.01521) (xy 353.312446 -278.041859) (xy 353.354117 -278.07509)
			(xy 353.390369 -278.114161) (xy 353.420393 -278.158198) (xy 353.443519 -278.206219) (xy 353.459229 -278.257149)
			(xy 353.467172 -278.309853) (xy 353.46767 -278.336502) (xy 353.467172 -278.363151) (xy 354.635806 -278.363151)
			(xy 354.635806 -278.309853) (xy 354.643749 -278.257149) (xy 354.659459 -278.206219) (xy 354.682585 -278.158198)
			(xy 354.712609 -278.114161) (xy 354.748861 -278.07509) (xy 354.790532 -278.041859) (xy 354.83669 -278.01521)
			(xy 354.886304 -277.995738) (xy 354.938266 -277.983878) (xy 354.991416 -277.979895) (xy 355.044566 -277.983878)
			(xy 355.096528 -277.995738) (xy 355.146142 -278.01521) (xy 355.1923 -278.041859) (xy 355.233971 -278.07509)
			(xy 355.270223 -278.114161) (xy 355.300247 -278.158198) (xy 355.323373 -278.206219) (xy 355.339083 -278.257149)
			(xy 355.347026 -278.309853) (xy 355.347524 -278.336502) (xy 355.347026 -278.363151) (xy 355.339083 -278.415855)
			(xy 355.323373 -278.466785) (xy 355.300247 -278.514806) (xy 355.270223 -278.558843) (xy 355.233971 -278.597914)
			(xy 355.1923 -278.631145) (xy 355.146142 -278.657794) (xy 355.096528 -278.677266) (xy 355.044566 -278.689126)
			(xy 354.991416 -278.69311) (xy 354.938266 -278.689126) (xy 354.886304 -278.677266) (xy 354.83669 -278.657794)
			(xy 354.790532 -278.631145) (xy 354.748861 -278.597914) (xy 354.712609 -278.558843) (xy 354.682585 -278.514806)
			(xy 354.659459 -278.466785) (xy 354.643749 -278.415855) (xy 354.635806 -278.363151) (xy 353.467172 -278.363151)
			(xy 353.459229 -278.415855) (xy 353.443519 -278.466785) (xy 353.420393 -278.514806) (xy 353.390369 -278.558843)
			(xy 353.354117 -278.597914) (xy 353.312446 -278.631145) (xy 353.266288 -278.657794) (xy 353.216674 -278.677266)
			(xy 353.164712 -278.689126) (xy 353.111562 -278.69311) (xy 353.058412 -278.689126) (xy 353.00645 -278.677266)
			(xy 352.956836 -278.657794) (xy 352.910678 -278.631145) (xy 352.869007 -278.597914) (xy 352.832755 -278.558843)
			(xy 352.802731 -278.514806) (xy 352.779605 -278.466785) (xy 352.763895 -278.415855) (xy 352.755952 -278.363151)
			(xy 352.527626 -278.363151) (xy 352.519683 -278.415855) (xy 352.503973 -278.466785) (xy 352.480847 -278.514806)
			(xy 352.450823 -278.558843) (xy 352.414571 -278.597914) (xy 352.3729 -278.631145) (xy 352.326742 -278.657794)
			(xy 352.277128 -278.677266) (xy 352.225166 -278.689126) (xy 352.172016 -278.69311) (xy 352.118866 -278.689126)
			(xy 352.066904 -278.677266) (xy 352.01729 -278.657794) (xy 351.971132 -278.631145) (xy 351.929461 -278.597914)
			(xy 351.893209 -278.558843) (xy 351.863185 -278.514806) (xy 351.840059 -278.466785) (xy 351.824349 -278.415855)
			(xy 351.816406 -278.363151) (xy 351.587826 -278.363151) (xy 351.579883 -278.415855) (xy 351.564173 -278.466785)
			(xy 351.541047 -278.514806) (xy 351.511023 -278.558843) (xy 351.474771 -278.597914) (xy 351.4331 -278.631145)
			(xy 351.386942 -278.657794) (xy 351.337328 -278.677266) (xy 351.285366 -278.689126) (xy 351.232216 -278.69311)
			(xy 351.179066 -278.689126) (xy 351.127104 -278.677266) (xy 351.07749 -278.657794) (xy 351.031332 -278.631145)
			(xy 350.989661 -278.597914) (xy 350.953409 -278.558843) (xy 350.923385 -278.514806) (xy 350.900259 -278.466785)
			(xy 350.884549 -278.415855) (xy 350.876606 -278.363151) (xy 350.648026 -278.363151) (xy 350.640083 -278.415855)
			(xy 350.624373 -278.466785) (xy 350.601247 -278.514806) (xy 350.571223 -278.558843) (xy 350.534971 -278.597914)
			(xy 350.4933 -278.631145) (xy 350.447142 -278.657794) (xy 350.397528 -278.677266) (xy 350.345566 -278.689126)
			(xy 350.292416 -278.69311) (xy 350.239266 -278.689126) (xy 350.187304 -278.677266) (xy 350.13769 -278.657794)
			(xy 350.091532 -278.631145) (xy 350.049861 -278.597914) (xy 350.013609 -278.558843) (xy 349.983585 -278.514806)
			(xy 349.960459 -278.466785) (xy 349.944749 -278.415855) (xy 349.936806 -278.363151) (xy 349.707972 -278.363151)
			(xy 349.700029 -278.415855) (xy 349.684319 -278.466785) (xy 349.661193 -278.514806) (xy 349.631169 -278.558843)
			(xy 349.594917 -278.597914) (xy 349.553246 -278.631145) (xy 349.507088 -278.657794) (xy 349.457474 -278.677266)
			(xy 349.405512 -278.689126) (xy 349.352362 -278.69311) (xy 349.299212 -278.689126) (xy 349.24725 -278.677266)
			(xy 349.197636 -278.657794) (xy 349.151478 -278.631145) (xy 349.109807 -278.597914) (xy 349.073555 -278.558843)
			(xy 349.043531 -278.514806) (xy 349.020405 -278.466785) (xy 349.004695 -278.415855) (xy 348.996752 -278.363151)
			(xy 348.768426 -278.363151) (xy 348.760483 -278.415855) (xy 348.744773 -278.466785) (xy 348.721647 -278.514806)
			(xy 348.691623 -278.558843) (xy 348.655371 -278.597914) (xy 348.6137 -278.631145) (xy 348.567542 -278.657794)
			(xy 348.517928 -278.677266) (xy 348.465966 -278.689126) (xy 348.412816 -278.69311) (xy 348.359666 -278.689126)
			(xy 348.307704 -278.677266) (xy 348.25809 -278.657794) (xy 348.211932 -278.631145) (xy 348.170261 -278.597914)
			(xy 348.134009 -278.558843) (xy 348.103985 -278.514806) (xy 348.080859 -278.466785) (xy 348.065149 -278.415855)
			(xy 348.057206 -278.363151) (xy 347.828626 -278.363151) (xy 347.820683 -278.415855) (xy 347.804973 -278.466785)
			(xy 347.781847 -278.514806) (xy 347.751823 -278.558843) (xy 347.715571 -278.597914) (xy 347.6739 -278.631145)
			(xy 347.627742 -278.657794) (xy 347.578128 -278.677266) (xy 347.526166 -278.689126) (xy 347.473016 -278.69311)
			(xy 347.419866 -278.689126) (xy 347.367904 -278.677266) (xy 347.31829 -278.657794) (xy 347.272132 -278.631145)
			(xy 347.230461 -278.597914) (xy 347.194209 -278.558843) (xy 347.164185 -278.514806) (xy 347.141059 -278.466785)
			(xy 347.125349 -278.415855) (xy 347.117406 -278.363151) (xy 346.888826 -278.363151) (xy 346.880883 -278.415855)
			(xy 346.865173 -278.466785) (xy 346.842047 -278.514806) (xy 346.812023 -278.558843) (xy 346.775771 -278.597914)
			(xy 346.7341 -278.631145) (xy 346.687942 -278.657794) (xy 346.638328 -278.677266) (xy 346.586366 -278.689126)
			(xy 346.533216 -278.69311) (xy 346.480066 -278.689126) (xy 346.428104 -278.677266) (xy 346.37849 -278.657794)
			(xy 346.332332 -278.631145) (xy 346.290661 -278.597914) (xy 346.254409 -278.558843) (xy 346.224385 -278.514806)
			(xy 346.201259 -278.466785) (xy 346.185549 -278.415855) (xy 346.177606 -278.363151) (xy 345.949026 -278.363151)
			(xy 345.941083 -278.415855) (xy 345.925373 -278.466785) (xy 345.902247 -278.514806) (xy 345.872223 -278.558843)
			(xy 345.835971 -278.597914) (xy 345.7943 -278.631145) (xy 345.748142 -278.657794) (xy 345.698528 -278.677266)
			(xy 345.646566 -278.689126) (xy 345.593416 -278.69311) (xy 345.540266 -278.689126) (xy 345.488304 -278.677266)
			(xy 345.43869 -278.657794) (xy 345.392532 -278.631145) (xy 345.350861 -278.597914) (xy 345.314609 -278.558843)
			(xy 345.284585 -278.514806) (xy 345.261459 -278.466785) (xy 345.245749 -278.415855) (xy 345.237806 -278.363151)
			(xy 343.129626 -278.363151) (xy 343.121683 -278.415855) (xy 343.105973 -278.466785) (xy 343.082847 -278.514806)
			(xy 343.052823 -278.558843) (xy 343.016571 -278.597914) (xy 342.9749 -278.631145) (xy 342.928742 -278.657794)
			(xy 342.879128 -278.677266) (xy 342.827166 -278.689126) (xy 342.774016 -278.69311) (xy 342.720866 -278.689126)
			(xy 342.668904 -278.677266) (xy 342.61929 -278.657794) (xy 342.573132 -278.631145) (xy 342.531461 -278.597914)
			(xy 342.495209 -278.558843) (xy 342.465185 -278.514806) (xy 342.442059 -278.466785) (xy 342.426349 -278.415855)
			(xy 342.418406 -278.363151) (xy 342.189826 -278.363151) (xy 342.181883 -278.415855) (xy 342.166173 -278.466785)
			(xy 342.143047 -278.514806) (xy 342.113023 -278.558843) (xy 342.076771 -278.597914) (xy 342.0351 -278.631145)
			(xy 341.988942 -278.657794) (xy 341.939328 -278.677266) (xy 341.887366 -278.689126) (xy 341.834216 -278.69311)
			(xy 341.781066 -278.689126) (xy 341.729104 -278.677266) (xy 341.67949 -278.657794) (xy 341.633332 -278.631145)
			(xy 341.591661 -278.597914) (xy 341.555409 -278.558843) (xy 341.525385 -278.514806) (xy 341.502259 -278.466785)
			(xy 341.486549 -278.415855) (xy 341.478606 -278.363151) (xy 341.250026 -278.363151) (xy 341.242083 -278.415855)
			(xy 341.226373 -278.466785) (xy 341.203247 -278.514806) (xy 341.173223 -278.558843) (xy 341.136971 -278.597914)
			(xy 341.0953 -278.631145) (xy 341.049142 -278.657794) (xy 340.999528 -278.677266) (xy 340.947566 -278.689126)
			(xy 340.894416 -278.69311) (xy 340.841266 -278.689126) (xy 340.789304 -278.677266) (xy 340.73969 -278.657794)
			(xy 340.693532 -278.631145) (xy 340.651861 -278.597914) (xy 340.615609 -278.558843) (xy 340.585585 -278.514806)
			(xy 340.562459 -278.466785) (xy 340.546749 -278.415855) (xy 340.538806 -278.363151) (xy 340.310226 -278.363151)
			(xy 340.302283 -278.415855) (xy 340.286573 -278.466785) (xy 340.263447 -278.514806) (xy 340.233423 -278.558843)
			(xy 340.197171 -278.597914) (xy 340.1555 -278.631145) (xy 340.109342 -278.657794) (xy 340.059728 -278.677266)
			(xy 340.007766 -278.689126) (xy 339.954616 -278.69311) (xy 339.901466 -278.689126) (xy 339.849504 -278.677266)
			(xy 339.79989 -278.657794) (xy 339.753732 -278.631145) (xy 339.712061 -278.597914) (xy 339.675809 -278.558843)
			(xy 339.645785 -278.514806) (xy 339.622659 -278.466785) (xy 339.606949 -278.415855) (xy 339.599006 -278.363151)
			(xy 339.370172 -278.363151) (xy 339.362229 -278.415855) (xy 339.346519 -278.466785) (xy 339.323393 -278.514806)
			(xy 339.293369 -278.558843) (xy 339.257117 -278.597914) (xy 339.215446 -278.631145) (xy 339.169288 -278.657794)
			(xy 339.119674 -278.677266) (xy 339.067712 -278.689126) (xy 339.014562 -278.69311) (xy 338.961412 -278.689126)
			(xy 338.90945 -278.677266) (xy 338.859836 -278.657794) (xy 338.813678 -278.631145) (xy 338.772007 -278.597914)
			(xy 338.735755 -278.558843) (xy 338.705731 -278.514806) (xy 338.682605 -278.466785) (xy 338.666895 -278.415855)
			(xy 338.658952 -278.363151) (xy 334.658416 -278.363151) (xy 334.650429 -278.414864) (xy 334.634543 -278.465063)
			(xy 334.61118 -278.512248) (xy 334.580888 -278.555314) (xy 334.544376 -278.593252) (xy 334.502502 -278.625171)
			(xy 334.456246 -278.650324) (xy 334.406693 -278.668122) (xy 334.355003 -278.678146) (xy 334.302389 -278.680163)
			(xy 334.250084 -278.674125) (xy 334.199313 -278.660173) (xy 334.151268 -278.638634) (xy 334.107073 -278.610014)
			(xy 334.067765 -278.574983) (xy 334.034265 -278.534362) (xy 334.007359 -278.489103) (xy 333.987676 -278.440268)
			(xy 333.975679 -278.389) (xy 333.971649 -278.336502) (xy 333.466948 -278.336502) (xy 333.466948 -278.64308)
			(xy 333.46771 -278.647398) (xy 333.470438 -278.663259) (xy 333.473364 -278.695313) (xy 333.473552 -278.711406)
			(xy 333.47336 -278.727499) (xy 333.470432 -278.759552) (xy 333.46771 -278.775414) (xy 333.466948 -278.779732)
			(xy 333.466948 -279.176967) (xy 336.309452 -279.176967) (xy 336.309452 -279.123669) (xy 336.317395 -279.070965)
			(xy 336.333105 -279.020035) (xy 336.356231 -278.972014) (xy 336.386255 -278.927977) (xy 336.422507 -278.888906)
			(xy 336.464178 -278.855675) (xy 336.510336 -278.829026) (xy 336.55995 -278.809554) (xy 336.611912 -278.797694)
			(xy 336.665062 -278.793711) (xy 336.718212 -278.797694) (xy 336.770174 -278.809554) (xy 336.819788 -278.829026)
			(xy 336.865946 -278.855675) (xy 336.907617 -278.888906) (xy 336.943869 -278.927977) (xy 336.973893 -278.972014)
			(xy 336.997019 -279.020035) (xy 337.012729 -279.070965) (xy 337.020672 -279.123669) (xy 337.02117 -279.150318)
			(xy 337.020672 -279.176967) (xy 337.249252 -279.176967) (xy 337.249252 -279.123669) (xy 337.257195 -279.070965)
			(xy 337.272905 -279.020035) (xy 337.296031 -278.972014) (xy 337.326055 -278.927977) (xy 337.362307 -278.888906)
			(xy 337.403978 -278.855675) (xy 337.450136 -278.829026) (xy 337.49975 -278.809554) (xy 337.551712 -278.797694)
			(xy 337.604862 -278.793711) (xy 337.658012 -278.797694) (xy 337.709974 -278.809554) (xy 337.759588 -278.829026)
			(xy 337.805746 -278.855675) (xy 337.847417 -278.888906) (xy 337.883669 -278.927977) (xy 337.913693 -278.972014)
			(xy 337.936819 -279.020035) (xy 337.952529 -279.070965) (xy 337.960472 -279.123669) (xy 337.96097 -279.150318)
			(xy 337.960472 -279.176967) (xy 338.189052 -279.176967) (xy 338.189052 -279.123669) (xy 338.196995 -279.070965)
			(xy 338.212705 -279.020035) (xy 338.235831 -278.972014) (xy 338.265855 -278.927977) (xy 338.302107 -278.888906)
			(xy 338.343778 -278.855675) (xy 338.389936 -278.829026) (xy 338.43955 -278.809554) (xy 338.491512 -278.797694)
			(xy 338.544662 -278.793711) (xy 338.597812 -278.797694) (xy 338.649774 -278.809554) (xy 338.699388 -278.829026)
			(xy 338.745546 -278.855675) (xy 338.787217 -278.888906) (xy 338.823469 -278.927977) (xy 338.853493 -278.972014)
			(xy 338.876619 -279.020035) (xy 338.892329 -279.070965) (xy 338.900272 -279.123669) (xy 338.90077 -279.150318)
			(xy 338.900272 -279.176967) (xy 339.128852 -279.176967) (xy 339.128852 -279.123669) (xy 339.136795 -279.070965)
			(xy 339.152505 -279.020035) (xy 339.175631 -278.972014) (xy 339.205655 -278.927977) (xy 339.241907 -278.888906)
			(xy 339.283578 -278.855675) (xy 339.329736 -278.829026) (xy 339.37935 -278.809554) (xy 339.431312 -278.797694)
			(xy 339.484462 -278.793711) (xy 339.537612 -278.797694) (xy 339.589574 -278.809554) (xy 339.639188 -278.829026)
			(xy 339.685346 -278.855675) (xy 339.727017 -278.888906) (xy 339.763269 -278.927977) (xy 339.793293 -278.972014)
			(xy 339.816419 -279.020035) (xy 339.832129 -279.070965) (xy 339.840072 -279.123669) (xy 339.84057 -279.150318)
			(xy 339.840072 -279.176967) (xy 340.068652 -279.176967) (xy 340.068652 -279.123669) (xy 340.076595 -279.070965)
			(xy 340.092305 -279.020035) (xy 340.115431 -278.972014) (xy 340.145455 -278.927977) (xy 340.181707 -278.888906)
			(xy 340.223378 -278.855675) (xy 340.269536 -278.829026) (xy 340.31915 -278.809554) (xy 340.371112 -278.797694)
			(xy 340.424262 -278.793711) (xy 340.477412 -278.797694) (xy 340.529374 -278.809554) (xy 340.578988 -278.829026)
			(xy 340.625146 -278.855675) (xy 340.666817 -278.888906) (xy 340.703069 -278.927977) (xy 340.733093 -278.972014)
			(xy 340.756219 -279.020035) (xy 340.771929 -279.070965) (xy 340.779872 -279.123669) (xy 340.78037 -279.150318)
			(xy 340.779872 -279.176967) (xy 341.008452 -279.176967) (xy 341.008452 -279.123669) (xy 341.016395 -279.070965)
			(xy 341.032105 -279.020035) (xy 341.055231 -278.972014) (xy 341.085255 -278.927977) (xy 341.121507 -278.888906)
			(xy 341.163178 -278.855675) (xy 341.209336 -278.829026) (xy 341.25895 -278.809554) (xy 341.310912 -278.797694)
			(xy 341.364062 -278.793711) (xy 341.417212 -278.797694) (xy 341.469174 -278.809554) (xy 341.518788 -278.829026)
			(xy 341.564946 -278.855675) (xy 341.606617 -278.888906) (xy 341.642869 -278.927977) (xy 341.672893 -278.972014)
			(xy 341.696019 -279.020035) (xy 341.711729 -279.070965) (xy 341.719672 -279.123669) (xy 341.72017 -279.150318)
			(xy 341.719672 -279.176967) (xy 341.948506 -279.176967) (xy 341.948506 -279.123669) (xy 341.956449 -279.070965)
			(xy 341.972159 -279.020035) (xy 341.995285 -278.972014) (xy 342.025309 -278.927977) (xy 342.061561 -278.888906)
			(xy 342.103232 -278.855675) (xy 342.14939 -278.829026) (xy 342.199004 -278.809554) (xy 342.250966 -278.797694)
			(xy 342.304116 -278.793711) (xy 342.357266 -278.797694) (xy 342.409228 -278.809554) (xy 342.458842 -278.829026)
			(xy 342.505 -278.855675) (xy 342.546671 -278.888906) (xy 342.582923 -278.927977) (xy 342.612947 -278.972014)
			(xy 342.636073 -279.020035) (xy 342.651783 -279.070965) (xy 342.659726 -279.123669) (xy 342.660224 -279.150318)
			(xy 342.659726 -279.176967) (xy 342.888306 -279.176967) (xy 342.888306 -279.123669) (xy 342.896249 -279.070965)
			(xy 342.911959 -279.020035) (xy 342.935085 -278.972014) (xy 342.965109 -278.927977) (xy 343.001361 -278.888906)
			(xy 343.043032 -278.855675) (xy 343.08919 -278.829026) (xy 343.138804 -278.809554) (xy 343.190766 -278.797694)
			(xy 343.243916 -278.793711) (xy 343.297066 -278.797694) (xy 343.349028 -278.809554) (xy 343.398642 -278.829026)
			(xy 343.4448 -278.855675) (xy 343.486471 -278.888906) (xy 343.522723 -278.927977) (xy 343.552747 -278.972014)
			(xy 343.575873 -279.020035) (xy 343.591583 -279.070965) (xy 343.599526 -279.123669) (xy 343.600024 -279.150318)
			(xy 343.599526 -279.176967) (xy 343.827852 -279.176967) (xy 343.827852 -279.123669) (xy 343.835795 -279.070965)
			(xy 343.851505 -279.020035) (xy 343.874631 -278.972014) (xy 343.904655 -278.927977) (xy 343.940907 -278.888906)
			(xy 343.982578 -278.855675) (xy 344.028736 -278.829026) (xy 344.07835 -278.809554) (xy 344.130312 -278.797694)
			(xy 344.183462 -278.793711) (xy 344.236612 -278.797694) (xy 344.288574 -278.809554) (xy 344.338188 -278.829026)
			(xy 344.384346 -278.855675) (xy 344.426017 -278.888906) (xy 344.462269 -278.927977) (xy 344.492293 -278.972014)
			(xy 344.515419 -279.020035) (xy 344.531129 -279.070965) (xy 344.539072 -279.123669) (xy 344.53957 -279.150318)
			(xy 344.539072 -279.176967) (xy 345.707706 -279.176967) (xy 345.707706 -279.123669) (xy 345.715649 -279.070965)
			(xy 345.731359 -279.020035) (xy 345.754485 -278.972014) (xy 345.784509 -278.927977) (xy 345.820761 -278.888906)
			(xy 345.862432 -278.855675) (xy 345.90859 -278.829026) (xy 345.958204 -278.809554) (xy 346.010166 -278.797694)
			(xy 346.063316 -278.793711) (xy 346.116466 -278.797694) (xy 346.168428 -278.809554) (xy 346.218042 -278.829026)
			(xy 346.2642 -278.855675) (xy 346.305871 -278.888906) (xy 346.342123 -278.927977) (xy 346.372147 -278.972014)
			(xy 346.395273 -279.020035) (xy 346.410983 -279.070965) (xy 346.418926 -279.123669) (xy 346.419424 -279.150318)
			(xy 346.418926 -279.176967) (xy 346.647252 -279.176967) (xy 346.647252 -279.123669) (xy 346.655195 -279.070965)
			(xy 346.670905 -279.020035) (xy 346.694031 -278.972014) (xy 346.724055 -278.927977) (xy 346.760307 -278.888906)
			(xy 346.801978 -278.855675) (xy 346.848136 -278.829026) (xy 346.89775 -278.809554) (xy 346.949712 -278.797694)
			(xy 347.002862 -278.793711) (xy 347.056012 -278.797694) (xy 347.107974 -278.809554) (xy 347.157588 -278.829026)
			(xy 347.203746 -278.855675) (xy 347.245417 -278.888906) (xy 347.281669 -278.927977) (xy 347.311693 -278.972014)
			(xy 347.334819 -279.020035) (xy 347.350529 -279.070965) (xy 347.358472 -279.123669) (xy 347.35897 -279.150318)
			(xy 347.358472 -279.176967) (xy 347.587052 -279.176967) (xy 347.587052 -279.123669) (xy 347.594995 -279.070965)
			(xy 347.610705 -279.020035) (xy 347.633831 -278.972014) (xy 347.663855 -278.927977) (xy 347.700107 -278.888906)
			(xy 347.741778 -278.855675) (xy 347.787936 -278.829026) (xy 347.83755 -278.809554) (xy 347.889512 -278.797694)
			(xy 347.942662 -278.793711) (xy 347.995812 -278.797694) (xy 348.047774 -278.809554) (xy 348.097388 -278.829026)
			(xy 348.143546 -278.855675) (xy 348.185217 -278.888906) (xy 348.221469 -278.927977) (xy 348.251493 -278.972014)
			(xy 348.274619 -279.020035) (xy 348.290329 -279.070965) (xy 348.298272 -279.123669) (xy 348.29877 -279.150318)
			(xy 348.298272 -279.176967) (xy 348.527106 -279.176967) (xy 348.527106 -279.123669) (xy 348.535049 -279.070965)
			(xy 348.550759 -279.020035) (xy 348.573885 -278.972014) (xy 348.603909 -278.927977) (xy 348.640161 -278.888906)
			(xy 348.681832 -278.855675) (xy 348.72799 -278.829026) (xy 348.777604 -278.809554) (xy 348.829566 -278.797694)
			(xy 348.882716 -278.793711) (xy 348.935866 -278.797694) (xy 348.987828 -278.809554) (xy 349.037442 -278.829026)
			(xy 349.0836 -278.855675) (xy 349.125271 -278.888906) (xy 349.161523 -278.927977) (xy 349.191547 -278.972014)
			(xy 349.214673 -279.020035) (xy 349.230383 -279.070965) (xy 349.238326 -279.123669) (xy 349.238824 -279.150318)
			(xy 349.466154 -279.150318) (xy 349.466652 -279.123669) (xy 349.474595 -279.070965) (xy 349.490305 -279.020035)
			(xy 349.513431 -278.972014) (xy 349.543455 -278.927977) (xy 349.579707 -278.888906) (xy 349.621378 -278.855675)
			(xy 349.667536 -278.829026) (xy 349.71715 -278.809554) (xy 349.769112 -278.797694) (xy 349.822262 -278.793711)
			(xy 349.875412 -278.797694) (xy 349.927374 -278.809554) (xy 349.976988 -278.829026) (xy 350.023146 -278.855675)
			(xy 350.064817 -278.888906) (xy 350.101069 -278.927977) (xy 350.131093 -278.972014) (xy 350.154219 -279.020035)
			(xy 350.169929 -279.070965) (xy 350.177872 -279.123669) (xy 350.17837 -279.1503) (xy 350.405511 -279.1503)
			(xy 350.409493 -279.097157) (xy 350.421351 -279.0452) (xy 350.44082 -278.995592) (xy 350.467464 -278.949438)
			(xy 350.500689 -278.907771) (xy 350.539753 -278.871521) (xy 350.583784 -278.841498) (xy 350.631796 -278.818371)
			(xy 350.68272 -278.802659) (xy 350.735416 -278.794711) (xy 350.762062 -278.79421) (xy 350.787087 -278.794654)
			(xy 350.836643 -278.801657) (xy 350.884731 -278.815531) (xy 350.930402 -278.836003) (xy 350.972756 -278.862668)
			(xy 351.010959 -278.895001) (xy 351.044258 -278.932366) (xy 351.05848 -278.95296) (xy 351.405444 -278.95296)
			(xy 351.419697 -278.932387) (xy 351.45299 -278.895019) (xy 351.491187 -278.862682) (xy 351.533535 -278.836011)
			(xy 351.579201 -278.815532) (xy 351.627285 -278.80165) (xy 351.676838 -278.794637) (xy 351.701862 -278.79421)
			(xy 351.728516 -278.794645) (xy 351.78123 -278.802585) (xy 351.832172 -278.818293) (xy 351.880203 -278.841419)
			(xy 351.924251 -278.871446) (xy 351.963331 -278.907703) (xy 351.99657 -278.94938) (xy 352.023226 -278.995546)
			(xy 352.042703 -279.045169) (xy 352.054566 -279.09714) (xy 352.05855 -279.1503) (xy 352.056551 -279.176967)
			(xy 352.286052 -279.176967) (xy 352.286052 -279.123669) (xy 352.293995 -279.070965) (xy 352.309705 -279.020035)
			(xy 352.332831 -278.972014) (xy 352.362855 -278.927977) (xy 352.399107 -278.888906) (xy 352.440778 -278.855675)
			(xy 352.486936 -278.829026) (xy 352.53655 -278.809554) (xy 352.588512 -278.797694) (xy 352.641662 -278.793711)
			(xy 352.694812 -278.797694) (xy 352.746774 -278.809554) (xy 352.796388 -278.829026) (xy 352.842546 -278.855675)
			(xy 352.884217 -278.888906) (xy 352.920469 -278.927977) (xy 352.950493 -278.972014) (xy 352.973619 -279.020035)
			(xy 352.989329 -279.070965) (xy 352.997272 -279.123669) (xy 352.99777 -279.150318) (xy 352.997272 -279.176967)
			(xy 353.226106 -279.176967) (xy 353.226106 -279.123669) (xy 353.234049 -279.070965) (xy 353.249759 -279.020035)
			(xy 353.272885 -278.972014) (xy 353.302909 -278.927977) (xy 353.339161 -278.888906) (xy 353.380832 -278.855675)
			(xy 353.42699 -278.829026) (xy 353.476604 -278.809554) (xy 353.528566 -278.797694) (xy 353.581716 -278.793711)
			(xy 353.634866 -278.797694) (xy 353.686828 -278.809554) (xy 353.736442 -278.829026) (xy 353.7826 -278.855675)
			(xy 353.824271 -278.888906) (xy 353.860523 -278.927977) (xy 353.890547 -278.972014) (xy 353.913673 -279.020035)
			(xy 353.929383 -279.070965) (xy 353.937326 -279.123669) (xy 353.937824 -279.150318) (xy 353.937326 -279.176967)
			(xy 354.165906 -279.176967) (xy 354.165906 -279.123669) (xy 354.173849 -279.070965) (xy 354.189559 -279.020035)
			(xy 354.212685 -278.972014) (xy 354.242709 -278.927977) (xy 354.278961 -278.888906) (xy 354.320632 -278.855675)
			(xy 354.36679 -278.829026) (xy 354.416404 -278.809554) (xy 354.468366 -278.797694) (xy 354.521516 -278.793711)
			(xy 354.574666 -278.797694) (xy 354.626628 -278.809554) (xy 354.676242 -278.829026) (xy 354.7224 -278.855675)
			(xy 354.764071 -278.888906) (xy 354.800323 -278.927977) (xy 354.830347 -278.972014) (xy 354.853473 -279.020035)
			(xy 354.869183 -279.070965) (xy 354.877126 -279.123669) (xy 354.877624 -279.150318) (xy 354.877126 -279.176967)
			(xy 354.869183 -279.229671) (xy 354.853473 -279.280601) (xy 354.830347 -279.328622) (xy 354.800323 -279.372659)
			(xy 354.764071 -279.41173) (xy 354.7224 -279.444961) (xy 354.676242 -279.47161) (xy 354.626628 -279.491082)
			(xy 354.574666 -279.502942) (xy 354.521516 -279.506926) (xy 354.468366 -279.502942) (xy 354.416404 -279.491082)
			(xy 354.36679 -279.47161) (xy 354.320632 -279.444961) (xy 354.278961 -279.41173) (xy 354.242709 -279.372659)
			(xy 354.212685 -279.328622) (xy 354.189559 -279.280601) (xy 354.173849 -279.229671) (xy 354.165906 -279.176967)
			(xy 353.937326 -279.176967) (xy 353.929383 -279.229671) (xy 353.913673 -279.280601) (xy 353.890547 -279.328622)
			(xy 353.860523 -279.372659) (xy 353.824271 -279.41173) (xy 353.7826 -279.444961) (xy 353.736442 -279.47161)
			(xy 353.686828 -279.491082) (xy 353.634866 -279.502942) (xy 353.581716 -279.506926) (xy 353.528566 -279.502942)
			(xy 353.476604 -279.491082) (xy 353.42699 -279.47161) (xy 353.380832 -279.444961) (xy 353.339161 -279.41173)
			(xy 353.302909 -279.372659) (xy 353.272885 -279.328622) (xy 353.249759 -279.280601) (xy 353.234049 -279.229671)
			(xy 353.226106 -279.176967) (xy 352.997272 -279.176967) (xy 352.989329 -279.229671) (xy 352.973619 -279.280601)
			(xy 352.950493 -279.328622) (xy 352.920469 -279.372659) (xy 352.884217 -279.41173) (xy 352.842546 -279.444961)
			(xy 352.796388 -279.47161) (xy 352.746774 -279.491082) (xy 352.694812 -279.502942) (xy 352.641662 -279.506926)
			(xy 352.588512 -279.502942) (xy 352.53655 -279.491082) (xy 352.486936 -279.47161) (xy 352.440778 -279.444961)
			(xy 352.399107 -279.41173) (xy 352.362855 -279.372659) (xy 352.332831 -279.328622) (xy 352.309705 -279.280601)
			(xy 352.293995 -279.229671) (xy 352.286052 -279.176967) (xy 352.056551 -279.176967) (xy 352.054566 -279.20346)
			(xy 352.042703 -279.255431) (xy 352.023226 -279.305054) (xy 351.99657 -279.35122) (xy 351.963331 -279.392897)
			(xy 351.924251 -279.429154) (xy 351.880203 -279.459181) (xy 351.832172 -279.482307) (xy 351.78123 -279.498015)
			(xy 351.728516 -279.505955) (xy 351.701862 -279.506426) (xy 351.676836 -279.506024) (xy 351.627278 -279.499011)
			(xy 351.57919 -279.485128) (xy 351.53352 -279.46465) (xy 351.491166 -279.437979) (xy 351.452964 -279.405641)
			(xy 351.419666 -279.368272) (xy 351.405444 -279.347676) (xy 351.05848 -279.347676) (xy 351.044287 -279.368292)
			(xy 351.010983 -279.405657) (xy 350.972775 -279.437991) (xy 350.930416 -279.464656) (xy 350.884741 -279.485127)
			(xy 350.836649 -279.499001) (xy 350.787089 -279.506004) (xy 350.762062 -279.506426) (xy 350.735416 -279.505889)
			(xy 350.68272 -279.497941) (xy 350.631796 -279.482229) (xy 350.583784 -279.459102) (xy 350.539753 -279.429079)
			(xy 350.500689 -279.392829) (xy 350.467464 -279.351162) (xy 350.44082 -279.305008) (xy 350.421351 -279.2554)
			(xy 350.409493 -279.203443) (xy 350.405511 -279.1503) (xy 350.17837 -279.1503) (xy 350.17837 -279.150318)
			(xy 350.178006 -279.17347) (xy 350.172017 -279.219384) (xy 350.160141 -279.264139) (xy 350.1517 -279.2857)
			(xy 350.142048 -279.308814) (xy 350.314768 -279.607772) (xy 350.339406 -279.611074) (xy 350.364743 -279.614933)
			(xy 350.414047 -279.62892) (xy 350.460837 -279.649827) (xy 350.504149 -279.677224) (xy 350.543087 -279.710545)
			(xy 350.576849 -279.749102) (xy 350.604736 -279.792099) (xy 350.626175 -279.838649) (xy 350.640721 -279.887791)
			(xy 350.648074 -279.938509) (xy 350.648524 -279.964134) (xy 350.648026 -279.990783) (xy 350.876352 -279.990783)
			(xy 350.876352 -279.937485) (xy 350.884295 -279.884781) (xy 350.900005 -279.833851) (xy 350.923131 -279.78583)
			(xy 350.953155 -279.741793) (xy 350.989407 -279.702722) (xy 351.031078 -279.669491) (xy 351.077236 -279.642842)
			(xy 351.12685 -279.62337) (xy 351.178812 -279.61151) (xy 351.231962 -279.607527) (xy 351.285112 -279.61151)
			(xy 351.337074 -279.62337) (xy 351.386688 -279.642842) (xy 351.432846 -279.669491) (xy 351.474517 -279.702722)
			(xy 351.510769 -279.741793) (xy 351.540793 -279.78583) (xy 351.563919 -279.833851) (xy 351.579629 -279.884781)
			(xy 351.587572 -279.937485) (xy 351.58807 -279.964134) (xy 351.587572 -279.990783) (xy 351.816406 -279.990783)
			(xy 351.816406 -279.937485) (xy 351.824349 -279.884781) (xy 351.840059 -279.833851) (xy 351.863185 -279.78583)
			(xy 351.893209 -279.741793) (xy 351.929461 -279.702722) (xy 351.971132 -279.669491) (xy 352.01729 -279.642842)
			(xy 352.066904 -279.62337) (xy 352.118866 -279.61151) (xy 352.172016 -279.607527) (xy 352.225166 -279.61151)
			(xy 352.277128 -279.62337) (xy 352.326742 -279.642842) (xy 352.3729 -279.669491) (xy 352.414571 -279.702722)
			(xy 352.450823 -279.741793) (xy 352.480847 -279.78583) (xy 352.503973 -279.833851) (xy 352.519683 -279.884781)
			(xy 352.527626 -279.937485) (xy 352.528124 -279.964134) (xy 352.527626 -279.990783) (xy 352.519683 -280.043487)
			(xy 352.503973 -280.094417) (xy 352.480847 -280.142438) (xy 352.450823 -280.186475) (xy 352.414571 -280.225546)
			(xy 352.3729 -280.258777) (xy 352.326742 -280.285426) (xy 352.277128 -280.304898) (xy 352.225166 -280.316758)
			(xy 352.172016 -280.320742) (xy 352.118866 -280.316758) (xy 352.066904 -280.304898) (xy 352.01729 -280.285426)
			(xy 351.971132 -280.258777) (xy 351.929461 -280.225546) (xy 351.893209 -280.186475) (xy 351.863185 -280.142438)
			(xy 351.840059 -280.094417) (xy 351.824349 -280.043487) (xy 351.816406 -279.990783) (xy 351.587572 -279.990783)
			(xy 351.579629 -280.043487) (xy 351.563919 -280.094417) (xy 351.540793 -280.142438) (xy 351.510769 -280.186475)
			(xy 351.474517 -280.225546) (xy 351.432846 -280.258777) (xy 351.386688 -280.285426) (xy 351.337074 -280.304898)
			(xy 351.285112 -280.316758) (xy 351.231962 -280.320742) (xy 351.178812 -280.316758) (xy 351.12685 -280.304898)
			(xy 351.077236 -280.285426) (xy 351.031078 -280.258777) (xy 350.989407 -280.225546) (xy 350.953155 -280.186475)
			(xy 350.923131 -280.142438) (xy 350.900005 -280.094417) (xy 350.884295 -280.043487) (xy 350.876352 -279.990783)
			(xy 350.648026 -279.990783) (xy 350.640083 -280.043487) (xy 350.624373 -280.094417) (xy 350.601247 -280.142438)
			(xy 350.571223 -280.186475) (xy 350.534971 -280.225546) (xy 350.4933 -280.258777) (xy 350.447142 -280.285426)
			(xy 350.397528 -280.304898) (xy 350.345566 -280.316758) (xy 350.292416 -280.320742) (xy 350.239266 -280.316758)
			(xy 350.187304 -280.304898) (xy 350.13769 -280.285426) (xy 350.091532 -280.258777) (xy 350.049861 -280.225546)
			(xy 350.013609 -280.186475) (xy 349.983585 -280.142438) (xy 349.960459 -280.094417) (xy 349.944749 -280.043487)
			(xy 349.936806 -279.990783) (xy 349.936308 -279.964134) (xy 349.936687 -279.940889) (xy 349.94273 -279.894794)
			(xy 349.954716 -279.849876) (xy 349.963232 -279.828244) (xy 349.972884 -279.80513) (xy 349.800418 -279.50668)
			(xy 349.775526 -279.503378) (xy 349.750171 -279.499552) (xy 349.700831 -279.485598) (xy 349.654003 -279.464713)
			(xy 349.610653 -279.437328) (xy 349.571679 -279.40401) (xy 349.537885 -279.365446) (xy 349.509971 -279.322435)
			(xy 349.488514 -279.275865) (xy 349.473957 -279.2267) (xy 349.466602 -279.175956) (xy 349.466154 -279.150318)
			(xy 349.238824 -279.150318) (xy 349.238326 -279.176967) (xy 349.230383 -279.229671) (xy 349.214673 -279.280601)
			(xy 349.191547 -279.328622) (xy 349.161523 -279.372659) (xy 349.125271 -279.41173) (xy 349.0836 -279.444961)
			(xy 349.037442 -279.47161) (xy 348.987828 -279.491082) (xy 348.935866 -279.502942) (xy 348.882716 -279.506926)
			(xy 348.829566 -279.502942) (xy 348.777604 -279.491082) (xy 348.72799 -279.47161) (xy 348.681832 -279.444961)
			(xy 348.640161 -279.41173) (xy 348.603909 -279.372659) (xy 348.573885 -279.328622) (xy 348.550759 -279.280601)
			(xy 348.535049 -279.229671) (xy 348.527106 -279.176967) (xy 348.298272 -279.176967) (xy 348.290329 -279.229671)
			(xy 348.274619 -279.280601) (xy 348.251493 -279.328622) (xy 348.221469 -279.372659) (xy 348.185217 -279.41173)
			(xy 348.143546 -279.444961) (xy 348.097388 -279.47161) (xy 348.047774 -279.491082) (xy 347.995812 -279.502942)
			(xy 347.942662 -279.506926) (xy 347.889512 -279.502942) (xy 347.83755 -279.491082) (xy 347.787936 -279.47161)
			(xy 347.741778 -279.444961) (xy 347.700107 -279.41173) (xy 347.663855 -279.372659) (xy 347.633831 -279.328622)
			(xy 347.610705 -279.280601) (xy 347.594995 -279.229671) (xy 347.587052 -279.176967) (xy 347.358472 -279.176967)
			(xy 347.350529 -279.229671) (xy 347.334819 -279.280601) (xy 347.311693 -279.328622) (xy 347.281669 -279.372659)
			(xy 347.245417 -279.41173) (xy 347.203746 -279.444961) (xy 347.157588 -279.47161) (xy 347.107974 -279.491082)
			(xy 347.056012 -279.502942) (xy 347.002862 -279.506926) (xy 346.949712 -279.502942) (xy 346.89775 -279.491082)
			(xy 346.848136 -279.47161) (xy 346.801978 -279.444961) (xy 346.760307 -279.41173) (xy 346.724055 -279.372659)
			(xy 346.694031 -279.328622) (xy 346.670905 -279.280601) (xy 346.655195 -279.229671) (xy 346.647252 -279.176967)
			(xy 346.418926 -279.176967) (xy 346.410983 -279.229671) (xy 346.395273 -279.280601) (xy 346.372147 -279.328622)
			(xy 346.342123 -279.372659) (xy 346.305871 -279.41173) (xy 346.2642 -279.444961) (xy 346.218042 -279.47161)
			(xy 346.168428 -279.491082) (xy 346.116466 -279.502942) (xy 346.063316 -279.506926) (xy 346.010166 -279.502942)
			(xy 345.958204 -279.491082) (xy 345.90859 -279.47161) (xy 345.862432 -279.444961) (xy 345.820761 -279.41173)
			(xy 345.784509 -279.372659) (xy 345.754485 -279.328622) (xy 345.731359 -279.280601) (xy 345.715649 -279.229671)
			(xy 345.707706 -279.176967) (xy 344.539072 -279.176967) (xy 344.531129 -279.229671) (xy 344.515419 -279.280601)
			(xy 344.492293 -279.328622) (xy 344.462269 -279.372659) (xy 344.426017 -279.41173) (xy 344.384346 -279.444961)
			(xy 344.338188 -279.47161) (xy 344.288574 -279.491082) (xy 344.236612 -279.502942) (xy 344.183462 -279.506926)
			(xy 344.130312 -279.502942) (xy 344.07835 -279.491082) (xy 344.028736 -279.47161) (xy 343.982578 -279.444961)
			(xy 343.940907 -279.41173) (xy 343.904655 -279.372659) (xy 343.874631 -279.328622) (xy 343.851505 -279.280601)
			(xy 343.835795 -279.229671) (xy 343.827852 -279.176967) (xy 343.599526 -279.176967) (xy 343.591583 -279.229671)
			(xy 343.575873 -279.280601) (xy 343.552747 -279.328622) (xy 343.522723 -279.372659) (xy 343.486471 -279.41173)
			(xy 343.4448 -279.444961) (xy 343.398642 -279.47161) (xy 343.349028 -279.491082) (xy 343.297066 -279.502942)
			(xy 343.243916 -279.506926) (xy 343.190766 -279.502942) (xy 343.138804 -279.491082) (xy 343.08919 -279.47161)
			(xy 343.043032 -279.444961) (xy 343.001361 -279.41173) (xy 342.965109 -279.372659) (xy 342.935085 -279.328622)
			(xy 342.911959 -279.280601) (xy 342.896249 -279.229671) (xy 342.888306 -279.176967) (xy 342.659726 -279.176967)
			(xy 342.651783 -279.229671) (xy 342.636073 -279.280601) (xy 342.612947 -279.328622) (xy 342.582923 -279.372659)
			(xy 342.546671 -279.41173) (xy 342.505 -279.444961) (xy 342.458842 -279.47161) (xy 342.409228 -279.491082)
			(xy 342.357266 -279.502942) (xy 342.304116 -279.506926) (xy 342.250966 -279.502942) (xy 342.199004 -279.491082)
			(xy 342.14939 -279.47161) (xy 342.103232 -279.444961) (xy 342.061561 -279.41173) (xy 342.025309 -279.372659)
			(xy 341.995285 -279.328622) (xy 341.972159 -279.280601) (xy 341.956449 -279.229671) (xy 341.948506 -279.176967)
			(xy 341.719672 -279.176967) (xy 341.711729 -279.229671) (xy 341.696019 -279.280601) (xy 341.672893 -279.328622)
			(xy 341.642869 -279.372659) (xy 341.606617 -279.41173) (xy 341.564946 -279.444961) (xy 341.518788 -279.47161)
			(xy 341.469174 -279.491082) (xy 341.417212 -279.502942) (xy 341.364062 -279.506926) (xy 341.310912 -279.502942)
			(xy 341.25895 -279.491082) (xy 341.209336 -279.47161) (xy 341.163178 -279.444961) (xy 341.121507 -279.41173)
			(xy 341.085255 -279.372659) (xy 341.055231 -279.328622) (xy 341.032105 -279.280601) (xy 341.016395 -279.229671)
			(xy 341.008452 -279.176967) (xy 340.779872 -279.176967) (xy 340.771929 -279.229671) (xy 340.756219 -279.280601)
			(xy 340.733093 -279.328622) (xy 340.703069 -279.372659) (xy 340.666817 -279.41173) (xy 340.625146 -279.444961)
			(xy 340.578988 -279.47161) (xy 340.529374 -279.491082) (xy 340.477412 -279.502942) (xy 340.424262 -279.506926)
			(xy 340.371112 -279.502942) (xy 340.31915 -279.491082) (xy 340.269536 -279.47161) (xy 340.223378 -279.444961)
			(xy 340.181707 -279.41173) (xy 340.145455 -279.372659) (xy 340.115431 -279.328622) (xy 340.092305 -279.280601)
			(xy 340.076595 -279.229671) (xy 340.068652 -279.176967) (xy 339.840072 -279.176967) (xy 339.832129 -279.229671)
			(xy 339.816419 -279.280601) (xy 339.793293 -279.328622) (xy 339.763269 -279.372659) (xy 339.727017 -279.41173)
			(xy 339.685346 -279.444961) (xy 339.639188 -279.47161) (xy 339.589574 -279.491082) (xy 339.537612 -279.502942)
			(xy 339.484462 -279.506926) (xy 339.431312 -279.502942) (xy 339.37935 -279.491082) (xy 339.329736 -279.47161)
			(xy 339.283578 -279.444961) (xy 339.241907 -279.41173) (xy 339.205655 -279.372659) (xy 339.175631 -279.328622)
			(xy 339.152505 -279.280601) (xy 339.136795 -279.229671) (xy 339.128852 -279.176967) (xy 338.900272 -279.176967)
			(xy 338.892329 -279.229671) (xy 338.876619 -279.280601) (xy 338.853493 -279.328622) (xy 338.823469 -279.372659)
			(xy 338.787217 -279.41173) (xy 338.745546 -279.444961) (xy 338.699388 -279.47161) (xy 338.649774 -279.491082)
			(xy 338.597812 -279.502942) (xy 338.544662 -279.506926) (xy 338.491512 -279.502942) (xy 338.43955 -279.491082)
			(xy 338.389936 -279.47161) (xy 338.343778 -279.444961) (xy 338.302107 -279.41173) (xy 338.265855 -279.372659)
			(xy 338.235831 -279.328622) (xy 338.212705 -279.280601) (xy 338.196995 -279.229671) (xy 338.189052 -279.176967)
			(xy 337.960472 -279.176967) (xy 337.952529 -279.229671) (xy 337.936819 -279.280601) (xy 337.913693 -279.328622)
			(xy 337.883669 -279.372659) (xy 337.847417 -279.41173) (xy 337.805746 -279.444961) (xy 337.759588 -279.47161)
			(xy 337.709974 -279.491082) (xy 337.658012 -279.502942) (xy 337.604862 -279.506926) (xy 337.551712 -279.502942)
			(xy 337.49975 -279.491082) (xy 337.450136 -279.47161) (xy 337.403978 -279.444961) (xy 337.362307 -279.41173)
			(xy 337.326055 -279.372659) (xy 337.296031 -279.328622) (xy 337.272905 -279.280601) (xy 337.257195 -279.229671)
			(xy 337.249252 -279.176967) (xy 337.020672 -279.176967) (xy 337.012729 -279.229671) (xy 336.997019 -279.280601)
			(xy 336.973893 -279.328622) (xy 336.943869 -279.372659) (xy 336.907617 -279.41173) (xy 336.865946 -279.444961)
			(xy 336.819788 -279.47161) (xy 336.770174 -279.491082) (xy 336.718212 -279.502942) (xy 336.665062 -279.506926)
			(xy 336.611912 -279.502942) (xy 336.55995 -279.491082) (xy 336.510336 -279.47161) (xy 336.464178 -279.444961)
			(xy 336.422507 -279.41173) (xy 336.386255 -279.372659) (xy 336.356231 -279.328622) (xy 336.333105 -279.280601)
			(xy 336.317395 -279.229671) (xy 336.309452 -279.176967) (xy 333.466948 -279.176967) (xy 333.466948 -279.990783)
			(xy 333.959952 -279.990783) (xy 333.959952 -279.937485) (xy 333.967895 -279.884781) (xy 333.983605 -279.833851)
			(xy 334.006731 -279.78583) (xy 334.036755 -279.741793) (xy 334.073007 -279.702722) (xy 334.114678 -279.669491)
			(xy 334.160836 -279.642842) (xy 334.21045 -279.62337) (xy 334.262412 -279.61151) (xy 334.315562 -279.607527)
			(xy 334.368712 -279.61151) (xy 334.420674 -279.62337) (xy 334.470288 -279.642842) (xy 334.516446 -279.669491)
			(xy 334.558117 -279.702722) (xy 334.594369 -279.741793) (xy 334.624393 -279.78583) (xy 334.647519 -279.833851)
			(xy 334.663229 -279.884781) (xy 334.671172 -279.937485) (xy 334.67167 -279.964134) (xy 334.671172 -279.990783)
			(xy 334.899752 -279.990783) (xy 334.899752 -279.937485) (xy 334.907695 -279.884781) (xy 334.923405 -279.833851)
			(xy 334.946531 -279.78583) (xy 334.976555 -279.741793) (xy 335.012807 -279.702722) (xy 335.054478 -279.669491)
			(xy 335.100636 -279.642842) (xy 335.15025 -279.62337) (xy 335.202212 -279.61151) (xy 335.255362 -279.607527)
			(xy 335.308512 -279.61151) (xy 335.360474 -279.62337) (xy 335.410088 -279.642842) (xy 335.456246 -279.669491)
			(xy 335.497917 -279.702722) (xy 335.534169 -279.741793) (xy 335.564193 -279.78583) (xy 335.587319 -279.833851)
			(xy 335.603029 -279.884781) (xy 335.610972 -279.937485) (xy 335.61147 -279.964134) (xy 335.610972 -279.990783)
			(xy 335.839552 -279.990783) (xy 335.839552 -279.937485) (xy 335.847495 -279.884781) (xy 335.863205 -279.833851)
			(xy 335.886331 -279.78583) (xy 335.916355 -279.741793) (xy 335.952607 -279.702722) (xy 335.994278 -279.669491)
			(xy 336.040436 -279.642842) (xy 336.09005 -279.62337) (xy 336.142012 -279.61151) (xy 336.195162 -279.607527)
			(xy 336.248312 -279.61151) (xy 336.300274 -279.62337) (xy 336.349888 -279.642842) (xy 336.396046 -279.669491)
			(xy 336.437717 -279.702722) (xy 336.473969 -279.741793) (xy 336.503993 -279.78583) (xy 336.527119 -279.833851)
			(xy 336.542829 -279.884781) (xy 336.550772 -279.937485) (xy 336.551269 -279.9641) (xy 336.778427 -279.9641)
			(xy 336.782409 -279.910959) (xy 336.794266 -279.859005) (xy 336.813734 -279.809399) (xy 336.840377 -279.763247)
			(xy 336.873601 -279.721582) (xy 336.912663 -279.685334) (xy 336.956692 -279.655311) (xy 337.004702 -279.632186)
			(xy 337.055623 -279.616474) (xy 337.108317 -279.608527) (xy 337.134962 -279.608026) (xy 337.159987 -279.608463)
			(xy 337.209544 -279.615467) (xy 337.257632 -279.629341) (xy 337.303304 -279.649814) (xy 337.345658 -279.67648)
			(xy 337.38386 -279.708815) (xy 337.417158 -279.746181) (xy 337.43138 -279.766776) (xy 337.778344 -279.766776)
			(xy 337.792602 -279.746207) (xy 337.825894 -279.708838) (xy 337.864089 -279.6765) (xy 337.906437 -279.649828)
			(xy 337.952102 -279.629349) (xy 338.000185 -279.615466) (xy 338.049739 -279.608453) (xy 338.074762 -279.608026)
			(xy 338.101418 -279.608429) (xy 338.154134 -279.616369) (xy 338.205078 -279.632078) (xy 338.253111 -279.655205)
			(xy 338.297161 -279.685234) (xy 338.336242 -279.721492) (xy 338.369483 -279.763171) (xy 338.39614 -279.809339)
			(xy 338.415618 -279.858964) (xy 338.427482 -279.910938) (xy 338.431466 -279.9641) (xy 338.429466 -279.990783)
			(xy 339.599006 -279.990783) (xy 339.599006 -279.937485) (xy 339.606949 -279.884781) (xy 339.622659 -279.833851)
			(xy 339.645785 -279.78583) (xy 339.675809 -279.741793) (xy 339.712061 -279.702722) (xy 339.753732 -279.669491)
			(xy 339.79989 -279.642842) (xy 339.849504 -279.62337) (xy 339.901466 -279.61151) (xy 339.954616 -279.607527)
			(xy 340.007766 -279.61151) (xy 340.059728 -279.62337) (xy 340.109342 -279.642842) (xy 340.1555 -279.669491)
			(xy 340.197171 -279.702722) (xy 340.233423 -279.741793) (xy 340.263447 -279.78583) (xy 340.286573 -279.833851)
			(xy 340.302283 -279.884781) (xy 340.310226 -279.937485) (xy 340.310724 -279.964134) (xy 340.310226 -279.990783)
			(xy 340.538806 -279.990783) (xy 340.538806 -279.937485) (xy 340.546749 -279.884781) (xy 340.562459 -279.833851)
			(xy 340.585585 -279.78583) (xy 340.615609 -279.741793) (xy 340.651861 -279.702722) (xy 340.693532 -279.669491)
			(xy 340.73969 -279.642842) (xy 340.789304 -279.62337) (xy 340.841266 -279.61151) (xy 340.894416 -279.607527)
			(xy 340.947566 -279.61151) (xy 340.999528 -279.62337) (xy 341.049142 -279.642842) (xy 341.0953 -279.669491)
			(xy 341.136971 -279.702722) (xy 341.173223 -279.741793) (xy 341.203247 -279.78583) (xy 341.226373 -279.833851)
			(xy 341.242083 -279.884781) (xy 341.250026 -279.937485) (xy 341.250524 -279.964134) (xy 341.250026 -279.990783)
			(xy 342.418152 -279.990783) (xy 342.418152 -279.937485) (xy 342.426095 -279.884781) (xy 342.441805 -279.833851)
			(xy 342.464931 -279.78583) (xy 342.494955 -279.741793) (xy 342.531207 -279.702722) (xy 342.572878 -279.669491)
			(xy 342.619036 -279.642842) (xy 342.66865 -279.62337) (xy 342.720612 -279.61151) (xy 342.773762 -279.607527)
			(xy 342.826912 -279.61151) (xy 342.878874 -279.62337) (xy 342.928488 -279.642842) (xy 342.974646 -279.669491)
			(xy 343.016317 -279.702722) (xy 343.052569 -279.741793) (xy 343.082593 -279.78583) (xy 343.105719 -279.833851)
			(xy 343.121429 -279.884781) (xy 343.129372 -279.937485) (xy 343.12987 -279.964134) (xy 343.129372 -279.990783)
			(xy 343.358206 -279.990783) (xy 343.358206 -279.937485) (xy 343.366149 -279.884781) (xy 343.381859 -279.833851)
			(xy 343.404985 -279.78583) (xy 343.435009 -279.741793) (xy 343.471261 -279.702722) (xy 343.512932 -279.669491)
			(xy 343.55909 -279.642842) (xy 343.608704 -279.62337) (xy 343.660666 -279.61151) (xy 343.713816 -279.607527)
			(xy 343.766966 -279.61151) (xy 343.818928 -279.62337) (xy 343.868542 -279.642842) (xy 343.9147 -279.669491)
			(xy 343.956371 -279.702722) (xy 343.992623 -279.741793) (xy 344.022647 -279.78583) (xy 344.045773 -279.833851)
			(xy 344.061483 -279.884781) (xy 344.069426 -279.937485) (xy 344.069924 -279.964134) (xy 344.297508 -279.964134)
			(xy 344.298006 -279.937485) (xy 344.305949 -279.884781) (xy 344.321659 -279.833851) (xy 344.344785 -279.78583)
			(xy 344.374809 -279.741793) (xy 344.411061 -279.702722) (xy 344.452732 -279.669491) (xy 344.49889 -279.642842)
			(xy 344.548504 -279.62337) (xy 344.600466 -279.61151) (xy 344.653616 -279.607527) (xy 344.706766 -279.61151)
			(xy 344.758728 -279.62337) (xy 344.808342 -279.642842) (xy 344.8545 -279.669491) (xy 344.896171 -279.702722)
			(xy 344.932423 -279.741793) (xy 344.962447 -279.78583) (xy 344.985573 -279.833851) (xy 345.001283 -279.884781)
			(xy 345.009226 -279.937485) (xy 345.009724 -279.964134) (xy 345.009374 -279.987423) (xy 345.008936 -279.990783)
			(xy 345.237806 -279.990783) (xy 345.237806 -279.937485) (xy 345.245749 -279.884781) (xy 345.261459 -279.833851)
			(xy 345.284585 -279.78583) (xy 345.314609 -279.741793) (xy 345.350861 -279.702722) (xy 345.392532 -279.669491)
			(xy 345.43869 -279.642842) (xy 345.488304 -279.62337) (xy 345.540266 -279.61151) (xy 345.593416 -279.607527)
			(xy 345.646566 -279.61151) (xy 345.698528 -279.62337) (xy 345.748142 -279.642842) (xy 345.7943 -279.669491)
			(xy 345.835971 -279.702722) (xy 345.872223 -279.741793) (xy 345.902247 -279.78583) (xy 345.925373 -279.833851)
			(xy 345.941083 -279.884781) (xy 345.949026 -279.937485) (xy 345.949524 -279.964134) (xy 345.949026 -279.990783)
			(xy 346.177606 -279.990783) (xy 346.177606 -279.937485) (xy 346.185549 -279.884781) (xy 346.201259 -279.833851)
			(xy 346.224385 -279.78583) (xy 346.254409 -279.741793) (xy 346.290661 -279.702722) (xy 346.332332 -279.669491)
			(xy 346.37849 -279.642842) (xy 346.428104 -279.62337) (xy 346.480066 -279.61151) (xy 346.533216 -279.607527)
			(xy 346.586366 -279.61151) (xy 346.638328 -279.62337) (xy 346.687942 -279.642842) (xy 346.7341 -279.669491)
			(xy 346.775771 -279.702722) (xy 346.812023 -279.741793) (xy 346.842047 -279.78583) (xy 346.865173 -279.833851)
			(xy 346.880883 -279.884781) (xy 346.888826 -279.937485) (xy 346.889324 -279.964134) (xy 346.888826 -279.990783)
			(xy 348.057206 -279.990783) (xy 348.057206 -279.937485) (xy 348.065149 -279.884781) (xy 348.080859 -279.833851)
			(xy 348.103985 -279.78583) (xy 348.134009 -279.741793) (xy 348.170261 -279.702722) (xy 348.211932 -279.669491)
			(xy 348.25809 -279.642842) (xy 348.307704 -279.62337) (xy 348.359666 -279.61151) (xy 348.412816 -279.607527)
			(xy 348.465966 -279.61151) (xy 348.517928 -279.62337) (xy 348.567542 -279.642842) (xy 348.6137 -279.669491)
			(xy 348.655371 -279.702722) (xy 348.691623 -279.741793) (xy 348.721647 -279.78583) (xy 348.744773 -279.833851)
			(xy 348.760483 -279.884781) (xy 348.768426 -279.937485) (xy 348.768924 -279.964134) (xy 348.768426 -279.990783)
			(xy 348.997006 -279.990783) (xy 348.997006 -279.937485) (xy 349.004949 -279.884781) (xy 349.020659 -279.833851)
			(xy 349.043785 -279.78583) (xy 349.073809 -279.741793) (xy 349.110061 -279.702722) (xy 349.151732 -279.669491)
			(xy 349.19789 -279.642842) (xy 349.247504 -279.62337) (xy 349.299466 -279.61151) (xy 349.352616 -279.607527)
			(xy 349.405766 -279.61151) (xy 349.457728 -279.62337) (xy 349.507342 -279.642842) (xy 349.5535 -279.669491)
			(xy 349.595171 -279.702722) (xy 349.631423 -279.741793) (xy 349.661447 -279.78583) (xy 349.684573 -279.833851)
			(xy 349.700283 -279.884781) (xy 349.708226 -279.937485) (xy 349.708724 -279.964134) (xy 349.708226 -279.990783)
			(xy 349.700283 -280.043487) (xy 349.684573 -280.094417) (xy 349.661447 -280.142438) (xy 349.631423 -280.186475)
			(xy 349.595171 -280.225546) (xy 349.5535 -280.258777) (xy 349.507342 -280.285426) (xy 349.457728 -280.304898)
			(xy 349.405766 -280.316758) (xy 349.352616 -280.320742) (xy 349.299466 -280.316758) (xy 349.247504 -280.304898)
			(xy 349.19789 -280.285426) (xy 349.151732 -280.258777) (xy 349.110061 -280.225546) (xy 349.073809 -280.186475)
			(xy 349.043785 -280.142438) (xy 349.020659 -280.094417) (xy 349.004949 -280.043487) (xy 348.997006 -279.990783)
			(xy 348.768426 -279.990783) (xy 348.760483 -280.043487) (xy 348.744773 -280.094417) (xy 348.721647 -280.142438)
			(xy 348.691623 -280.186475) (xy 348.655371 -280.225546) (xy 348.6137 -280.258777) (xy 348.567542 -280.285426)
			(xy 348.517928 -280.304898) (xy 348.465966 -280.316758) (xy 348.412816 -280.320742) (xy 348.359666 -280.316758)
			(xy 348.307704 -280.304898) (xy 348.25809 -280.285426) (xy 348.211932 -280.258777) (xy 348.170261 -280.225546)
			(xy 348.134009 -280.186475) (xy 348.103985 -280.142438) (xy 348.080859 -280.094417) (xy 348.065149 -280.043487)
			(xy 348.057206 -279.990783) (xy 346.888826 -279.990783) (xy 346.880883 -280.043487) (xy 346.865173 -280.094417)
			(xy 346.842047 -280.142438) (xy 346.812023 -280.186475) (xy 346.775771 -280.225546) (xy 346.7341 -280.258777)
			(xy 346.687942 -280.285426) (xy 346.638328 -280.304898) (xy 346.586366 -280.316758) (xy 346.533216 -280.320742)
			(xy 346.480066 -280.316758) (xy 346.428104 -280.304898) (xy 346.37849 -280.285426) (xy 346.332332 -280.258777)
			(xy 346.290661 -280.225546) (xy 346.254409 -280.186475) (xy 346.224385 -280.142438) (xy 346.201259 -280.094417)
			(xy 346.185549 -280.043487) (xy 346.177606 -279.990783) (xy 345.949026 -279.990783) (xy 345.941083 -280.043487)
			(xy 345.925373 -280.094417) (xy 345.902247 -280.142438) (xy 345.872223 -280.186475) (xy 345.835971 -280.225546)
			(xy 345.7943 -280.258777) (xy 345.748142 -280.285426) (xy 345.698528 -280.304898) (xy 345.646566 -280.316758)
			(xy 345.593416 -280.320742) (xy 345.540266 -280.316758) (xy 345.488304 -280.304898) (xy 345.43869 -280.285426)
			(xy 345.392532 -280.258777) (xy 345.350861 -280.225546) (xy 345.314609 -280.186475) (xy 345.284585 -280.142438)
			(xy 345.261459 -280.094417) (xy 345.245749 -280.043487) (xy 345.237806 -279.990783) (xy 345.008936 -279.990783)
			(xy 345.003352 -280.033609) (xy 344.991351 -280.078613) (xy 344.9828 -280.100278) (xy 344.973148 -280.123392)
			(xy 345.145614 -280.421842) (xy 345.170252 -280.425144) (xy 345.195589 -280.428996) (xy 345.244891 -280.442987)
			(xy 345.29168 -280.463898) (xy 345.33499 -280.491297) (xy 345.373926 -280.524619) (xy 345.407687 -280.563176)
			(xy 345.435574 -280.606173) (xy 345.457013 -280.652721) (xy 345.471561 -280.701862) (xy 345.478918 -280.75258)
			(xy 345.47937 -280.778204) (xy 345.478872 -280.804853) (xy 345.470929 -280.857557) (xy 345.455219 -280.908487)
			(xy 345.432093 -280.956508) (xy 345.402069 -281.000545) (xy 345.365817 -281.039616) (xy 345.324146 -281.072847)
			(xy 345.277988 -281.099496) (xy 345.228374 -281.118968) (xy 345.176412 -281.130828) (xy 345.123262 -281.134812)
			(xy 345.070112 -281.130828) (xy 345.01815 -281.118968) (xy 344.968536 -281.099496) (xy 344.922378 -281.072847)
			(xy 344.880707 -281.039616) (xy 344.844455 -281.000545) (xy 344.814431 -280.956508) (xy 344.791305 -280.908487)
			(xy 344.775595 -280.857557) (xy 344.767652 -280.804853) (xy 344.767154 -280.778204) (xy 344.767527 -280.754959)
			(xy 344.773573 -280.708864) (xy 344.785561 -280.663946) (xy 344.794078 -280.642314) (xy 344.80373 -280.6192)
			(xy 344.63101 -280.320496) (xy 344.606372 -280.317194) (xy 344.581041 -280.31337) (xy 344.531767 -280.299349)
			(xy 344.48501 -280.278414) (xy 344.441732 -280.250999) (xy 344.402828 -280.217668) (xy 344.369098 -280.179109)
			(xy 344.341239 -280.136116) (xy 344.319825 -280.089577) (xy 344.305297 -280.04045) (xy 344.297955 -279.989749)
			(xy 344.297508 -279.964134) (xy 344.069924 -279.964134) (xy 344.069426 -279.990783) (xy 344.061483 -280.043487)
			(xy 344.045773 -280.094417) (xy 344.022647 -280.142438) (xy 343.992623 -280.186475) (xy 343.956371 -280.225546)
			(xy 343.9147 -280.258777) (xy 343.868542 -280.285426) (xy 343.818928 -280.304898) (xy 343.766966 -280.316758)
			(xy 343.713816 -280.320742) (xy 343.660666 -280.316758) (xy 343.608704 -280.304898) (xy 343.55909 -280.285426)
			(xy 343.512932 -280.258777) (xy 343.471261 -280.225546) (xy 343.435009 -280.186475) (xy 343.404985 -280.142438)
			(xy 343.381859 -280.094417) (xy 343.366149 -280.043487) (xy 343.358206 -279.990783) (xy 343.129372 -279.990783)
			(xy 343.121429 -280.043487) (xy 343.105719 -280.094417) (xy 343.082593 -280.142438) (xy 343.052569 -280.186475)
			(xy 343.016317 -280.225546) (xy 342.974646 -280.258777) (xy 342.928488 -280.285426) (xy 342.878874 -280.304898)
			(xy 342.826912 -280.316758) (xy 342.773762 -280.320742) (xy 342.720612 -280.316758) (xy 342.66865 -280.304898)
			(xy 342.619036 -280.285426) (xy 342.572878 -280.258777) (xy 342.531207 -280.225546) (xy 342.494955 -280.186475)
			(xy 342.464931 -280.142438) (xy 342.441805 -280.094417) (xy 342.426095 -280.043487) (xy 342.418152 -279.990783)
			(xy 341.250026 -279.990783) (xy 341.242083 -280.043487) (xy 341.226373 -280.094417) (xy 341.203247 -280.142438)
			(xy 341.173223 -280.186475) (xy 341.136971 -280.225546) (xy 341.0953 -280.258777) (xy 341.049142 -280.285426)
			(xy 340.999528 -280.304898) (xy 340.947566 -280.316758) (xy 340.894416 -280.320742) (xy 340.841266 -280.316758)
			(xy 340.789304 -280.304898) (xy 340.73969 -280.285426) (xy 340.693532 -280.258777) (xy 340.651861 -280.225546)
			(xy 340.615609 -280.186475) (xy 340.585585 -280.142438) (xy 340.562459 -280.094417) (xy 340.546749 -280.043487)
			(xy 340.538806 -279.990783) (xy 340.310226 -279.990783) (xy 340.302283 -280.043487) (xy 340.286573 -280.094417)
			(xy 340.263447 -280.142438) (xy 340.233423 -280.186475) (xy 340.197171 -280.225546) (xy 340.1555 -280.258777)
			(xy 340.109342 -280.285426) (xy 340.059728 -280.304898) (xy 340.007766 -280.316758) (xy 339.954616 -280.320742)
			(xy 339.901466 -280.316758) (xy 339.849504 -280.304898) (xy 339.79989 -280.285426) (xy 339.753732 -280.258777)
			(xy 339.712061 -280.225546) (xy 339.675809 -280.186475) (xy 339.645785 -280.142438) (xy 339.622659 -280.094417)
			(xy 339.606949 -280.043487) (xy 339.599006 -279.990783) (xy 338.429466 -279.990783) (xy 338.427482 -280.017262)
			(xy 338.415618 -280.069236) (xy 338.39614 -280.118861) (xy 338.369483 -280.165029) (xy 338.336242 -280.206708)
			(xy 338.297161 -280.242966) (xy 338.253111 -280.272995) (xy 338.205078 -280.296122) (xy 338.154134 -280.311831)
			(xy 338.101418 -280.319771) (xy 338.074762 -280.320242) (xy 338.049737 -280.319833) (xy 338.000179 -280.31282)
			(xy 337.952092 -280.298938) (xy 337.906422 -280.278461) (xy 337.864068 -280.251791) (xy 337.825866 -280.219454)
			(xy 337.792567 -280.182087) (xy 337.778344 -280.161492) (xy 337.43138 -280.161492) (xy 337.417192 -280.182112)
			(xy 337.383887 -280.219476) (xy 337.345678 -280.251809) (xy 337.303318 -280.278473) (xy 337.257642 -280.298944)
			(xy 337.20955 -280.312817) (xy 337.159989 -280.31982) (xy 337.134962 -280.320242) (xy 337.108317 -280.319673)
			(xy 337.055623 -280.311726) (xy 337.004702 -280.296014) (xy 336.956692 -280.272889) (xy 336.912663 -280.242866)
			(xy 336.873601 -280.206618) (xy 336.840377 -280.164953) (xy 336.813734 -280.118801) (xy 336.794266 -280.069195)
			(xy 336.782409 -280.017241) (xy 336.778427 -279.9641) (xy 336.551269 -279.9641) (xy 336.55127 -279.964134)
			(xy 336.550772 -279.990783) (xy 336.542829 -280.043487) (xy 336.527119 -280.094417) (xy 336.503993 -280.142438)
			(xy 336.473969 -280.186475) (xy 336.437717 -280.225546) (xy 336.396046 -280.258777) (xy 336.349888 -280.285426)
			(xy 336.300274 -280.304898) (xy 336.248312 -280.316758) (xy 336.195162 -280.320742) (xy 336.142012 -280.316758)
			(xy 336.09005 -280.304898) (xy 336.040436 -280.285426) (xy 335.994278 -280.258777) (xy 335.952607 -280.225546)
			(xy 335.916355 -280.186475) (xy 335.886331 -280.142438) (xy 335.863205 -280.094417) (xy 335.847495 -280.043487)
			(xy 335.839552 -279.990783) (xy 335.610972 -279.990783) (xy 335.603029 -280.043487) (xy 335.587319 -280.094417)
			(xy 335.564193 -280.142438) (xy 335.534169 -280.186475) (xy 335.497917 -280.225546) (xy 335.456246 -280.258777)
			(xy 335.410088 -280.285426) (xy 335.360474 -280.304898) (xy 335.308512 -280.316758) (xy 335.255362 -280.320742)
			(xy 335.202212 -280.316758) (xy 335.15025 -280.304898) (xy 335.100636 -280.285426) (xy 335.054478 -280.258777)
			(xy 335.012807 -280.225546) (xy 334.976555 -280.186475) (xy 334.946531 -280.142438) (xy 334.923405 -280.094417)
			(xy 334.907695 -280.043487) (xy 334.899752 -279.990783) (xy 334.671172 -279.990783) (xy 334.663229 -280.043487)
			(xy 334.647519 -280.094417) (xy 334.624393 -280.142438) (xy 334.594369 -280.186475) (xy 334.558117 -280.225546)
			(xy 334.516446 -280.258777) (xy 334.470288 -280.285426) (xy 334.420674 -280.304898) (xy 334.368712 -280.316758)
			(xy 334.315562 -280.320742) (xy 334.262412 -280.316758) (xy 334.21045 -280.304898) (xy 334.160836 -280.285426)
			(xy 334.114678 -280.258777) (xy 334.073007 -280.225546) (xy 334.036755 -280.186475) (xy 334.006731 -280.142438)
			(xy 333.983605 -280.094417) (xy 333.967895 -280.043487) (xy 333.959952 -279.990783) (xy 333.466948 -279.990783)
			(xy 333.466948 -280.42997) (xy 333.467424 -280.444237) (xy 333.475314 -280.471658) (xy 333.490485 -280.495824)
			(xy 333.511753 -280.514846) (xy 333.537455 -280.527238) (xy 333.565583 -280.532032) (xy 333.593939 -280.528853)
			(xy 333.620307 -280.51795) (xy 333.631794 -280.509472) (xy 333.654764 -280.49197) (xy 333.705338 -280.464098)
			(xy 333.759857 -280.445067) (xy 333.816789 -280.435413) (xy 333.845662 -280.434796) (xy 333.871364 -280.435249)
			(xy 333.922195 -280.442906) (xy 333.971317 -280.458053) (xy 334.017633 -280.480353) (xy 334.060107 -280.509307)
			(xy 334.097791 -280.544269) (xy 334.129843 -280.584457) (xy 334.155547 -280.628973) (xy 334.174328 -280.676824)
			(xy 334.185768 -280.726939) (xy 334.18961 -280.7782) (xy 334.428896 -280.7782) (xy 334.432879 -280.725055)
			(xy 334.444737 -280.673096) (xy 334.464207 -280.623485) (xy 334.490852 -280.57733) (xy 334.524079 -280.535661)
			(xy 334.563144 -280.49941) (xy 334.607176 -280.469385) (xy 334.655191 -280.446258) (xy 334.706116 -280.430545)
			(xy 334.758815 -280.422596) (xy 334.785462 -280.422096) (xy 334.810477 -280.422493) (xy 334.860016 -280.429486)
			(xy 334.908089 -280.44334) (xy 334.953752 -280.463782) (xy 334.996107 -280.49041) (xy 335.034321 -280.522701)
			(xy 335.067642 -280.56002) (xy 335.08188 -280.580592) (xy 335.428844 -280.580592) (xy 335.443086 -280.560025)
			(xy 335.476414 -280.522717) (xy 335.514631 -280.490436) (xy 335.556985 -280.463814) (xy 335.602645 -280.443375)
			(xy 335.650715 -280.42952) (xy 335.700249 -280.422521) (xy 335.725262 -280.422096) (xy 335.751915 -280.422559)
			(xy 335.804627 -280.430498) (xy 335.855567 -280.446206) (xy 335.903596 -280.469331) (xy 335.947642 -280.499357)
			(xy 335.98672 -280.535613) (xy 336.019958 -280.577288) (xy 336.046613 -280.623452) (xy 336.06609 -280.673073)
			(xy 336.077952 -280.725043) (xy 336.081936 -280.7782) (xy 336.077952 -280.831357) (xy 336.06609 -280.883327)
			(xy 336.046613 -280.932948) (xy 336.019958 -280.979112) (xy 335.98672 -281.020787) (xy 335.947642 -281.057043)
			(xy 335.903596 -281.087069) (xy 335.855567 -281.110194) (xy 335.804627 -281.125902) (xy 335.751915 -281.133841)
			(xy 335.725262 -281.134312) (xy 335.700248 -281.133893) (xy 335.65071 -281.126904) (xy 335.602637 -281.113054)
			(xy 335.556974 -281.092615) (xy 335.514619 -281.06599) (xy 335.476405 -281.033702) (xy 335.443083 -280.996386)
			(xy 335.428844 -280.975816) (xy 335.08188 -280.975816) (xy 335.067626 -280.996374) (xy 335.034299 -281.033681)
			(xy 334.996084 -281.065963) (xy 334.953732 -281.092586) (xy 334.908074 -281.113027) (xy 334.860007 -281.126884)
			(xy 334.810474 -281.133886) (xy 334.785462 -281.134312) (xy 334.758815 -281.133804) (xy 334.706116 -281.125855)
			(xy 334.655191 -281.110142) (xy 334.607176 -281.087015) (xy 334.563144 -281.05699) (xy 334.524079 -281.020739)
			(xy 334.490852 -280.97907) (xy 334.464207 -280.932915) (xy 334.444737 -280.883304) (xy 334.432879 -280.831345)
			(xy 334.428896 -280.7782) (xy 334.18961 -280.7782) (xy 334.185768 -280.829461) (xy 334.174328 -280.879576)
			(xy 334.155547 -280.927427) (xy 334.129843 -280.971943) (xy 334.097791 -281.012131) (xy 334.060107 -281.047093)
			(xy 334.017633 -281.076047) (xy 333.971317 -281.098347) (xy 333.922195 -281.113494) (xy 333.871364 -281.121151)
			(xy 333.845662 -281.121612) (xy 333.816787 -281.121025) (xy 333.759847 -281.111378) (xy 333.705323 -281.092345)
			(xy 333.654749 -281.064462) (xy 333.631794 -281.046936) (xy 333.620331 -281.038419) (xy 333.593951 -281.02751)
			(xy 333.565583 -281.024329) (xy 333.537443 -281.029124) (xy 333.511729 -281.041523) (xy 333.490453 -281.060554)
			(xy 333.475276 -281.084731) (xy 333.467384 -281.112165) (xy 333.466948 -281.126438) (xy 333.466948 -281.618669)
			(xy 333.959952 -281.618669) (xy 333.959952 -281.565371) (xy 333.967895 -281.512667) (xy 333.983605 -281.461737)
			(xy 334.006731 -281.413716) (xy 334.036755 -281.369679) (xy 334.073007 -281.330608) (xy 334.114678 -281.297377)
			(xy 334.160836 -281.270728) (xy 334.21045 -281.251256) (xy 334.262412 -281.239396) (xy 334.315562 -281.235413)
			(xy 334.368712 -281.239396) (xy 334.420674 -281.251256) (xy 334.470288 -281.270728) (xy 334.516446 -281.297377)
			(xy 334.558117 -281.330608) (xy 334.594369 -281.369679) (xy 334.624393 -281.413716) (xy 334.647519 -281.461737)
			(xy 334.663229 -281.512667) (xy 334.671172 -281.565371) (xy 334.67167 -281.59202) (xy 334.671172 -281.618669)
			(xy 334.663229 -281.671373) (xy 334.647519 -281.722303) (xy 334.624393 -281.770324) (xy 334.594369 -281.814361)
			(xy 334.558117 -281.853432) (xy 334.516446 -281.886663) (xy 334.470288 -281.913312) (xy 334.420674 -281.932784)
			(xy 334.368712 -281.944644) (xy 334.315562 -281.948628) (xy 334.262412 -281.944644) (xy 334.21045 -281.932784)
			(xy 334.160836 -281.913312) (xy 334.114678 -281.886663) (xy 334.073007 -281.853432) (xy 334.036755 -281.814361)
			(xy 334.006731 -281.770324) (xy 333.983605 -281.722303) (xy 333.967895 -281.671373) (xy 333.959952 -281.618669)
			(xy 333.466948 -281.618669) (xy 333.466948 -282.0416) (xy 333.467396 -282.055738) (xy 333.475127 -282.082937)
			(xy 333.490022 -282.106971) (xy 333.51094 -282.125997) (xy 333.536275 -282.138554) (xy 333.564083 -282.143678)
			(xy 333.592229 -282.140978) (xy 333.618555 -282.130658) (xy 333.630016 -282.122372) (xy 333.653422 -282.105294)
			(xy 333.704612 -282.07816) (xy 333.759518 -282.059667) (xy 333.816693 -282.050302) (xy 333.845662 -282.049728)
			(xy 333.872312 -282.050198) (xy 333.925018 -282.058137) (xy 333.975952 -282.073844) (xy 334.023976 -282.096966)
			(xy 334.068017 -282.126988) (xy 334.107091 -282.16324) (xy 334.140325 -282.20491) (xy 334.166977 -282.251069)
			(xy 334.186451 -282.300685) (xy 334.198313 -282.352649) (xy 334.202296 -282.4058) (xy 334.202293 -282.405836)
			(xy 334.429608 -282.405836) (xy 334.4301 -282.380209) (xy 334.43743 -282.329483) (xy 334.451957 -282.280333)
			(xy 334.473383 -282.233773) (xy 334.501263 -282.190767) (xy 334.535021 -282.152202) (xy 334.57396 -282.118877)
			(xy 334.617276 -282.09148) (xy 334.664072 -282.070576) (xy 334.713383 -282.056599) (xy 334.738726 -282.052776)
			(xy 334.763364 -282.049474) (xy 334.93583 -281.75077) (xy 334.926432 -281.727656) (xy 334.917935 -281.706062)
			(xy 334.90596 -281.661229) (xy 334.899901 -281.615222) (xy 334.899508 -281.59202) (xy 334.900006 -281.565371)
			(xy 334.907949 -281.512667) (xy 334.923659 -281.461737) (xy 334.946785 -281.413716) (xy 334.976809 -281.369679)
			(xy 335.013061 -281.330608) (xy 335.054732 -281.297377) (xy 335.10089 -281.270728) (xy 335.150504 -281.251256)
			(xy 335.202466 -281.239396) (xy 335.255616 -281.235413) (xy 335.308766 -281.239396) (xy 335.360728 -281.251256)
			(xy 335.410342 -281.270728) (xy 335.4565 -281.297377) (xy 335.498171 -281.330608) (xy 335.534423 -281.369679)
			(xy 335.564447 -281.413716) (xy 335.587573 -281.461737) (xy 335.603283 -281.512667) (xy 335.611226 -281.565371)
			(xy 335.611724 -281.59202) (xy 335.611342 -281.617651) (xy 335.611195 -281.618669) (xy 335.839552 -281.618669)
			(xy 335.839552 -281.565371) (xy 335.847495 -281.512667) (xy 335.863205 -281.461737) (xy 335.886331 -281.413716)
			(xy 335.916355 -281.369679) (xy 335.952607 -281.330608) (xy 335.994278 -281.297377) (xy 336.040436 -281.270728)
			(xy 336.09005 -281.251256) (xy 336.142012 -281.239396) (xy 336.195162 -281.235413) (xy 336.248312 -281.239396)
			(xy 336.300274 -281.251256) (xy 336.349888 -281.270728) (xy 336.396046 -281.297377) (xy 336.437717 -281.330608)
			(xy 336.473969 -281.369679) (xy 336.503993 -281.413716) (xy 336.527119 -281.461737) (xy 336.542829 -281.512667)
			(xy 336.550772 -281.565371) (xy 336.55127 -281.59202) (xy 336.779108 -281.59202) (xy 336.779585 -281.566393)
			(xy 336.786917 -281.515666) (xy 336.801447 -281.466515) (xy 336.822874 -281.419956) (xy 336.850756 -281.376949)
			(xy 336.884516 -281.338385) (xy 336.923457 -281.30506) (xy 336.966773 -281.277663) (xy 337.013571 -281.25676)
			(xy 337.062882 -281.242783) (xy 337.088226 -281.23896) (xy 337.113118 -281.235658) (xy 337.28533 -280.937462)
			(xy 337.275678 -280.914348) (xy 337.267153 -280.892674) (xy 337.255156 -280.847672) (xy 337.249119 -280.801491)
			(xy 337.248754 -280.778204) (xy 337.249252 -280.751555) (xy 337.257195 -280.698851) (xy 337.272905 -280.647921)
			(xy 337.296031 -280.5999) (xy 337.326055 -280.555863) (xy 337.362307 -280.516792) (xy 337.403978 -280.483561)
			(xy 337.450136 -280.456912) (xy 337.49975 -280.43744) (xy 337.551712 -280.42558) (xy 337.604862 -280.421597)
			(xy 337.658012 -280.42558) (xy 337.709974 -280.43744) (xy 337.759588 -280.456912) (xy 337.805746 -280.483561)
			(xy 337.847417 -280.516792) (xy 337.883669 -280.555863) (xy 337.913693 -280.5999) (xy 337.936819 -280.647921)
			(xy 337.952529 -280.698851) (xy 337.960472 -280.751555) (xy 337.96097 -280.778204) (xy 337.960563 -280.803824)
			(xy 337.960414 -280.804853) (xy 338.189052 -280.804853) (xy 338.189052 -280.751555) (xy 338.196995 -280.698851)
			(xy 338.212705 -280.647921) (xy 338.235831 -280.5999) (xy 338.265855 -280.555863) (xy 338.302107 -280.516792)
			(xy 338.343778 -280.483561) (xy 338.389936 -280.456912) (xy 338.43955 -280.43744) (xy 338.491512 -280.42558)
			(xy 338.544662 -280.421597) (xy 338.597812 -280.42558) (xy 338.649774 -280.43744) (xy 338.699388 -280.456912)
			(xy 338.745546 -280.483561) (xy 338.787217 -280.516792) (xy 338.823469 -280.555863) (xy 338.853493 -280.5999)
			(xy 338.876619 -280.647921) (xy 338.892329 -280.698851) (xy 338.900272 -280.751555) (xy 338.90077 -280.778204)
			(xy 340.068408 -280.778204) (xy 340.068906 -280.751555) (xy 340.076849 -280.698851) (xy 340.092559 -280.647921)
			(xy 340.115685 -280.5999) (xy 340.145709 -280.555863) (xy 340.181961 -280.516792) (xy 340.223632 -280.483561)
			(xy 340.26979 -280.456912) (xy 340.319404 -280.43744) (xy 340.371366 -280.42558) (xy 340.424516 -280.421597)
			(xy 340.477666 -280.42558) (xy 340.529628 -280.43744) (xy 340.579242 -280.456912) (xy 340.6254 -280.483561)
			(xy 340.667071 -280.516792) (xy 340.703323 -280.555863) (xy 340.733347 -280.5999) (xy 340.756473 -280.647921)
			(xy 340.772183 -280.698851) (xy 340.780126 -280.751555) (xy 340.780624 -280.778204) (xy 340.780296 -280.801494)
			(xy 340.779857 -280.804853) (xy 341.948506 -280.804853) (xy 341.948506 -280.751555) (xy 341.956449 -280.698851)
			(xy 341.972159 -280.647921) (xy 341.995285 -280.5999) (xy 342.025309 -280.555863) (xy 342.061561 -280.516792)
			(xy 342.103232 -280.483561) (xy 342.14939 -280.456912) (xy 342.199004 -280.43744) (xy 342.250966 -280.42558)
			(xy 342.304116 -280.421597) (xy 342.357266 -280.42558) (xy 342.409228 -280.43744) (xy 342.458842 -280.456912)
			(xy 342.505 -280.483561) (xy 342.546671 -280.516792) (xy 342.582923 -280.555863) (xy 342.612947 -280.5999)
			(xy 342.636073 -280.647921) (xy 342.651783 -280.698851) (xy 342.659726 -280.751555) (xy 342.660224 -280.7782)
			(xy 342.887096 -280.7782) (xy 342.891079 -280.725055) (xy 342.902937 -280.673096) (xy 342.922407 -280.623485)
			(xy 342.949052 -280.57733) (xy 342.982279 -280.535661) (xy 343.021344 -280.49941) (xy 343.065376 -280.469385)
			(xy 343.113391 -280.446258) (xy 343.164316 -280.430545) (xy 343.217015 -280.422596) (xy 343.243662 -280.422096)
			(xy 343.268677 -280.422493) (xy 343.318216 -280.429486) (xy 343.366289 -280.44334) (xy 343.411952 -280.463782)
			(xy 343.454307 -280.49041) (xy 343.492521 -280.522701) (xy 343.525842 -280.56002) (xy 343.54008 -280.580592)
			(xy 343.887298 -280.580592) (xy 343.901505 -280.56) (xy 343.934839 -280.522693) (xy 343.973062 -280.490413)
			(xy 344.015422 -280.463794) (xy 344.061088 -280.443359) (xy 344.109163 -280.429509) (xy 344.158701 -280.422517)
			(xy 344.183716 -280.422096) (xy 344.210365 -280.422587) (xy 344.263067 -280.430533) (xy 344.313996 -280.446244)
			(xy 344.362015 -280.469371) (xy 344.406051 -280.499396) (xy 344.44512 -280.535648) (xy 344.47835 -280.577319)
			(xy 344.504998 -280.623476) (xy 344.524469 -280.67309) (xy 344.536329 -280.725051) (xy 344.540312 -280.7782)
			(xy 344.536329 -280.831349) (xy 344.524469 -280.88331) (xy 344.504998 -280.932924) (xy 344.47835 -280.979081)
			(xy 344.44512 -281.020752) (xy 344.406051 -281.057004) (xy 344.362015 -281.087029) (xy 344.313996 -281.110156)
			(xy 344.263067 -281.125867) (xy 344.210365 -281.133813) (xy 344.183716 -281.134312) (xy 344.158703 -281.133852)
			(xy 344.109167 -281.12687) (xy 344.061095 -281.113027) (xy 344.015433 -281.092595) (xy 343.973077 -281.065977)
			(xy 343.934862 -281.033694) (xy 343.901538 -280.996384) (xy 343.887298 -280.975816) (xy 343.54008 -280.975816)
			(xy 343.525826 -280.996374) (xy 343.492499 -281.033681) (xy 343.454284 -281.065963) (xy 343.411932 -281.092586)
			(xy 343.366274 -281.113027) (xy 343.318207 -281.126884) (xy 343.268674 -281.133886) (xy 343.243662 -281.134312)
			(xy 343.217015 -281.133804) (xy 343.164316 -281.125855) (xy 343.113391 -281.110142) (xy 343.065376 -281.087015)
			(xy 343.021344 -281.05699) (xy 342.982279 -281.020739) (xy 342.949052 -280.97907) (xy 342.922407 -280.932915)
			(xy 342.902937 -280.883304) (xy 342.891079 -280.831345) (xy 342.887096 -280.7782) (xy 342.660224 -280.7782)
			(xy 342.660224 -280.778204) (xy 342.659726 -280.804853) (xy 342.651783 -280.857557) (xy 342.636073 -280.908487)
			(xy 342.612947 -280.956508) (xy 342.582923 -281.000545) (xy 342.546671 -281.039616) (xy 342.505 -281.072847)
			(xy 342.458842 -281.099496) (xy 342.409228 -281.118968) (xy 342.357266 -281.130828) (xy 342.304116 -281.134812)
			(xy 342.250966 -281.130828) (xy 342.199004 -281.118968) (xy 342.14939 -281.099496) (xy 342.103232 -281.072847)
			(xy 342.061561 -281.039616) (xy 342.025309 -281.000545) (xy 341.995285 -280.956508) (xy 341.972159 -280.908487)
			(xy 341.956449 -280.857557) (xy 341.948506 -280.804853) (xy 340.779857 -280.804853) (xy 340.774266 -280.84768)
			(xy 340.762255 -280.892684) (xy 340.7537 -280.914348) (xy 340.744048 -280.937462) (xy 340.91626 -281.235658)
			(xy 340.941152 -281.23896) (xy 340.966492 -281.242796) (xy 341.015795 -281.256788) (xy 341.062585 -281.2777)
			(xy 341.105895 -281.305101) (xy 341.144832 -281.338425) (xy 341.178593 -281.376984) (xy 341.20648 -281.419982)
			(xy 341.227918 -281.466533) (xy 341.242464 -281.515675) (xy 341.249819 -281.566395) (xy 341.25027 -281.59202)
			(xy 341.249772 -281.618669) (xy 341.241829 -281.671373) (xy 341.226119 -281.722303) (xy 341.202993 -281.770324)
			(xy 341.172969 -281.814361) (xy 341.136717 -281.853432) (xy 341.095046 -281.886663) (xy 341.048888 -281.913312)
			(xy 340.999274 -281.932784) (xy 340.947312 -281.944644) (xy 340.894162 -281.948628) (xy 340.841012 -281.944644)
			(xy 340.78905 -281.932784) (xy 340.739436 -281.913312) (xy 340.693278 -281.886663) (xy 340.651607 -281.853432)
			(xy 340.615355 -281.814361) (xy 340.585331 -281.770324) (xy 340.562205 -281.722303) (xy 340.546495 -281.671373)
			(xy 340.538552 -281.618669) (xy 340.538054 -281.59202) (xy 340.538437 -281.568817) (xy 340.544485 -281.522806)
			(xy 340.556468 -281.477974) (xy 340.564978 -281.456384) (xy 340.574376 -281.43327) (xy 340.40191 -281.134566)
			(xy 340.377272 -281.131264) (xy 340.351953 -281.127373) (xy 340.302684 -281.113355) (xy 340.255931 -281.092426)
			(xy 340.212657 -281.065017) (xy 340.173754 -281.031694) (xy 340.140024 -280.993143) (xy 340.112163 -280.950159)
			(xy 340.090744 -280.903628) (xy 340.07621 -280.85451) (xy 340.068859 -280.803816) (xy 340.068408 -280.778204)
			(xy 338.90077 -280.778204) (xy 338.900272 -280.804853) (xy 338.892329 -280.857557) (xy 338.876619 -280.908487)
			(xy 338.853493 -280.956508) (xy 338.823469 -281.000545) (xy 338.787217 -281.039616) (xy 338.745546 -281.072847)
			(xy 338.699388 -281.099496) (xy 338.649774 -281.118968) (xy 338.597812 -281.130828) (xy 338.544662 -281.134812)
			(xy 338.491512 -281.130828) (xy 338.43955 -281.118968) (xy 338.389936 -281.099496) (xy 338.343778 -281.072847)
			(xy 338.302107 -281.039616) (xy 338.265855 -281.000545) (xy 338.235831 -280.956508) (xy 338.212705 -280.908487)
			(xy 338.196995 -280.857557) (xy 338.189052 -280.804853) (xy 337.960414 -280.804853) (xy 337.953244 -280.854537)
			(xy 337.938731 -280.903678) (xy 337.917323 -280.95023) (xy 337.889462 -280.993232) (xy 337.855723 -281.031795)
			(xy 337.816804 -281.065123) (xy 337.773509 -281.092527) (xy 337.726733 -281.113441) (xy 337.677441 -281.127432)
			(xy 337.652106 -281.131264) (xy 337.627468 -281.134566) (xy 337.455002 -281.433016) (xy 337.4644 -281.45613)
			(xy 337.472924 -281.477759) (xy 337.484908 -281.522679) (xy 337.49095 -281.568775) (xy 337.491324 -281.59202)
			(xy 337.490826 -281.618669) (xy 337.719152 -281.618669) (xy 337.719152 -281.565371) (xy 337.727095 -281.512667)
			(xy 337.742805 -281.461737) (xy 337.765931 -281.413716) (xy 337.795955 -281.369679) (xy 337.832207 -281.330608)
			(xy 337.873878 -281.297377) (xy 337.920036 -281.270728) (xy 337.96965 -281.251256) (xy 338.021612 -281.239396)
			(xy 338.074762 -281.235413) (xy 338.127912 -281.239396) (xy 338.179874 -281.251256) (xy 338.229488 -281.270728)
			(xy 338.275646 -281.297377) (xy 338.317317 -281.330608) (xy 338.353569 -281.369679) (xy 338.383593 -281.413716)
			(xy 338.406719 -281.461737) (xy 338.422429 -281.512667) (xy 338.430372 -281.565371) (xy 338.43087 -281.592)
			(xy 338.658013 -281.592) (xy 338.661995 -281.538857) (xy 338.673853 -281.486901) (xy 338.693321 -281.437292)
			(xy 338.719966 -281.391139) (xy 338.753191 -281.349473) (xy 338.792255 -281.313223) (xy 338.836285 -281.283199)
			(xy 338.884297 -281.260073) (xy 338.93522 -281.244361) (xy 338.987916 -281.236413) (xy 339.014562 -281.235912)
			(xy 339.039577 -281.236302) (xy 339.089117 -281.243295) (xy 339.137191 -281.25715) (xy 339.182854 -281.277593)
			(xy 339.225209 -281.304222) (xy 339.263422 -281.336515) (xy 339.296742 -281.373836) (xy 339.31098 -281.394408)
			(xy 339.657944 -281.394408) (xy 339.672191 -281.373844) (xy 339.705518 -281.336536) (xy 339.743733 -281.304254)
			(xy 339.786087 -281.277631) (xy 339.831746 -281.257191) (xy 339.879815 -281.243336) (xy 339.929349 -281.236337)
			(xy 339.954362 -281.235912) (xy 339.981016 -281.236343) (xy 340.033731 -281.244283) (xy 340.084673 -281.259991)
			(xy 340.132704 -281.283118) (xy 340.176752 -281.313145) (xy 340.215832 -281.349402) (xy 340.249072 -281.391079)
			(xy 340.275728 -281.437245) (xy 340.295205 -281.486868) (xy 340.307068 -281.53884) (xy 340.311052 -281.592)
			(xy 340.307068 -281.64516) (xy 340.295205 -281.697132) (xy 340.275728 -281.746755) (xy 340.249072 -281.792921)
			(xy 340.215832 -281.834598) (xy 340.176752 -281.870855) (xy 340.132704 -281.900882) (xy 340.084673 -281.924009)
			(xy 340.033731 -281.939717) (xy 339.981016 -281.947657) (xy 339.954362 -281.948128) (xy 339.929346 -281.947746)
			(xy 339.879805 -281.940755) (xy 339.83173 -281.926901) (xy 339.786065 -281.906457) (xy 339.743711 -281.879826)
			(xy 339.705498 -281.84753) (xy 339.67218 -281.810206) (xy 339.657944 -281.789632) (xy 339.31098 -281.789632)
			(xy 339.296731 -281.810193) (xy 339.263403 -281.8475) (xy 339.225187 -281.879781) (xy 339.182834 -281.906403)
			(xy 339.137175 -281.926843) (xy 339.089107 -281.9407) (xy 339.039575 -281.947702) (xy 339.014562 -281.948128)
			(xy 338.987916 -281.947587) (xy 338.93522 -281.939639) (xy 338.884297 -281.923927) (xy 338.836285 -281.900801)
			(xy 338.792255 -281.870777) (xy 338.753191 -281.834527) (xy 338.719966 -281.792861) (xy 338.693321 -281.746708)
			(xy 338.673853 -281.697099) (xy 338.661995 -281.645143) (xy 338.658013 -281.592) (xy 338.43087 -281.592)
			(xy 338.43087 -281.59202) (xy 338.430372 -281.618669) (xy 338.422429 -281.671373) (xy 338.406719 -281.722303)
			(xy 338.383593 -281.770324) (xy 338.353569 -281.814361) (xy 338.317317 -281.853432) (xy 338.275646 -281.886663)
			(xy 338.229488 -281.913312) (xy 338.179874 -281.932784) (xy 338.127912 -281.944644) (xy 338.074762 -281.948628)
			(xy 338.021612 -281.944644) (xy 337.96965 -281.932784) (xy 337.920036 -281.913312) (xy 337.873878 -281.886663)
			(xy 337.832207 -281.853432) (xy 337.795955 -281.814361) (xy 337.765931 -281.770324) (xy 337.742805 -281.722303)
			(xy 337.727095 -281.671373) (xy 337.719152 -281.618669) (xy 337.490826 -281.618669) (xy 337.482883 -281.671373)
			(xy 337.467173 -281.722303) (xy 337.444047 -281.770324) (xy 337.414023 -281.814361) (xy 337.377771 -281.853432)
			(xy 337.3361 -281.886663) (xy 337.289942 -281.913312) (xy 337.240328 -281.932784) (xy 337.188366 -281.944644)
			(xy 337.135216 -281.948628) (xy 337.082066 -281.944644) (xy 337.030104 -281.932784) (xy 336.98049 -281.913312)
			(xy 336.934332 -281.886663) (xy 336.892661 -281.853432) (xy 336.856409 -281.814361) (xy 336.826385 -281.770324)
			(xy 336.803259 -281.722303) (xy 336.787549 -281.671373) (xy 336.779606 -281.618669) (xy 336.779108 -281.59202)
			(xy 336.55127 -281.59202) (xy 336.550772 -281.618669) (xy 336.542829 -281.671373) (xy 336.527119 -281.722303)
			(xy 336.503993 -281.770324) (xy 336.473969 -281.814361) (xy 336.437717 -281.853432) (xy 336.396046 -281.886663)
			(xy 336.349888 -281.913312) (xy 336.300274 -281.932784) (xy 336.248312 -281.944644) (xy 336.195162 -281.948628)
			(xy 336.142012 -281.944644) (xy 336.09005 -281.932784) (xy 336.040436 -281.913312) (xy 335.994278 -281.886663)
			(xy 335.952607 -281.853432) (xy 335.916355 -281.814361) (xy 335.886331 -281.770324) (xy 335.863205 -281.722303)
			(xy 335.847495 -281.671373) (xy 335.839552 -281.618669) (xy 335.611195 -281.618669) (xy 335.604003 -281.668384)
			(xy 335.589465 -281.717541) (xy 335.568028 -281.764104) (xy 335.540136 -281.807113) (xy 335.506364 -281.845678)
			(xy 335.467412 -281.879001) (xy 335.424084 -281.906395) (xy 335.377276 -281.927292) (xy 335.327955 -281.941261)
			(xy 335.302606 -281.94508) (xy 335.277968 -281.948382) (xy 335.105502 -282.247086) (xy 335.1149 -282.2702)
			(xy 335.123386 -282.291798) (xy 335.135364 -282.336629) (xy 335.141428 -282.382635) (xy 335.141824 -282.405836)
			(xy 335.369154 -282.405836) (xy 335.369652 -282.379187) (xy 335.377595 -282.326483) (xy 335.393305 -282.275553)
			(xy 335.416431 -282.227532) (xy 335.446455 -282.183495) (xy 335.482707 -282.144424) (xy 335.524378 -282.111193)
			(xy 335.570536 -282.084544) (xy 335.62015 -282.065072) (xy 335.672112 -282.053212) (xy 335.725262 -282.049229)
			(xy 335.778412 -282.053212) (xy 335.830374 -282.065072) (xy 335.879988 -282.084544) (xy 335.926146 -282.111193)
			(xy 335.967817 -282.144424) (xy 336.004069 -282.183495) (xy 336.034093 -282.227532) (xy 336.057219 -282.275553)
			(xy 336.072929 -282.326483) (xy 336.080872 -282.379187) (xy 336.081369 -282.4058) (xy 336.308704 -282.4058)
			(xy 336.312687 -282.352651) (xy 336.324547 -282.300689) (xy 336.34402 -282.251075) (xy 336.37067 -282.204917)
			(xy 336.403902 -282.163248) (xy 336.442973 -282.126996) (xy 336.487011 -282.096973) (xy 336.535032 -282.07385)
			(xy 336.585963 -282.058142) (xy 336.638667 -282.0502) (xy 336.665316 -282.049728) (xy 336.69033 -282.050146)
			(xy 336.739869 -282.057133) (xy 336.787943 -282.070982) (xy 336.833606 -282.09142) (xy 336.875961 -282.118046)
			(xy 336.914175 -282.150335) (xy 336.947496 -282.187653) (xy 336.961734 -282.208224) (xy 337.308698 -282.208224)
			(xy 337.322915 -282.187639) (xy 337.356247 -282.150331) (xy 337.394467 -282.118049) (xy 337.436826 -282.091429)
			(xy 337.48249 -282.070992) (xy 337.530564 -282.057142) (xy 337.580102 -282.050149) (xy 337.605116 -282.049728)
			(xy 337.631767 -282.050155) (xy 337.684474 -282.058101) (xy 337.735408 -282.073814) (xy 337.783431 -282.096943)
			(xy 337.827471 -282.126971) (xy 337.866543 -282.163226) (xy 337.899776 -282.204901) (xy 337.926427 -282.251062)
			(xy 337.9459 -282.30068) (xy 337.95776 -282.352647) (xy 337.961744 -282.4058) (xy 337.959744 -282.432485)
			(xy 338.189306 -282.432485) (xy 338.189306 -282.379187) (xy 338.197249 -282.326483) (xy 338.212959 -282.275553)
			(xy 338.236085 -282.227532) (xy 338.266109 -282.183495) (xy 338.302361 -282.144424) (xy 338.344032 -282.111193)
			(xy 338.39019 -282.084544) (xy 338.439804 -282.065072) (xy 338.491766 -282.053212) (xy 338.544916 -282.049229)
			(xy 338.598066 -282.053212) (xy 338.650028 -282.065072) (xy 338.699642 -282.084544) (xy 338.7458 -282.111193)
			(xy 338.787471 -282.144424) (xy 338.823723 -282.183495) (xy 338.853747 -282.227532) (xy 338.876873 -282.275553)
			(xy 338.892583 -282.326483) (xy 338.900526 -282.379187) (xy 338.901024 -282.405836) (xy 338.900526 -282.432485)
			(xy 338.892583 -282.485189) (xy 338.876873 -282.536119) (xy 338.853747 -282.58414) (xy 338.823723 -282.628177)
			(xy 338.787471 -282.667248) (xy 338.7458 -282.700479) (xy 338.699642 -282.727128) (xy 338.650028 -282.7466)
			(xy 338.598066 -282.75846) (xy 338.544916 -282.762444) (xy 338.491766 -282.75846) (xy 338.439804 -282.7466)
			(xy 338.39019 -282.727128) (xy 338.344032 -282.700479) (xy 338.302361 -282.667248) (xy 338.266109 -282.628177)
			(xy 338.236085 -282.58414) (xy 338.212959 -282.536119) (xy 338.197249 -282.485189) (xy 338.189306 -282.432485)
			(xy 337.959744 -282.432485) (xy 337.95776 -282.458953) (xy 337.9459 -282.51092) (xy 337.926427 -282.560538)
			(xy 337.899776 -282.606699) (xy 337.866543 -282.648374) (xy 337.827471 -282.684629) (xy 337.783431 -282.714657)
			(xy 337.735408 -282.737786) (xy 337.684474 -282.753499) (xy 337.631767 -282.761445) (xy 337.605116 -282.761944)
			(xy 337.580102 -282.761514) (xy 337.530563 -282.75453) (xy 337.482489 -282.740685) (xy 337.436825 -282.720249)
			(xy 337.39447 -282.693625) (xy 337.356256 -282.661336) (xy 337.322936 -282.624019) (xy 337.308698 -282.603448)
			(xy 336.961734 -282.603448) (xy 336.947487 -282.624012) (xy 336.914162 -282.661322) (xy 336.875947 -282.693606)
			(xy 336.833593 -282.720229) (xy 336.787933 -282.740669) (xy 336.739864 -282.754523) (xy 336.690329 -282.76152)
			(xy 336.665316 -282.761944) (xy 336.638667 -282.7614) (xy 336.585963 -282.753458) (xy 336.535032 -282.73775)
			(xy 336.487011 -282.714627) (xy 336.442973 -282.684604) (xy 336.403902 -282.648352) (xy 336.37067 -282.606683)
			(xy 336.34402 -282.560525) (xy 336.324547 -282.510911) (xy 336.312687 -282.458949) (xy 336.308704 -282.4058)
			(xy 336.081369 -282.4058) (xy 336.08137 -282.405836) (xy 336.080983 -282.429081) (xy 336.074944 -282.475176)
			(xy 336.06296 -282.520094) (xy 336.054446 -282.541726) (xy 336.044794 -282.56484) (xy 336.217514 -282.863544)
			(xy 336.242152 -282.866846) (xy 336.26749 -282.870696) (xy 336.316792 -282.884687) (xy 336.363581 -282.905598)
			(xy 336.40689 -282.932997) (xy 336.445827 -282.966319) (xy 336.479588 -283.004877) (xy 336.507475 -283.047874)
			(xy 336.528914 -283.094423) (xy 336.543462 -283.143564) (xy 336.550818 -283.194282) (xy 336.55127 -283.219906)
			(xy 336.550772 -283.246555) (xy 336.779352 -283.246555) (xy 336.779352 -283.193257) (xy 336.787295 -283.140553)
			(xy 336.803005 -283.089623) (xy 336.826131 -283.041602) (xy 336.856155 -282.997565) (xy 336.892407 -282.958494)
			(xy 336.934078 -282.925263) (xy 336.980236 -282.898614) (xy 337.02985 -282.879142) (xy 337.081812 -282.867282)
			(xy 337.134962 -282.863299) (xy 337.188112 -282.867282) (xy 337.240074 -282.879142) (xy 337.289688 -282.898614)
			(xy 337.335846 -282.925263) (xy 337.377517 -282.958494) (xy 337.413769 -282.997565) (xy 337.443793 -283.041602)
			(xy 337.466919 -283.089623) (xy 337.482629 -283.140553) (xy 337.490572 -283.193257) (xy 337.49107 -283.219906)
			(xy 337.490572 -283.246555) (xy 337.719152 -283.246555) (xy 337.719152 -283.193257) (xy 337.727095 -283.140553)
			(xy 337.742805 -283.089623) (xy 337.765931 -283.041602) (xy 337.795955 -282.997565) (xy 337.832207 -282.958494)
			(xy 337.873878 -282.925263) (xy 337.920036 -282.898614) (xy 337.96965 -282.879142) (xy 338.021612 -282.867282)
			(xy 338.074762 -282.863299) (xy 338.127912 -282.867282) (xy 338.179874 -282.879142) (xy 338.229488 -282.898614)
			(xy 338.275646 -282.925263) (xy 338.317317 -282.958494) (xy 338.353569 -282.997565) (xy 338.383593 -283.041602)
			(xy 338.406719 -283.089623) (xy 338.422429 -283.140553) (xy 338.430372 -283.193257) (xy 338.43087 -283.219906)
			(xy 338.658454 -283.219906) (xy 338.658879 -283.194277) (xy 338.666214 -283.143546) (xy 338.680748 -283.094392)
			(xy 338.70218 -283.047829) (xy 338.730067 -283.004821) (xy 338.763833 -282.966257) (xy 338.802781 -282.932933)
			(xy 338.846104 -282.905538) (xy 338.892908 -282.884638) (xy 338.942225 -282.870666) (xy 338.967572 -282.866846)
			(xy 338.992464 -282.863544) (xy 339.16493 -282.564586) (xy 339.155532 -282.541472) (xy 339.147039 -282.519877)
			(xy 339.135063 -282.475044) (xy 339.129002 -282.429038) (xy 339.128608 -282.405836) (xy 339.129106 -282.379187)
			(xy 339.137049 -282.326483) (xy 339.152759 -282.275553) (xy 339.175885 -282.227532) (xy 339.205909 -282.183495)
			(xy 339.242161 -282.144424) (xy 339.283832 -282.111193) (xy 339.32999 -282.084544) (xy 339.379604 -282.065072)
			(xy 339.431566 -282.053212) (xy 339.484716 -282.049229) (xy 339.537866 -282.053212) (xy 339.589828 -282.065072)
			(xy 339.639442 -282.084544) (xy 339.6856 -282.111193) (xy 339.727271 -282.144424) (xy 339.763523 -282.183495)
			(xy 339.793547 -282.227532) (xy 339.816673 -282.275553) (xy 339.832383 -282.326483) (xy 339.840326 -282.379187)
			(xy 339.840824 -282.405836) (xy 339.840336 -282.431473) (xy 339.84019 -282.432485) (xy 340.068906 -282.432485)
			(xy 340.068906 -282.379187) (xy 340.076849 -282.326483) (xy 340.092559 -282.275553) (xy 340.115685 -282.227532)
			(xy 340.145709 -282.183495) (xy 340.181961 -282.144424) (xy 340.223632 -282.111193) (xy 340.26979 -282.084544)
			(xy 340.319404 -282.065072) (xy 340.371366 -282.053212) (xy 340.424516 -282.049229) (xy 340.477666 -282.053212)
			(xy 340.529628 -282.065072) (xy 340.579242 -282.084544) (xy 340.6254 -282.111193) (xy 340.667071 -282.144424)
			(xy 340.703323 -282.183495) (xy 340.733347 -282.227532) (xy 340.756473 -282.275553) (xy 340.772183 -282.326483)
			(xy 340.780126 -282.379187) (xy 340.780624 -282.405836) (xy 341.008208 -282.405836) (xy 341.0087 -282.380209)
			(xy 341.01603 -282.329483) (xy 341.030557 -282.280333) (xy 341.051983 -282.233773) (xy 341.079863 -282.190767)
			(xy 341.113621 -282.152202) (xy 341.15256 -282.118877) (xy 341.195876 -282.09148) (xy 341.242672 -282.070576)
			(xy 341.291983 -282.056599) (xy 341.317326 -282.052776) (xy 341.341964 -282.049474) (xy 341.51443 -281.751024)
			(xy 341.504778 -281.72791) (xy 341.496265 -281.706277) (xy 341.484277 -281.661359) (xy 341.478231 -281.615265)
			(xy 341.477854 -281.59202) (xy 341.478352 -281.565371) (xy 341.486295 -281.512667) (xy 341.502005 -281.461737)
			(xy 341.525131 -281.413716) (xy 341.555155 -281.369679) (xy 341.591407 -281.330608) (xy 341.633078 -281.297377)
			(xy 341.679236 -281.270728) (xy 341.72885 -281.251256) (xy 341.780812 -281.239396) (xy 341.833962 -281.235413)
			(xy 341.887112 -281.239396) (xy 341.939074 -281.251256) (xy 341.988688 -281.270728) (xy 342.034846 -281.297377)
			(xy 342.076517 -281.330608) (xy 342.112769 -281.369679) (xy 342.142793 -281.413716) (xy 342.165919 -281.461737)
			(xy 342.181629 -281.512667) (xy 342.189572 -281.565371) (xy 342.19007 -281.59202) (xy 342.189677 -281.61764)
			(xy 342.189528 -281.618669) (xy 342.418152 -281.618669) (xy 342.418152 -281.565371) (xy 342.426095 -281.512667)
			(xy 342.441805 -281.461737) (xy 342.464931 -281.413716) (xy 342.494955 -281.369679) (xy 342.531207 -281.330608)
			(xy 342.572878 -281.297377) (xy 342.619036 -281.270728) (xy 342.66865 -281.251256) (xy 342.720612 -281.239396)
			(xy 342.773762 -281.235413) (xy 342.826912 -281.239396) (xy 342.878874 -281.251256) (xy 342.928488 -281.270728)
			(xy 342.974646 -281.297377) (xy 343.016317 -281.330608) (xy 343.052569 -281.369679) (xy 343.082593 -281.413716)
			(xy 343.105719 -281.461737) (xy 343.121429 -281.512667) (xy 343.129372 -281.565371) (xy 343.12987 -281.59202)
			(xy 343.129372 -281.618669) (xy 343.121429 -281.671373) (xy 343.105719 -281.722303) (xy 343.082593 -281.770324)
			(xy 343.052569 -281.814361) (xy 343.016317 -281.853432) (xy 342.974646 -281.886663) (xy 342.928488 -281.913312)
			(xy 342.878874 -281.932784) (xy 342.826912 -281.944644) (xy 342.773762 -281.948628) (xy 342.720612 -281.944644)
			(xy 342.66865 -281.932784) (xy 342.619036 -281.913312) (xy 342.572878 -281.886663) (xy 342.531207 -281.853432)
			(xy 342.494955 -281.814361) (xy 342.464931 -281.770324) (xy 342.441805 -281.722303) (xy 342.426095 -281.671373)
			(xy 342.418152 -281.618669) (xy 342.189528 -281.618669) (xy 342.182357 -281.668354) (xy 342.167842 -281.717495)
			(xy 342.146431 -281.764047) (xy 342.118568 -281.807049) (xy 342.084828 -281.845612) (xy 342.045908 -281.87894)
			(xy 342.002612 -281.906344) (xy 341.955834 -281.927257) (xy 341.906542 -281.941248) (xy 341.881206 -281.94508)
			(xy 341.856314 -281.948382) (xy 341.683848 -282.246832) (xy 341.6935 -282.269946) (xy 341.702028 -282.291573)
			(xy 341.714011 -282.336494) (xy 341.720051 -282.382591) (xy 341.720424 -282.405836) (xy 341.719926 -282.432485)
			(xy 341.948506 -282.432485) (xy 341.948506 -282.379187) (xy 341.956449 -282.326483) (xy 341.972159 -282.275553)
			(xy 341.995285 -282.227532) (xy 342.025309 -282.183495) (xy 342.061561 -282.144424) (xy 342.103232 -282.111193)
			(xy 342.14939 -282.084544) (xy 342.199004 -282.065072) (xy 342.250966 -282.053212) (xy 342.304116 -282.049229)
			(xy 342.357266 -282.053212) (xy 342.409228 -282.065072) (xy 342.458842 -282.084544) (xy 342.505 -282.111193)
			(xy 342.546671 -282.144424) (xy 342.582923 -282.183495) (xy 342.612947 -282.227532) (xy 342.636073 -282.275553)
			(xy 342.651783 -282.326483) (xy 342.659726 -282.379187) (xy 342.660224 -282.405836) (xy 342.887554 -282.405836)
			(xy 342.888006 -282.380208) (xy 342.895337 -282.329478) (xy 342.909867 -282.280324) (xy 342.931296 -282.233762)
			(xy 342.95918 -282.190754) (xy 342.992943 -282.152189) (xy 343.031888 -282.118864) (xy 343.075209 -282.091469)
			(xy 343.122011 -282.070569) (xy 343.171326 -282.056597) (xy 343.196672 -282.052776) (xy 343.22131 -282.049474)
			(xy 343.39403 -281.750516) (xy 343.384378 -281.727402) (xy 343.375906 -281.705851) (xy 343.364024 -281.661095)
			(xy 343.358057 -281.615174) (xy 343.357708 -281.59202) (xy 343.358206 -281.565371) (xy 343.366149 -281.512667)
			(xy 343.381859 -281.461737) (xy 343.404985 -281.413716) (xy 343.435009 -281.369679) (xy 343.471261 -281.330608)
			(xy 343.512932 -281.297377) (xy 343.55909 -281.270728) (xy 343.608704 -281.251256) (xy 343.660666 -281.239396)
			(xy 343.713816 -281.235413) (xy 343.766966 -281.239396) (xy 343.818928 -281.251256) (xy 343.868542 -281.270728)
			(xy 343.9147 -281.297377) (xy 343.956371 -281.330608) (xy 343.992623 -281.369679) (xy 344.022647 -281.413716)
			(xy 344.045773 -281.461737) (xy 344.061483 -281.512667) (xy 344.069426 -281.565371) (xy 344.069924 -281.59202)
			(xy 344.069422 -281.617657) (xy 344.069276 -281.618669) (xy 344.298006 -281.618669) (xy 344.298006 -281.565371)
			(xy 344.305949 -281.512667) (xy 344.321659 -281.461737) (xy 344.344785 -281.413716) (xy 344.374809 -281.369679)
			(xy 344.411061 -281.330608) (xy 344.452732 -281.297377) (xy 344.49889 -281.270728) (xy 344.548504 -281.251256)
			(xy 344.600466 -281.239396) (xy 344.653616 -281.235413) (xy 344.706766 -281.239396) (xy 344.758728 -281.251256)
			(xy 344.808342 -281.270728) (xy 344.8545 -281.297377) (xy 344.896171 -281.330608) (xy 344.932423 -281.369679)
			(xy 344.962447 -281.413716) (xy 344.985573 -281.461737) (xy 345.001283 -281.512667) (xy 345.009226 -281.565371)
			(xy 345.009724 -281.59202) (xy 345.237308 -281.59202) (xy 345.237785 -281.566393) (xy 345.245117 -281.515666)
			(xy 345.259647 -281.466515) (xy 345.281074 -281.419956) (xy 345.308956 -281.376949) (xy 345.342716 -281.338385)
			(xy 345.381657 -281.30506) (xy 345.424973 -281.277663) (xy 345.471771 -281.25676) (xy 345.521082 -281.242783)
			(xy 345.546426 -281.23896) (xy 345.571064 -281.235658) (xy 345.74353 -280.937208) (xy 345.733878 -280.914094)
			(xy 345.725361 -280.892463) (xy 345.713374 -280.847544) (xy 345.70733 -280.801449) (xy 345.706954 -280.778204)
			(xy 345.707452 -280.751555) (xy 345.715395 -280.698851) (xy 345.731105 -280.647921) (xy 345.754231 -280.5999)
			(xy 345.784255 -280.555863) (xy 345.820507 -280.516792) (xy 345.862178 -280.483561) (xy 345.908336 -280.456912)
			(xy 345.95795 -280.43744) (xy 346.009912 -280.42558) (xy 346.063062 -280.421597) (xy 346.116212 -280.42558)
			(xy 346.168174 -280.43744) (xy 346.217788 -280.456912) (xy 346.263946 -280.483561) (xy 346.305617 -280.516792)
			(xy 346.341869 -280.555863) (xy 346.371893 -280.5999) (xy 346.395019 -280.647921) (xy 346.410729 -280.698851)
			(xy 346.418672 -280.751555) (xy 346.41917 -280.778204) (xy 346.418763 -280.803824) (xy 346.418614 -280.804853)
			(xy 346.647252 -280.804853) (xy 346.647252 -280.751555) (xy 346.655195 -280.698851) (xy 346.670905 -280.647921)
			(xy 346.694031 -280.5999) (xy 346.724055 -280.555863) (xy 346.760307 -280.516792) (xy 346.801978 -280.483561)
			(xy 346.848136 -280.456912) (xy 346.89775 -280.43744) (xy 346.949712 -280.42558) (xy 347.002862 -280.421597)
			(xy 347.056012 -280.42558) (xy 347.107974 -280.43744) (xy 347.157588 -280.456912) (xy 347.203746 -280.483561)
			(xy 347.245417 -280.516792) (xy 347.281669 -280.555863) (xy 347.311693 -280.5999) (xy 347.334819 -280.647921)
			(xy 347.350529 -280.698851) (xy 347.358472 -280.751555) (xy 347.35897 -280.778204) (xy 348.526354 -280.778204)
			(xy 348.526852 -280.751555) (xy 348.534795 -280.698851) (xy 348.550505 -280.647921) (xy 348.573631 -280.5999)
			(xy 348.603655 -280.555863) (xy 348.639907 -280.516792) (xy 348.681578 -280.483561) (xy 348.727736 -280.456912)
			(xy 348.77735 -280.43744) (xy 348.829312 -280.42558) (xy 348.882462 -280.421597) (xy 348.935612 -280.42558)
			(xy 348.987574 -280.43744) (xy 349.037188 -280.456912) (xy 349.083346 -280.483561) (xy 349.125017 -280.516792)
			(xy 349.161269 -280.555863) (xy 349.191293 -280.5999) (xy 349.214419 -280.647921) (xy 349.230129 -280.698851)
			(xy 349.238072 -280.751555) (xy 349.23857 -280.778204) (xy 349.238202 -280.801356) (xy 349.237746 -280.804853)
			(xy 349.466652 -280.804853) (xy 349.466652 -280.751555) (xy 349.474595 -280.698851) (xy 349.490305 -280.647921)
			(xy 349.513431 -280.5999) (xy 349.543455 -280.555863) (xy 349.579707 -280.516792) (xy 349.621378 -280.483561)
			(xy 349.667536 -280.456912) (xy 349.71715 -280.43744) (xy 349.769112 -280.42558) (xy 349.822262 -280.421597)
			(xy 349.875412 -280.42558) (xy 349.927374 -280.43744) (xy 349.976988 -280.456912) (xy 350.023146 -280.483561)
			(xy 350.064817 -280.516792) (xy 350.101069 -280.555863) (xy 350.131093 -280.5999) (xy 350.154219 -280.647921)
			(xy 350.169929 -280.698851) (xy 350.177872 -280.751555) (xy 350.17837 -280.778204) (xy 350.177872 -280.804853)
			(xy 350.406706 -280.804853) (xy 350.406706 -280.751555) (xy 350.414649 -280.698851) (xy 350.430359 -280.647921)
			(xy 350.453485 -280.5999) (xy 350.483509 -280.555863) (xy 350.519761 -280.516792) (xy 350.561432 -280.483561)
			(xy 350.60759 -280.456912) (xy 350.657204 -280.43744) (xy 350.709166 -280.42558) (xy 350.762316 -280.421597)
			(xy 350.815466 -280.42558) (xy 350.867428 -280.43744) (xy 350.917042 -280.456912) (xy 350.9632 -280.483561)
			(xy 351.004871 -280.516792) (xy 351.041123 -280.555863) (xy 351.071147 -280.5999) (xy 351.094273 -280.647921)
			(xy 351.109983 -280.698851) (xy 351.117926 -280.751555) (xy 351.118424 -280.778204) (xy 351.345754 -280.778204)
			(xy 351.346252 -280.751555) (xy 351.354195 -280.698851) (xy 351.369905 -280.647921) (xy 351.393031 -280.5999)
			(xy 351.423055 -280.555863) (xy 351.459307 -280.516792) (xy 351.500978 -280.483561) (xy 351.547136 -280.456912)
			(xy 351.59675 -280.43744) (xy 351.648712 -280.42558) (xy 351.701862 -280.421597) (xy 351.755012 -280.42558)
			(xy 351.806974 -280.43744) (xy 351.856588 -280.456912) (xy 351.902746 -280.483561) (xy 351.944417 -280.516792)
			(xy 351.980669 -280.555863) (xy 352.010693 -280.5999) (xy 352.033819 -280.647921) (xy 352.049529 -280.698851)
			(xy 352.057472 -280.751555) (xy 352.05797 -280.778204) (xy 352.285554 -280.778204) (xy 352.285977 -280.752575)
			(xy 352.293312 -280.701844) (xy 352.307846 -280.65269) (xy 352.329279 -280.606127) (xy 352.357166 -280.563119)
			(xy 352.390933 -280.524555) (xy 352.42988 -280.49123) (xy 352.473204 -280.463836) (xy 352.520008 -280.442936)
			(xy 352.569325 -280.428964) (xy 352.594672 -280.425144) (xy 352.61931 -280.421842) (xy 352.79203 -280.122884)
			(xy 352.782632 -280.09977) (xy 352.774139 -280.078175) (xy 352.762163 -280.033343) (xy 352.756102 -279.987336)
			(xy 352.755708 -279.964134) (xy 352.756206 -279.937485) (xy 352.764149 -279.884781) (xy 352.779859 -279.833851)
			(xy 352.802985 -279.78583) (xy 352.833009 -279.741793) (xy 352.869261 -279.702722) (xy 352.910932 -279.669491)
			(xy 352.95709 -279.642842) (xy 353.006704 -279.62337) (xy 353.058666 -279.61151) (xy 353.111816 -279.607527)
			(xy 353.164966 -279.61151) (xy 353.216928 -279.62337) (xy 353.266542 -279.642842) (xy 353.3127 -279.669491)
			(xy 353.354371 -279.702722) (xy 353.390623 -279.741793) (xy 353.420647 -279.78583) (xy 353.443773 -279.833851)
			(xy 353.459483 -279.884781) (xy 353.467426 -279.937485) (xy 353.467924 -279.964134) (xy 353.467434 -279.989771)
			(xy 353.467288 -279.990783) (xy 353.696006 -279.990783) (xy 353.696006 -279.937485) (xy 353.703949 -279.884781)
			(xy 353.719659 -279.833851) (xy 353.742785 -279.78583) (xy 353.772809 -279.741793) (xy 353.809061 -279.702722)
			(xy 353.850732 -279.669491) (xy 353.89689 -279.642842) (xy 353.946504 -279.62337) (xy 353.998466 -279.61151)
			(xy 354.051616 -279.607527) (xy 354.104766 -279.61151) (xy 354.156728 -279.62337) (xy 354.206342 -279.642842)
			(xy 354.2525 -279.669491) (xy 354.294171 -279.702722) (xy 354.330423 -279.741793) (xy 354.360447 -279.78583)
			(xy 354.383573 -279.833851) (xy 354.399283 -279.884781) (xy 354.407226 -279.937485) (xy 354.407724 -279.964134)
			(xy 354.407226 -279.990783) (xy 354.399283 -280.043487) (xy 354.383573 -280.094417) (xy 354.360447 -280.142438)
			(xy 354.330423 -280.186475) (xy 354.294171 -280.225546) (xy 354.2525 -280.258777) (xy 354.206342 -280.285426)
			(xy 354.156728 -280.304898) (xy 354.104766 -280.316758) (xy 354.051616 -280.320742) (xy 353.998466 -280.316758)
			(xy 353.946504 -280.304898) (xy 353.89689 -280.285426) (xy 353.850732 -280.258777) (xy 353.809061 -280.225546)
			(xy 353.772809 -280.186475) (xy 353.742785 -280.142438) (xy 353.719659 -280.094417) (xy 353.703949 -280.043487)
			(xy 353.696006 -279.990783) (xy 353.467288 -279.990783) (xy 353.460089 -280.040517) (xy 353.445542 -280.089684)
			(xy 353.424092 -280.136257) (xy 353.396184 -280.179271) (xy 353.362395 -280.217837) (xy 353.323424 -280.251159)
			(xy 353.280076 -280.278545) (xy 353.233248 -280.299431) (xy 353.183909 -280.313385) (xy 353.158552 -280.317194)
			(xy 353.133914 -280.320496) (xy 352.961194 -280.6192) (xy 352.970846 -280.642314) (xy 352.979362 -280.663946)
			(xy 352.99135 -280.708864) (xy 352.997395 -280.754959) (xy 352.99777 -280.778204) (xy 352.997272 -280.804853)
			(xy 352.989329 -280.857557) (xy 352.973619 -280.908487) (xy 352.950493 -280.956508) (xy 352.920469 -281.000545)
			(xy 352.884217 -281.039616) (xy 352.842546 -281.072847) (xy 352.796388 -281.099496) (xy 352.746774 -281.118968)
			(xy 352.694812 -281.130828) (xy 352.641662 -281.134812) (xy 352.588512 -281.130828) (xy 352.53655 -281.118968)
			(xy 352.486936 -281.099496) (xy 352.440778 -281.072847) (xy 352.399107 -281.039616) (xy 352.362855 -281.000545)
			(xy 352.332831 -280.956508) (xy 352.309705 -280.908487) (xy 352.293995 -280.857557) (xy 352.286052 -280.804853)
			(xy 352.285554 -280.778204) (xy 352.05797 -280.778204) (xy 352.057602 -280.801356) (xy 352.051614 -280.84727)
			(xy 352.03974 -280.892025) (xy 352.0313 -280.913586) (xy 352.021648 -280.9367) (xy 352.194368 -281.235658)
			(xy 352.219006 -281.23896) (xy 352.24434 -281.242833) (xy 352.293643 -281.256818) (xy 352.340433 -281.277725)
			(xy 352.383744 -281.30512) (xy 352.422682 -281.33844) (xy 352.456444 -281.376995) (xy 352.484332 -281.41999)
			(xy 352.505771 -281.466539) (xy 352.520318 -281.515679) (xy 352.527673 -281.566396) (xy 352.528124 -281.59202)
			(xy 352.527626 -281.618669) (xy 352.756206 -281.618669) (xy 352.756206 -281.565371) (xy 352.764149 -281.512667)
			(xy 352.779859 -281.461737) (xy 352.802985 -281.413716) (xy 352.833009 -281.369679) (xy 352.869261 -281.330608)
			(xy 352.910932 -281.297377) (xy 352.95709 -281.270728) (xy 353.006704 -281.251256) (xy 353.058666 -281.239396)
			(xy 353.111816 -281.235413) (xy 353.164966 -281.239396) (xy 353.216928 -281.251256) (xy 353.266542 -281.270728)
			(xy 353.3127 -281.297377) (xy 353.354371 -281.330608) (xy 353.390623 -281.369679) (xy 353.420647 -281.413716)
			(xy 353.443773 -281.461737) (xy 353.459483 -281.512667) (xy 353.467426 -281.565371) (xy 353.467924 -281.59202)
			(xy 353.467426 -281.618669) (xy 353.459483 -281.671373) (xy 353.443773 -281.722303) (xy 353.420647 -281.770324)
			(xy 353.390623 -281.814361) (xy 353.354371 -281.853432) (xy 353.3127 -281.886663) (xy 353.266542 -281.913312)
			(xy 353.216928 -281.932784) (xy 353.164966 -281.944644) (xy 353.111816 -281.948628) (xy 353.058666 -281.944644)
			(xy 353.006704 -281.932784) (xy 352.95709 -281.913312) (xy 352.910932 -281.886663) (xy 352.869261 -281.853432)
			(xy 352.833009 -281.814361) (xy 352.802985 -281.770324) (xy 352.779859 -281.722303) (xy 352.764149 -281.671373)
			(xy 352.756206 -281.618669) (xy 352.527626 -281.618669) (xy 352.519683 -281.671373) (xy 352.503973 -281.722303)
			(xy 352.480847 -281.770324) (xy 352.450823 -281.814361) (xy 352.414571 -281.853432) (xy 352.3729 -281.886663)
			(xy 352.326742 -281.913312) (xy 352.277128 -281.932784) (xy 352.225166 -281.944644) (xy 352.172016 -281.948628)
			(xy 352.118866 -281.944644) (xy 352.066904 -281.932784) (xy 352.01729 -281.913312) (xy 351.971132 -281.886663)
			(xy 351.929461 -281.853432) (xy 351.893209 -281.814361) (xy 351.863185 -281.770324) (xy 351.840059 -281.722303)
			(xy 351.824349 -281.671373) (xy 351.816406 -281.618669) (xy 351.815908 -281.59202) (xy 351.816283 -281.568775)
			(xy 351.822327 -281.52268) (xy 351.834315 -281.477762) (xy 351.842832 -281.45613) (xy 351.852484 -281.433016)
			(xy 351.680018 -281.134566) (xy 351.655126 -281.131264) (xy 351.629769 -281.127452) (xy 351.580428 -281.113497)
			(xy 351.533598 -281.092611) (xy 351.490248 -281.065224) (xy 351.451273 -281.031904) (xy 351.41748 -280.993339)
			(xy 351.389567 -280.950326) (xy 351.36811 -280.903755) (xy 351.353555 -280.854588) (xy 351.346201 -280.803842)
			(xy 351.345754 -280.778204) (xy 351.118424 -280.778204) (xy 351.117926 -280.804853) (xy 351.109983 -280.857557)
			(xy 351.094273 -280.908487) (xy 351.071147 -280.956508) (xy 351.041123 -281.000545) (xy 351.004871 -281.039616)
			(xy 350.9632 -281.072847) (xy 350.917042 -281.099496) (xy 350.867428 -281.118968) (xy 350.815466 -281.130828)
			(xy 350.762316 -281.134812) (xy 350.709166 -281.130828) (xy 350.657204 -281.118968) (xy 350.60759 -281.099496)
			(xy 350.561432 -281.072847) (xy 350.519761 -281.039616) (xy 350.483509 -281.000545) (xy 350.453485 -280.956508)
			(xy 350.430359 -280.908487) (xy 350.414649 -280.857557) (xy 350.406706 -280.804853) (xy 350.177872 -280.804853)
			(xy 350.169929 -280.857557) (xy 350.154219 -280.908487) (xy 350.131093 -280.956508) (xy 350.101069 -281.000545)
			(xy 350.064817 -281.039616) (xy 350.023146 -281.072847) (xy 349.976988 -281.099496) (xy 349.927374 -281.118968)
			(xy 349.875412 -281.130828) (xy 349.822262 -281.134812) (xy 349.769112 -281.130828) (xy 349.71715 -281.118968)
			(xy 349.667536 -281.099496) (xy 349.621378 -281.072847) (xy 349.579707 -281.039616) (xy 349.543455 -281.000545)
			(xy 349.513431 -280.956508) (xy 349.490305 -280.908487) (xy 349.474595 -280.857557) (xy 349.466652 -280.804853)
			(xy 349.237746 -280.804853) (xy 349.232214 -280.84727) (xy 349.22034 -280.892025) (xy 349.2119 -280.913586)
			(xy 349.202248 -280.9367) (xy 349.374968 -281.235658) (xy 349.399606 -281.23896) (xy 349.42494 -281.242833)
			(xy 349.474243 -281.256818) (xy 349.521033 -281.277725) (xy 349.564344 -281.30512) (xy 349.603282 -281.33844)
			(xy 349.637044 -281.376995) (xy 349.664932 -281.41999) (xy 349.686371 -281.466539) (xy 349.700918 -281.515679)
			(xy 349.708273 -281.566396) (xy 349.708724 -281.59202) (xy 349.708226 -281.618669) (xy 349.700283 -281.671373)
			(xy 349.684573 -281.722303) (xy 349.661447 -281.770324) (xy 349.631423 -281.814361) (xy 349.595171 -281.853432)
			(xy 349.5535 -281.886663) (xy 349.507342 -281.913312) (xy 349.457728 -281.932784) (xy 349.405766 -281.944644)
			(xy 349.352616 -281.948628) (xy 349.299466 -281.944644) (xy 349.247504 -281.932784) (xy 349.19789 -281.913312)
			(xy 349.151732 -281.886663) (xy 349.110061 -281.853432) (xy 349.073809 -281.814361) (xy 349.043785 -281.770324)
			(xy 349.020659 -281.722303) (xy 349.004949 -281.671373) (xy 348.997006 -281.618669) (xy 348.996508 -281.59202)
			(xy 348.996883 -281.568775) (xy 349.002927 -281.52268) (xy 349.014915 -281.477762) (xy 349.023432 -281.45613)
			(xy 349.033084 -281.433016) (xy 348.860618 -281.134566) (xy 348.835726 -281.131264) (xy 348.810369 -281.127452)
			(xy 348.761028 -281.113497) (xy 348.714198 -281.092611) (xy 348.670848 -281.065224) (xy 348.631873 -281.031904)
			(xy 348.59808 -280.993339) (xy 348.570167 -280.950326) (xy 348.54871 -280.903755) (xy 348.534155 -280.854588)
			(xy 348.526801 -280.803842) (xy 348.526354 -280.778204) (xy 347.35897 -280.778204) (xy 347.358472 -280.804853)
			(xy 347.350529 -280.857557) (xy 347.334819 -280.908487) (xy 347.311693 -280.956508) (xy 347.281669 -281.000545)
			(xy 347.245417 -281.039616) (xy 347.203746 -281.072847) (xy 347.157588 -281.099496) (xy 347.107974 -281.118968)
			(xy 347.056012 -281.130828) (xy 347.002862 -281.134812) (xy 346.949712 -281.130828) (xy 346.89775 -281.118968)
			(xy 346.848136 -281.099496) (xy 346.801978 -281.072847) (xy 346.760307 -281.039616) (xy 346.724055 -281.000545)
			(xy 346.694031 -280.956508) (xy 346.670905 -280.908487) (xy 346.655195 -280.857557) (xy 346.647252 -280.804853)
			(xy 346.418614 -280.804853) (xy 346.411444 -280.854537) (xy 346.396931 -280.903678) (xy 346.375523 -280.95023)
			(xy 346.347662 -280.993232) (xy 346.313923 -281.031795) (xy 346.275004 -281.065123) (xy 346.231709 -281.092527)
			(xy 346.184933 -281.113441) (xy 346.135641 -281.127432) (xy 346.110306 -281.131264) (xy 346.085414 -281.134566)
			(xy 345.912948 -281.433016) (xy 345.9226 -281.45613) (xy 345.931124 -281.477759) (xy 345.943108 -281.522679)
			(xy 345.94915 -281.568775) (xy 345.949524 -281.59202) (xy 345.949026 -281.618669) (xy 346.177606 -281.618669)
			(xy 346.177606 -281.565371) (xy 346.185549 -281.512667) (xy 346.201259 -281.461737) (xy 346.224385 -281.413716)
			(xy 346.254409 -281.369679) (xy 346.290661 -281.330608) (xy 346.332332 -281.297377) (xy 346.37849 -281.270728)
			(xy 346.428104 -281.251256) (xy 346.480066 -281.239396) (xy 346.533216 -281.235413) (xy 346.586366 -281.239396)
			(xy 346.638328 -281.251256) (xy 346.687942 -281.270728) (xy 346.7341 -281.297377) (xy 346.775771 -281.330608)
			(xy 346.812023 -281.369679) (xy 346.842047 -281.413716) (xy 346.865173 -281.461737) (xy 346.880883 -281.512667)
			(xy 346.888826 -281.565371) (xy 346.889324 -281.592) (xy 347.116388 -281.592) (xy 347.120371 -281.538848)
			(xy 347.132232 -281.486884) (xy 347.151706 -281.437268) (xy 347.178357 -281.391108) (xy 347.21159 -281.349437)
			(xy 347.250663 -281.313184) (xy 347.294703 -281.28316) (xy 347.342726 -281.260035) (xy 347.39366 -281.244326)
			(xy 347.446366 -281.236384) (xy 347.473016 -281.235912) (xy 347.49803 -281.236337) (xy 347.547568 -281.243324)
			(xy 347.595641 -281.257172) (xy 347.641305 -281.27761) (xy 347.68366 -281.304234) (xy 347.721874 -281.336521)
			(xy 347.755195 -281.373838) (xy 347.769434 -281.394408) (xy 348.116398 -281.394408) (xy 348.13061 -281.373819)
			(xy 348.163943 -281.336512) (xy 348.202164 -281.304231) (xy 348.244524 -281.277611) (xy 348.290189 -281.257176)
			(xy 348.338263 -281.243326) (xy 348.387801 -281.236333) (xy 348.412816 -281.235912) (xy 348.439466 -281.236371)
			(xy 348.49217 -281.244317) (xy 348.543102 -281.260029) (xy 348.591123 -281.283157) (xy 348.635161 -281.313183)
			(xy 348.674232 -281.349437) (xy 348.707463 -281.39111) (xy 348.734112 -281.437269) (xy 348.753584 -281.486885)
			(xy 348.765444 -281.538849) (xy 348.769428 -281.592) (xy 348.765444 -281.645151) (xy 348.753584 -281.697115)
			(xy 348.734112 -281.746731) (xy 348.707463 -281.79289) (xy 348.674232 -281.834563) (xy 348.635161 -281.870817)
			(xy 348.591123 -281.900843) (xy 348.543102 -281.923971) (xy 348.49217 -281.939683) (xy 348.439466 -281.947629)
			(xy 348.412816 -281.948128) (xy 348.387801 -281.947705) (xy 348.338262 -281.940721) (xy 348.290188 -281.926875)
			(xy 348.244524 -281.906438) (xy 348.202168 -281.879812) (xy 348.163955 -281.847523) (xy 348.130635 -281.810204)
			(xy 348.116398 -281.789632) (xy 347.769434 -281.789632) (xy 347.755214 -281.810215) (xy 347.721881 -281.847521)
			(xy 347.68366 -281.8798) (xy 347.641302 -281.90642) (xy 347.595639 -281.926857) (xy 347.547567 -281.940709)
			(xy 347.49803 -281.947705) (xy 347.473016 -281.948128) (xy 347.446366 -281.947616) (xy 347.39366 -281.939674)
			(xy 347.342726 -281.923965) (xy 347.294703 -281.90084) (xy 347.250663 -281.870816) (xy 347.21159 -281.834563)
			(xy 347.178357 -281.792892) (xy 347.151706 -281.746732) (xy 347.132232 -281.697116) (xy 347.120371 -281.645152)
			(xy 347.116388 -281.592) (xy 346.889324 -281.592) (xy 346.889324 -281.59202) (xy 346.888826 -281.618669)
			(xy 346.880883 -281.671373) (xy 346.865173 -281.722303) (xy 346.842047 -281.770324) (xy 346.812023 -281.814361)
			(xy 346.775771 -281.853432) (xy 346.7341 -281.886663) (xy 346.687942 -281.913312) (xy 346.638328 -281.932784)
			(xy 346.586366 -281.944644) (xy 346.533216 -281.948628) (xy 346.480066 -281.944644) (xy 346.428104 -281.932784)
			(xy 346.37849 -281.913312) (xy 346.332332 -281.886663) (xy 346.290661 -281.853432) (xy 346.254409 -281.814361)
			(xy 346.224385 -281.770324) (xy 346.201259 -281.722303) (xy 346.185549 -281.671373) (xy 346.177606 -281.618669)
			(xy 345.949026 -281.618669) (xy 345.941083 -281.671373) (xy 345.925373 -281.722303) (xy 345.902247 -281.770324)
			(xy 345.872223 -281.814361) (xy 345.835971 -281.853432) (xy 345.7943 -281.886663) (xy 345.748142 -281.913312)
			(xy 345.698528 -281.932784) (xy 345.646566 -281.944644) (xy 345.593416 -281.948628) (xy 345.540266 -281.944644)
			(xy 345.488304 -281.932784) (xy 345.43869 -281.913312) (xy 345.392532 -281.886663) (xy 345.350861 -281.853432)
			(xy 345.314609 -281.814361) (xy 345.284585 -281.770324) (xy 345.261459 -281.722303) (xy 345.245749 -281.671373)
			(xy 345.237806 -281.618669) (xy 345.237308 -281.59202) (xy 345.009724 -281.59202) (xy 345.009226 -281.618669)
			(xy 345.001283 -281.671373) (xy 344.985573 -281.722303) (xy 344.962447 -281.770324) (xy 344.932423 -281.814361)
			(xy 344.896171 -281.853432) (xy 344.8545 -281.886663) (xy 344.808342 -281.913312) (xy 344.758728 -281.932784)
			(xy 344.706766 -281.944644) (xy 344.653616 -281.948628) (xy 344.600466 -281.944644) (xy 344.548504 -281.932784)
			(xy 344.49889 -281.913312) (xy 344.452732 -281.886663) (xy 344.411061 -281.853432) (xy 344.374809 -281.814361)
			(xy 344.344785 -281.770324) (xy 344.321659 -281.722303) (xy 344.305949 -281.671373) (xy 344.298006 -281.618669)
			(xy 344.069276 -281.618669) (xy 344.062078 -281.668402) (xy 344.047532 -281.717569) (xy 344.026084 -281.764141)
			(xy 343.998178 -281.807156) (xy 343.96439 -281.845722) (xy 343.92542 -281.879044) (xy 343.882074 -281.906431)
			(xy 343.835247 -281.927317) (xy 343.785908 -281.941271) (xy 343.760552 -281.94508) (xy 343.73566 -281.948382)
			(xy 343.563194 -282.246832) (xy 343.572846 -282.269946) (xy 343.581372 -282.291574) (xy 343.593356 -282.336494)
			(xy 343.599397 -282.382591) (xy 343.59977 -282.405836) (xy 343.827354 -282.405836) (xy 343.827852 -282.379187)
			(xy 343.835795 -282.326483) (xy 343.851505 -282.275553) (xy 343.874631 -282.227532) (xy 343.904655 -282.183495)
			(xy 343.940907 -282.144424) (xy 343.982578 -282.111193) (xy 344.028736 -282.084544) (xy 344.07835 -282.065072)
			(xy 344.130312 -282.053212) (xy 344.183462 -282.049229) (xy 344.236612 -282.053212) (xy 344.288574 -282.065072)
			(xy 344.338188 -282.084544) (xy 344.384346 -282.111193) (xy 344.426017 -282.144424) (xy 344.462269 -282.183495)
			(xy 344.492293 -282.227532) (xy 344.515419 -282.275553) (xy 344.531129 -282.326483) (xy 344.539072 -282.379187)
			(xy 344.539569 -282.4058) (xy 344.766729 -282.4058) (xy 344.770711 -282.352659) (xy 344.782568 -282.300706)
			(xy 344.802036 -282.251099) (xy 344.828679 -282.204948) (xy 344.861903 -282.163283) (xy 344.900965 -282.127035)
			(xy 344.944993 -282.097013) (xy 344.993003 -282.073888) (xy 345.043924 -282.058176) (xy 345.096617 -282.050229)
			(xy 345.123262 -282.049728) (xy 345.148278 -282.050111) (xy 345.197818 -282.057105) (xy 345.245892 -282.07096)
			(xy 345.291556 -282.091404) (xy 345.333911 -282.118035) (xy 345.372123 -282.150329) (xy 345.405443 -282.187651)
			(xy 345.41968 -282.208224) (xy 345.766644 -282.208224) (xy 345.780896 -282.187664) (xy 345.814221 -282.150355)
			(xy 345.852436 -282.118072) (xy 345.894789 -282.091449) (xy 345.940448 -282.071008) (xy 345.988516 -282.057152)
			(xy 346.038049 -282.050153) (xy 346.063062 -282.049728) (xy 346.089718 -282.050127) (xy 346.142434 -282.058067)
			(xy 346.193378 -282.073777) (xy 346.241412 -282.096904) (xy 346.285462 -282.126932) (xy 346.324544 -282.163191)
			(xy 346.357785 -282.20487) (xy 346.384442 -282.251038) (xy 346.40392 -282.300663) (xy 346.415784 -282.352638)
			(xy 346.419768 -282.4058) (xy 346.417768 -282.432485) (xy 346.647252 -282.432485) (xy 346.647252 -282.379187)
			(xy 346.655195 -282.326483) (xy 346.670905 -282.275553) (xy 346.694031 -282.227532) (xy 346.724055 -282.183495)
			(xy 346.760307 -282.144424) (xy 346.801978 -282.111193) (xy 346.848136 -282.084544) (xy 346.89775 -282.065072)
			(xy 346.949712 -282.053212) (xy 347.002862 -282.049229) (xy 347.056012 -282.053212) (xy 347.107974 -282.065072)
			(xy 347.157588 -282.084544) (xy 347.203746 -282.111193) (xy 347.245417 -282.144424) (xy 347.281669 -282.183495)
			(xy 347.311693 -282.227532) (xy 347.334819 -282.275553) (xy 347.350529 -282.326483) (xy 347.358472 -282.379187)
			(xy 347.35897 -282.405836) (xy 347.358472 -282.432485) (xy 347.350529 -282.485189) (xy 347.334819 -282.536119)
			(xy 347.311693 -282.58414) (xy 347.281669 -282.628177) (xy 347.245417 -282.667248) (xy 347.203746 -282.700479)
			(xy 347.157588 -282.727128) (xy 347.107974 -282.7466) (xy 347.056012 -282.75846) (xy 347.002862 -282.762444)
			(xy 346.949712 -282.75846) (xy 346.89775 -282.7466) (xy 346.848136 -282.727128) (xy 346.801978 -282.700479)
			(xy 346.760307 -282.667248) (xy 346.724055 -282.628177) (xy 346.694031 -282.58414) (xy 346.670905 -282.536119)
			(xy 346.655195 -282.485189) (xy 346.647252 -282.432485) (xy 346.417768 -282.432485) (xy 346.415784 -282.458962)
			(xy 346.40392 -282.510937) (xy 346.384442 -282.560562) (xy 346.357785 -282.60673) (xy 346.324544 -282.648409)
			(xy 346.285462 -282.684668) (xy 346.241412 -282.714696) (xy 346.193378 -282.737823) (xy 346.142434 -282.753533)
			(xy 346.089718 -282.761473) (xy 346.063062 -282.761944) (xy 346.038046 -282.761555) (xy 345.988506 -282.754564)
			(xy 345.940431 -282.740711) (xy 345.894767 -282.720268) (xy 345.852412 -282.693638) (xy 345.8142 -282.661344)
			(xy 345.780881 -282.624022) (xy 345.766644 -282.603448) (xy 345.41968 -282.603448) (xy 345.405404 -282.62399)
			(xy 345.372083 -282.661301) (xy 345.333873 -282.693586) (xy 345.291525 -282.720212) (xy 345.245869 -282.740655)
			(xy 345.197804 -282.754514) (xy 345.148274 -282.761517) (xy 345.123262 -282.761944) (xy 345.096617 -282.761371)
			(xy 345.043924 -282.753424) (xy 344.993003 -282.737712) (xy 344.944993 -282.714587) (xy 344.900965 -282.684565)
			(xy 344.861903 -282.648317) (xy 344.828679 -282.606652) (xy 344.802036 -282.560501) (xy 344.782568 -282.510894)
			(xy 344.770711 -282.458941) (xy 344.766729 -282.4058) (xy 344.539569 -282.4058) (xy 344.53957 -282.405836)
			(xy 344.539203 -282.42904) (xy 344.533148 -282.475051) (xy 344.521159 -282.519883) (xy 344.512646 -282.541472)
			(xy 344.503248 -282.564586) (xy 344.675968 -282.863544) (xy 344.700606 -282.866846) (xy 344.725938 -282.870732)
			(xy 344.77524 -282.884717) (xy 344.822029 -282.905622) (xy 344.865339 -282.933017) (xy 344.904277 -282.966334)
			(xy 344.938038 -283.004888) (xy 344.965927 -283.047882) (xy 344.987367 -283.094428) (xy 345.001915 -283.143567)
			(xy 345.009272 -283.194283) (xy 345.009724 -283.219906) (xy 345.009226 -283.246555) (xy 345.237552 -283.246555)
			(xy 345.237552 -283.193257) (xy 345.245495 -283.140553) (xy 345.261205 -283.089623) (xy 345.284331 -283.041602)
			(xy 345.314355 -282.997565) (xy 345.350607 -282.958494) (xy 345.392278 -282.925263) (xy 345.438436 -282.898614)
			(xy 345.48805 -282.879142) (xy 345.540012 -282.867282) (xy 345.593162 -282.863299) (xy 345.646312 -282.867282)
			(xy 345.698274 -282.879142) (xy 345.747888 -282.898614) (xy 345.794046 -282.925263) (xy 345.835717 -282.958494)
			(xy 345.871969 -282.997565) (xy 345.901993 -283.041602) (xy 345.925119 -283.089623) (xy 345.940829 -283.140553)
			(xy 345.948772 -283.193257) (xy 345.94927 -283.219906) (xy 345.948772 -283.246555) (xy 346.177352 -283.246555)
			(xy 346.177352 -283.193257) (xy 346.185295 -283.140553) (xy 346.201005 -283.089623) (xy 346.224131 -283.041602)
			(xy 346.254155 -282.997565) (xy 346.290407 -282.958494) (xy 346.332078 -282.925263) (xy 346.378236 -282.898614)
			(xy 346.42785 -282.879142) (xy 346.479812 -282.867282) (xy 346.532962 -282.863299) (xy 346.586112 -282.867282)
			(xy 346.638074 -282.879142) (xy 346.687688 -282.898614) (xy 346.733846 -282.925263) (xy 346.775517 -282.958494)
			(xy 346.811769 -282.997565) (xy 346.841793 -283.041602) (xy 346.864919 -283.089623) (xy 346.880629 -283.140553)
			(xy 346.888572 -283.193257) (xy 346.88907 -283.219906) (xy 347.116908 -283.219906) (xy 347.117372 -283.194279)
			(xy 347.124706 -283.143552) (xy 347.139238 -283.0944) (xy 347.160667 -283.04784) (xy 347.18855 -283.004834)
			(xy 347.222311 -282.96627) (xy 347.261253 -282.932945) (xy 347.304571 -282.905548) (xy 347.35137 -282.884646)
			(xy 347.400682 -282.870669) (xy 347.426026 -282.866846) (xy 347.450664 -282.863544) (xy 347.62313 -282.565094)
			(xy 347.613478 -282.54198) (xy 347.604963 -282.520303) (xy 347.592962 -282.475302) (xy 347.586921 -282.429123)
			(xy 347.586554 -282.405836) (xy 347.587052 -282.379187) (xy 347.594995 -282.326483) (xy 347.610705 -282.275553)
			(xy 347.633831 -282.227532) (xy 347.663855 -282.183495) (xy 347.700107 -282.144424) (xy 347.741778 -282.111193)
			(xy 347.787936 -282.084544) (xy 347.83755 -282.065072) (xy 347.889512 -282.053212) (xy 347.942662 -282.049229)
			(xy 347.995812 -282.053212) (xy 348.047774 -282.065072) (xy 348.097388 -282.084544) (xy 348.143546 -282.111193)
			(xy 348.185217 -282.144424) (xy 348.221469 -282.183495) (xy 348.251493 -282.227532) (xy 348.274619 -282.275553)
			(xy 348.290329 -282.326483) (xy 348.298272 -282.379187) (xy 348.29877 -282.405836) (xy 348.298392 -282.431457)
			(xy 348.298244 -282.432485) (xy 348.526852 -282.432485) (xy 348.526852 -282.379187) (xy 348.534795 -282.326483)
			(xy 348.550505 -282.275553) (xy 348.573631 -282.227532) (xy 348.603655 -282.183495) (xy 348.639907 -282.144424)
			(xy 348.681578 -282.111193) (xy 348.727736 -282.084544) (xy 348.77735 -282.065072) (xy 348.829312 -282.053212)
			(xy 348.882462 -282.049229) (xy 348.935612 -282.053212) (xy 348.987574 -282.065072) (xy 349.037188 -282.084544)
			(xy 349.083346 -282.111193) (xy 349.125017 -282.144424) (xy 349.161269 -282.183495) (xy 349.191293 -282.227532)
			(xy 349.214419 -282.275553) (xy 349.230129 -282.326483) (xy 349.238072 -282.379187) (xy 349.23857 -282.405836)
			(xy 349.466154 -282.405836) (xy 349.466606 -282.380208) (xy 349.473937 -282.329478) (xy 349.488467 -282.280324)
			(xy 349.509896 -282.233762) (xy 349.53778 -282.190754) (xy 349.571543 -282.152189) (xy 349.610488 -282.118864)
			(xy 349.653809 -282.091469) (xy 349.700611 -282.070569) (xy 349.749926 -282.056597) (xy 349.775272 -282.052776)
			(xy 349.79991 -282.049474) (xy 349.97263 -281.750516) (xy 349.962978 -281.727402) (xy 349.954506 -281.705851)
			(xy 349.942624 -281.661095) (xy 349.936657 -281.615174) (xy 349.936308 -281.59202) (xy 349.936806 -281.565371)
			(xy 349.944749 -281.512667) (xy 349.960459 -281.461737) (xy 349.983585 -281.413716) (xy 350.013609 -281.369679)
			(xy 350.049861 -281.330608) (xy 350.091532 -281.297377) (xy 350.13769 -281.270728) (xy 350.187304 -281.251256)
			(xy 350.239266 -281.239396) (xy 350.292416 -281.235413) (xy 350.345566 -281.239396) (xy 350.397528 -281.251256)
			(xy 350.447142 -281.270728) (xy 350.4933 -281.297377) (xy 350.534971 -281.330608) (xy 350.571223 -281.369679)
			(xy 350.601247 -281.413716) (xy 350.624373 -281.461737) (xy 350.640083 -281.512667) (xy 350.648026 -281.565371)
			(xy 350.648524 -281.59202) (xy 350.648022 -281.617657) (xy 350.647876 -281.618669) (xy 350.876352 -281.618669)
			(xy 350.876352 -281.565371) (xy 350.884295 -281.512667) (xy 350.900005 -281.461737) (xy 350.923131 -281.413716)
			(xy 350.953155 -281.369679) (xy 350.989407 -281.330608) (xy 351.031078 -281.297377) (xy 351.077236 -281.270728)
			(xy 351.12685 -281.251256) (xy 351.178812 -281.239396) (xy 351.231962 -281.235413) (xy 351.285112 -281.239396)
			(xy 351.337074 -281.251256) (xy 351.386688 -281.270728) (xy 351.432846 -281.297377) (xy 351.474517 -281.330608)
			(xy 351.510769 -281.369679) (xy 351.540793 -281.413716) (xy 351.563919 -281.461737) (xy 351.579629 -281.512667)
			(xy 351.587572 -281.565371) (xy 351.58807 -281.59202) (xy 351.587572 -281.618669) (xy 351.579629 -281.671373)
			(xy 351.563919 -281.722303) (xy 351.540793 -281.770324) (xy 351.510769 -281.814361) (xy 351.474517 -281.853432)
			(xy 351.432846 -281.886663) (xy 351.386688 -281.913312) (xy 351.337074 -281.932784) (xy 351.285112 -281.944644)
			(xy 351.231962 -281.948628) (xy 351.178812 -281.944644) (xy 351.12685 -281.932784) (xy 351.077236 -281.913312)
			(xy 351.031078 -281.886663) (xy 350.989407 -281.853432) (xy 350.953155 -281.814361) (xy 350.923131 -281.770324)
			(xy 350.900005 -281.722303) (xy 350.884295 -281.671373) (xy 350.876352 -281.618669) (xy 350.647876 -281.618669)
			(xy 350.640678 -281.668402) (xy 350.626132 -281.717569) (xy 350.604684 -281.764141) (xy 350.576778 -281.807156)
			(xy 350.54299 -281.845722) (xy 350.50402 -281.879044) (xy 350.460674 -281.906431) (xy 350.413847 -281.927317)
			(xy 350.364508 -281.941271) (xy 350.339152 -281.94508) (xy 350.31426 -281.948382) (xy 350.141794 -282.246832)
			(xy 350.151446 -282.269946) (xy 350.159972 -282.291574) (xy 350.171956 -282.336494) (xy 350.177997 -282.382591)
			(xy 350.17837 -282.405836) (xy 350.177872 -282.432485) (xy 350.406706 -282.432485) (xy 350.406706 -282.379187)
			(xy 350.414649 -282.326483) (xy 350.430359 -282.275553) (xy 350.453485 -282.227532) (xy 350.483509 -282.183495)
			(xy 350.519761 -282.144424) (xy 350.561432 -282.111193) (xy 350.60759 -282.084544) (xy 350.657204 -282.065072)
			(xy 350.709166 -282.053212) (xy 350.762316 -282.049229) (xy 350.815466 -282.053212) (xy 350.867428 -282.065072)
			(xy 350.917042 -282.084544) (xy 350.9632 -282.111193) (xy 351.004871 -282.144424) (xy 351.041123 -282.183495)
			(xy 351.071147 -282.227532) (xy 351.094273 -282.275553) (xy 351.109983 -282.326483) (xy 351.117926 -282.379187)
			(xy 351.118424 -282.405836) (xy 351.117926 -282.432485) (xy 351.109983 -282.485189) (xy 351.094273 -282.536119)
			(xy 351.071147 -282.58414) (xy 351.041123 -282.628177) (xy 351.004871 -282.667248) (xy 350.9632 -282.700479)
			(xy 350.917042 -282.727128) (xy 350.867428 -282.7466) (xy 350.815466 -282.75846) (xy 350.762316 -282.762444)
			(xy 350.709166 -282.75846) (xy 350.657204 -282.7466) (xy 350.60759 -282.727128) (xy 350.561432 -282.700479)
			(xy 350.519761 -282.667248) (xy 350.483509 -282.628177) (xy 350.453485 -282.58414) (xy 350.430359 -282.536119)
			(xy 350.414649 -282.485189) (xy 350.406706 -282.432485) (xy 350.177872 -282.432485) (xy 350.169929 -282.485189)
			(xy 350.154219 -282.536119) (xy 350.131093 -282.58414) (xy 350.101069 -282.628177) (xy 350.064817 -282.667248)
			(xy 350.023146 -282.700479) (xy 349.976988 -282.727128) (xy 349.927374 -282.7466) (xy 349.875412 -282.75846)
			(xy 349.822262 -282.762444) (xy 349.769112 -282.75846) (xy 349.71715 -282.7466) (xy 349.667536 -282.727128)
			(xy 349.621378 -282.700479) (xy 349.579707 -282.667248) (xy 349.543455 -282.628177) (xy 349.513431 -282.58414)
			(xy 349.490305 -282.536119) (xy 349.474595 -282.485189) (xy 349.466652 -282.432485) (xy 349.466154 -282.405836)
			(xy 349.23857 -282.405836) (xy 349.238072 -282.432485) (xy 349.230129 -282.485189) (xy 349.214419 -282.536119)
			(xy 349.191293 -282.58414) (xy 349.161269 -282.628177) (xy 349.125017 -282.667248) (xy 349.083346 -282.700479)
			(xy 349.037188 -282.727128) (xy 348.987574 -282.7466) (xy 348.935612 -282.75846) (xy 348.882462 -282.762444)
			(xy 348.829312 -282.75846) (xy 348.77735 -282.7466) (xy 348.727736 -282.727128) (xy 348.681578 -282.700479)
			(xy 348.639907 -282.667248) (xy 348.603655 -282.628177) (xy 348.573631 -282.58414) (xy 348.550505 -282.536119)
			(xy 348.534795 -282.485189) (xy 348.526852 -282.432485) (xy 348.298244 -282.432485) (xy 348.29107 -282.482171)
			(xy 348.276552 -282.531312) (xy 348.25514 -282.577865) (xy 348.227275 -282.620867) (xy 348.193533 -282.659429)
			(xy 348.154612 -282.692757) (xy 348.111314 -282.72016) (xy 348.064536 -282.741073) (xy 348.015242 -282.755064)
			(xy 347.989906 -282.758896) (xy 347.965268 -282.762198) (xy 347.792548 -283.060902) (xy 347.8022 -283.084016)
			(xy 347.810719 -283.105647) (xy 347.822705 -283.150565) (xy 347.828749 -283.196661) (xy 347.829124 -283.219906)
			(xy 347.828626 -283.246555) (xy 348.056952 -283.246555) (xy 348.056952 -283.193257) (xy 348.064895 -283.140553)
			(xy 348.080605 -283.089623) (xy 348.103731 -283.041602) (xy 348.133755 -282.997565) (xy 348.170007 -282.958494)
			(xy 348.211678 -282.925263) (xy 348.257836 -282.898614) (xy 348.30745 -282.879142) (xy 348.359412 -282.867282)
			(xy 348.412562 -282.863299) (xy 348.465712 -282.867282) (xy 348.517674 -282.879142) (xy 348.567288 -282.898614)
			(xy 348.613446 -282.925263) (xy 348.655117 -282.958494) (xy 348.691369 -282.997565) (xy 348.721393 -283.041602)
			(xy 348.744519 -283.089623) (xy 348.760229 -283.140553) (xy 348.768172 -283.193257) (xy 348.76867 -283.2199)
			(xy 348.995974 -283.2199) (xy 348.999957 -283.166746) (xy 349.011819 -283.11478) (xy 349.031293 -283.065162)
			(xy 349.057945 -283.019) (xy 349.09118 -282.977327) (xy 349.130254 -282.941073) (xy 349.174296 -282.911047)
			(xy 349.222321 -282.887922) (xy 349.273257 -282.872212) (xy 349.325965 -282.86427) (xy 349.352616 -282.863798)
			(xy 349.377642 -282.864206) (xy 349.4272 -282.871217) (xy 349.475288 -282.885097) (xy 349.520959 -282.905575)
			(xy 349.563313 -282.932245) (xy 349.601515 -282.964583) (xy 349.634812 -283.001952) (xy 349.649034 -283.022548)
			(xy 349.995998 -283.022548) (xy 350.010213 -283.001947) (xy 350.043512 -282.964581) (xy 350.081716 -282.932245)
			(xy 350.124071 -282.905578) (xy 350.169743 -282.885104) (xy 350.217832 -282.871227) (xy 350.26739 -282.864221)
			(xy 350.292416 -282.863798) (xy 350.319065 -282.864285) (xy 350.371767 -282.872231) (xy 350.422697 -282.887942)
			(xy 350.470716 -282.911069) (xy 350.514752 -282.941094) (xy 350.553821 -282.977347) (xy 350.587051 -283.019018)
			(xy 350.6137 -283.065175) (xy 350.633171 -283.114789) (xy 350.645031 -283.166751) (xy 350.649014 -283.2199)
			(xy 350.647016 -283.246555) (xy 350.876352 -283.246555) (xy 350.876352 -283.193257) (xy 350.884295 -283.140553)
			(xy 350.900005 -283.089623) (xy 350.923131 -283.041602) (xy 350.953155 -282.997565) (xy 350.989407 -282.958494)
			(xy 351.031078 -282.925263) (xy 351.077236 -282.898614) (xy 351.12685 -282.879142) (xy 351.178812 -282.867282)
			(xy 351.231962 -282.863299) (xy 351.285112 -282.867282) (xy 351.337074 -282.879142) (xy 351.386688 -282.898614)
			(xy 351.432846 -282.925263) (xy 351.474517 -282.958494) (xy 351.510769 -282.997565) (xy 351.540793 -283.041602)
			(xy 351.563919 -283.089623) (xy 351.579629 -283.140553) (xy 351.587572 -283.193257) (xy 351.58807 -283.219906)
			(xy 351.587572 -283.246555) (xy 351.579629 -283.299259) (xy 351.563919 -283.350189) (xy 351.540793 -283.39821)
			(xy 351.510769 -283.442247) (xy 351.474517 -283.481318) (xy 351.432846 -283.514549) (xy 351.386688 -283.541198)
			(xy 351.337074 -283.56067) (xy 351.285112 -283.57253) (xy 351.231962 -283.576514) (xy 351.178812 -283.57253)
			(xy 351.12685 -283.56067) (xy 351.077236 -283.541198) (xy 351.031078 -283.514549) (xy 350.989407 -283.481318)
			(xy 350.953155 -283.442247) (xy 350.923131 -283.39821) (xy 350.900005 -283.350189) (xy 350.884295 -283.299259)
			(xy 350.876352 -283.246555) (xy 350.647016 -283.246555) (xy 350.645031 -283.273049) (xy 350.633171 -283.325011)
			(xy 350.6137 -283.374625) (xy 350.587051 -283.420782) (xy 350.553821 -283.462453) (xy 350.514752 -283.498706)
			(xy 350.470716 -283.528731) (xy 350.422697 -283.551858) (xy 350.371767 -283.567569) (xy 350.319065 -283.575515)
			(xy 350.292416 -283.576014) (xy 350.267391 -283.575576) (xy 350.217835 -283.56857) (xy 350.169748 -283.554694)
			(xy 350.124077 -283.534222) (xy 350.081723 -283.507556) (xy 350.04352 -283.475223) (xy 350.010221 -283.437858)
			(xy 349.995998 -283.417264) (xy 349.649034 -283.417264) (xy 349.634802 -283.437852) (xy 349.601505 -283.475219)
			(xy 349.563304 -283.507555) (xy 349.520952 -283.534223) (xy 349.475283 -283.554699) (xy 349.427197 -283.568579)
			(xy 349.377641 -283.575589) (xy 349.352616 -283.576014) (xy 349.325965 -283.57553) (xy 349.273257 -283.567588)
			(xy 349.222321 -283.551878) (xy 349.174296 -283.528753) (xy 349.130254 -283.498727) (xy 349.09118 -283.462473)
			(xy 349.057945 -283.4208) (xy 349.031293 -283.374638) (xy 349.011819 -283.32502) (xy 348.999957 -283.273054)
			(xy 348.995974 -283.2199) (xy 348.76867 -283.2199) (xy 348.76867 -283.219906) (xy 348.768172 -283.246555)
			(xy 348.760229 -283.299259) (xy 348.744519 -283.350189) (xy 348.721393 -283.39821) (xy 348.691369 -283.442247)
			(xy 348.655117 -283.481318) (xy 348.613446 -283.514549) (xy 348.567288 -283.541198) (xy 348.517674 -283.56067)
			(xy 348.465712 -283.57253) (xy 348.412562 -283.576514) (xy 348.359412 -283.57253) (xy 348.30745 -283.56067)
			(xy 348.257836 -283.541198) (xy 348.211678 -283.514549) (xy 348.170007 -283.481318) (xy 348.133755 -283.442247)
			(xy 348.103731 -283.39821) (xy 348.080605 -283.350189) (xy 348.064895 -283.299259) (xy 348.056952 -283.246555)
			(xy 347.828626 -283.246555) (xy 347.820683 -283.299259) (xy 347.804973 -283.350189) (xy 347.781847 -283.39821)
			(xy 347.751823 -283.442247) (xy 347.715571 -283.481318) (xy 347.6739 -283.514549) (xy 347.627742 -283.541198)
			(xy 347.578128 -283.56067) (xy 347.526166 -283.57253) (xy 347.473016 -283.576514) (xy 347.419866 -283.57253)
			(xy 347.367904 -283.56067) (xy 347.31829 -283.541198) (xy 347.272132 -283.514549) (xy 347.230461 -283.481318)
			(xy 347.194209 -283.442247) (xy 347.164185 -283.39821) (xy 347.141059 -283.350189) (xy 347.125349 -283.299259)
			(xy 347.117406 -283.246555) (xy 347.116908 -283.219906) (xy 346.88907 -283.219906) (xy 346.888572 -283.246555)
			(xy 346.880629 -283.299259) (xy 346.864919 -283.350189) (xy 346.841793 -283.39821) (xy 346.811769 -283.442247)
			(xy 346.775517 -283.481318) (xy 346.733846 -283.514549) (xy 346.687688 -283.541198) (xy 346.638074 -283.56067)
			(xy 346.586112 -283.57253) (xy 346.532962 -283.576514) (xy 346.479812 -283.57253) (xy 346.42785 -283.56067)
			(xy 346.378236 -283.541198) (xy 346.332078 -283.514549) (xy 346.290407 -283.481318) (xy 346.254155 -283.442247)
			(xy 346.224131 -283.39821) (xy 346.201005 -283.350189) (xy 346.185295 -283.299259) (xy 346.177352 -283.246555)
			(xy 345.948772 -283.246555) (xy 345.940829 -283.299259) (xy 345.925119 -283.350189) (xy 345.901993 -283.39821)
			(xy 345.871969 -283.442247) (xy 345.835717 -283.481318) (xy 345.794046 -283.514549) (xy 345.747888 -283.541198)
			(xy 345.698274 -283.56067) (xy 345.646312 -283.57253) (xy 345.593162 -283.576514) (xy 345.540012 -283.57253)
			(xy 345.48805 -283.56067) (xy 345.438436 -283.541198) (xy 345.392278 -283.514549) (xy 345.350607 -283.481318)
			(xy 345.314355 -283.442247) (xy 345.284331 -283.39821) (xy 345.261205 -283.350189) (xy 345.245495 -283.299259)
			(xy 345.237552 -283.246555) (xy 345.009226 -283.246555) (xy 345.001283 -283.299259) (xy 344.985573 -283.350189)
			(xy 344.962447 -283.39821) (xy 344.932423 -283.442247) (xy 344.896171 -283.481318) (xy 344.8545 -283.514549)
			(xy 344.808342 -283.541198) (xy 344.758728 -283.56067) (xy 344.706766 -283.57253) (xy 344.653616 -283.576514)
			(xy 344.600466 -283.57253) (xy 344.548504 -283.56067) (xy 344.49889 -283.541198) (xy 344.452732 -283.514549)
			(xy 344.411061 -283.481318) (xy 344.374809 -283.442247) (xy 344.344785 -283.39821) (xy 344.321659 -283.350189)
			(xy 344.305949 -283.299259) (xy 344.298006 -283.246555) (xy 344.297508 -283.219906) (xy 344.297879 -283.196661)
			(xy 344.303925 -283.150565) (xy 344.315915 -283.105648) (xy 344.324432 -283.084016) (xy 344.334084 -283.060902)
			(xy 344.161364 -282.762198) (xy 344.136726 -282.758896) (xy 344.111374 -282.755053) (xy 344.062036 -282.7411)
			(xy 344.015208 -282.720216) (xy 343.971859 -282.692833) (xy 343.932885 -282.659516) (xy 343.899092 -282.620955)
			(xy 343.871177 -282.577946) (xy 343.849719 -282.531379) (xy 343.835161 -282.482216) (xy 343.827803 -282.431473)
			(xy 343.827354 -282.405836) (xy 343.59977 -282.405836) (xy 343.599272 -282.432485) (xy 343.591329 -282.485189)
			(xy 343.575619 -282.536119) (xy 343.552493 -282.58414) (xy 343.522469 -282.628177) (xy 343.486217 -282.667248)
			(xy 343.444546 -282.700479) (xy 343.398388 -282.727128) (xy 343.348774 -282.7466) (xy 343.296812 -282.75846)
			(xy 343.243662 -282.762444) (xy 343.190512 -282.75846) (xy 343.13855 -282.7466) (xy 343.088936 -282.727128)
			(xy 343.042778 -282.700479) (xy 343.001107 -282.667248) (xy 342.964855 -282.628177) (xy 342.934831 -282.58414)
			(xy 342.911705 -282.536119) (xy 342.895995 -282.485189) (xy 342.888052 -282.432485) (xy 342.887554 -282.405836)
			(xy 342.660224 -282.405836) (xy 342.659726 -282.432485) (xy 342.651783 -282.485189) (xy 342.636073 -282.536119)
			(xy 342.612947 -282.58414) (xy 342.582923 -282.628177) (xy 342.546671 -282.667248) (xy 342.505 -282.700479)
			(xy 342.458842 -282.727128) (xy 342.409228 -282.7466) (xy 342.357266 -282.75846) (xy 342.304116 -282.762444)
			(xy 342.250966 -282.75846) (xy 342.199004 -282.7466) (xy 342.14939 -282.727128) (xy 342.103232 -282.700479)
			(xy 342.061561 -282.667248) (xy 342.025309 -282.628177) (xy 341.995285 -282.58414) (xy 341.972159 -282.536119)
			(xy 341.956449 -282.485189) (xy 341.948506 -282.432485) (xy 341.719926 -282.432485) (xy 341.711983 -282.485189)
			(xy 341.696273 -282.536119) (xy 341.673147 -282.58414) (xy 341.643123 -282.628177) (xy 341.606871 -282.667248)
			(xy 341.5652 -282.700479) (xy 341.519042 -282.727128) (xy 341.469428 -282.7466) (xy 341.417466 -282.75846)
			(xy 341.364316 -282.762444) (xy 341.311166 -282.75846) (xy 341.259204 -282.7466) (xy 341.20959 -282.727128)
			(xy 341.163432 -282.700479) (xy 341.121761 -282.667248) (xy 341.085509 -282.628177) (xy 341.055485 -282.58414)
			(xy 341.032359 -282.536119) (xy 341.016649 -282.485189) (xy 341.008706 -282.432485) (xy 341.008208 -282.405836)
			(xy 340.780624 -282.405836) (xy 340.780126 -282.432485) (xy 340.772183 -282.485189) (xy 340.756473 -282.536119)
			(xy 340.733347 -282.58414) (xy 340.703323 -282.628177) (xy 340.667071 -282.667248) (xy 340.6254 -282.700479)
			(xy 340.579242 -282.727128) (xy 340.529628 -282.7466) (xy 340.477666 -282.75846) (xy 340.424516 -282.762444)
			(xy 340.371366 -282.75846) (xy 340.319404 -282.7466) (xy 340.26979 -282.727128) (xy 340.223632 -282.700479)
			(xy 340.181961 -282.667248) (xy 340.145709 -282.628177) (xy 340.115685 -282.58414) (xy 340.092559 -282.536119)
			(xy 340.076849 -282.485189) (xy 340.068906 -282.432485) (xy 339.84019 -282.432485) (xy 339.832991 -282.482219)
			(xy 339.818443 -282.531387) (xy 339.796993 -282.577959) (xy 339.769085 -282.620973) (xy 339.735296 -282.659539)
			(xy 339.696324 -282.692861) (xy 339.652976 -282.720247) (xy 339.606148 -282.741133) (xy 339.556809 -282.755087)
			(xy 339.531452 -282.758896) (xy 339.50656 -282.762198) (xy 339.334094 -283.060902) (xy 339.343746 -283.084016)
			(xy 339.352263 -283.105648) (xy 339.36425 -283.150566) (xy 339.370295 -283.196661) (xy 339.37067 -283.219906)
			(xy 339.370172 -283.246555) (xy 339.598752 -283.246555) (xy 339.598752 -283.193257) (xy 339.606695 -283.140553)
			(xy 339.622405 -283.089623) (xy 339.645531 -283.041602) (xy 339.675555 -282.997565) (xy 339.711807 -282.958494)
			(xy 339.753478 -282.925263) (xy 339.799636 -282.898614) (xy 339.84925 -282.879142) (xy 339.901212 -282.867282)
			(xy 339.954362 -282.863299) (xy 340.007512 -282.867282) (xy 340.059474 -282.879142) (xy 340.109088 -282.898614)
			(xy 340.155246 -282.925263) (xy 340.196917 -282.958494) (xy 340.233169 -282.997565) (xy 340.263193 -283.041602)
			(xy 340.286319 -283.089623) (xy 340.302029 -283.140553) (xy 340.309972 -283.193257) (xy 340.31047 -283.2199)
			(xy 340.537598 -283.2199) (xy 340.541581 -283.166755) (xy 340.553439 -283.114797) (xy 340.572908 -283.065186)
			(xy 340.599554 -283.019031) (xy 340.63278 -282.977363) (xy 340.671846 -282.941111) (xy 340.715877 -282.911087)
			(xy 340.763892 -282.88796) (xy 340.814817 -282.872247) (xy 340.867515 -282.864298) (xy 340.894162 -282.863798)
			(xy 340.919186 -282.864247) (xy 340.968743 -282.87125) (xy 341.01683 -282.885124) (xy 341.062501 -282.905594)
			(xy 341.104855 -282.932258) (xy 341.143058 -282.964591) (xy 341.176357 -283.001954) (xy 341.19058 -283.022548)
			(xy 341.537544 -283.022548) (xy 341.551794 -283.001972) (xy 341.585087 -282.964605) (xy 341.623285 -282.932268)
			(xy 341.665634 -282.905598) (xy 341.711301 -282.88512) (xy 341.759384 -282.871238) (xy 341.808938 -282.864225)
			(xy 341.833962 -282.863798) (xy 341.860615 -282.864257) (xy 341.913328 -282.872196) (xy 341.964268 -282.887904)
			(xy 342.012297 -282.91103) (xy 342.056343 -282.941056) (xy 342.095422 -282.977311) (xy 342.12866 -283.018987)
			(xy 342.155315 -283.065151) (xy 342.174791 -283.114772) (xy 342.186654 -283.166742) (xy 342.190638 -283.2199)
			(xy 342.18864 -283.246555) (xy 342.418152 -283.246555) (xy 342.418152 -283.193257) (xy 342.426095 -283.140553)
			(xy 342.441805 -283.089623) (xy 342.464931 -283.041602) (xy 342.494955 -282.997565) (xy 342.531207 -282.958494)
			(xy 342.572878 -282.925263) (xy 342.619036 -282.898614) (xy 342.66865 -282.879142) (xy 342.720612 -282.867282)
			(xy 342.773762 -282.863299) (xy 342.826912 -282.867282) (xy 342.878874 -282.879142) (xy 342.928488 -282.898614)
			(xy 342.974646 -282.925263) (xy 343.016317 -282.958494) (xy 343.052569 -282.997565) (xy 343.082593 -283.041602)
			(xy 343.105719 -283.089623) (xy 343.121429 -283.140553) (xy 343.129372 -283.193257) (xy 343.12987 -283.219906)
			(xy 343.129372 -283.246555) (xy 343.357952 -283.246555) (xy 343.357952 -283.193257) (xy 343.365895 -283.140553)
			(xy 343.381605 -283.089623) (xy 343.404731 -283.041602) (xy 343.434755 -282.997565) (xy 343.471007 -282.958494)
			(xy 343.512678 -282.925263) (xy 343.558836 -282.898614) (xy 343.60845 -282.879142) (xy 343.660412 -282.867282)
			(xy 343.713562 -282.863299) (xy 343.766712 -282.867282) (xy 343.818674 -282.879142) (xy 343.868288 -282.898614)
			(xy 343.914446 -282.925263) (xy 343.956117 -282.958494) (xy 343.992369 -282.997565) (xy 344.022393 -283.041602)
			(xy 344.045519 -283.089623) (xy 344.061229 -283.140553) (xy 344.069172 -283.193257) (xy 344.06967 -283.219906)
			(xy 344.069172 -283.246555) (xy 344.061229 -283.299259) (xy 344.045519 -283.350189) (xy 344.022393 -283.39821)
			(xy 343.992369 -283.442247) (xy 343.956117 -283.481318) (xy 343.914446 -283.514549) (xy 343.868288 -283.541198)
			(xy 343.818674 -283.56067) (xy 343.766712 -283.57253) (xy 343.713562 -283.576514) (xy 343.660412 -283.57253)
			(xy 343.60845 -283.56067) (xy 343.558836 -283.541198) (xy 343.512678 -283.514549) (xy 343.471007 -283.481318)
			(xy 343.434755 -283.442247) (xy 343.404731 -283.39821) (xy 343.381605 -283.350189) (xy 343.365895 -283.299259)
			(xy 343.357952 -283.246555) (xy 343.129372 -283.246555) (xy 343.121429 -283.299259) (xy 343.105719 -283.350189)
			(xy 343.082593 -283.39821) (xy 343.052569 -283.442247) (xy 343.016317 -283.481318) (xy 342.974646 -283.514549)
			(xy 342.928488 -283.541198) (xy 342.878874 -283.56067) (xy 342.826912 -283.57253) (xy 342.773762 -283.576514)
			(xy 342.720612 -283.57253) (xy 342.66865 -283.56067) (xy 342.619036 -283.541198) (xy 342.572878 -283.514549)
			(xy 342.531207 -283.481318) (xy 342.494955 -283.442247) (xy 342.464931 -283.39821) (xy 342.441805 -283.350189)
			(xy 342.426095 -283.299259) (xy 342.418152 -283.246555) (xy 342.18864 -283.246555) (xy 342.186654 -283.273058)
			(xy 342.174791 -283.325028) (xy 342.155315 -283.374649) (xy 342.12866 -283.420813) (xy 342.095422 -283.462489)
			(xy 342.056343 -283.498744) (xy 342.012297 -283.52877) (xy 341.964268 -283.551896) (xy 341.913328 -283.567604)
			(xy 341.860615 -283.575543) (xy 341.833962 -283.576014) (xy 341.808936 -283.575617) (xy 341.759378 -283.568604)
			(xy 341.711289 -283.554721) (xy 341.665619 -283.534242) (xy 341.623265 -283.50757) (xy 341.585063 -283.47523)
			(xy 341.551766 -283.437861) (xy 341.537544 -283.417264) (xy 341.19058 -283.417264) (xy 341.176383 -283.437878)
			(xy 341.14308 -283.475243) (xy 341.104873 -283.507577) (xy 341.062515 -283.534243) (xy 341.01684 -283.554715)
			(xy 340.968749 -283.568589) (xy 340.919188 -283.575592) (xy 340.894162 -283.576014) (xy 340.867515 -283.575502)
			(xy 340.814817 -283.567553) (xy 340.763892 -283.55184) (xy 340.715877 -283.528713) (xy 340.671846 -283.498689)
			(xy 340.63278 -283.462437) (xy 340.599554 -283.420769) (xy 340.572908 -283.374614) (xy 340.553439 -283.325003)
			(xy 340.541581 -283.273045) (xy 340.537598 -283.2199) (xy 340.31047 -283.2199) (xy 340.31047 -283.219906)
			(xy 340.309972 -283.246555) (xy 340.302029 -283.299259) (xy 340.286319 -283.350189) (xy 340.263193 -283.39821)
			(xy 340.233169 -283.442247) (xy 340.196917 -283.481318) (xy 340.155246 -283.514549) (xy 340.109088 -283.541198)
			(xy 340.059474 -283.56067) (xy 340.007512 -283.57253) (xy 339.954362 -283.576514) (xy 339.901212 -283.57253)
			(xy 339.84925 -283.56067) (xy 339.799636 -283.541198) (xy 339.753478 -283.514549) (xy 339.711807 -283.481318)
			(xy 339.675555 -283.442247) (xy 339.645531 -283.39821) (xy 339.622405 -283.350189) (xy 339.606695 -283.299259)
			(xy 339.598752 -283.246555) (xy 339.370172 -283.246555) (xy 339.362229 -283.299259) (xy 339.346519 -283.350189)
			(xy 339.323393 -283.39821) (xy 339.293369 -283.442247) (xy 339.257117 -283.481318) (xy 339.215446 -283.514549)
			(xy 339.169288 -283.541198) (xy 339.119674 -283.56067) (xy 339.067712 -283.57253) (xy 339.014562 -283.576514)
			(xy 338.961412 -283.57253) (xy 338.90945 -283.56067) (xy 338.859836 -283.541198) (xy 338.813678 -283.514549)
			(xy 338.772007 -283.481318) (xy 338.735755 -283.442247) (xy 338.705731 -283.39821) (xy 338.682605 -283.350189)
			(xy 338.666895 -283.299259) (xy 338.658952 -283.246555) (xy 338.658454 -283.219906) (xy 338.43087 -283.219906)
			(xy 338.430372 -283.246555) (xy 338.422429 -283.299259) (xy 338.406719 -283.350189) (xy 338.383593 -283.39821)
			(xy 338.353569 -283.442247) (xy 338.317317 -283.481318) (xy 338.275646 -283.514549) (xy 338.229488 -283.541198)
			(xy 338.179874 -283.56067) (xy 338.127912 -283.57253) (xy 338.074762 -283.576514) (xy 338.021612 -283.57253)
			(xy 337.96965 -283.56067) (xy 337.920036 -283.541198) (xy 337.873878 -283.514549) (xy 337.832207 -283.481318)
			(xy 337.795955 -283.442247) (xy 337.765931 -283.39821) (xy 337.742805 -283.350189) (xy 337.727095 -283.299259)
			(xy 337.719152 -283.246555) (xy 337.490572 -283.246555) (xy 337.482629 -283.299259) (xy 337.466919 -283.350189)
			(xy 337.443793 -283.39821) (xy 337.413769 -283.442247) (xy 337.377517 -283.481318) (xy 337.335846 -283.514549)
			(xy 337.289688 -283.541198) (xy 337.240074 -283.56067) (xy 337.188112 -283.57253) (xy 337.134962 -283.576514)
			(xy 337.081812 -283.57253) (xy 337.02985 -283.56067) (xy 336.980236 -283.541198) (xy 336.934078 -283.514549)
			(xy 336.892407 -283.481318) (xy 336.856155 -283.442247) (xy 336.826131 -283.39821) (xy 336.803005 -283.350189)
			(xy 336.787295 -283.299259) (xy 336.779352 -283.246555) (xy 336.550772 -283.246555) (xy 336.542829 -283.299259)
			(xy 336.527119 -283.350189) (xy 336.503993 -283.39821) (xy 336.473969 -283.442247) (xy 336.437717 -283.481318)
			(xy 336.396046 -283.514549) (xy 336.349888 -283.541198) (xy 336.300274 -283.56067) (xy 336.248312 -283.57253)
			(xy 336.195162 -283.576514) (xy 336.142012 -283.57253) (xy 336.09005 -283.56067) (xy 336.040436 -283.541198)
			(xy 335.994278 -283.514549) (xy 335.952607 -283.481318) (xy 335.916355 -283.442247) (xy 335.886331 -283.39821)
			(xy 335.863205 -283.350189) (xy 335.847495 -283.299259) (xy 335.839552 -283.246555) (xy 335.839054 -283.219906)
			(xy 335.839428 -283.196661) (xy 335.845473 -283.150566) (xy 335.857461 -283.105648) (xy 335.865978 -283.084016)
			(xy 335.87563 -283.060902) (xy 335.70291 -282.762198) (xy 335.678272 -282.758896) (xy 335.652927 -282.755083)
			(xy 335.603621 -282.741092) (xy 335.556829 -282.72018) (xy 335.513516 -282.692778) (xy 335.474578 -282.659451)
			(xy 335.440817 -282.620889) (xy 335.412931 -282.577887) (xy 335.391495 -282.531332) (xy 335.376952 -282.482185)
			(xy 335.369602 -282.431462) (xy 335.369154 -282.405836) (xy 335.141824 -282.405836) (xy 335.141326 -282.432485)
			(xy 335.133383 -282.485189) (xy 335.117673 -282.536119) (xy 335.094547 -282.58414) (xy 335.064523 -282.628177)
			(xy 335.028271 -282.667248) (xy 334.9866 -282.700479) (xy 334.940442 -282.727128) (xy 334.890828 -282.7466)
			(xy 334.838866 -282.75846) (xy 334.785716 -282.762444) (xy 334.732566 -282.75846) (xy 334.680604 -282.7466)
			(xy 334.63099 -282.727128) (xy 334.584832 -282.700479) (xy 334.543161 -282.667248) (xy 334.506909 -282.628177)
			(xy 334.476885 -282.58414) (xy 334.453759 -282.536119) (xy 334.438049 -282.485189) (xy 334.430106 -282.432485)
			(xy 334.429608 -282.405836) (xy 334.202293 -282.405836) (xy 334.198313 -282.458951) (xy 334.186451 -282.510915)
			(xy 334.166977 -282.560531) (xy 334.140325 -282.60669) (xy 334.107091 -282.64836) (xy 334.068017 -282.684612)
			(xy 334.023976 -282.714634) (xy 333.975952 -282.737756) (xy 333.925018 -282.753463) (xy 333.872312 -282.761402)
			(xy 333.845662 -282.761944) (xy 333.816694 -282.761375) (xy 333.759522 -282.751999) (xy 333.704619 -282.733501)
			(xy 333.65343 -282.706366) (xy 333.630016 -282.6893) (xy 333.618494 -282.681115) (xy 333.59218 -282.670828)
			(xy 333.564055 -282.668142) (xy 333.536271 -282.673263) (xy 333.510951 -282.685798) (xy 333.490034 -282.704789)
			(xy 333.475118 -282.728784) (xy 333.467345 -282.755946) (xy 333.466948 -282.770072) (xy 333.466948 -282.873958)
			(xy 333.499968 -282.88615) (xy 333.525142 -282.896052) (xy 333.572405 -282.922365) (xy 333.615144 -282.955524)
			(xy 333.652376 -282.994765) (xy 333.683245 -283.039186) (xy 333.707041 -283.087765) (xy 333.723215 -283.139384)
			(xy 333.731396 -283.192855) (xy 333.731396 -283.246555) (xy 333.959952 -283.246555) (xy 333.959952 -283.193257)
			(xy 333.967895 -283.140553) (xy 333.983605 -283.089623) (xy 334.006731 -283.041602) (xy 334.036755 -282.997565)
			(xy 334.073007 -282.958494) (xy 334.114678 -282.925263) (xy 334.160836 -282.898614) (xy 334.21045 -282.879142)
			(xy 334.262412 -282.867282) (xy 334.315562 -282.863299) (xy 334.368712 -282.867282) (xy 334.420674 -282.879142)
			(xy 334.470288 -282.898614) (xy 334.516446 -282.925263) (xy 334.558117 -282.958494) (xy 334.594369 -282.997565)
			(xy 334.624393 -283.041602) (xy 334.647519 -283.089623) (xy 334.663229 -283.140553) (xy 334.671172 -283.193257)
			(xy 334.67167 -283.219906) (xy 334.671172 -283.246555) (xy 334.899752 -283.246555) (xy 334.899752 -283.193257)
			(xy 334.907695 -283.140553) (xy 334.923405 -283.089623) (xy 334.946531 -283.041602) (xy 334.976555 -282.997565)
			(xy 335.012807 -282.958494) (xy 335.054478 -282.925263) (xy 335.100636 -282.898614) (xy 335.15025 -282.879142)
			(xy 335.202212 -282.867282) (xy 335.255362 -282.863299) (xy 335.308512 -282.867282) (xy 335.360474 -282.879142)
			(xy 335.410088 -282.898614) (xy 335.456246 -282.925263) (xy 335.497917 -282.958494) (xy 335.534169 -282.997565)
			(xy 335.564193 -283.041602) (xy 335.587319 -283.089623) (xy 335.603029 -283.140553) (xy 335.610972 -283.193257)
			(xy 335.61147 -283.219906) (xy 335.610972 -283.246555) (xy 335.603029 -283.299259) (xy 335.587319 -283.350189)
			(xy 335.564193 -283.39821) (xy 335.534169 -283.442247) (xy 335.497917 -283.481318) (xy 335.456246 -283.514549)
			(xy 335.410088 -283.541198) (xy 335.360474 -283.56067) (xy 335.308512 -283.57253) (xy 335.255362 -283.576514)
			(xy 335.202212 -283.57253) (xy 335.15025 -283.56067) (xy 335.100636 -283.541198) (xy 335.054478 -283.514549)
			(xy 335.012807 -283.481318) (xy 334.976555 -283.442247) (xy 334.946531 -283.39821) (xy 334.923405 -283.350189)
			(xy 334.907695 -283.299259) (xy 334.899752 -283.246555) (xy 334.671172 -283.246555) (xy 334.663229 -283.299259)
			(xy 334.647519 -283.350189) (xy 334.624393 -283.39821) (xy 334.594369 -283.442247) (xy 334.558117 -283.481318)
			(xy 334.516446 -283.514549) (xy 334.470288 -283.541198) (xy 334.420674 -283.56067) (xy 334.368712 -283.57253)
			(xy 334.315562 -283.576514) (xy 334.262412 -283.57253) (xy 334.21045 -283.56067) (xy 334.160836 -283.541198)
			(xy 334.114678 -283.514549) (xy 334.073007 -283.481318) (xy 334.036755 -283.442247) (xy 334.006731 -283.39821)
			(xy 333.983605 -283.350189) (xy 333.967895 -283.299259) (xy 333.959952 -283.246555) (xy 333.731396 -283.246555)
			(xy 333.731396 -283.246949) (xy 333.723214 -283.30042) (xy 333.707039 -283.352039) (xy 333.683243 -283.400618)
			(xy 333.652374 -283.445038) (xy 333.615141 -283.484279) (xy 333.572401 -283.517437) (xy 333.525138 -283.543749)
			(xy 333.499968 -283.553662) (xy 333.466948 -283.565854) (xy 333.466948 -284.033722) (xy 334.429608 -284.033722)
			(xy 334.430106 -284.007073) (xy 334.438049 -283.954369) (xy 334.453759 -283.903439) (xy 334.476885 -283.855418)
			(xy 334.506909 -283.811381) (xy 334.543161 -283.77231) (xy 334.584832 -283.739079) (xy 334.63099 -283.71243)
			(xy 334.680604 -283.692958) (xy 334.732566 -283.681098) (xy 334.785716 -283.677115) (xy 334.838866 -283.681098)
			(xy 334.890828 -283.692958) (xy 334.940442 -283.71243) (xy 334.9866 -283.739079) (xy 335.028271 -283.77231)
			(xy 335.064523 -283.811381) (xy 335.094547 -283.855418) (xy 335.117673 -283.903439) (xy 335.133383 -283.954369)
			(xy 335.141326 -284.007073) (xy 335.141824 -284.033722) (xy 335.14146 -284.056967) (xy 335.141013 -284.060371)
			(xy 335.369652 -284.060371) (xy 335.369652 -284.007073) (xy 335.377595 -283.954369) (xy 335.393305 -283.903439)
			(xy 335.416431 -283.855418) (xy 335.446455 -283.811381) (xy 335.482707 -283.77231) (xy 335.524378 -283.739079)
			(xy 335.570536 -283.71243) (xy 335.62015 -283.692958) (xy 335.672112 -283.681098) (xy 335.725262 -283.677115)
			(xy 335.778412 -283.681098) (xy 335.830374 -283.692958) (xy 335.879988 -283.71243) (xy 335.926146 -283.739079)
			(xy 335.967817 -283.77231) (xy 336.004069 -283.811381) (xy 336.034093 -283.855418) (xy 336.057219 -283.903439)
			(xy 336.072929 -283.954369) (xy 336.080872 -284.007073) (xy 336.08137 -284.033722) (xy 336.080872 -284.060371)
			(xy 336.309706 -284.060371) (xy 336.309706 -284.007073) (xy 336.317649 -283.954369) (xy 336.333359 -283.903439)
			(xy 336.356485 -283.855418) (xy 336.386509 -283.811381) (xy 336.422761 -283.77231) (xy 336.464432 -283.739079)
			(xy 336.51059 -283.71243) (xy 336.560204 -283.692958) (xy 336.612166 -283.681098) (xy 336.665316 -283.677115)
			(xy 336.718466 -283.681098) (xy 336.770428 -283.692958) (xy 336.820042 -283.71243) (xy 336.8662 -283.739079)
			(xy 336.907871 -283.77231) (xy 336.944123 -283.811381) (xy 336.974147 -283.855418) (xy 336.997273 -283.903439)
			(xy 337.012983 -283.954369) (xy 337.020926 -284.007073) (xy 337.021424 -284.033722) (xy 337.020926 -284.060371)
			(xy 338.189052 -284.060371) (xy 338.189052 -284.007073) (xy 338.196995 -283.954369) (xy 338.212705 -283.903439)
			(xy 338.235831 -283.855418) (xy 338.265855 -283.811381) (xy 338.302107 -283.77231) (xy 338.343778 -283.739079)
			(xy 338.389936 -283.71243) (xy 338.43955 -283.692958) (xy 338.491512 -283.681098) (xy 338.544662 -283.677115)
			(xy 338.597812 -283.681098) (xy 338.649774 -283.692958) (xy 338.699388 -283.71243) (xy 338.745546 -283.739079)
			(xy 338.787217 -283.77231) (xy 338.823469 -283.811381) (xy 338.853493 -283.855418) (xy 338.876619 -283.903439)
			(xy 338.892329 -283.954369) (xy 338.900272 -284.007073) (xy 338.90077 -284.033722) (xy 338.900272 -284.060371)
			(xy 339.128852 -284.060371) (xy 339.128852 -284.007073) (xy 339.136795 -283.954369) (xy 339.152505 -283.903439)
			(xy 339.175631 -283.855418) (xy 339.205655 -283.811381) (xy 339.241907 -283.77231) (xy 339.283578 -283.739079)
			(xy 339.329736 -283.71243) (xy 339.37935 -283.692958) (xy 339.431312 -283.681098) (xy 339.484462 -283.677115)
			(xy 339.537612 -283.681098) (xy 339.589574 -283.692958) (xy 339.639188 -283.71243) (xy 339.685346 -283.739079)
			(xy 339.727017 -283.77231) (xy 339.763269 -283.811381) (xy 339.793293 -283.855418) (xy 339.816419 -283.903439)
			(xy 339.832129 -283.954369) (xy 339.840072 -284.007073) (xy 339.84057 -284.033722) (xy 339.840072 -284.060371)
			(xy 340.068652 -284.060371) (xy 340.068652 -284.007073) (xy 340.076595 -283.954369) (xy 340.092305 -283.903439)
			(xy 340.115431 -283.855418) (xy 340.145455 -283.811381) (xy 340.181707 -283.77231) (xy 340.223378 -283.739079)
			(xy 340.269536 -283.71243) (xy 340.31915 -283.692958) (xy 340.371112 -283.681098) (xy 340.424262 -283.677115)
			(xy 340.477412 -283.681098) (xy 340.529374 -283.692958) (xy 340.578988 -283.71243) (xy 340.625146 -283.739079)
			(xy 340.666817 -283.77231) (xy 340.703069 -283.811381) (xy 340.733093 -283.855418) (xy 340.756219 -283.903439)
			(xy 340.771929 -283.954369) (xy 340.779872 -284.007073) (xy 340.78037 -284.033722) (xy 340.779872 -284.060371)
			(xy 341.008452 -284.060371) (xy 341.008452 -284.007073) (xy 341.016395 -283.954369) (xy 341.032105 -283.903439)
			(xy 341.055231 -283.855418) (xy 341.085255 -283.811381) (xy 341.121507 -283.77231) (xy 341.163178 -283.739079)
			(xy 341.209336 -283.71243) (xy 341.25895 -283.692958) (xy 341.310912 -283.681098) (xy 341.364062 -283.677115)
			(xy 341.417212 -283.681098) (xy 341.469174 -283.692958) (xy 341.518788 -283.71243) (xy 341.564946 -283.739079)
			(xy 341.606617 -283.77231) (xy 341.642869 -283.811381) (xy 341.672893 -283.855418) (xy 341.696019 -283.903439)
			(xy 341.711729 -283.954369) (xy 341.719672 -284.007073) (xy 341.72017 -284.033722) (xy 341.719672 -284.060371)
			(xy 341.948252 -284.060371) (xy 341.948252 -284.007073) (xy 341.956195 -283.954369) (xy 341.971905 -283.903439)
			(xy 341.995031 -283.855418) (xy 342.025055 -283.811381) (xy 342.061307 -283.77231) (xy 342.102978 -283.739079)
			(xy 342.149136 -283.71243) (xy 342.19875 -283.692958) (xy 342.250712 -283.681098) (xy 342.303862 -283.677115)
			(xy 342.357012 -283.681098) (xy 342.408974 -283.692958) (xy 342.458588 -283.71243) (xy 342.504746 -283.739079)
			(xy 342.546417 -283.77231) (xy 342.582669 -283.811381) (xy 342.612693 -283.855418) (xy 342.635819 -283.903439)
			(xy 342.651529 -283.954369) (xy 342.659472 -284.007073) (xy 342.65997 -284.033722) (xy 342.659472 -284.060371)
			(xy 342.888052 -284.060371) (xy 342.888052 -284.007073) (xy 342.895995 -283.954369) (xy 342.911705 -283.903439)
			(xy 342.934831 -283.855418) (xy 342.964855 -283.811381) (xy 343.001107 -283.77231) (xy 343.042778 -283.739079)
			(xy 343.088936 -283.71243) (xy 343.13855 -283.692958) (xy 343.190512 -283.681098) (xy 343.243662 -283.677115)
			(xy 343.296812 -283.681098) (xy 343.348774 -283.692958) (xy 343.398388 -283.71243) (xy 343.444546 -283.739079)
			(xy 343.486217 -283.77231) (xy 343.522469 -283.811381) (xy 343.552493 -283.855418) (xy 343.575619 -283.903439)
			(xy 343.591329 -283.954369) (xy 343.599272 -284.007073) (xy 343.59977 -284.033722) (xy 343.599272 -284.060371)
			(xy 343.827852 -284.060371) (xy 343.827852 -284.007073) (xy 343.835795 -283.954369) (xy 343.851505 -283.903439)
			(xy 343.874631 -283.855418) (xy 343.904655 -283.811381) (xy 343.940907 -283.77231) (xy 343.982578 -283.739079)
			(xy 344.028736 -283.71243) (xy 344.07835 -283.692958) (xy 344.130312 -283.681098) (xy 344.183462 -283.677115)
			(xy 344.236612 -283.681098) (xy 344.288574 -283.692958) (xy 344.338188 -283.71243) (xy 344.384346 -283.739079)
			(xy 344.426017 -283.77231) (xy 344.462269 -283.811381) (xy 344.492293 -283.855418) (xy 344.515419 -283.903439)
			(xy 344.531129 -283.954369) (xy 344.539072 -284.007073) (xy 344.53957 -284.033722) (xy 344.539072 -284.060371)
			(xy 344.767652 -284.060371) (xy 344.767652 -284.007073) (xy 344.775595 -283.954369) (xy 344.791305 -283.903439)
			(xy 344.814431 -283.855418) (xy 344.844455 -283.811381) (xy 344.880707 -283.77231) (xy 344.922378 -283.739079)
			(xy 344.968536 -283.71243) (xy 345.01815 -283.692958) (xy 345.070112 -283.681098) (xy 345.123262 -283.677115)
			(xy 345.176412 -283.681098) (xy 345.228374 -283.692958) (xy 345.277988 -283.71243) (xy 345.324146 -283.739079)
			(xy 345.365817 -283.77231) (xy 345.402069 -283.811381) (xy 345.432093 -283.855418) (xy 345.455219 -283.903439)
			(xy 345.470929 -283.954369) (xy 345.478872 -284.007073) (xy 345.47937 -284.033722) (xy 345.478872 -284.060371)
			(xy 345.707452 -284.060371) (xy 345.707452 -284.007073) (xy 345.715395 -283.954369) (xy 345.731105 -283.903439)
			(xy 345.754231 -283.855418) (xy 345.784255 -283.811381) (xy 345.820507 -283.77231) (xy 345.862178 -283.739079)
			(xy 345.908336 -283.71243) (xy 345.95795 -283.692958) (xy 346.009912 -283.681098) (xy 346.063062 -283.677115)
			(xy 346.116212 -283.681098) (xy 346.168174 -283.692958) (xy 346.217788 -283.71243) (xy 346.263946 -283.739079)
			(xy 346.305617 -283.77231) (xy 346.341869 -283.811381) (xy 346.371893 -283.855418) (xy 346.395019 -283.903439)
			(xy 346.410729 -283.954369) (xy 346.418672 -284.007073) (xy 346.41917 -284.033722) (xy 346.418672 -284.060371)
			(xy 346.647252 -284.060371) (xy 346.647252 -284.007073) (xy 346.655195 -283.954369) (xy 346.670905 -283.903439)
			(xy 346.694031 -283.855418) (xy 346.724055 -283.811381) (xy 346.760307 -283.77231) (xy 346.801978 -283.739079)
			(xy 346.848136 -283.71243) (xy 346.89775 -283.692958) (xy 346.949712 -283.681098) (xy 347.002862 -283.677115)
			(xy 347.056012 -283.681098) (xy 347.107974 -283.692958) (xy 347.157588 -283.71243) (xy 347.203746 -283.739079)
			(xy 347.245417 -283.77231) (xy 347.281669 -283.811381) (xy 347.311693 -283.855418) (xy 347.334819 -283.903439)
			(xy 347.350529 -283.954369) (xy 347.358472 -284.007073) (xy 347.35897 -284.033722) (xy 347.358472 -284.060371)
			(xy 347.587052 -284.060371) (xy 347.587052 -284.007073) (xy 347.594995 -283.954369) (xy 347.610705 -283.903439)
			(xy 347.633831 -283.855418) (xy 347.663855 -283.811381) (xy 347.700107 -283.77231) (xy 347.741778 -283.739079)
			(xy 347.787936 -283.71243) (xy 347.83755 -283.692958) (xy 347.889512 -283.681098) (xy 347.942662 -283.677115)
			(xy 347.995812 -283.681098) (xy 348.047774 -283.692958) (xy 348.097388 -283.71243) (xy 348.143546 -283.739079)
			(xy 348.185217 -283.77231) (xy 348.221469 -283.811381) (xy 348.251493 -283.855418) (xy 348.274619 -283.903439)
			(xy 348.290329 -283.954369) (xy 348.298272 -284.007073) (xy 348.29877 -284.033722) (xy 348.298272 -284.060371)
			(xy 348.526852 -284.060371) (xy 348.526852 -284.007073) (xy 348.534795 -283.954369) (xy 348.550505 -283.903439)
			(xy 348.573631 -283.855418) (xy 348.603655 -283.811381) (xy 348.639907 -283.77231) (xy 348.681578 -283.739079)
			(xy 348.727736 -283.71243) (xy 348.77735 -283.692958) (xy 348.829312 -283.681098) (xy 348.882462 -283.677115)
			(xy 348.935612 -283.681098) (xy 348.987574 -283.692958) (xy 349.037188 -283.71243) (xy 349.083346 -283.739079)
			(xy 349.125017 -283.77231) (xy 349.161269 -283.811381) (xy 349.191293 -283.855418) (xy 349.214419 -283.903439)
			(xy 349.230129 -283.954369) (xy 349.238072 -284.007073) (xy 349.23857 -284.033722) (xy 349.238072 -284.060371)
			(xy 349.466652 -284.060371) (xy 349.466652 -284.007073) (xy 349.474595 -283.954369) (xy 349.490305 -283.903439)
			(xy 349.513431 -283.855418) (xy 349.543455 -283.811381) (xy 349.579707 -283.77231) (xy 349.621378 -283.739079)
			(xy 349.667536 -283.71243) (xy 349.71715 -283.692958) (xy 349.769112 -283.681098) (xy 349.822262 -283.677115)
			(xy 349.875412 -283.681098) (xy 349.927374 -283.692958) (xy 349.976988 -283.71243) (xy 350.023146 -283.739079)
			(xy 350.064817 -283.77231) (xy 350.101069 -283.811381) (xy 350.131093 -283.855418) (xy 350.154219 -283.903439)
			(xy 350.169929 -283.954369) (xy 350.177872 -284.007073) (xy 350.17837 -284.033722) (xy 350.177872 -284.060371)
			(xy 350.406452 -284.060371) (xy 350.406452 -284.007073) (xy 350.414395 -283.954369) (xy 350.430105 -283.903439)
			(xy 350.453231 -283.855418) (xy 350.483255 -283.811381) (xy 350.519507 -283.77231) (xy 350.561178 -283.739079)
			(xy 350.607336 -283.71243) (xy 350.65695 -283.692958) (xy 350.708912 -283.681098) (xy 350.762062 -283.677115)
			(xy 350.815212 -283.681098) (xy 350.867174 -283.692958) (xy 350.916788 -283.71243) (xy 350.962946 -283.739079)
			(xy 351.004617 -283.77231) (xy 351.040869 -283.811381) (xy 351.070893 -283.855418) (xy 351.094019 -283.903439)
			(xy 351.109729 -283.954369) (xy 351.117672 -284.007073) (xy 351.11817 -284.033722) (xy 351.117672 -284.060371)
			(xy 351.109729 -284.113075) (xy 351.094019 -284.164005) (xy 351.070893 -284.212026) (xy 351.040869 -284.256063)
			(xy 351.004617 -284.295134) (xy 350.962946 -284.328365) (xy 350.916788 -284.355014) (xy 350.867174 -284.374486)
			(xy 350.815212 -284.386346) (xy 350.762062 -284.39033) (xy 350.708912 -284.386346) (xy 350.65695 -284.374486)
			(xy 350.607336 -284.355014) (xy 350.561178 -284.328365) (xy 350.519507 -284.295134) (xy 350.483255 -284.256063)
			(xy 350.453231 -284.212026) (xy 350.430105 -284.164005) (xy 350.414395 -284.113075) (xy 350.406452 -284.060371)
			(xy 350.177872 -284.060371) (xy 350.169929 -284.113075) (xy 350.154219 -284.164005) (xy 350.131093 -284.212026)
			(xy 350.101069 -284.256063) (xy 350.064817 -284.295134) (xy 350.023146 -284.328365) (xy 349.976988 -284.355014)
			(xy 349.927374 -284.374486) (xy 349.875412 -284.386346) (xy 349.822262 -284.39033) (xy 349.769112 -284.386346)
			(xy 349.71715 -284.374486) (xy 349.667536 -284.355014) (xy 349.621378 -284.328365) (xy 349.579707 -284.295134)
			(xy 349.543455 -284.256063) (xy 349.513431 -284.212026) (xy 349.490305 -284.164005) (xy 349.474595 -284.113075)
			(xy 349.466652 -284.060371) (xy 349.238072 -284.060371) (xy 349.230129 -284.113075) (xy 349.214419 -284.164005)
			(xy 349.191293 -284.212026) (xy 349.161269 -284.256063) (xy 349.125017 -284.295134) (xy 349.083346 -284.328365)
			(xy 349.037188 -284.355014) (xy 348.987574 -284.374486) (xy 348.935612 -284.386346) (xy 348.882462 -284.39033)
			(xy 348.829312 -284.386346) (xy 348.77735 -284.374486) (xy 348.727736 -284.355014) (xy 348.681578 -284.328365)
			(xy 348.639907 -284.295134) (xy 348.603655 -284.256063) (xy 348.573631 -284.212026) (xy 348.550505 -284.164005)
			(xy 348.534795 -284.113075) (xy 348.526852 -284.060371) (xy 348.298272 -284.060371) (xy 348.290329 -284.113075)
			(xy 348.274619 -284.164005) (xy 348.251493 -284.212026) (xy 348.221469 -284.256063) (xy 348.185217 -284.295134)
			(xy 348.143546 -284.328365) (xy 348.097388 -284.355014) (xy 348.047774 -284.374486) (xy 347.995812 -284.386346)
			(xy 347.942662 -284.39033) (xy 347.889512 -284.386346) (xy 347.83755 -284.374486) (xy 347.787936 -284.355014)
			(xy 347.741778 -284.328365) (xy 347.700107 -284.295134) (xy 347.663855 -284.256063) (xy 347.633831 -284.212026)
			(xy 347.610705 -284.164005) (xy 347.594995 -284.113075) (xy 347.587052 -284.060371) (xy 347.358472 -284.060371)
			(xy 347.350529 -284.113075) (xy 347.334819 -284.164005) (xy 347.311693 -284.212026) (xy 347.281669 -284.256063)
			(xy 347.245417 -284.295134) (xy 347.203746 -284.328365) (xy 347.157588 -284.355014) (xy 347.107974 -284.374486)
			(xy 347.056012 -284.386346) (xy 347.002862 -284.39033) (xy 346.949712 -284.386346) (xy 346.89775 -284.374486)
			(xy 346.848136 -284.355014) (xy 346.801978 -284.328365) (xy 346.760307 -284.295134) (xy 346.724055 -284.256063)
			(xy 346.694031 -284.212026) (xy 346.670905 -284.164005) (xy 346.655195 -284.113075) (xy 346.647252 -284.060371)
			(xy 346.418672 -284.060371) (xy 346.410729 -284.113075) (xy 346.395019 -284.164005) (xy 346.371893 -284.212026)
			(xy 346.341869 -284.256063) (xy 346.305617 -284.295134) (xy 346.263946 -284.328365) (xy 346.217788 -284.355014)
			(xy 346.168174 -284.374486) (xy 346.116212 -284.386346) (xy 346.063062 -284.39033) (xy 346.009912 -284.386346)
			(xy 345.95795 -284.374486) (xy 345.908336 -284.355014) (xy 345.862178 -284.328365) (xy 345.820507 -284.295134)
			(xy 345.784255 -284.256063) (xy 345.754231 -284.212026) (xy 345.731105 -284.164005) (xy 345.715395 -284.113075)
			(xy 345.707452 -284.060371) (xy 345.478872 -284.060371) (xy 345.470929 -284.113075) (xy 345.455219 -284.164005)
			(xy 345.432093 -284.212026) (xy 345.402069 -284.256063) (xy 345.365817 -284.295134) (xy 345.324146 -284.328365)
			(xy 345.277988 -284.355014) (xy 345.228374 -284.374486) (xy 345.176412 -284.386346) (xy 345.123262 -284.39033)
			(xy 345.070112 -284.386346) (xy 345.01815 -284.374486) (xy 344.968536 -284.355014) (xy 344.922378 -284.328365)
			(xy 344.880707 -284.295134) (xy 344.844455 -284.256063) (xy 344.814431 -284.212026) (xy 344.791305 -284.164005)
			(xy 344.775595 -284.113075) (xy 344.767652 -284.060371) (xy 344.539072 -284.060371) (xy 344.531129 -284.113075)
			(xy 344.515419 -284.164005) (xy 344.492293 -284.212026) (xy 344.462269 -284.256063) (xy 344.426017 -284.295134)
			(xy 344.384346 -284.328365) (xy 344.338188 -284.355014) (xy 344.288574 -284.374486) (xy 344.236612 -284.386346)
			(xy 344.183462 -284.39033) (xy 344.130312 -284.386346) (xy 344.07835 -284.374486) (xy 344.028736 -284.355014)
			(xy 343.982578 -284.328365) (xy 343.940907 -284.295134) (xy 343.904655 -284.256063) (xy 343.874631 -284.212026)
			(xy 343.851505 -284.164005) (xy 343.835795 -284.113075) (xy 343.827852 -284.060371) (xy 343.599272 -284.060371)
			(xy 343.591329 -284.113075) (xy 343.575619 -284.164005) (xy 343.552493 -284.212026) (xy 343.522469 -284.256063)
			(xy 343.486217 -284.295134) (xy 343.444546 -284.328365) (xy 343.398388 -284.355014) (xy 343.348774 -284.374486)
			(xy 343.296812 -284.386346) (xy 343.243662 -284.39033) (xy 343.190512 -284.386346) (xy 343.13855 -284.374486)
			(xy 343.088936 -284.355014) (xy 343.042778 -284.328365) (xy 343.001107 -284.295134) (xy 342.964855 -284.256063)
			(xy 342.934831 -284.212026) (xy 342.911705 -284.164005) (xy 342.895995 -284.113075) (xy 342.888052 -284.060371)
			(xy 342.659472 -284.060371) (xy 342.651529 -284.113075) (xy 342.635819 -284.164005) (xy 342.612693 -284.212026)
			(xy 342.582669 -284.256063) (xy 342.546417 -284.295134) (xy 342.504746 -284.328365) (xy 342.458588 -284.355014)
			(xy 342.408974 -284.374486) (xy 342.357012 -284.386346) (xy 342.303862 -284.39033) (xy 342.250712 -284.386346)
			(xy 342.19875 -284.374486) (xy 342.149136 -284.355014) (xy 342.102978 -284.328365) (xy 342.061307 -284.295134)
			(xy 342.025055 -284.256063) (xy 341.995031 -284.212026) (xy 341.971905 -284.164005) (xy 341.956195 -284.113075)
			(xy 341.948252 -284.060371) (xy 341.719672 -284.060371) (xy 341.711729 -284.113075) (xy 341.696019 -284.164005)
			(xy 341.672893 -284.212026) (xy 341.642869 -284.256063) (xy 341.606617 -284.295134) (xy 341.564946 -284.328365)
			(xy 341.518788 -284.355014) (xy 341.469174 -284.374486) (xy 341.417212 -284.386346) (xy 341.364062 -284.39033)
			(xy 341.310912 -284.386346) (xy 341.25895 -284.374486) (xy 341.209336 -284.355014) (xy 341.163178 -284.328365)
			(xy 341.121507 -284.295134) (xy 341.085255 -284.256063) (xy 341.055231 -284.212026) (xy 341.032105 -284.164005)
			(xy 341.016395 -284.113075) (xy 341.008452 -284.060371) (xy 340.779872 -284.060371) (xy 340.771929 -284.113075)
			(xy 340.756219 -284.164005) (xy 340.733093 -284.212026) (xy 340.703069 -284.256063) (xy 340.666817 -284.295134)
			(xy 340.625146 -284.328365) (xy 340.578988 -284.355014) (xy 340.529374 -284.374486) (xy 340.477412 -284.386346)
			(xy 340.424262 -284.39033) (xy 340.371112 -284.386346) (xy 340.31915 -284.374486) (xy 340.269536 -284.355014)
			(xy 340.223378 -284.328365) (xy 340.181707 -284.295134) (xy 340.145455 -284.256063) (xy 340.115431 -284.212026)
			(xy 340.092305 -284.164005) (xy 340.076595 -284.113075) (xy 340.068652 -284.060371) (xy 339.840072 -284.060371)
			(xy 339.832129 -284.113075) (xy 339.816419 -284.164005) (xy 339.793293 -284.212026) (xy 339.763269 -284.256063)
			(xy 339.727017 -284.295134) (xy 339.685346 -284.328365) (xy 339.639188 -284.355014) (xy 339.589574 -284.374486)
			(xy 339.537612 -284.386346) (xy 339.484462 -284.39033) (xy 339.431312 -284.386346) (xy 339.37935 -284.374486)
			(xy 339.329736 -284.355014) (xy 339.283578 -284.328365) (xy 339.241907 -284.295134) (xy 339.205655 -284.256063)
			(xy 339.175631 -284.212026) (xy 339.152505 -284.164005) (xy 339.136795 -284.113075) (xy 339.128852 -284.060371)
			(xy 338.900272 -284.060371) (xy 338.892329 -284.113075) (xy 338.876619 -284.164005) (xy 338.853493 -284.212026)
			(xy 338.823469 -284.256063) (xy 338.787217 -284.295134) (xy 338.745546 -284.328365) (xy 338.699388 -284.355014)
			(xy 338.649774 -284.374486) (xy 338.597812 -284.386346) (xy 338.544662 -284.39033) (xy 338.491512 -284.386346)
			(xy 338.43955 -284.374486) (xy 338.389936 -284.355014) (xy 338.343778 -284.328365) (xy 338.302107 -284.295134)
			(xy 338.265855 -284.256063) (xy 338.235831 -284.212026) (xy 338.212705 -284.164005) (xy 338.196995 -284.113075)
			(xy 338.189052 -284.060371) (xy 337.020926 -284.060371) (xy 337.012983 -284.113075) (xy 336.997273 -284.164005)
			(xy 336.974147 -284.212026) (xy 336.944123 -284.256063) (xy 336.907871 -284.295134) (xy 336.8662 -284.328365)
			(xy 336.820042 -284.355014) (xy 336.770428 -284.374486) (xy 336.718466 -284.386346) (xy 336.665316 -284.39033)
			(xy 336.612166 -284.386346) (xy 336.560204 -284.374486) (xy 336.51059 -284.355014) (xy 336.464432 -284.328365)
			(xy 336.422761 -284.295134) (xy 336.386509 -284.256063) (xy 336.356485 -284.212026) (xy 336.333359 -284.164005)
			(xy 336.317649 -284.113075) (xy 336.309706 -284.060371) (xy 336.080872 -284.060371) (xy 336.072929 -284.113075)
			(xy 336.057219 -284.164005) (xy 336.034093 -284.212026) (xy 336.004069 -284.256063) (xy 335.967817 -284.295134)
			(xy 335.926146 -284.328365) (xy 335.879988 -284.355014) (xy 335.830374 -284.374486) (xy 335.778412 -284.386346)
			(xy 335.725262 -284.39033) (xy 335.672112 -284.386346) (xy 335.62015 -284.374486) (xy 335.570536 -284.355014)
			(xy 335.524378 -284.328365) (xy 335.482707 -284.295134) (xy 335.446455 -284.256063) (xy 335.416431 -284.212026)
			(xy 335.393305 -284.164005) (xy 335.377595 -284.113075) (xy 335.369652 -284.060371) (xy 335.141013 -284.060371)
			(xy 335.135411 -284.103063) (xy 335.123419 -284.147981) (xy 335.1149 -284.169612) (xy 335.105248 -284.192726)
			(xy 335.277714 -284.491176) (xy 335.302352 -284.494478) (xy 335.327695 -284.498297) (xy 335.377 -284.51229)
			(xy 335.42379 -284.533203) (xy 335.467101 -284.560605) (xy 335.506039 -284.593931) (xy 335.539799 -284.632492)
			(xy 335.567686 -284.675493) (xy 335.589123 -284.722046) (xy 335.603668 -284.771191) (xy 335.61102 -284.821912)
			(xy 335.61147 -284.847538) (xy 335.610972 -284.874187) (xy 335.603029 -284.926891) (xy 335.587319 -284.977821)
			(xy 335.564193 -285.025842) (xy 335.534169 -285.069879) (xy 335.497917 -285.10895) (xy 335.456246 -285.142181)
			(xy 335.410088 -285.16883) (xy 335.360474 -285.188302) (xy 335.308512 -285.200162) (xy 335.255362 -285.204146)
			(xy 335.202212 -285.200162) (xy 335.15025 -285.188302) (xy 335.100636 -285.16883) (xy 335.054478 -285.142181)
			(xy 335.012807 -285.10895) (xy 334.976555 -285.069879) (xy 334.946531 -285.025842) (xy 334.923405 -284.977821)
			(xy 334.907695 -284.926891) (xy 334.899752 -284.874187) (xy 334.899254 -284.847538) (xy 334.899638 -284.824293)
			(xy 334.905679 -284.778198) (xy 334.917663 -284.73328) (xy 334.926178 -284.711648) (xy 334.93583 -284.688534)
			(xy 334.763364 -284.390084) (xy 334.738726 -284.386782) (xy 334.713386 -284.38294) (xy 334.664079 -284.368956)
			(xy 334.617285 -284.348049) (xy 334.573971 -284.320651) (xy 334.535031 -284.287329) (xy 334.501269 -284.248769)
			(xy 334.473382 -284.205768) (xy 334.451946 -284.159215) (xy 334.437404 -284.11007) (xy 334.430055 -284.059348)
			(xy 334.429608 -284.033722) (xy 333.466948 -284.033722) (xy 333.466948 -284.50159) (xy 333.499968 -284.513782)
			(xy 333.525956 -284.524033) (xy 333.574627 -284.55145) (xy 333.618419 -284.586131) (xy 333.656258 -284.627225)
			(xy 333.67218 -284.65018) (xy 334.019144 -284.65018) (xy 334.033364 -284.629581) (xy 334.06666 -284.592207)
			(xy 334.104861 -284.559864) (xy 334.147214 -284.533188) (xy 334.192885 -284.512706) (xy 334.240975 -284.498821)
			(xy 334.290535 -284.491807) (xy 334.315562 -284.49143) (xy 334.342212 -284.4919) (xy 334.394918 -284.499839)
			(xy 334.445851 -284.515545) (xy 334.493875 -284.538668) (xy 334.537916 -284.56869) (xy 334.57699 -284.604941)
			(xy 334.610224 -284.646611) (xy 334.636875 -284.69277) (xy 334.656349 -284.742385) (xy 334.668211 -284.794349)
			(xy 334.672194 -284.8475) (xy 334.668211 -284.900651) (xy 334.656349 -284.952615) (xy 334.636875 -285.00223)
			(xy 334.610224 -285.048389) (xy 334.57699 -285.090059) (xy 334.537916 -285.12631) (xy 334.493875 -285.156332)
			(xy 334.445851 -285.179455) (xy 334.394918 -285.195161) (xy 334.342212 -285.2031) (xy 334.315562 -285.203646)
			(xy 334.290538 -285.203219) (xy 334.240983 -285.196207) (xy 334.192898 -285.182326) (xy 334.14723 -285.16185)
			(xy 334.104878 -285.135181) (xy 334.066677 -285.102846) (xy 334.03338 -285.065481) (xy 334.019144 -285.044896)
			(xy 333.67218 -285.044896) (xy 333.656248 -285.067843) (xy 333.61841 -285.108938) (xy 333.574622 -285.143622)
			(xy 333.525956 -285.171045) (xy 333.499968 -285.181294) (xy 333.466948 -285.193486) (xy 333.466948 -285.297118)
			(xy 333.467398 -285.311255) (xy 333.475132 -285.338449) (xy 333.490028 -285.362478) (xy 333.510945 -285.3815)
			(xy 333.536277 -285.394054) (xy 333.564081 -285.399178) (xy 333.592224 -285.396479) (xy 333.618547 -285.386163)
			(xy 333.630016 -285.37789) (xy 333.653423 -285.360815) (xy 333.704615 -285.333688) (xy 333.759521 -285.315199)
			(xy 333.816694 -285.305836) (xy 333.845662 -285.305246) (xy 333.872318 -285.305717) (xy 333.925037 -285.313657)
			(xy 333.975982 -285.329367) (xy 334.024017 -285.352495) (xy 334.068068 -285.382524) (xy 334.107151 -285.418784)
			(xy 334.140393 -285.460464) (xy 334.167051 -285.506633) (xy 334.18653 -285.55626) (xy 334.198394 -285.608236)
			(xy 334.202378 -285.6614) (xy 334.200384 -285.688003) (xy 334.429852 -285.688003) (xy 334.429852 -285.634705)
			(xy 334.437795 -285.582001) (xy 334.453505 -285.531071) (xy 334.476631 -285.48305) (xy 334.506655 -285.439013)
			(xy 334.542907 -285.399942) (xy 334.584578 -285.366711) (xy 334.630736 -285.340062) (xy 334.68035 -285.32059)
			(xy 334.732312 -285.30873) (xy 334.785462 -285.304747) (xy 334.838612 -285.30873) (xy 334.890574 -285.32059)
			(xy 334.940188 -285.340062) (xy 334.986346 -285.366711) (xy 335.028017 -285.399942) (xy 335.064269 -285.439013)
			(xy 335.094293 -285.48305) (xy 335.117419 -285.531071) (xy 335.133129 -285.582001) (xy 335.141072 -285.634705)
			(xy 335.14157 -285.661354) (xy 335.369154 -285.661354) (xy 335.369623 -285.635726) (xy 335.376951 -285.584997)
			(xy 335.391479 -285.535844) (xy 335.412905 -285.489282) (xy 335.440787 -285.446273) (xy 335.474549 -285.407708)
			(xy 335.513492 -285.374383) (xy 335.556812 -285.346988) (xy 335.603613 -285.326087) (xy 335.652927 -285.312115)
			(xy 335.678272 -285.308294) (xy 335.70291 -285.304992) (xy 335.875376 -285.006288) (xy 335.865978 -284.983174)
			(xy 335.857483 -284.961579) (xy 335.845509 -284.916747) (xy 335.839448 -284.87074) (xy 335.839054 -284.847538)
			(xy 335.839552 -284.820889) (xy 335.847495 -284.768185) (xy 335.863205 -284.717255) (xy 335.886331 -284.669234)
			(xy 335.916355 -284.625197) (xy 335.952607 -284.586126) (xy 335.994278 -284.552895) (xy 336.040436 -284.526246)
			(xy 336.09005 -284.506774) (xy 336.142012 -284.494914) (xy 336.195162 -284.490931) (xy 336.248312 -284.494914)
			(xy 336.300274 -284.506774) (xy 336.349888 -284.526246) (xy 336.396046 -284.552895) (xy 336.437717 -284.586126)
			(xy 336.473969 -284.625197) (xy 336.503993 -284.669234) (xy 336.527119 -284.717255) (xy 336.542829 -284.768185)
			(xy 336.550772 -284.820889) (xy 336.55127 -284.847538) (xy 336.550773 -284.873165) (xy 336.550625 -284.874187)
			(xy 336.779352 -284.874187) (xy 336.779352 -284.820889) (xy 336.787295 -284.768185) (xy 336.803005 -284.717255)
			(xy 336.826131 -284.669234) (xy 336.856155 -284.625197) (xy 336.892407 -284.586126) (xy 336.934078 -284.552895)
			(xy 336.980236 -284.526246) (xy 337.02985 -284.506774) (xy 337.081812 -284.494914) (xy 337.134962 -284.490931)
			(xy 337.188112 -284.494914) (xy 337.240074 -284.506774) (xy 337.289688 -284.526246) (xy 337.335846 -284.552895)
			(xy 337.377517 -284.586126) (xy 337.413769 -284.625197) (xy 337.443793 -284.669234) (xy 337.466919 -284.717255)
			(xy 337.482629 -284.768185) (xy 337.490572 -284.820889) (xy 337.49107 -284.847538) (xy 337.490572 -284.874187)
			(xy 337.482629 -284.926891) (xy 337.466919 -284.977821) (xy 337.443793 -285.025842) (xy 337.413769 -285.069879)
			(xy 337.377517 -285.10895) (xy 337.335846 -285.142181) (xy 337.289688 -285.16883) (xy 337.240074 -285.188302)
			(xy 337.188112 -285.200162) (xy 337.134962 -285.204146) (xy 337.081812 -285.200162) (xy 337.02985 -285.188302)
			(xy 336.980236 -285.16883) (xy 336.934078 -285.142181) (xy 336.892407 -285.10895) (xy 336.856155 -285.069879)
			(xy 336.826131 -285.025842) (xy 336.803005 -284.977821) (xy 336.787295 -284.926891) (xy 336.779352 -284.874187)
			(xy 336.550625 -284.874187) (xy 336.543446 -284.923891) (xy 336.528921 -284.973043) (xy 336.507497 -285.019604)
			(xy 336.479618 -285.062611) (xy 336.44586 -285.101176) (xy 336.40692 -285.134502) (xy 336.363604 -285.161899)
			(xy 336.316807 -285.182801) (xy 336.267496 -285.196776) (xy 336.242152 -285.200598) (xy 336.217514 -285.2039)
			(xy 336.045048 -285.502604) (xy 336.054446 -285.525718) (xy 336.062935 -285.547315) (xy 336.074913 -285.592146)
			(xy 336.080975 -285.638152) (xy 336.08137 -285.661354) (xy 336.080872 -285.688003) (xy 336.309452 -285.688003)
			(xy 336.309452 -285.634705) (xy 336.317395 -285.582001) (xy 336.333105 -285.531071) (xy 336.356231 -285.48305)
			(xy 336.386255 -285.439013) (xy 336.422507 -285.399942) (xy 336.464178 -285.366711) (xy 336.510336 -285.340062)
			(xy 336.55995 -285.32059) (xy 336.611912 -285.30873) (xy 336.665062 -285.304747) (xy 336.718212 -285.30873)
			(xy 336.770174 -285.32059) (xy 336.819788 -285.340062) (xy 336.865946 -285.366711) (xy 336.907617 -285.399942)
			(xy 336.943869 -285.439013) (xy 336.973893 -285.48305) (xy 336.997019 -285.531071) (xy 337.012729 -285.582001)
			(xy 337.020672 -285.634705) (xy 337.02117 -285.661354) (xy 337.248754 -285.661354) (xy 337.249252 -285.634705)
			(xy 337.257195 -285.582001) (xy 337.272905 -285.531071) (xy 337.296031 -285.48305) (xy 337.326055 -285.439013)
			(xy 337.362307 -285.399942) (xy 337.403978 -285.366711) (xy 337.450136 -285.340062) (xy 337.49975 -285.32059)
			(xy 337.551712 -285.30873) (xy 337.604862 -285.304747) (xy 337.658012 -285.30873) (xy 337.709974 -285.32059)
			(xy 337.759588 -285.340062) (xy 337.805746 -285.366711) (xy 337.847417 -285.399942) (xy 337.883669 -285.439013)
			(xy 337.913693 -285.48305) (xy 337.936819 -285.531071) (xy 337.952529 -285.582001) (xy 337.960472 -285.634705)
			(xy 337.96097 -285.661354) (xy 338.188808 -285.661354) (xy 338.189317 -285.635728) (xy 338.196644 -285.585003)
			(xy 338.211169 -285.535852) (xy 338.232592 -285.489293) (xy 338.26047 -285.446286) (xy 338.294227 -285.407721)
			(xy 338.333165 -285.374396) (xy 338.376479 -285.346998) (xy 338.423274 -285.326095) (xy 338.472583 -285.312117)
			(xy 338.497926 -285.308294) (xy 338.522564 -285.304992) (xy 338.69503 -285.006542) (xy 338.685378 -284.983428)
			(xy 338.676871 -284.961793) (xy 338.664881 -284.916876) (xy 338.658832 -284.870783) (xy 338.658454 -284.847538)
			(xy 338.658952 -284.820889) (xy 338.666895 -284.768185) (xy 338.682605 -284.717255) (xy 338.705731 -284.669234)
			(xy 338.735755 -284.625197) (xy 338.772007 -284.586126) (xy 338.813678 -284.552895) (xy 338.859836 -284.526246)
			(xy 338.90945 -284.506774) (xy 338.961412 -284.494914) (xy 339.014562 -284.490931) (xy 339.067712 -284.494914)
			(xy 339.119674 -284.506774) (xy 339.169288 -284.526246) (xy 339.215446 -284.552895) (xy 339.257117 -284.586126)
			(xy 339.293369 -284.625197) (xy 339.323393 -284.669234) (xy 339.346519 -284.717255) (xy 339.362229 -284.768185)
			(xy 339.370172 -284.820889) (xy 339.37067 -284.847538) (xy 339.370294 -284.873159) (xy 339.362971 -284.923873)
			(xy 339.348453 -284.973015) (xy 339.327041 -285.019567) (xy 339.299176 -285.062569) (xy 339.265434 -285.101132)
			(xy 339.226512 -285.134459) (xy 339.183215 -285.161862) (xy 339.136436 -285.182775) (xy 339.087142 -285.196766)
			(xy 339.061806 -285.200598) (xy 339.036914 -285.2039) (xy 338.864448 -285.50235) (xy 338.8741 -285.525464)
			(xy 338.882604 -285.547101) (xy 338.894595 -285.592016) (xy 338.900646 -285.63811) (xy 338.901024 -285.661354)
			(xy 339.128608 -285.661354) (xy 339.129106 -285.634705) (xy 339.137049 -285.582001) (xy 339.152759 -285.531071)
			(xy 339.175885 -285.48305) (xy 339.205909 -285.439013) (xy 339.242161 -285.399942) (xy 339.283832 -285.366711)
			(xy 339.32999 -285.340062) (xy 339.379604 -285.32059) (xy 339.431566 -285.30873) (xy 339.484716 -285.304747)
			(xy 339.537866 -285.30873) (xy 339.589828 -285.32059) (xy 339.639442 -285.340062) (xy 339.6856 -285.366711)
			(xy 339.727271 -285.399942) (xy 339.763523 -285.439013) (xy 339.793547 -285.48305) (xy 339.816673 -285.531071)
			(xy 339.832383 -285.582001) (xy 339.840326 -285.634705) (xy 339.840824 -285.661354) (xy 340.068154 -285.661354)
			(xy 340.068623 -285.635726) (xy 340.075951 -285.584997) (xy 340.090479 -285.535844) (xy 340.111905 -285.489282)
			(xy 340.139787 -285.446273) (xy 340.173549 -285.407708) (xy 340.212492 -285.374383) (xy 340.255812 -285.346988)
			(xy 340.302613 -285.326087) (xy 340.351927 -285.312115) (xy 340.377272 -285.308294) (xy 340.40191 -285.304992)
			(xy 340.57463 -285.006034) (xy 340.564978 -284.98292) (xy 340.556512 -284.961367) (xy 340.544627 -284.916612)
			(xy 340.538658 -284.870692) (xy 340.538308 -284.847538) (xy 340.538806 -284.820889) (xy 340.546749 -284.768185)
			(xy 340.562459 -284.717255) (xy 340.585585 -284.669234) (xy 340.615609 -284.625197) (xy 340.651861 -284.586126)
			(xy 340.693532 -284.552895) (xy 340.73969 -284.526246) (xy 340.789304 -284.506774) (xy 340.841266 -284.494914)
			(xy 340.894416 -284.490931) (xy 340.947566 -284.494914) (xy 340.999528 -284.506774) (xy 341.049142 -284.526246)
			(xy 341.0953 -284.552895) (xy 341.136971 -284.586126) (xy 341.173223 -284.625197) (xy 341.203247 -284.669234)
			(xy 341.226373 -284.717255) (xy 341.242083 -284.768185) (xy 341.250026 -284.820889) (xy 341.250524 -284.847538)
			(xy 341.250038 -284.873175) (xy 341.242692 -284.923921) (xy 341.228144 -284.973089) (xy 341.206694 -285.019661)
			(xy 341.178786 -285.062675) (xy 341.144996 -285.101242) (xy 341.106025 -285.134563) (xy 341.062676 -285.161949)
			(xy 341.015848 -285.182836) (xy 340.966509 -285.196789) (xy 340.941152 -285.200598) (xy 340.91626 -285.2039)
			(xy 340.743794 -285.50235) (xy 340.753446 -285.525464) (xy 340.761947 -285.547102) (xy 340.77394 -285.592017)
			(xy 340.779991 -285.63811) (xy 340.78037 -285.661354) (xy 341.007954 -285.661354) (xy 341.008452 -285.634705)
			(xy 341.016395 -285.582001) (xy 341.032105 -285.531071) (xy 341.055231 -285.48305) (xy 341.085255 -285.439013)
			(xy 341.121507 -285.399942) (xy 341.163178 -285.366711) (xy 341.209336 -285.340062) (xy 341.25895 -285.32059)
			(xy 341.310912 -285.30873) (xy 341.364062 -285.304747) (xy 341.417212 -285.30873) (xy 341.469174 -285.32059)
			(xy 341.518788 -285.340062) (xy 341.564946 -285.366711) (xy 341.606617 -285.399942) (xy 341.642869 -285.439013)
			(xy 341.672893 -285.48305) (xy 341.696019 -285.531071) (xy 341.711729 -285.582001) (xy 341.719672 -285.634705)
			(xy 341.72017 -285.661354) (xy 341.947754 -285.661354) (xy 341.948223 -285.635726) (xy 341.955551 -285.584997)
			(xy 341.970079 -285.535844) (xy 341.991505 -285.489282) (xy 342.019387 -285.446273) (xy 342.053149 -285.407708)
			(xy 342.092092 -285.374383) (xy 342.135412 -285.346988) (xy 342.182213 -285.326087) (xy 342.231527 -285.312115)
			(xy 342.256872 -285.308294) (xy 342.28151 -285.304992) (xy 342.45423 -285.006034) (xy 342.444578 -284.98292)
			(xy 342.436112 -284.961367) (xy 342.424227 -284.916612) (xy 342.418258 -284.870692) (xy 342.417908 -284.847538)
			(xy 342.418406 -284.820889) (xy 342.426349 -284.768185) (xy 342.442059 -284.717255) (xy 342.465185 -284.669234)
			(xy 342.495209 -284.625197) (xy 342.531461 -284.586126) (xy 342.573132 -284.552895) (xy 342.61929 -284.526246)
			(xy 342.668904 -284.506774) (xy 342.720866 -284.494914) (xy 342.774016 -284.490931) (xy 342.827166 -284.494914)
			(xy 342.879128 -284.506774) (xy 342.928742 -284.526246) (xy 342.9749 -284.552895) (xy 343.016571 -284.586126)
			(xy 343.052823 -284.625197) (xy 343.082847 -284.669234) (xy 343.105973 -284.717255) (xy 343.121683 -284.768185)
			(xy 343.129626 -284.820889) (xy 343.130124 -284.847538) (xy 343.129638 -284.873175) (xy 343.122292 -284.923921)
			(xy 343.107744 -284.973089) (xy 343.086294 -285.019661) (xy 343.058386 -285.062675) (xy 343.024596 -285.101242)
			(xy 342.985625 -285.134563) (xy 342.942276 -285.161949) (xy 342.895448 -285.182836) (xy 342.846109 -285.196789)
			(xy 342.820752 -285.200598) (xy 342.79586 -285.2039) (xy 342.623394 -285.50235) (xy 342.633046 -285.525464)
			(xy 342.641547 -285.547102) (xy 342.65354 -285.592017) (xy 342.659591 -285.63811) (xy 342.65997 -285.661354)
			(xy 342.887554 -285.661354) (xy 342.888052 -285.634705) (xy 342.895995 -285.582001) (xy 342.911705 -285.531071)
			(xy 342.934831 -285.48305) (xy 342.964855 -285.439013) (xy 343.001107 -285.399942) (xy 343.042778 -285.366711)
			(xy 343.088936 -285.340062) (xy 343.13855 -285.32059) (xy 343.190512 -285.30873) (xy 343.243662 -285.304747)
			(xy 343.296812 -285.30873) (xy 343.348774 -285.32059) (xy 343.398388 -285.340062) (xy 343.444546 -285.366711)
			(xy 343.486217 -285.399942) (xy 343.522469 -285.439013) (xy 343.552493 -285.48305) (xy 343.575619 -285.531071)
			(xy 343.591329 -285.582001) (xy 343.599272 -285.634705) (xy 343.59977 -285.661354) (xy 343.827354 -285.661354)
			(xy 343.827823 -285.635726) (xy 343.835151 -285.584997) (xy 343.849679 -285.535844) (xy 343.871105 -285.489282)
			(xy 343.898987 -285.446273) (xy 343.932749 -285.407708) (xy 343.971692 -285.374383) (xy 344.015012 -285.346988)
			(xy 344.061813 -285.326087) (xy 344.111127 -285.312115) (xy 344.136472 -285.308294) (xy 344.16111 -285.304992)
			(xy 344.33383 -285.006034) (xy 344.324178 -284.98292) (xy 344.315712 -284.961367) (xy 344.303827 -284.916612)
			(xy 344.297858 -284.870692) (xy 344.297508 -284.847538) (xy 344.298006 -284.820889) (xy 344.305949 -284.768185)
			(xy 344.321659 -284.717255) (xy 344.344785 -284.669234) (xy 344.374809 -284.625197) (xy 344.411061 -284.586126)
			(xy 344.452732 -284.552895) (xy 344.49889 -284.526246) (xy 344.548504 -284.506774) (xy 344.600466 -284.494914)
			(xy 344.653616 -284.490931) (xy 344.706766 -284.494914) (xy 344.758728 -284.506774) (xy 344.808342 -284.526246)
			(xy 344.8545 -284.552895) (xy 344.896171 -284.586126) (xy 344.932423 -284.625197) (xy 344.962447 -284.669234)
			(xy 344.985573 -284.717255) (xy 345.001283 -284.768185) (xy 345.009226 -284.820889) (xy 345.009724 -284.847538)
			(xy 345.009238 -284.873175) (xy 345.001892 -284.923921) (xy 344.987344 -284.973089) (xy 344.965894 -285.019661)
			(xy 344.937986 -285.062675) (xy 344.904196 -285.101242) (xy 344.865225 -285.134563) (xy 344.821876 -285.161949)
			(xy 344.775048 -285.182836) (xy 344.725709 -285.196789) (xy 344.700352 -285.200598) (xy 344.67546 -285.2039)
			(xy 344.502994 -285.50235) (xy 344.512646 -285.525464) (xy 344.521147 -285.547102) (xy 344.53314 -285.592017)
			(xy 344.539191 -285.63811) (xy 344.53957 -285.661354) (xy 344.767154 -285.661354) (xy 344.767652 -285.634705)
			(xy 344.775595 -285.582001) (xy 344.791305 -285.531071) (xy 344.814431 -285.48305) (xy 344.844455 -285.439013)
			(xy 344.880707 -285.399942) (xy 344.922378 -285.366711) (xy 344.968536 -285.340062) (xy 345.01815 -285.32059)
			(xy 345.070112 -285.30873) (xy 345.123262 -285.304747) (xy 345.176412 -285.30873) (xy 345.228374 -285.32059)
			(xy 345.277988 -285.340062) (xy 345.324146 -285.366711) (xy 345.365817 -285.399942) (xy 345.402069 -285.439013)
			(xy 345.432093 -285.48305) (xy 345.455219 -285.531071) (xy 345.470929 -285.582001) (xy 345.478872 -285.634705)
			(xy 345.47937 -285.661354) (xy 345.706954 -285.661354) (xy 345.707423 -285.635726) (xy 345.714751 -285.584997)
			(xy 345.729279 -285.535844) (xy 345.750705 -285.489282) (xy 345.778587 -285.446273) (xy 345.812349 -285.407708)
			(xy 345.851292 -285.374383) (xy 345.894612 -285.346988) (xy 345.941413 -285.326087) (xy 345.990727 -285.312115)
			(xy 346.016072 -285.308294) (xy 346.04071 -285.304992) (xy 346.21343 -285.006034) (xy 346.203778 -284.98292)
			(xy 346.195312 -284.961367) (xy 346.183427 -284.916612) (xy 346.177458 -284.870692) (xy 346.177108 -284.847538)
			(xy 346.177606 -284.820889) (xy 346.185549 -284.768185) (xy 346.201259 -284.717255) (xy 346.224385 -284.669234)
			(xy 346.254409 -284.625197) (xy 346.290661 -284.586126) (xy 346.332332 -284.552895) (xy 346.37849 -284.526246)
			(xy 346.428104 -284.506774) (xy 346.480066 -284.494914) (xy 346.533216 -284.490931) (xy 346.586366 -284.494914)
			(xy 346.638328 -284.506774) (xy 346.687942 -284.526246) (xy 346.7341 -284.552895) (xy 346.775771 -284.586126)
			(xy 346.812023 -284.625197) (xy 346.842047 -284.669234) (xy 346.865173 -284.717255) (xy 346.880883 -284.768185)
			(xy 346.888826 -284.820889) (xy 346.889324 -284.847538) (xy 346.888838 -284.873175) (xy 346.881492 -284.923921)
			(xy 346.866944 -284.973089) (xy 346.845494 -285.019661) (xy 346.817586 -285.062675) (xy 346.783796 -285.101242)
			(xy 346.744825 -285.134563) (xy 346.701476 -285.161949) (xy 346.654648 -285.182836) (xy 346.605309 -285.196789)
			(xy 346.579952 -285.200598) (xy 346.55506 -285.2039) (xy 346.382594 -285.50235) (xy 346.392246 -285.525464)
			(xy 346.400747 -285.547102) (xy 346.41274 -285.592017) (xy 346.418791 -285.63811) (xy 346.41917 -285.661354)
			(xy 346.646754 -285.661354) (xy 346.647252 -285.634705) (xy 346.655195 -285.582001) (xy 346.670905 -285.531071)
			(xy 346.694031 -285.48305) (xy 346.724055 -285.439013) (xy 346.760307 -285.399942) (xy 346.801978 -285.366711)
			(xy 346.848136 -285.340062) (xy 346.89775 -285.32059) (xy 346.949712 -285.30873) (xy 347.002862 -285.304747)
			(xy 347.056012 -285.30873) (xy 347.107974 -285.32059) (xy 347.157588 -285.340062) (xy 347.203746 -285.366711)
			(xy 347.245417 -285.399942) (xy 347.281669 -285.439013) (xy 347.311693 -285.48305) (xy 347.334819 -285.531071)
			(xy 347.350529 -285.582001) (xy 347.358472 -285.634705) (xy 347.35897 -285.661354) (xy 347.586554 -285.661354)
			(xy 347.587023 -285.635726) (xy 347.594351 -285.584997) (xy 347.608879 -285.535844) (xy 347.630305 -285.489282)
			(xy 347.658187 -285.446273) (xy 347.691949 -285.407708) (xy 347.730892 -285.374383) (xy 347.774212 -285.346988)
			(xy 347.821013 -285.326087) (xy 347.870327 -285.312115) (xy 347.895672 -285.308294) (xy 347.92031 -285.304992)
			(xy 348.09303 -285.006034) (xy 348.083378 -284.98292) (xy 348.074912 -284.961367) (xy 348.063027 -284.916612)
			(xy 348.057058 -284.870692) (xy 348.056708 -284.847538) (xy 348.057206 -284.820889) (xy 348.065149 -284.768185)
			(xy 348.080859 -284.717255) (xy 348.103985 -284.669234) (xy 348.134009 -284.625197) (xy 348.170261 -284.586126)
			(xy 348.211932 -284.552895) (xy 348.25809 -284.526246) (xy 348.307704 -284.506774) (xy 348.359666 -284.494914)
			(xy 348.412816 -284.490931) (xy 348.465966 -284.494914) (xy 348.517928 -284.506774) (xy 348.567542 -284.526246)
			(xy 348.6137 -284.552895) (xy 348.655371 -284.586126) (xy 348.691623 -284.625197) (xy 348.721647 -284.669234)
			(xy 348.744773 -284.717255) (xy 348.760483 -284.768185) (xy 348.768426 -284.820889) (xy 348.768924 -284.847538)
			(xy 348.768438 -284.873175) (xy 348.768292 -284.874187) (xy 348.997006 -284.874187) (xy 348.997006 -284.820889)
			(xy 349.004949 -284.768185) (xy 349.020659 -284.717255) (xy 349.043785 -284.669234) (xy 349.073809 -284.625197)
			(xy 349.110061 -284.586126) (xy 349.151732 -284.552895) (xy 349.19789 -284.526246) (xy 349.247504 -284.506774)
			(xy 349.299466 -284.494914) (xy 349.352616 -284.490931) (xy 349.405766 -284.494914) (xy 349.457728 -284.506774)
			(xy 349.507342 -284.526246) (xy 349.5535 -284.552895) (xy 349.595171 -284.586126) (xy 349.631423 -284.625197)
			(xy 349.661447 -284.669234) (xy 349.684573 -284.717255) (xy 349.700283 -284.768185) (xy 349.708226 -284.820889)
			(xy 349.708724 -284.847538) (xy 349.708226 -284.874187) (xy 349.700283 -284.926891) (xy 349.684573 -284.977821)
			(xy 349.661447 -285.025842) (xy 349.631423 -285.069879) (xy 349.595171 -285.10895) (xy 349.5535 -285.142181)
			(xy 349.507342 -285.16883) (xy 349.457728 -285.188302) (xy 349.405766 -285.200162) (xy 349.352616 -285.204146)
			(xy 349.299466 -285.200162) (xy 349.247504 -285.188302) (xy 349.19789 -285.16883) (xy 349.151732 -285.142181)
			(xy 349.110061 -285.10895) (xy 349.073809 -285.069879) (xy 349.043785 -285.025842) (xy 349.020659 -284.977821)
			(xy 349.004949 -284.926891) (xy 348.997006 -284.874187) (xy 348.768292 -284.874187) (xy 348.761092 -284.923921)
			(xy 348.746544 -284.973089) (xy 348.725094 -285.019661) (xy 348.697186 -285.062675) (xy 348.663396 -285.101242)
			(xy 348.624425 -285.134563) (xy 348.581076 -285.161949) (xy 348.534248 -285.182836) (xy 348.484909 -285.196789)
			(xy 348.459552 -285.200598) (xy 348.43466 -285.2039) (xy 348.262194 -285.50235) (xy 348.271846 -285.525464)
			(xy 348.280347 -285.547102) (xy 348.29234 -285.592017) (xy 348.298391 -285.63811) (xy 348.29877 -285.661354)
			(xy 348.526354 -285.661354) (xy 348.526852 -285.634705) (xy 348.534795 -285.582001) (xy 348.550505 -285.531071)
			(xy 348.573631 -285.48305) (xy 348.603655 -285.439013) (xy 348.639907 -285.399942) (xy 348.681578 -285.366711)
			(xy 348.727736 -285.340062) (xy 348.77735 -285.32059) (xy 348.829312 -285.30873) (xy 348.882462 -285.304747)
			(xy 348.935612 -285.30873) (xy 348.987574 -285.32059) (xy 349.037188 -285.340062) (xy 349.083346 -285.366711)
			(xy 349.125017 -285.399942) (xy 349.161269 -285.439013) (xy 349.191293 -285.48305) (xy 349.214419 -285.531071)
			(xy 349.230129 -285.582001) (xy 349.238072 -285.634705) (xy 349.23857 -285.661354) (xy 349.466154 -285.661354)
			(xy 349.466623 -285.635726) (xy 349.473951 -285.584997) (xy 349.488479 -285.535844) (xy 349.509905 -285.489282)
			(xy 349.537787 -285.446273) (xy 349.571549 -285.407708) (xy 349.610492 -285.374383) (xy 349.653812 -285.346988)
			(xy 349.700613 -285.326087) (xy 349.749927 -285.312115) (xy 349.775272 -285.308294) (xy 349.79991 -285.304992)
			(xy 349.97263 -285.006034) (xy 349.962978 -284.98292) (xy 349.954512 -284.961367) (xy 349.942627 -284.916612)
			(xy 349.936658 -284.870692) (xy 349.936308 -284.847538) (xy 349.936806 -284.820889) (xy 349.944749 -284.768185)
			(xy 349.960459 -284.717255) (xy 349.983585 -284.669234) (xy 350.013609 -284.625197) (xy 350.049861 -284.586126)
			(xy 350.091532 -284.552895) (xy 350.13769 -284.526246) (xy 350.187304 -284.506774) (xy 350.239266 -284.494914)
			(xy 350.292416 -284.490931) (xy 350.345566 -284.494914) (xy 350.397528 -284.506774) (xy 350.447142 -284.526246)
			(xy 350.4933 -284.552895) (xy 350.534971 -284.586126) (xy 350.571223 -284.625197) (xy 350.601247 -284.669234)
			(xy 350.624373 -284.717255) (xy 350.640083 -284.768185) (xy 350.648026 -284.820889) (xy 350.648524 -284.847538)
			(xy 350.648038 -284.873175) (xy 350.647892 -284.874187) (xy 350.876352 -284.874187) (xy 350.876352 -284.820889)
			(xy 350.884295 -284.768185) (xy 350.900005 -284.717255) (xy 350.923131 -284.669234) (xy 350.953155 -284.625197)
			(xy 350.989407 -284.586126) (xy 351.031078 -284.552895) (xy 351.077236 -284.526246) (xy 351.12685 -284.506774)
			(xy 351.178812 -284.494914) (xy 351.231962 -284.490931) (xy 351.285112 -284.494914) (xy 351.337074 -284.506774)
			(xy 351.386688 -284.526246) (xy 351.432846 -284.552895) (xy 351.474517 -284.586126) (xy 351.510769 -284.625197)
			(xy 351.540793 -284.669234) (xy 351.563919 -284.717255) (xy 351.579629 -284.768185) (xy 351.587572 -284.820889)
			(xy 351.58807 -284.847538) (xy 351.587572 -284.874187) (xy 351.579629 -284.926891) (xy 351.563919 -284.977821)
			(xy 351.540793 -285.025842) (xy 351.510769 -285.069879) (xy 351.474517 -285.10895) (xy 351.432846 -285.142181)
			(xy 351.386688 -285.16883) (xy 351.337074 -285.188302) (xy 351.285112 -285.200162) (xy 351.231962 -285.204146)
			(xy 351.178812 -285.200162) (xy 351.12685 -285.188302) (xy 351.077236 -285.16883) (xy 351.031078 -285.142181)
			(xy 350.989407 -285.10895) (xy 350.953155 -285.069879) (xy 350.923131 -285.025842) (xy 350.900005 -284.977821)
			(xy 350.884295 -284.926891) (xy 350.876352 -284.874187) (xy 350.647892 -284.874187) (xy 350.640692 -284.923921)
			(xy 350.626144 -284.973089) (xy 350.604694 -285.019661) (xy 350.576786 -285.062675) (xy 350.542996 -285.101242)
			(xy 350.504025 -285.134563) (xy 350.460676 -285.161949) (xy 350.413848 -285.182836) (xy 350.364509 -285.196789)
			(xy 350.339152 -285.200598) (xy 350.31426 -285.2039) (xy 350.141794 -285.50235) (xy 350.151446 -285.525464)
			(xy 350.159947 -285.547102) (xy 350.17194 -285.592017) (xy 350.177991 -285.63811) (xy 350.17837 -285.661354)
			(xy 350.405954 -285.661354) (xy 350.406452 -285.634705) (xy 350.414395 -285.582001) (xy 350.430105 -285.531071)
			(xy 350.453231 -285.48305) (xy 350.483255 -285.439013) (xy 350.519507 -285.399942) (xy 350.561178 -285.366711)
			(xy 350.607336 -285.340062) (xy 350.65695 -285.32059) (xy 350.708912 -285.30873) (xy 350.762062 -285.304747)
			(xy 350.815212 -285.30873) (xy 350.867174 -285.32059) (xy 350.916788 -285.340062) (xy 350.962946 -285.366711)
			(xy 351.004617 -285.399942) (xy 351.040869 -285.439013) (xy 351.070893 -285.48305) (xy 351.094019 -285.531071)
			(xy 351.109729 -285.582001) (xy 351.117672 -285.634705) (xy 351.11817 -285.661354) (xy 351.117777 -285.684557)
			(xy 351.111732 -285.730567) (xy 351.099754 -285.7754) (xy 351.091246 -285.79699) (xy 351.081848 -285.820104)
			(xy 351.254568 -286.119062) (xy 351.279206 -286.122364) (xy 351.304541 -286.126233) (xy 351.353844 -286.140219)
			(xy 351.400634 -286.161125) (xy 351.443945 -286.188521) (xy 351.482884 -286.221841) (xy 351.516645 -286.260397)
			(xy 351.544533 -286.303393) (xy 351.565972 -286.349942) (xy 351.580519 -286.399082) (xy 351.587873 -286.4498)
			(xy 351.588324 -286.475424) (xy 351.587826 -286.502073) (xy 351.579883 -286.554777) (xy 351.564173 -286.605707)
			(xy 351.541047 -286.653728) (xy 351.511023 -286.697765) (xy 351.474771 -286.736836) (xy 351.4331 -286.770067)
			(xy 351.386942 -286.796716) (xy 351.337328 -286.816188) (xy 351.285366 -286.828048) (xy 351.232216 -286.832032)
			(xy 351.179066 -286.828048) (xy 351.127104 -286.816188) (xy 351.07749 -286.796716) (xy 351.031332 -286.770067)
			(xy 350.989661 -286.736836) (xy 350.953409 -286.697765) (xy 350.923385 -286.653728) (xy 350.900259 -286.605707)
			(xy 350.884549 -286.554777) (xy 350.876606 -286.502073) (xy 350.876108 -286.475424) (xy 350.876484 -286.452179)
			(xy 350.882528 -286.406084) (xy 350.894516 -286.361166) (xy 350.903032 -286.339534) (xy 350.912684 -286.31642)
			(xy 350.739964 -286.017716) (xy 350.715326 -286.014414) (xy 350.689977 -286.010553) (xy 350.64064 -285.996602)
			(xy 350.593814 -285.975719) (xy 350.550466 -285.948337) (xy 350.511492 -285.915023) (xy 350.477698 -285.876464)
			(xy 350.449784 -285.833457) (xy 350.428324 -285.786892) (xy 350.413764 -285.737731) (xy 350.406404 -285.68699)
			(xy 350.405954 -285.661354) (xy 350.17837 -285.661354) (xy 350.177872 -285.688003) (xy 350.169929 -285.740707)
			(xy 350.154219 -285.791637) (xy 350.131093 -285.839658) (xy 350.101069 -285.883695) (xy 350.064817 -285.922766)
			(xy 350.023146 -285.955997) (xy 349.976988 -285.982646) (xy 349.927374 -286.002118) (xy 349.875412 -286.013978)
			(xy 349.822262 -286.017962) (xy 349.769112 -286.013978) (xy 349.71715 -286.002118) (xy 349.667536 -285.982646)
			(xy 349.621378 -285.955997) (xy 349.579707 -285.922766) (xy 349.543455 -285.883695) (xy 349.513431 -285.839658)
			(xy 349.490305 -285.791637) (xy 349.474595 -285.740707) (xy 349.466652 -285.688003) (xy 349.466154 -285.661354)
			(xy 349.23857 -285.661354) (xy 349.238177 -285.684557) (xy 349.232132 -285.730567) (xy 349.220154 -285.7754)
			(xy 349.211646 -285.79699) (xy 349.202248 -285.820104) (xy 349.374968 -286.119062) (xy 349.399606 -286.122364)
			(xy 349.424941 -286.126233) (xy 349.474244 -286.140219) (xy 349.521034 -286.161125) (xy 349.564345 -286.188521)
			(xy 349.603284 -286.221841) (xy 349.637045 -286.260397) (xy 349.664933 -286.303393) (xy 349.686372 -286.349942)
			(xy 349.700919 -286.399082) (xy 349.708273 -286.4498) (xy 349.708724 -286.475424) (xy 349.708226 -286.502073)
			(xy 349.936552 -286.502073) (xy 349.936552 -286.448775) (xy 349.944495 -286.396071) (xy 349.960205 -286.345141)
			(xy 349.983331 -286.29712) (xy 350.013355 -286.253083) (xy 350.049607 -286.214012) (xy 350.091278 -286.180781)
			(xy 350.137436 -286.154132) (xy 350.18705 -286.13466) (xy 350.239012 -286.1228) (xy 350.292162 -286.118817)
			(xy 350.345312 -286.1228) (xy 350.397274 -286.13466) (xy 350.446888 -286.154132) (xy 350.493046 -286.180781)
			(xy 350.534717 -286.214012) (xy 350.570969 -286.253083) (xy 350.600993 -286.29712) (xy 350.624119 -286.345141)
			(xy 350.639829 -286.396071) (xy 350.647772 -286.448775) (xy 350.64827 -286.475424) (xy 350.647772 -286.502073)
			(xy 350.639829 -286.554777) (xy 350.624119 -286.605707) (xy 350.600993 -286.653728) (xy 350.570969 -286.697765)
			(xy 350.534717 -286.736836) (xy 350.493046 -286.770067) (xy 350.446888 -286.796716) (xy 350.397274 -286.816188)
			(xy 350.345312 -286.828048) (xy 350.292162 -286.832032) (xy 350.239012 -286.828048) (xy 350.18705 -286.816188)
			(xy 350.137436 -286.796716) (xy 350.091278 -286.770067) (xy 350.049607 -286.736836) (xy 350.013355 -286.697765)
			(xy 349.983331 -286.653728) (xy 349.960205 -286.605707) (xy 349.944495 -286.554777) (xy 349.936552 -286.502073)
			(xy 349.708226 -286.502073) (xy 349.700283 -286.554777) (xy 349.684573 -286.605707) (xy 349.661447 -286.653728)
			(xy 349.631423 -286.697765) (xy 349.595171 -286.736836) (xy 349.5535 -286.770067) (xy 349.507342 -286.796716)
			(xy 349.457728 -286.816188) (xy 349.405766 -286.828048) (xy 349.352616 -286.832032) (xy 349.299466 -286.828048)
			(xy 349.247504 -286.816188) (xy 349.19789 -286.796716) (xy 349.151732 -286.770067) (xy 349.110061 -286.736836)
			(xy 349.073809 -286.697765) (xy 349.043785 -286.653728) (xy 349.020659 -286.605707) (xy 349.004949 -286.554777)
			(xy 348.997006 -286.502073) (xy 348.996508 -286.475424) (xy 348.996884 -286.452179) (xy 349.002928 -286.406084)
			(xy 349.014916 -286.361166) (xy 349.023432 -286.339534) (xy 349.033084 -286.31642) (xy 348.860364 -286.017716)
			(xy 348.835726 -286.014414) (xy 348.810377 -286.010553) (xy 348.76104 -285.996602) (xy 348.714214 -285.975719)
			(xy 348.670866 -285.948337) (xy 348.631892 -285.915023) (xy 348.598098 -285.876464) (xy 348.570184 -285.833457)
			(xy 348.548724 -285.786892) (xy 348.534164 -285.737731) (xy 348.526804 -285.68699) (xy 348.526354 -285.661354)
			(xy 348.29877 -285.661354) (xy 348.298272 -285.688003) (xy 348.290329 -285.740707) (xy 348.274619 -285.791637)
			(xy 348.251493 -285.839658) (xy 348.221469 -285.883695) (xy 348.185217 -285.922766) (xy 348.143546 -285.955997)
			(xy 348.097388 -285.982646) (xy 348.047774 -286.002118) (xy 347.995812 -286.013978) (xy 347.942662 -286.017962)
			(xy 347.889512 -286.013978) (xy 347.83755 -286.002118) (xy 347.787936 -285.982646) (xy 347.741778 -285.955997)
			(xy 347.700107 -285.922766) (xy 347.663855 -285.883695) (xy 347.633831 -285.839658) (xy 347.610705 -285.791637)
			(xy 347.594995 -285.740707) (xy 347.587052 -285.688003) (xy 347.586554 -285.661354) (xy 347.35897 -285.661354)
			(xy 347.358577 -285.684557) (xy 347.352532 -285.730567) (xy 347.340554 -285.7754) (xy 347.332046 -285.79699)
			(xy 347.322648 -285.820104) (xy 347.495368 -286.119062) (xy 347.520006 -286.122364) (xy 347.545341 -286.126233)
			(xy 347.594644 -286.140219) (xy 347.641434 -286.161125) (xy 347.684745 -286.188521) (xy 347.723684 -286.221841)
			(xy 347.757445 -286.260397) (xy 347.785333 -286.303393) (xy 347.806772 -286.349942) (xy 347.821319 -286.399082)
			(xy 347.828673 -286.4498) (xy 347.829124 -286.475424) (xy 347.828626 -286.502073) (xy 348.056952 -286.502073)
			(xy 348.056952 -286.448775) (xy 348.064895 -286.396071) (xy 348.080605 -286.345141) (xy 348.103731 -286.29712)
			(xy 348.133755 -286.253083) (xy 348.170007 -286.214012) (xy 348.211678 -286.180781) (xy 348.257836 -286.154132)
			(xy 348.30745 -286.13466) (xy 348.359412 -286.1228) (xy 348.412562 -286.118817) (xy 348.465712 -286.1228)
			(xy 348.517674 -286.13466) (xy 348.567288 -286.154132) (xy 348.613446 -286.180781) (xy 348.655117 -286.214012)
			(xy 348.691369 -286.253083) (xy 348.721393 -286.29712) (xy 348.744519 -286.345141) (xy 348.760229 -286.396071)
			(xy 348.768172 -286.448775) (xy 348.76867 -286.475424) (xy 348.768172 -286.502073) (xy 348.760229 -286.554777)
			(xy 348.744519 -286.605707) (xy 348.721393 -286.653728) (xy 348.691369 -286.697765) (xy 348.655117 -286.736836)
			(xy 348.613446 -286.770067) (xy 348.567288 -286.796716) (xy 348.517674 -286.816188) (xy 348.465712 -286.828048)
			(xy 348.412562 -286.832032) (xy 348.359412 -286.828048) (xy 348.30745 -286.816188) (xy 348.257836 -286.796716)
			(xy 348.211678 -286.770067) (xy 348.170007 -286.736836) (xy 348.133755 -286.697765) (xy 348.103731 -286.653728)
			(xy 348.080605 -286.605707) (xy 348.064895 -286.554777) (xy 348.056952 -286.502073) (xy 347.828626 -286.502073)
			(xy 347.820683 -286.554777) (xy 347.804973 -286.605707) (xy 347.781847 -286.653728) (xy 347.751823 -286.697765)
			(xy 347.715571 -286.736836) (xy 347.6739 -286.770067) (xy 347.627742 -286.796716) (xy 347.578128 -286.816188)
			(xy 347.526166 -286.828048) (xy 347.473016 -286.832032) (xy 347.419866 -286.828048) (xy 347.367904 -286.816188)
			(xy 347.31829 -286.796716) (xy 347.272132 -286.770067) (xy 347.230461 -286.736836) (xy 347.194209 -286.697765)
			(xy 347.164185 -286.653728) (xy 347.141059 -286.605707) (xy 347.125349 -286.554777) (xy 347.117406 -286.502073)
			(xy 347.116908 -286.475424) (xy 347.117284 -286.452179) (xy 347.123328 -286.406084) (xy 347.135316 -286.361166)
			(xy 347.143832 -286.339534) (xy 347.153484 -286.31642) (xy 346.980764 -286.017716) (xy 346.956126 -286.014414)
			(xy 346.930777 -286.010553) (xy 346.88144 -285.996602) (xy 346.834614 -285.975719) (xy 346.791266 -285.948337)
			(xy 346.752292 -285.915023) (xy 346.718498 -285.876464) (xy 346.690584 -285.833457) (xy 346.669124 -285.786892)
			(xy 346.654564 -285.737731) (xy 346.647204 -285.68699) (xy 346.646754 -285.661354) (xy 346.41917 -285.661354)
			(xy 346.418672 -285.688003) (xy 346.410729 -285.740707) (xy 346.395019 -285.791637) (xy 346.371893 -285.839658)
			(xy 346.341869 -285.883695) (xy 346.305617 -285.922766) (xy 346.263946 -285.955997) (xy 346.217788 -285.982646)
			(xy 346.168174 -286.002118) (xy 346.116212 -286.013978) (xy 346.063062 -286.017962) (xy 346.009912 -286.013978)
			(xy 345.95795 -286.002118) (xy 345.908336 -285.982646) (xy 345.862178 -285.955997) (xy 345.820507 -285.922766)
			(xy 345.784255 -285.883695) (xy 345.754231 -285.839658) (xy 345.731105 -285.791637) (xy 345.715395 -285.740707)
			(xy 345.707452 -285.688003) (xy 345.706954 -285.661354) (xy 345.47937 -285.661354) (xy 345.478977 -285.684557)
			(xy 345.472932 -285.730567) (xy 345.460954 -285.7754) (xy 345.452446 -285.79699) (xy 345.443048 -285.820104)
			(xy 345.615768 -286.119062) (xy 345.640406 -286.122364) (xy 345.665741 -286.126233) (xy 345.715044 -286.140219)
			(xy 345.761834 -286.161125) (xy 345.805145 -286.188521) (xy 345.844084 -286.221841) (xy 345.877845 -286.260397)
			(xy 345.905733 -286.303393) (xy 345.927172 -286.349942) (xy 345.941719 -286.399082) (xy 345.949073 -286.4498)
			(xy 345.949524 -286.475424) (xy 345.949026 -286.502073) (xy 346.177352 -286.502073) (xy 346.177352 -286.448775)
			(xy 346.185295 -286.396071) (xy 346.201005 -286.345141) (xy 346.224131 -286.29712) (xy 346.254155 -286.253083)
			(xy 346.290407 -286.214012) (xy 346.332078 -286.180781) (xy 346.378236 -286.154132) (xy 346.42785 -286.13466)
			(xy 346.479812 -286.1228) (xy 346.532962 -286.118817) (xy 346.586112 -286.1228) (xy 346.638074 -286.13466)
			(xy 346.687688 -286.154132) (xy 346.733846 -286.180781) (xy 346.775517 -286.214012) (xy 346.811769 -286.253083)
			(xy 346.841793 -286.29712) (xy 346.864919 -286.345141) (xy 346.880629 -286.396071) (xy 346.888572 -286.448775)
			(xy 346.88907 -286.475424) (xy 346.888572 -286.502073) (xy 346.880629 -286.554777) (xy 346.864919 -286.605707)
			(xy 346.841793 -286.653728) (xy 346.811769 -286.697765) (xy 346.775517 -286.736836) (xy 346.733846 -286.770067)
			(xy 346.687688 -286.796716) (xy 346.638074 -286.816188) (xy 346.586112 -286.828048) (xy 346.532962 -286.832032)
			(xy 346.479812 -286.828048) (xy 346.42785 -286.816188) (xy 346.378236 -286.796716) (xy 346.332078 -286.770067)
			(xy 346.290407 -286.736836) (xy 346.254155 -286.697765) (xy 346.224131 -286.653728) (xy 346.201005 -286.605707)
			(xy 346.185295 -286.554777) (xy 346.177352 -286.502073) (xy 345.949026 -286.502073) (xy 345.941083 -286.554777)
			(xy 345.925373 -286.605707) (xy 345.902247 -286.653728) (xy 345.872223 -286.697765) (xy 345.835971 -286.736836)
			(xy 345.7943 -286.770067) (xy 345.748142 -286.796716) (xy 345.698528 -286.816188) (xy 345.646566 -286.828048)
			(xy 345.593416 -286.832032) (xy 345.540266 -286.828048) (xy 345.488304 -286.816188) (xy 345.43869 -286.796716)
			(xy 345.392532 -286.770067) (xy 345.350861 -286.736836) (xy 345.314609 -286.697765) (xy 345.284585 -286.653728)
			(xy 345.261459 -286.605707) (xy 345.245749 -286.554777) (xy 345.237806 -286.502073) (xy 345.237308 -286.475424)
			(xy 345.237684 -286.452179) (xy 345.243728 -286.406084) (xy 345.255716 -286.361166) (xy 345.264232 -286.339534)
			(xy 345.273884 -286.31642) (xy 345.101164 -286.017716) (xy 345.076526 -286.014414) (xy 345.051177 -286.010553)
			(xy 345.00184 -285.996602) (xy 344.955014 -285.975719) (xy 344.911666 -285.948337) (xy 344.872692 -285.915023)
			(xy 344.838898 -285.876464) (xy 344.810984 -285.833457) (xy 344.789524 -285.786892) (xy 344.774964 -285.737731)
			(xy 344.767604 -285.68699) (xy 344.767154 -285.661354) (xy 344.53957 -285.661354) (xy 344.539072 -285.688003)
			(xy 344.531129 -285.740707) (xy 344.515419 -285.791637) (xy 344.492293 -285.839658) (xy 344.462269 -285.883695)
			(xy 344.426017 -285.922766) (xy 344.384346 -285.955997) (xy 344.338188 -285.982646) (xy 344.288574 -286.002118)
			(xy 344.236612 -286.013978) (xy 344.183462 -286.017962) (xy 344.130312 -286.013978) (xy 344.07835 -286.002118)
			(xy 344.028736 -285.982646) (xy 343.982578 -285.955997) (xy 343.940907 -285.922766) (xy 343.904655 -285.883695)
			(xy 343.874631 -285.839658) (xy 343.851505 -285.791637) (xy 343.835795 -285.740707) (xy 343.827852 -285.688003)
			(xy 343.827354 -285.661354) (xy 343.59977 -285.661354) (xy 343.599377 -285.684557) (xy 343.593332 -285.730567)
			(xy 343.581354 -285.7754) (xy 343.572846 -285.79699) (xy 343.563448 -285.820104) (xy 343.736168 -286.119062)
			(xy 343.760806 -286.122364) (xy 343.786141 -286.126233) (xy 343.835444 -286.140219) (xy 343.882234 -286.161125)
			(xy 343.925545 -286.188521) (xy 343.964484 -286.221841) (xy 343.998245 -286.260397) (xy 344.026133 -286.303393)
			(xy 344.047572 -286.349942) (xy 344.062119 -286.399082) (xy 344.069473 -286.4498) (xy 344.069924 -286.475424)
			(xy 344.069426 -286.502073) (xy 344.297752 -286.502073) (xy 344.297752 -286.448775) (xy 344.305695 -286.396071)
			(xy 344.321405 -286.345141) (xy 344.344531 -286.29712) (xy 344.374555 -286.253083) (xy 344.410807 -286.214012)
			(xy 344.452478 -286.180781) (xy 344.498636 -286.154132) (xy 344.54825 -286.13466) (xy 344.600212 -286.1228)
			(xy 344.653362 -286.118817) (xy 344.706512 -286.1228) (xy 344.758474 -286.13466) (xy 344.808088 -286.154132)
			(xy 344.854246 -286.180781) (xy 344.895917 -286.214012) (xy 344.932169 -286.253083) (xy 344.962193 -286.29712)
			(xy 344.985319 -286.345141) (xy 345.001029 -286.396071) (xy 345.008972 -286.448775) (xy 345.00947 -286.475424)
			(xy 345.008972 -286.502073) (xy 345.001029 -286.554777) (xy 344.985319 -286.605707) (xy 344.962193 -286.653728)
			(xy 344.932169 -286.697765) (xy 344.895917 -286.736836) (xy 344.854246 -286.770067) (xy 344.808088 -286.796716)
			(xy 344.758474 -286.816188) (xy 344.706512 -286.828048) (xy 344.653362 -286.832032) (xy 344.600212 -286.828048)
			(xy 344.54825 -286.816188) (xy 344.498636 -286.796716) (xy 344.452478 -286.770067) (xy 344.410807 -286.736836)
			(xy 344.374555 -286.697765) (xy 344.344531 -286.653728) (xy 344.321405 -286.605707) (xy 344.305695 -286.554777)
			(xy 344.297752 -286.502073) (xy 344.069426 -286.502073) (xy 344.061483 -286.554777) (xy 344.045773 -286.605707)
			(xy 344.022647 -286.653728) (xy 343.992623 -286.697765) (xy 343.956371 -286.736836) (xy 343.9147 -286.770067)
			(xy 343.868542 -286.796716) (xy 343.818928 -286.816188) (xy 343.766966 -286.828048) (xy 343.713816 -286.832032)
			(xy 343.660666 -286.828048) (xy 343.608704 -286.816188) (xy 343.55909 -286.796716) (xy 343.512932 -286.770067)
			(xy 343.471261 -286.736836) (xy 343.435009 -286.697765) (xy 343.404985 -286.653728) (xy 343.381859 -286.605707)
			(xy 343.366149 -286.554777) (xy 343.358206 -286.502073) (xy 343.357708 -286.475424) (xy 343.358084 -286.452179)
			(xy 343.364128 -286.406084) (xy 343.376116 -286.361166) (xy 343.384632 -286.339534) (xy 343.394284 -286.31642)
			(xy 343.221564 -286.017716) (xy 343.196926 -286.014414) (xy 343.171577 -286.010553) (xy 343.12224 -285.996602)
			(xy 343.075414 -285.975719) (xy 343.032066 -285.948337) (xy 342.993092 -285.915023) (xy 342.959298 -285.876464)
			(xy 342.931384 -285.833457) (xy 342.909924 -285.786892) (xy 342.895364 -285.737731) (xy 342.888004 -285.68699)
			(xy 342.887554 -285.661354) (xy 342.65997 -285.661354) (xy 342.659472 -285.688003) (xy 342.651529 -285.740707)
			(xy 342.635819 -285.791637) (xy 342.612693 -285.839658) (xy 342.582669 -285.883695) (xy 342.546417 -285.922766)
			(xy 342.504746 -285.955997) (xy 342.458588 -285.982646) (xy 342.408974 -286.002118) (xy 342.357012 -286.013978)
			(xy 342.303862 -286.017962) (xy 342.250712 -286.013978) (xy 342.19875 -286.002118) (xy 342.149136 -285.982646)
			(xy 342.102978 -285.955997) (xy 342.061307 -285.922766) (xy 342.025055 -285.883695) (xy 341.995031 -285.839658)
			(xy 341.971905 -285.791637) (xy 341.956195 -285.740707) (xy 341.948252 -285.688003) (xy 341.947754 -285.661354)
			(xy 341.72017 -285.661354) (xy 341.719777 -285.684557) (xy 341.713732 -285.730567) (xy 341.701754 -285.7754)
			(xy 341.693246 -285.79699) (xy 341.683848 -285.820104) (xy 341.856568 -286.119062) (xy 341.881206 -286.122364)
			(xy 341.906541 -286.126233) (xy 341.955844 -286.140219) (xy 342.002634 -286.161125) (xy 342.045945 -286.188521)
			(xy 342.084884 -286.221841) (xy 342.118645 -286.260397) (xy 342.146533 -286.303393) (xy 342.167972 -286.349942)
			(xy 342.182519 -286.399082) (xy 342.189873 -286.4498) (xy 342.190324 -286.475424) (xy 342.189826 -286.502073)
			(xy 342.418152 -286.502073) (xy 342.418152 -286.448775) (xy 342.426095 -286.396071) (xy 342.441805 -286.345141)
			(xy 342.464931 -286.29712) (xy 342.494955 -286.253083) (xy 342.531207 -286.214012) (xy 342.572878 -286.180781)
			(xy 342.619036 -286.154132) (xy 342.66865 -286.13466) (xy 342.720612 -286.1228) (xy 342.773762 -286.118817)
			(xy 342.826912 -286.1228) (xy 342.878874 -286.13466) (xy 342.928488 -286.154132) (xy 342.974646 -286.180781)
			(xy 343.016317 -286.214012) (xy 343.052569 -286.253083) (xy 343.082593 -286.29712) (xy 343.105719 -286.345141)
			(xy 343.121429 -286.396071) (xy 343.129372 -286.448775) (xy 343.12987 -286.475424) (xy 343.129372 -286.502073)
			(xy 343.121429 -286.554777) (xy 343.105719 -286.605707) (xy 343.082593 -286.653728) (xy 343.052569 -286.697765)
			(xy 343.016317 -286.736836) (xy 342.974646 -286.770067) (xy 342.928488 -286.796716) (xy 342.878874 -286.816188)
			(xy 342.826912 -286.828048) (xy 342.773762 -286.832032) (xy 342.720612 -286.828048) (xy 342.66865 -286.816188)
			(xy 342.619036 -286.796716) (xy 342.572878 -286.770067) (xy 342.531207 -286.736836) (xy 342.494955 -286.697765)
			(xy 342.464931 -286.653728) (xy 342.441805 -286.605707) (xy 342.426095 -286.554777) (xy 342.418152 -286.502073)
			(xy 342.189826 -286.502073) (xy 342.181883 -286.554777) (xy 342.166173 -286.605707) (xy 342.143047 -286.653728)
			(xy 342.113023 -286.697765) (xy 342.076771 -286.736836) (xy 342.0351 -286.770067) (xy 341.988942 -286.796716)
			(xy 341.939328 -286.816188) (xy 341.887366 -286.828048) (xy 341.834216 -286.832032) (xy 341.781066 -286.828048)
			(xy 341.729104 -286.816188) (xy 341.67949 -286.796716) (xy 341.633332 -286.770067) (xy 341.591661 -286.736836)
			(xy 341.555409 -286.697765) (xy 341.525385 -286.653728) (xy 341.502259 -286.605707) (xy 341.486549 -286.554777)
			(xy 341.478606 -286.502073) (xy 341.478108 -286.475424) (xy 341.478484 -286.452179) (xy 341.484528 -286.406084)
			(xy 341.496516 -286.361166) (xy 341.505032 -286.339534) (xy 341.514684 -286.31642) (xy 341.341964 -286.017716)
			(xy 341.317326 -286.014414) (xy 341.291977 -286.010553) (xy 341.24264 -285.996602) (xy 341.195814 -285.975719)
			(xy 341.152466 -285.948337) (xy 341.113492 -285.915023) (xy 341.079698 -285.876464) (xy 341.051784 -285.833457)
			(xy 341.030324 -285.786892) (xy 341.015764 -285.737731) (xy 341.008404 -285.68699) (xy 341.007954 -285.661354)
			(xy 340.78037 -285.661354) (xy 340.779872 -285.688003) (xy 340.771929 -285.740707) (xy 340.756219 -285.791637)
			(xy 340.733093 -285.839658) (xy 340.703069 -285.883695) (xy 340.666817 -285.922766) (xy 340.625146 -285.955997)
			(xy 340.578988 -285.982646) (xy 340.529374 -286.002118) (xy 340.477412 -286.013978) (xy 340.424262 -286.017962)
			(xy 340.371112 -286.013978) (xy 340.31915 -286.002118) (xy 340.269536 -285.982646) (xy 340.223378 -285.955997)
			(xy 340.181707 -285.922766) (xy 340.145455 -285.883695) (xy 340.115431 -285.839658) (xy 340.092305 -285.791637)
			(xy 340.076595 -285.740707) (xy 340.068652 -285.688003) (xy 340.068154 -285.661354) (xy 339.840824 -285.661354)
			(xy 339.840439 -285.684599) (xy 339.834399 -285.730694) (xy 339.822415 -285.775612) (xy 339.8139 -285.797244)
			(xy 339.804248 -285.820358) (xy 339.976968 -286.119062) (xy 340.001606 -286.122364) (xy 340.026941 -286.126233)
			(xy 340.076244 -286.140219) (xy 340.123034 -286.161125) (xy 340.166345 -286.188521) (xy 340.205284 -286.221841)
			(xy 340.239045 -286.260397) (xy 340.266933 -286.303393) (xy 340.288372 -286.349942) (xy 340.302919 -286.399082)
			(xy 340.310273 -286.4498) (xy 340.310724 -286.475424) (xy 340.310226 -286.502073) (xy 340.538806 -286.502073)
			(xy 340.538806 -286.448775) (xy 340.546749 -286.396071) (xy 340.562459 -286.345141) (xy 340.585585 -286.29712)
			(xy 340.615609 -286.253083) (xy 340.651861 -286.214012) (xy 340.693532 -286.180781) (xy 340.73969 -286.154132)
			(xy 340.789304 -286.13466) (xy 340.841266 -286.1228) (xy 340.894416 -286.118817) (xy 340.947566 -286.1228)
			(xy 340.999528 -286.13466) (xy 341.049142 -286.154132) (xy 341.0953 -286.180781) (xy 341.136971 -286.214012)
			(xy 341.173223 -286.253083) (xy 341.203247 -286.29712) (xy 341.226373 -286.345141) (xy 341.242083 -286.396071)
			(xy 341.250026 -286.448775) (xy 341.250524 -286.475424) (xy 341.250026 -286.502073) (xy 341.242083 -286.554777)
			(xy 341.226373 -286.605707) (xy 341.203247 -286.653728) (xy 341.173223 -286.697765) (xy 341.136971 -286.736836)
			(xy 341.0953 -286.770067) (xy 341.049142 -286.796716) (xy 340.999528 -286.816188) (xy 340.947566 -286.828048)
			(xy 340.894416 -286.832032) (xy 340.841266 -286.828048) (xy 340.789304 -286.816188) (xy 340.73969 -286.796716)
			(xy 340.693532 -286.770067) (xy 340.651861 -286.736836) (xy 340.615609 -286.697765) (xy 340.585585 -286.653728)
			(xy 340.562459 -286.605707) (xy 340.546749 -286.554777) (xy 340.538806 -286.502073) (xy 340.310226 -286.502073)
			(xy 340.302283 -286.554777) (xy 340.286573 -286.605707) (xy 340.263447 -286.653728) (xy 340.233423 -286.697765)
			(xy 340.197171 -286.736836) (xy 340.1555 -286.770067) (xy 340.109342 -286.796716) (xy 340.059728 -286.816188)
			(xy 340.007766 -286.828048) (xy 339.954616 -286.832032) (xy 339.901466 -286.828048) (xy 339.849504 -286.816188)
			(xy 339.79989 -286.796716) (xy 339.753732 -286.770067) (xy 339.712061 -286.736836) (xy 339.675809 -286.697765)
			(xy 339.645785 -286.653728) (xy 339.622659 -286.605707) (xy 339.606949 -286.554777) (xy 339.599006 -286.502073)
			(xy 339.598508 -286.475424) (xy 339.598884 -286.452179) (xy 339.604928 -286.406084) (xy 339.616916 -286.361166)
			(xy 339.625432 -286.339534) (xy 339.635084 -286.31642) (xy 339.462364 -286.017716) (xy 339.437726 -286.014414)
			(xy 339.412391 -286.010541) (xy 339.363087 -285.996559) (xy 339.316295 -285.975654) (xy 339.272983 -285.94826)
			(xy 339.234043 -285.91494) (xy 339.200281 -285.876384) (xy 339.172393 -285.833388) (xy 339.150955 -285.786838)
			(xy 339.13641 -285.737697) (xy 339.129057 -285.686978) (xy 339.128608 -285.661354) (xy 338.901024 -285.661354)
			(xy 338.900526 -285.688003) (xy 338.892583 -285.740707) (xy 338.876873 -285.791637) (xy 338.853747 -285.839658)
			(xy 338.823723 -285.883695) (xy 338.787471 -285.922766) (xy 338.7458 -285.955997) (xy 338.699642 -285.982646)
			(xy 338.650028 -286.002118) (xy 338.598066 -286.013978) (xy 338.544916 -286.017962) (xy 338.491766 -286.013978)
			(xy 338.439804 -286.002118) (xy 338.39019 -285.982646) (xy 338.344032 -285.955997) (xy 338.302361 -285.922766)
			(xy 338.266109 -285.883695) (xy 338.236085 -285.839658) (xy 338.212959 -285.791637) (xy 338.197249 -285.740707)
			(xy 338.189306 -285.688003) (xy 338.188808 -285.661354) (xy 337.96097 -285.661354) (xy 337.960588 -285.684599)
			(xy 337.954547 -285.730694) (xy 337.942561 -285.775612) (xy 337.934046 -285.797244) (xy 337.924394 -285.820358)
			(xy 338.097114 -286.119062) (xy 338.121752 -286.122364) (xy 338.147093 -286.126197) (xy 338.196396 -286.140189)
			(xy 338.243186 -286.161101) (xy 338.286497 -286.188502) (xy 338.325434 -286.221826) (xy 338.359194 -286.260386)
			(xy 338.387081 -286.303385) (xy 338.408519 -286.349936) (xy 338.423065 -286.399079) (xy 338.43042 -286.449799)
			(xy 338.43087 -286.475424) (xy 338.430372 -286.502073) (xy 338.658952 -286.502073) (xy 338.658952 -286.448775)
			(xy 338.666895 -286.396071) (xy 338.682605 -286.345141) (xy 338.705731 -286.29712) (xy 338.735755 -286.253083)
			(xy 338.772007 -286.214012) (xy 338.813678 -286.180781) (xy 338.859836 -286.154132) (xy 338.90945 -286.13466)
			(xy 338.961412 -286.1228) (xy 339.014562 -286.118817) (xy 339.067712 -286.1228) (xy 339.119674 -286.13466)
			(xy 339.169288 -286.154132) (xy 339.215446 -286.180781) (xy 339.257117 -286.214012) (xy 339.293369 -286.253083)
			(xy 339.323393 -286.29712) (xy 339.346519 -286.345141) (xy 339.362229 -286.396071) (xy 339.370172 -286.448775)
			(xy 339.37067 -286.475424) (xy 339.370172 -286.502073) (xy 339.362229 -286.554777) (xy 339.346519 -286.605707)
			(xy 339.323393 -286.653728) (xy 339.293369 -286.697765) (xy 339.257117 -286.736836) (xy 339.215446 -286.770067)
			(xy 339.169288 -286.796716) (xy 339.119674 -286.816188) (xy 339.067712 -286.828048) (xy 339.014562 -286.832032)
			(xy 338.961412 -286.828048) (xy 338.90945 -286.816188) (xy 338.859836 -286.796716) (xy 338.813678 -286.770067)
			(xy 338.772007 -286.736836) (xy 338.735755 -286.697765) (xy 338.705731 -286.653728) (xy 338.682605 -286.605707)
			(xy 338.666895 -286.554777) (xy 338.658952 -286.502073) (xy 338.430372 -286.502073) (xy 338.422429 -286.554777)
			(xy 338.406719 -286.605707) (xy 338.383593 -286.653728) (xy 338.353569 -286.697765) (xy 338.317317 -286.736836)
			(xy 338.275646 -286.770067) (xy 338.229488 -286.796716) (xy 338.179874 -286.816188) (xy 338.127912 -286.828048)
			(xy 338.074762 -286.832032) (xy 338.021612 -286.828048) (xy 337.96965 -286.816188) (xy 337.920036 -286.796716)
			(xy 337.873878 -286.770067) (xy 337.832207 -286.736836) (xy 337.795955 -286.697765) (xy 337.765931 -286.653728)
			(xy 337.742805 -286.605707) (xy 337.727095 -286.554777) (xy 337.719152 -286.502073) (xy 337.718654 -286.475424)
			(xy 337.719034 -286.452179) (xy 337.725076 -286.406084) (xy 337.737062 -286.361166) (xy 337.745578 -286.339534)
			(xy 337.75523 -286.31642) (xy 337.58251 -286.017716) (xy 337.557872 -286.014414) (xy 337.53253 -286.010584)
			(xy 337.483225 -285.996594) (xy 337.436434 -285.975683) (xy 337.393122 -285.948282) (xy 337.354184 -285.914958)
			(xy 337.320423 -285.876398) (xy 337.292537 -285.833398) (xy 337.2711 -285.786845) (xy 337.256555 -285.737701)
			(xy 337.249203 -285.68698) (xy 337.248754 -285.661354) (xy 337.02117 -285.661354) (xy 337.020672 -285.688003)
			(xy 337.012729 -285.740707) (xy 336.997019 -285.791637) (xy 336.973893 -285.839658) (xy 336.943869 -285.883695)
			(xy 336.907617 -285.922766) (xy 336.865946 -285.955997) (xy 336.819788 -285.982646) (xy 336.770174 -286.002118)
			(xy 336.718212 -286.013978) (xy 336.665062 -286.017962) (xy 336.611912 -286.013978) (xy 336.55995 -286.002118)
			(xy 336.510336 -285.982646) (xy 336.464178 -285.955997) (xy 336.422507 -285.922766) (xy 336.386255 -285.883695)
			(xy 336.356231 -285.839658) (xy 336.333105 -285.791637) (xy 336.317395 -285.740707) (xy 336.309452 -285.688003)
			(xy 336.080872 -285.688003) (xy 336.072929 -285.740707) (xy 336.057219 -285.791637) (xy 336.034093 -285.839658)
			(xy 336.004069 -285.883695) (xy 335.967817 -285.922766) (xy 335.926146 -285.955997) (xy 335.879988 -285.982646)
			(xy 335.830374 -286.002118) (xy 335.778412 -286.013978) (xy 335.725262 -286.017962) (xy 335.672112 -286.013978)
			(xy 335.62015 -286.002118) (xy 335.570536 -285.982646) (xy 335.524378 -285.955997) (xy 335.482707 -285.922766)
			(xy 335.446455 -285.883695) (xy 335.416431 -285.839658) (xy 335.393305 -285.791637) (xy 335.377595 -285.740707)
			(xy 335.369652 -285.688003) (xy 335.369154 -285.661354) (xy 335.14157 -285.661354) (xy 335.141072 -285.688003)
			(xy 335.133129 -285.740707) (xy 335.117419 -285.791637) (xy 335.094293 -285.839658) (xy 335.064269 -285.883695)
			(xy 335.028017 -285.922766) (xy 334.986346 -285.955997) (xy 334.940188 -285.982646) (xy 334.890574 -286.002118)
			(xy 334.838612 -286.013978) (xy 334.785462 -286.017962) (xy 334.732312 -286.013978) (xy 334.68035 -286.002118)
			(xy 334.630736 -285.982646) (xy 334.584578 -285.955997) (xy 334.542907 -285.922766) (xy 334.506655 -285.883695)
			(xy 334.476631 -285.839658) (xy 334.453505 -285.791637) (xy 334.437795 -285.740707) (xy 334.429852 -285.688003)
			(xy 334.200384 -285.688003) (xy 334.198394 -285.714564) (xy 334.18653 -285.76654) (xy 334.167051 -285.816167)
			(xy 334.140393 -285.862336) (xy 334.107151 -285.904016) (xy 334.068068 -285.940276) (xy 334.024017 -285.970305)
			(xy 333.975982 -285.993433) (xy 333.925037 -286.009143) (xy 333.872318 -286.017083) (xy 333.845662 -286.017462)
			(xy 333.816694 -286.016893) (xy 333.759522 -286.007518) (xy 333.704618 -285.98902) (xy 333.653428 -285.961887)
			(xy 333.630016 -285.944818) (xy 333.618494 -285.936632) (xy 333.592182 -285.926343) (xy 333.564058 -285.923657)
			(xy 333.536274 -285.928777) (xy 333.510955 -285.941313) (xy 333.490039 -285.960306) (xy 333.475126 -285.984301)
			(xy 333.467357 -286.011464) (xy 333.466948 -286.02559) (xy 333.466948 -286.129476) (xy 333.499968 -286.141668)
			(xy 333.525141 -286.15157) (xy 333.572401 -286.177883) (xy 333.615137 -286.211041) (xy 333.652367 -286.250281)
			(xy 333.683234 -286.2947) (xy 333.707028 -286.343277) (xy 333.7232 -286.394894) (xy 333.73138 -286.448363)
			(xy 333.731379 -286.475424) (xy 333.959454 -286.475424) (xy 333.959952 -286.448775) (xy 333.967895 -286.396071)
			(xy 333.983605 -286.345141) (xy 334.006731 -286.29712) (xy 334.036755 -286.253083) (xy 334.073007 -286.214012)
			(xy 334.114678 -286.180781) (xy 334.160836 -286.154132) (xy 334.21045 -286.13466) (xy 334.262412 -286.1228)
			(xy 334.315562 -286.118817) (xy 334.368712 -286.1228) (xy 334.420674 -286.13466) (xy 334.470288 -286.154132)
			(xy 334.516446 -286.180781) (xy 334.558117 -286.214012) (xy 334.594369 -286.253083) (xy 334.624393 -286.29712)
			(xy 334.647519 -286.345141) (xy 334.663229 -286.396071) (xy 334.671172 -286.448775) (xy 334.67167 -286.4754)
			(xy 334.898817 -286.4754) (xy 334.902799 -286.422258) (xy 334.914657 -286.370302) (xy 334.934125 -286.320694)
			(xy 334.960769 -286.274542) (xy 334.993994 -286.232875) (xy 335.033057 -286.196626) (xy 335.077087 -286.166603)
			(xy 335.125099 -286.143477) (xy 335.176021 -286.127765) (xy 335.228716 -286.119817) (xy 335.255362 -286.119316)
			(xy 335.280377 -286.119704) (xy 335.329917 -286.126698) (xy 335.377991 -286.140552) (xy 335.423655 -286.160995)
			(xy 335.466009 -286.187625) (xy 335.504222 -286.219918) (xy 335.537542 -286.257239) (xy 335.55178 -286.277812)
			(xy 335.898744 -286.277812) (xy 335.912992 -286.257249) (xy 335.946319 -286.219941) (xy 335.984534 -286.187658)
			(xy 336.026887 -286.161036) (xy 336.072547 -286.140596) (xy 336.120615 -286.12674) (xy 336.170149 -286.119741)
			(xy 336.195162 -286.119316) (xy 336.221817 -286.119739) (xy 336.274532 -286.127679) (xy 336.325474 -286.143388)
			(xy 336.373506 -286.166514) (xy 336.417554 -286.196542) (xy 336.456635 -286.232799) (xy 336.489875 -286.274477)
			(xy 336.516531 -286.320643) (xy 336.536009 -286.370267) (xy 336.547872 -286.42224) (xy 336.551856 -286.4754)
			(xy 336.547872 -286.52856) (xy 336.536009 -286.580533) (xy 336.516531 -286.630157) (xy 336.489875 -286.676323)
			(xy 336.456635 -286.718001) (xy 336.417554 -286.754258) (xy 336.373506 -286.784286) (xy 336.325474 -286.807412)
			(xy 336.274532 -286.823121) (xy 336.221817 -286.831061) (xy 336.195162 -286.831532) (xy 336.170146 -286.831148)
			(xy 336.120605 -286.824157) (xy 336.07253 -286.810304) (xy 336.026866 -286.78986) (xy 335.984511 -286.763229)
			(xy 335.946299 -286.730934) (xy 335.91298 -286.69361) (xy 335.898744 -286.673036) (xy 335.55178 -286.673036)
			(xy 335.537532 -286.693598) (xy 335.504204 -286.730904) (xy 335.465988 -286.763185) (xy 335.423634 -286.789807)
			(xy 335.377975 -286.810247) (xy 335.329907 -286.824104) (xy 335.280375 -286.831106) (xy 335.255362 -286.831532)
			(xy 335.228716 -286.830983) (xy 335.176021 -286.823035) (xy 335.125099 -286.807323) (xy 335.077087 -286.784197)
			(xy 335.033057 -286.754174) (xy 334.993994 -286.717925) (xy 334.960769 -286.676258) (xy 334.934125 -286.630106)
			(xy 334.914657 -286.580498) (xy 334.902799 -286.528542) (xy 334.898817 -286.4754) (xy 334.67167 -286.4754)
			(xy 334.67167 -286.475424) (xy 334.671299 -286.498628) (xy 334.665246 -286.544638) (xy 334.653258 -286.589471)
			(xy 334.644746 -286.61106) (xy 334.635348 -286.634174) (xy 334.807814 -286.932878) (xy 334.832706 -286.93618)
			(xy 334.85803 -286.940046) (xy 334.907302 -286.954063) (xy 334.954058 -286.974993) (xy 334.997334 -287.002403)
			(xy 335.036238 -287.035729) (xy 335.069968 -287.074284) (xy 335.097829 -287.117272) (xy 335.119245 -287.163807)
			(xy 335.133776 -287.212929) (xy 335.141122 -287.263627) (xy 335.14157 -287.28924) (xy 335.141072 -287.315889)
			(xy 335.369652 -287.315889) (xy 335.369652 -287.262591) (xy 335.377595 -287.209887) (xy 335.393305 -287.158957)
			(xy 335.416431 -287.110936) (xy 335.446455 -287.066899) (xy 335.482707 -287.027828) (xy 335.524378 -286.994597)
			(xy 335.570536 -286.967948) (xy 335.62015 -286.948476) (xy 335.672112 -286.936616) (xy 335.725262 -286.932633)
			(xy 335.778412 -286.936616) (xy 335.830374 -286.948476) (xy 335.879988 -286.967948) (xy 335.926146 -286.994597)
			(xy 335.967817 -287.027828) (xy 336.004069 -287.066899) (xy 336.034093 -287.110936) (xy 336.057219 -287.158957)
			(xy 336.072929 -287.209887) (xy 336.080872 -287.262591) (xy 336.08137 -287.28924) (xy 336.080872 -287.315889)
			(xy 336.309452 -287.315889) (xy 336.309452 -287.262591) (xy 336.317395 -287.209887) (xy 336.333105 -287.158957)
			(xy 336.356231 -287.110936) (xy 336.386255 -287.066899) (xy 336.422507 -287.027828) (xy 336.464178 -286.994597)
			(xy 336.510336 -286.967948) (xy 336.55995 -286.948476) (xy 336.611912 -286.936616) (xy 336.665062 -286.932633)
			(xy 336.718212 -286.936616) (xy 336.770174 -286.948476) (xy 336.819788 -286.967948) (xy 336.865946 -286.994597)
			(xy 336.907617 -287.027828) (xy 336.943869 -287.066899) (xy 336.973893 -287.110936) (xy 336.997019 -287.158957)
			(xy 337.012729 -287.209887) (xy 337.020672 -287.262591) (xy 337.02117 -287.28924) (xy 337.020672 -287.315889)
			(xy 337.249252 -287.315889) (xy 337.249252 -287.262591) (xy 337.257195 -287.209887) (xy 337.272905 -287.158957)
			(xy 337.296031 -287.110936) (xy 337.326055 -287.066899) (xy 337.362307 -287.027828) (xy 337.403978 -286.994597)
			(xy 337.450136 -286.967948) (xy 337.49975 -286.948476) (xy 337.551712 -286.936616) (xy 337.604862 -286.932633)
			(xy 337.658012 -286.936616) (xy 337.709974 -286.948476) (xy 337.759588 -286.967948) (xy 337.805746 -286.994597)
			(xy 337.847417 -287.027828) (xy 337.883669 -287.066899) (xy 337.913693 -287.110936) (xy 337.936819 -287.158957)
			(xy 337.952529 -287.209887) (xy 337.960472 -287.262591) (xy 337.96097 -287.28924) (xy 337.960472 -287.315889)
			(xy 338.189306 -287.315889) (xy 338.189306 -287.262591) (xy 338.197249 -287.209887) (xy 338.212959 -287.158957)
			(xy 338.236085 -287.110936) (xy 338.266109 -287.066899) (xy 338.302361 -287.027828) (xy 338.344032 -286.994597)
			(xy 338.39019 -286.967948) (xy 338.439804 -286.948476) (xy 338.491766 -286.936616) (xy 338.544916 -286.932633)
			(xy 338.598066 -286.936616) (xy 338.650028 -286.948476) (xy 338.699642 -286.967948) (xy 338.7458 -286.994597)
			(xy 338.787471 -287.027828) (xy 338.823723 -287.066899) (xy 338.853747 -287.110936) (xy 338.876873 -287.158957)
			(xy 338.892583 -287.209887) (xy 338.900526 -287.262591) (xy 338.901024 -287.28924) (xy 338.900526 -287.315889)
			(xy 339.129106 -287.315889) (xy 339.129106 -287.262591) (xy 339.137049 -287.209887) (xy 339.152759 -287.158957)
			(xy 339.175885 -287.110936) (xy 339.205909 -287.066899) (xy 339.242161 -287.027828) (xy 339.283832 -286.994597)
			(xy 339.32999 -286.967948) (xy 339.379604 -286.948476) (xy 339.431566 -286.936616) (xy 339.484716 -286.932633)
			(xy 339.537866 -286.936616) (xy 339.589828 -286.948476) (xy 339.639442 -286.967948) (xy 339.6856 -286.994597)
			(xy 339.727271 -287.027828) (xy 339.763523 -287.066899) (xy 339.793547 -287.110936) (xy 339.816673 -287.158957)
			(xy 339.832383 -287.209887) (xy 339.840326 -287.262591) (xy 339.840824 -287.28924) (xy 339.840326 -287.315889)
			(xy 340.068906 -287.315889) (xy 340.068906 -287.262591) (xy 340.076849 -287.209887) (xy 340.092559 -287.158957)
			(xy 340.115685 -287.110936) (xy 340.145709 -287.066899) (xy 340.181961 -287.027828) (xy 340.223632 -286.994597)
			(xy 340.26979 -286.967948) (xy 340.319404 -286.948476) (xy 340.371366 -286.936616) (xy 340.424516 -286.932633)
			(xy 340.477666 -286.936616) (xy 340.529628 -286.948476) (xy 340.579242 -286.967948) (xy 340.6254 -286.994597)
			(xy 340.667071 -287.027828) (xy 340.703323 -287.066899) (xy 340.733347 -287.110936) (xy 340.756473 -287.158957)
			(xy 340.772183 -287.209887) (xy 340.780126 -287.262591) (xy 340.780624 -287.28924) (xy 340.780126 -287.315889)
			(xy 341.008452 -287.315889) (xy 341.008452 -287.262591) (xy 341.016395 -287.209887) (xy 341.032105 -287.158957)
			(xy 341.055231 -287.110936) (xy 341.085255 -287.066899) (xy 341.121507 -287.027828) (xy 341.163178 -286.994597)
			(xy 341.209336 -286.967948) (xy 341.25895 -286.948476) (xy 341.310912 -286.936616) (xy 341.364062 -286.932633)
			(xy 341.417212 -286.936616) (xy 341.469174 -286.948476) (xy 341.518788 -286.967948) (xy 341.564946 -286.994597)
			(xy 341.606617 -287.027828) (xy 341.642869 -287.066899) (xy 341.672893 -287.110936) (xy 341.696019 -287.158957)
			(xy 341.711729 -287.209887) (xy 341.719672 -287.262591) (xy 341.72017 -287.28924) (xy 341.719672 -287.315889)
			(xy 341.948252 -287.315889) (xy 341.948252 -287.262591) (xy 341.956195 -287.209887) (xy 341.971905 -287.158957)
			(xy 341.995031 -287.110936) (xy 342.025055 -287.066899) (xy 342.061307 -287.027828) (xy 342.102978 -286.994597)
			(xy 342.149136 -286.967948) (xy 342.19875 -286.948476) (xy 342.250712 -286.936616) (xy 342.303862 -286.932633)
			(xy 342.357012 -286.936616) (xy 342.408974 -286.948476) (xy 342.458588 -286.967948) (xy 342.504746 -286.994597)
			(xy 342.546417 -287.027828) (xy 342.582669 -287.066899) (xy 342.612693 -287.110936) (xy 342.635819 -287.158957)
			(xy 342.651529 -287.209887) (xy 342.659472 -287.262591) (xy 342.65997 -287.28924) (xy 342.659472 -287.315889)
			(xy 342.888052 -287.315889) (xy 342.888052 -287.262591) (xy 342.895995 -287.209887) (xy 342.911705 -287.158957)
			(xy 342.934831 -287.110936) (xy 342.964855 -287.066899) (xy 343.001107 -287.027828) (xy 343.042778 -286.994597)
			(xy 343.088936 -286.967948) (xy 343.13855 -286.948476) (xy 343.190512 -286.936616) (xy 343.243662 -286.932633)
			(xy 343.296812 -286.936616) (xy 343.348774 -286.948476) (xy 343.398388 -286.967948) (xy 343.444546 -286.994597)
			(xy 343.486217 -287.027828) (xy 343.522469 -287.066899) (xy 343.552493 -287.110936) (xy 343.575619 -287.158957)
			(xy 343.591329 -287.209887) (xy 343.599272 -287.262591) (xy 343.59977 -287.28924) (xy 343.599272 -287.315889)
			(xy 343.827852 -287.315889) (xy 343.827852 -287.262591) (xy 343.835795 -287.209887) (xy 343.851505 -287.158957)
			(xy 343.874631 -287.110936) (xy 343.904655 -287.066899) (xy 343.940907 -287.027828) (xy 343.982578 -286.994597)
			(xy 344.028736 -286.967948) (xy 344.07835 -286.948476) (xy 344.130312 -286.936616) (xy 344.183462 -286.932633)
			(xy 344.236612 -286.936616) (xy 344.288574 -286.948476) (xy 344.338188 -286.967948) (xy 344.384346 -286.994597)
			(xy 344.426017 -287.027828) (xy 344.462269 -287.066899) (xy 344.492293 -287.110936) (xy 344.515419 -287.158957)
			(xy 344.531129 -287.209887) (xy 344.539072 -287.262591) (xy 344.53957 -287.28924) (xy 344.539072 -287.315889)
			(xy 344.767652 -287.315889) (xy 344.767652 -287.262591) (xy 344.775595 -287.209887) (xy 344.791305 -287.158957)
			(xy 344.814431 -287.110936) (xy 344.844455 -287.066899) (xy 344.880707 -287.027828) (xy 344.922378 -286.994597)
			(xy 344.968536 -286.967948) (xy 345.01815 -286.948476) (xy 345.070112 -286.936616) (xy 345.123262 -286.932633)
			(xy 345.176412 -286.936616) (xy 345.228374 -286.948476) (xy 345.277988 -286.967948) (xy 345.324146 -286.994597)
			(xy 345.365817 -287.027828) (xy 345.402069 -287.066899) (xy 345.432093 -287.110936) (xy 345.455219 -287.158957)
			(xy 345.470929 -287.209887) (xy 345.478872 -287.262591) (xy 345.47937 -287.28924) (xy 345.478872 -287.315889)
			(xy 345.707452 -287.315889) (xy 345.707452 -287.262591) (xy 345.715395 -287.209887) (xy 345.731105 -287.158957)
			(xy 345.754231 -287.110936) (xy 345.784255 -287.066899) (xy 345.820507 -287.027828) (xy 345.862178 -286.994597)
			(xy 345.908336 -286.967948) (xy 345.95795 -286.948476) (xy 346.009912 -286.936616) (xy 346.063062 -286.932633)
			(xy 346.116212 -286.936616) (xy 346.168174 -286.948476) (xy 346.217788 -286.967948) (xy 346.263946 -286.994597)
			(xy 346.305617 -287.027828) (xy 346.341869 -287.066899) (xy 346.371893 -287.110936) (xy 346.395019 -287.158957)
			(xy 346.410729 -287.209887) (xy 346.418672 -287.262591) (xy 346.41917 -287.28924) (xy 346.418672 -287.315889)
			(xy 346.647252 -287.315889) (xy 346.647252 -287.262591) (xy 346.655195 -287.209887) (xy 346.670905 -287.158957)
			(xy 346.694031 -287.110936) (xy 346.724055 -287.066899) (xy 346.760307 -287.027828) (xy 346.801978 -286.994597)
			(xy 346.848136 -286.967948) (xy 346.89775 -286.948476) (xy 346.949712 -286.936616) (xy 347.002862 -286.932633)
			(xy 347.056012 -286.936616) (xy 347.107974 -286.948476) (xy 347.157588 -286.967948) (xy 347.203746 -286.994597)
			(xy 347.245417 -287.027828) (xy 347.281669 -287.066899) (xy 347.311693 -287.110936) (xy 347.334819 -287.158957)
			(xy 347.350529 -287.209887) (xy 347.358472 -287.262591) (xy 347.35897 -287.28924) (xy 347.358472 -287.315889)
			(xy 347.587052 -287.315889) (xy 347.587052 -287.262591) (xy 347.594995 -287.209887) (xy 347.610705 -287.158957)
			(xy 347.633831 -287.110936) (xy 347.663855 -287.066899) (xy 347.700107 -287.027828) (xy 347.741778 -286.994597)
			(xy 347.787936 -286.967948) (xy 347.83755 -286.948476) (xy 347.889512 -286.936616) (xy 347.942662 -286.932633)
			(xy 347.995812 -286.936616) (xy 348.047774 -286.948476) (xy 348.097388 -286.967948) (xy 348.143546 -286.994597)
			(xy 348.185217 -287.027828) (xy 348.221469 -287.066899) (xy 348.251493 -287.110936) (xy 348.274619 -287.158957)
			(xy 348.290329 -287.209887) (xy 348.298272 -287.262591) (xy 348.29877 -287.28924) (xy 348.298272 -287.315889)
			(xy 348.526852 -287.315889) (xy 348.526852 -287.262591) (xy 348.534795 -287.209887) (xy 348.550505 -287.158957)
			(xy 348.573631 -287.110936) (xy 348.603655 -287.066899) (xy 348.639907 -287.027828) (xy 348.681578 -286.994597)
			(xy 348.727736 -286.967948) (xy 348.77735 -286.948476) (xy 348.829312 -286.936616) (xy 348.882462 -286.932633)
			(xy 348.935612 -286.936616) (xy 348.987574 -286.948476) (xy 349.037188 -286.967948) (xy 349.083346 -286.994597)
			(xy 349.125017 -287.027828) (xy 349.161269 -287.066899) (xy 349.191293 -287.110936) (xy 349.214419 -287.158957)
			(xy 349.230129 -287.209887) (xy 349.238072 -287.262591) (xy 349.23857 -287.28924) (xy 349.238072 -287.315889)
			(xy 349.466652 -287.315889) (xy 349.466652 -287.262591) (xy 349.474595 -287.209887) (xy 349.490305 -287.158957)
			(xy 349.513431 -287.110936) (xy 349.543455 -287.066899) (xy 349.579707 -287.027828) (xy 349.621378 -286.994597)
			(xy 349.667536 -286.967948) (xy 349.71715 -286.948476) (xy 349.769112 -286.936616) (xy 349.822262 -286.932633)
			(xy 349.875412 -286.936616) (xy 349.927374 -286.948476) (xy 349.976988 -286.967948) (xy 350.023146 -286.994597)
			(xy 350.064817 -287.027828) (xy 350.101069 -287.066899) (xy 350.131093 -287.110936) (xy 350.154219 -287.158957)
			(xy 350.169929 -287.209887) (xy 350.177872 -287.262591) (xy 350.17837 -287.28924) (xy 350.177872 -287.315889)
			(xy 350.406452 -287.315889) (xy 350.406452 -287.262591) (xy 350.414395 -287.209887) (xy 350.430105 -287.158957)
			(xy 350.453231 -287.110936) (xy 350.483255 -287.066899) (xy 350.519507 -287.027828) (xy 350.561178 -286.994597)
			(xy 350.607336 -286.967948) (xy 350.65695 -286.948476) (xy 350.708912 -286.936616) (xy 350.762062 -286.932633)
			(xy 350.815212 -286.936616) (xy 350.867174 -286.948476) (xy 350.916788 -286.967948) (xy 350.962946 -286.994597)
			(xy 351.004617 -287.027828) (xy 351.040869 -287.066899) (xy 351.070893 -287.110936) (xy 351.094019 -287.158957)
			(xy 351.109729 -287.209887) (xy 351.117672 -287.262591) (xy 351.11817 -287.28924) (xy 351.117672 -287.315889)
			(xy 351.109729 -287.368593) (xy 351.094019 -287.419523) (xy 351.070893 -287.467544) (xy 351.040869 -287.511581)
			(xy 351.004617 -287.550652) (xy 350.962946 -287.583883) (xy 350.916788 -287.610532) (xy 350.867174 -287.630004)
			(xy 350.815212 -287.641864) (xy 350.762062 -287.645848) (xy 350.708912 -287.641864) (xy 350.65695 -287.630004)
			(xy 350.607336 -287.610532) (xy 350.561178 -287.583883) (xy 350.519507 -287.550652) (xy 350.483255 -287.511581)
			(xy 350.453231 -287.467544) (xy 350.430105 -287.419523) (xy 350.414395 -287.368593) (xy 350.406452 -287.315889)
			(xy 350.177872 -287.315889) (xy 350.169929 -287.368593) (xy 350.154219 -287.419523) (xy 350.131093 -287.467544)
			(xy 350.101069 -287.511581) (xy 350.064817 -287.550652) (xy 350.023146 -287.583883) (xy 349.976988 -287.610532)
			(xy 349.927374 -287.630004) (xy 349.875412 -287.641864) (xy 349.822262 -287.645848) (xy 349.769112 -287.641864)
			(xy 349.71715 -287.630004) (xy 349.667536 -287.610532) (xy 349.621378 -287.583883) (xy 349.579707 -287.550652)
			(xy 349.543455 -287.511581) (xy 349.513431 -287.467544) (xy 349.490305 -287.419523) (xy 349.474595 -287.368593)
			(xy 349.466652 -287.315889) (xy 349.238072 -287.315889) (xy 349.230129 -287.368593) (xy 349.214419 -287.419523)
			(xy 349.191293 -287.467544) (xy 349.161269 -287.511581) (xy 349.125017 -287.550652) (xy 349.083346 -287.583883)
			(xy 349.037188 -287.610532) (xy 348.987574 -287.630004) (xy 348.935612 -287.641864) (xy 348.882462 -287.645848)
			(xy 348.829312 -287.641864) (xy 348.77735 -287.630004) (xy 348.727736 -287.610532) (xy 348.681578 -287.583883)
			(xy 348.639907 -287.550652) (xy 348.603655 -287.511581) (xy 348.573631 -287.467544) (xy 348.550505 -287.419523)
			(xy 348.534795 -287.368593) (xy 348.526852 -287.315889) (xy 348.298272 -287.315889) (xy 348.290329 -287.368593)
			(xy 348.274619 -287.419523) (xy 348.251493 -287.467544) (xy 348.221469 -287.511581) (xy 348.185217 -287.550652)
			(xy 348.143546 -287.583883) (xy 348.097388 -287.610532) (xy 348.047774 -287.630004) (xy 347.995812 -287.641864)
			(xy 347.942662 -287.645848) (xy 347.889512 -287.641864) (xy 347.83755 -287.630004) (xy 347.787936 -287.610532)
			(xy 347.741778 -287.583883) (xy 347.700107 -287.550652) (xy 347.663855 -287.511581) (xy 347.633831 -287.467544)
			(xy 347.610705 -287.419523) (xy 347.594995 -287.368593) (xy 347.587052 -287.315889) (xy 347.358472 -287.315889)
			(xy 347.350529 -287.368593) (xy 347.334819 -287.419523) (xy 347.311693 -287.467544) (xy 347.281669 -287.511581)
			(xy 347.245417 -287.550652) (xy 347.203746 -287.583883) (xy 347.157588 -287.610532) (xy 347.107974 -287.630004)
			(xy 347.056012 -287.641864) (xy 347.002862 -287.645848) (xy 346.949712 -287.641864) (xy 346.89775 -287.630004)
			(xy 346.848136 -287.610532) (xy 346.801978 -287.583883) (xy 346.760307 -287.550652) (xy 346.724055 -287.511581)
			(xy 346.694031 -287.467544) (xy 346.670905 -287.419523) (xy 346.655195 -287.368593) (xy 346.647252 -287.315889)
			(xy 346.418672 -287.315889) (xy 346.410729 -287.368593) (xy 346.395019 -287.419523) (xy 346.371893 -287.467544)
			(xy 346.341869 -287.511581) (xy 346.305617 -287.550652) (xy 346.263946 -287.583883) (xy 346.217788 -287.610532)
			(xy 346.168174 -287.630004) (xy 346.116212 -287.641864) (xy 346.063062 -287.645848) (xy 346.009912 -287.641864)
			(xy 345.95795 -287.630004) (xy 345.908336 -287.610532) (xy 345.862178 -287.583883) (xy 345.820507 -287.550652)
			(xy 345.784255 -287.511581) (xy 345.754231 -287.467544) (xy 345.731105 -287.419523) (xy 345.715395 -287.368593)
			(xy 345.707452 -287.315889) (xy 345.478872 -287.315889) (xy 345.470929 -287.368593) (xy 345.455219 -287.419523)
			(xy 345.432093 -287.467544) (xy 345.402069 -287.511581) (xy 345.365817 -287.550652) (xy 345.324146 -287.583883)
			(xy 345.277988 -287.610532) (xy 345.228374 -287.630004) (xy 345.176412 -287.641864) (xy 345.123262 -287.645848)
			(xy 345.070112 -287.641864) (xy 345.01815 -287.630004) (xy 344.968536 -287.610532) (xy 344.922378 -287.583883)
			(xy 344.880707 -287.550652) (xy 344.844455 -287.511581) (xy 344.814431 -287.467544) (xy 344.791305 -287.419523)
			(xy 344.775595 -287.368593) (xy 344.767652 -287.315889) (xy 344.539072 -287.315889) (xy 344.531129 -287.368593)
			(xy 344.515419 -287.419523) (xy 344.492293 -287.467544) (xy 344.462269 -287.511581) (xy 344.426017 -287.550652)
			(xy 344.384346 -287.583883) (xy 344.338188 -287.610532) (xy 344.288574 -287.630004) (xy 344.236612 -287.641864)
			(xy 344.183462 -287.645848) (xy 344.130312 -287.641864) (xy 344.07835 -287.630004) (xy 344.028736 -287.610532)
			(xy 343.982578 -287.583883) (xy 343.940907 -287.550652) (xy 343.904655 -287.511581) (xy 343.874631 -287.467544)
			(xy 343.851505 -287.419523) (xy 343.835795 -287.368593) (xy 343.827852 -287.315889) (xy 343.599272 -287.315889)
			(xy 343.591329 -287.368593) (xy 343.575619 -287.419523) (xy 343.552493 -287.467544) (xy 343.522469 -287.511581)
			(xy 343.486217 -287.550652) (xy 343.444546 -287.583883) (xy 343.398388 -287.610532) (xy 343.348774 -287.630004)
			(xy 343.296812 -287.641864) (xy 343.243662 -287.645848) (xy 343.190512 -287.641864) (xy 343.13855 -287.630004)
			(xy 343.088936 -287.610532) (xy 343.042778 -287.583883) (xy 343.001107 -287.550652) (xy 342.964855 -287.511581)
			(xy 342.934831 -287.467544) (xy 342.911705 -287.419523) (xy 342.895995 -287.368593) (xy 342.888052 -287.315889)
			(xy 342.659472 -287.315889) (xy 342.651529 -287.368593) (xy 342.635819 -287.419523) (xy 342.612693 -287.467544)
			(xy 342.582669 -287.511581) (xy 342.546417 -287.550652) (xy 342.504746 -287.583883) (xy 342.458588 -287.610532)
			(xy 342.408974 -287.630004) (xy 342.357012 -287.641864) (xy 342.303862 -287.645848) (xy 342.250712 -287.641864)
			(xy 342.19875 -287.630004) (xy 342.149136 -287.610532) (xy 342.102978 -287.583883) (xy 342.061307 -287.550652)
			(xy 342.025055 -287.511581) (xy 341.995031 -287.467544) (xy 341.971905 -287.419523) (xy 341.956195 -287.368593)
			(xy 341.948252 -287.315889) (xy 341.719672 -287.315889) (xy 341.711729 -287.368593) (xy 341.696019 -287.419523)
			(xy 341.672893 -287.467544) (xy 341.642869 -287.511581) (xy 341.606617 -287.550652) (xy 341.564946 -287.583883)
			(xy 341.518788 -287.610532) (xy 341.469174 -287.630004) (xy 341.417212 -287.641864) (xy 341.364062 -287.645848)
			(xy 341.310912 -287.641864) (xy 341.25895 -287.630004) (xy 341.209336 -287.610532) (xy 341.163178 -287.583883)
			(xy 341.121507 -287.550652) (xy 341.085255 -287.511581) (xy 341.055231 -287.467544) (xy 341.032105 -287.419523)
			(xy 341.016395 -287.368593) (xy 341.008452 -287.315889) (xy 340.780126 -287.315889) (xy 340.772183 -287.368593)
			(xy 340.756473 -287.419523) (xy 340.733347 -287.467544) (xy 340.703323 -287.511581) (xy 340.667071 -287.550652)
			(xy 340.6254 -287.583883) (xy 340.579242 -287.610532) (xy 340.529628 -287.630004) (xy 340.477666 -287.641864)
			(xy 340.424516 -287.645848) (xy 340.371366 -287.641864) (xy 340.319404 -287.630004) (xy 340.26979 -287.610532)
			(xy 340.223632 -287.583883) (xy 340.181961 -287.550652) (xy 340.145709 -287.511581) (xy 340.115685 -287.467544)
			(xy 340.092559 -287.419523) (xy 340.076849 -287.368593) (xy 340.068906 -287.315889) (xy 339.840326 -287.315889)
			(xy 339.832383 -287.368593) (xy 339.816673 -287.419523) (xy 339.793547 -287.467544) (xy 339.763523 -287.511581)
			(xy 339.727271 -287.550652) (xy 339.6856 -287.583883) (xy 339.639442 -287.610532) (xy 339.589828 -287.630004)
			(xy 339.537866 -287.641864) (xy 339.484716 -287.645848) (xy 339.431566 -287.641864) (xy 339.379604 -287.630004)
			(xy 339.32999 -287.610532) (xy 339.283832 -287.583883) (xy 339.242161 -287.550652) (xy 339.205909 -287.511581)
			(xy 339.175885 -287.467544) (xy 339.152759 -287.419523) (xy 339.137049 -287.368593) (xy 339.129106 -287.315889)
			(xy 338.900526 -287.315889) (xy 338.892583 -287.368593) (xy 338.876873 -287.419523) (xy 338.853747 -287.467544)
			(xy 338.823723 -287.511581) (xy 338.787471 -287.550652) (xy 338.7458 -287.583883) (xy 338.699642 -287.610532)
			(xy 338.650028 -287.630004) (xy 338.598066 -287.641864) (xy 338.544916 -287.645848) (xy 338.491766 -287.641864)
			(xy 338.439804 -287.630004) (xy 338.39019 -287.610532) (xy 338.344032 -287.583883) (xy 338.302361 -287.550652)
			(xy 338.266109 -287.511581) (xy 338.236085 -287.467544) (xy 338.212959 -287.419523) (xy 338.197249 -287.368593)
			(xy 338.189306 -287.315889) (xy 337.960472 -287.315889) (xy 337.952529 -287.368593) (xy 337.936819 -287.419523)
			(xy 337.913693 -287.467544) (xy 337.883669 -287.511581) (xy 337.847417 -287.550652) (xy 337.805746 -287.583883)
			(xy 337.759588 -287.610532) (xy 337.709974 -287.630004) (xy 337.658012 -287.641864) (xy 337.604862 -287.645848)
			(xy 337.551712 -287.641864) (xy 337.49975 -287.630004) (xy 337.450136 -287.610532) (xy 337.403978 -287.583883)
			(xy 337.362307 -287.550652) (xy 337.326055 -287.511581) (xy 337.296031 -287.467544) (xy 337.272905 -287.419523)
			(xy 337.257195 -287.368593) (xy 337.249252 -287.315889) (xy 337.020672 -287.315889) (xy 337.012729 -287.368593)
			(xy 336.997019 -287.419523) (xy 336.973893 -287.467544) (xy 336.943869 -287.511581) (xy 336.907617 -287.550652)
			(xy 336.865946 -287.583883) (xy 336.819788 -287.610532) (xy 336.770174 -287.630004) (xy 336.718212 -287.641864)
			(xy 336.665062 -287.645848) (xy 336.611912 -287.641864) (xy 336.55995 -287.630004) (xy 336.510336 -287.610532)
			(xy 336.464178 -287.583883) (xy 336.422507 -287.550652) (xy 336.386255 -287.511581) (xy 336.356231 -287.467544)
			(xy 336.333105 -287.419523) (xy 336.317395 -287.368593) (xy 336.309452 -287.315889) (xy 336.080872 -287.315889)
			(xy 336.072929 -287.368593) (xy 336.057219 -287.419523) (xy 336.034093 -287.467544) (xy 336.004069 -287.511581)
			(xy 335.967817 -287.550652) (xy 335.926146 -287.583883) (xy 335.879988 -287.610532) (xy 335.830374 -287.630004)
			(xy 335.778412 -287.641864) (xy 335.725262 -287.645848) (xy 335.672112 -287.641864) (xy 335.62015 -287.630004)
			(xy 335.570536 -287.610532) (xy 335.524378 -287.583883) (xy 335.482707 -287.550652) (xy 335.446455 -287.511581)
			(xy 335.416431 -287.467544) (xy 335.393305 -287.419523) (xy 335.377595 -287.368593) (xy 335.369652 -287.315889)
			(xy 335.141072 -287.315889) (xy 335.133129 -287.368593) (xy 335.117419 -287.419523) (xy 335.094293 -287.467544)
			(xy 335.064269 -287.511581) (xy 335.028017 -287.550652) (xy 334.986346 -287.583883) (xy 334.940188 -287.610532)
			(xy 334.890574 -287.630004) (xy 334.838612 -287.641864) (xy 334.785462 -287.645848) (xy 334.732312 -287.641864)
			(xy 334.68035 -287.630004) (xy 334.630736 -287.610532) (xy 334.584578 -287.583883) (xy 334.542907 -287.550652)
			(xy 334.506655 -287.511581) (xy 334.476631 -287.467544) (xy 334.453505 -287.419523) (xy 334.437795 -287.368593)
			(xy 334.429852 -287.315889) (xy 334.429354 -287.28924) (xy 334.429744 -287.266037) (xy 334.435789 -287.220027)
			(xy 334.447769 -287.175194) (xy 334.456278 -287.153604) (xy 334.465676 -287.13049) (xy 334.29321 -286.831786)
			(xy 334.268318 -286.828484) (xy 334.242995 -286.824616) (xy 334.193728 -286.810592) (xy 334.146976 -286.789658)
			(xy 334.103704 -286.762245) (xy 334.064803 -286.728919) (xy 334.031074 -286.690366) (xy 334.003213 -286.647381)
			(xy 333.981794 -286.600849) (xy 333.967259 -286.55173) (xy 333.959907 -286.501036) (xy 333.959454 -286.475424)
			(xy 333.731379 -286.475424) (xy 333.731379 -286.502454) (xy 333.723196 -286.555923) (xy 333.707021 -286.607539)
			(xy 333.683226 -286.656114) (xy 333.652357 -286.700532) (xy 333.615125 -286.739771) (xy 333.572387 -286.772926)
			(xy 333.525125 -286.799237) (xy 333.499968 -286.80918) (xy 333.466948 -286.821372) (xy 333.466948 -287.597088)
			(xy 333.473044 -287.603184) (xy 333.473044 -288.129705) (xy 334.899752 -288.129705) (xy 334.899752 -288.076407)
			(xy 334.907695 -288.023703) (xy 334.923405 -287.972773) (xy 334.946531 -287.924752) (xy 334.976555 -287.880715)
			(xy 335.012807 -287.841644) (xy 335.054478 -287.808413) (xy 335.100636 -287.781764) (xy 335.15025 -287.762292)
			(xy 335.202212 -287.750432) (xy 335.255362 -287.746449) (xy 335.308512 -287.750432) (xy 335.360474 -287.762292)
			(xy 335.410088 -287.781764) (xy 335.456246 -287.808413) (xy 335.497917 -287.841644) (xy 335.534169 -287.880715)
			(xy 335.564193 -287.924752) (xy 335.587319 -287.972773) (xy 335.603029 -288.023703) (xy 335.610972 -288.076407)
			(xy 335.61147 -288.103056) (xy 335.610972 -288.129705) (xy 335.603029 -288.182409) (xy 335.587319 -288.233339)
			(xy 335.564193 -288.28136) (xy 335.534169 -288.325397) (xy 335.497917 -288.364468) (xy 335.456246 -288.397699)
			(xy 335.410088 -288.424348) (xy 335.360474 -288.44382) (xy 335.308512 -288.45568) (xy 335.255362 -288.459664)
			(xy 335.202212 -288.45568) (xy 335.15025 -288.44382) (xy 335.100636 -288.424348) (xy 335.054478 -288.397699)
			(xy 335.012807 -288.364468) (xy 334.976555 -288.325397) (xy 334.946531 -288.28136) (xy 334.923405 -288.233339)
			(xy 334.907695 -288.182409) (xy 334.899752 -288.129705) (xy 333.473044 -288.129705) (xy 333.473044 -288.231072)
			(xy 334.07858 -288.836608) (xy 335.376266 -288.836608)
		)
		(stroke
			(width 0)
			(type solid)
		)
		(fill yes)
		(layer "In15.Cu")
		(net "PVCCFA_EHV_FIVRA_CPU0")
	)
	(gr_poly
		(pts
			(xy 409.426664 -314.540392) (xy 409.433141 -314.515155) (xy 409.452947 -314.466965) (xy 409.480063 -314.422477)
			(xy 409.51382 -314.38279) (xy 409.553382 -314.348888) (xy 409.597771 -314.321608) (xy 409.645887 -314.301626)
			(xy 409.696542 -314.289435) (xy 409.748482 -314.285338) (xy 409.800422 -314.289435) (xy 409.851077 -314.301626)
			(xy 409.899193 -314.321608) (xy 409.943582 -314.348888) (xy 409.983144 -314.38279) (xy 410.016901 -314.422477)
			(xy 410.044017 -314.466965) (xy 410.063823 -314.515155) (xy 410.0703 -314.540392) (xy 410.079444 -314.579508)
			(xy 411.62732 -314.579508) (xy 411.636464 -314.540392) (xy 411.642941 -314.515155) (xy 411.662747 -314.466965)
			(xy 411.689863 -314.422477) (xy 411.72362 -314.38279) (xy 411.763182 -314.348888) (xy 411.807571 -314.321608)
			(xy 411.855687 -314.301626) (xy 411.906342 -314.289435) (xy 411.958282 -314.285338) (xy 412.010222 -314.289435)
			(xy 412.060877 -314.301626) (xy 412.108993 -314.321608) (xy 412.153382 -314.348888) (xy 412.192944 -314.38279)
			(xy 412.226701 -314.422477) (xy 412.253817 -314.466965) (xy 412.273623 -314.515155) (xy 412.2801 -314.540392)
			(xy 412.289244 -314.579508) (xy 416.96132 -314.579508) (xy 416.970464 -314.540392) (xy 416.976941 -314.515155)
			(xy 416.996747 -314.466965) (xy 417.023863 -314.422477) (xy 417.05762 -314.38279) (xy 417.097182 -314.348888)
			(xy 417.141571 -314.321608) (xy 417.189687 -314.301626) (xy 417.240342 -314.289435) (xy 417.292282 -314.285338)
			(xy 417.344222 -314.289435) (xy 417.394877 -314.301626) (xy 417.442993 -314.321608) (xy 417.487382 -314.348888)
			(xy 417.526944 -314.38279) (xy 417.560701 -314.422477) (xy 417.587817 -314.466965) (xy 417.607623 -314.515155)
			(xy 417.6141 -314.540392) (xy 417.623244 -314.579508) (xy 419.17112 -314.579508) (xy 419.180264 -314.540392)
			(xy 419.186741 -314.515155) (xy 419.206547 -314.466965) (xy 419.233663 -314.422477) (xy 419.26742 -314.38279)
			(xy 419.306982 -314.348888) (xy 419.351371 -314.321608) (xy 419.399487 -314.301626) (xy 419.450142 -314.289435)
			(xy 419.502082 -314.285338) (xy 419.554022 -314.289435) (xy 419.604677 -314.301626) (xy 419.652793 -314.321608)
			(xy 419.697182 -314.348888) (xy 419.736744 -314.38279) (xy 419.770501 -314.422477) (xy 419.797617 -314.466965)
			(xy 419.817423 -314.515155) (xy 419.8239 -314.540392) (xy 419.833044 -314.579508) (xy 420.379398 -314.579508)
			(xy 420.388288 -314.53963) (xy 420.394548 -314.513584) (xy 420.413826 -314.463606) (xy 420.440372 -314.417078)
			(xy 420.473586 -314.375052) (xy 420.51272 -314.338473) (xy 420.556891 -314.308168) (xy 420.605103 -314.284821)
			(xy 420.656267 -314.268956) (xy 420.70923 -314.260934) (xy 420.762798 -314.260934) (xy 420.815761 -314.268956)
			(xy 420.866925 -314.284821) (xy 420.915137 -314.308168) (xy 420.959308 -314.338473) (xy 420.998442 -314.375052)
			(xy 421.031656 -314.417078) (xy 421.058202 -314.463606) (xy 421.07748 -314.513584) (xy 421.08374 -314.53963)
			(xy 421.09263 -314.579508) (xy 424.50512 -314.579508) (xy 424.514264 -314.540392) (xy 424.520741 -314.515155)
			(xy 424.540547 -314.466965) (xy 424.567663 -314.422477) (xy 424.60142 -314.38279) (xy 424.640982 -314.348888)
			(xy 424.685371 -314.321608) (xy 424.733487 -314.301626) (xy 424.784142 -314.289435) (xy 424.836082 -314.285338)
			(xy 424.888022 -314.289435) (xy 424.938677 -314.301626) (xy 424.986793 -314.321608) (xy 425.031182 -314.348888)
			(xy 425.070744 -314.38279) (xy 425.104501 -314.422477) (xy 425.131617 -314.466965) (xy 425.151423 -314.515155)
			(xy 425.1579 -314.540392) (xy 425.167044 -314.579508) (xy 426.71492 -314.579508) (xy 426.724064 -314.540392)
			(xy 426.730541 -314.515155) (xy 426.750347 -314.466965) (xy 426.777463 -314.422477) (xy 426.81122 -314.38279)
			(xy 426.850782 -314.348888) (xy 426.895171 -314.321608) (xy 426.943287 -314.301626) (xy 426.993942 -314.289435)
			(xy 427.045882 -314.285338) (xy 427.097822 -314.289435) (xy 427.148477 -314.301626) (xy 427.196593 -314.321608)
			(xy 427.240982 -314.348888) (xy 427.280544 -314.38279) (xy 427.314301 -314.422477) (xy 427.341417 -314.466965)
			(xy 427.361223 -314.515155) (xy 427.3677 -314.540392) (xy 427.376844 -314.579508) (xy 432.04892 -314.579508)
			(xy 432.058064 -314.540392) (xy 432.064541 -314.515155) (xy 432.084347 -314.466965) (xy 432.111463 -314.422477)
			(xy 432.14522 -314.38279) (xy 432.184782 -314.348888) (xy 432.229171 -314.321608) (xy 432.277287 -314.301626)
			(xy 432.327942 -314.289435) (xy 432.379882 -314.285338) (xy 432.431822 -314.289435) (xy 432.482477 -314.301626)
			(xy 432.530593 -314.321608) (xy 432.574982 -314.348888) (xy 432.614544 -314.38279) (xy 432.648301 -314.422477)
			(xy 432.675417 -314.466965) (xy 432.695223 -314.515155) (xy 432.7017 -314.540392) (xy 432.710844 -314.579508)
			(xy 434.25872 -314.579508) (xy 434.267864 -314.540392) (xy 434.274341 -314.515155) (xy 434.294147 -314.466965)
			(xy 434.321263 -314.422477) (xy 434.35502 -314.38279) (xy 434.394582 -314.348888) (xy 434.438971 -314.321608)
			(xy 434.487087 -314.301626) (xy 434.537742 -314.289435) (xy 434.589682 -314.285338) (xy 434.641622 -314.289435)
			(xy 434.692277 -314.301626) (xy 434.740393 -314.321608) (xy 434.784782 -314.348888) (xy 434.824344 -314.38279)
			(xy 434.858101 -314.422477) (xy 434.885217 -314.466965) (xy 434.905023 -314.515155) (xy 434.9115 -314.540392)
			(xy 434.920644 -314.579508) (xy 435.466998 -314.579508) (xy 435.475888 -314.53963) (xy 435.482148 -314.513584)
			(xy 435.501426 -314.463606) (xy 435.527972 -314.417078) (xy 435.561186 -314.375052) (xy 435.60032 -314.338473)
			(xy 435.644491 -314.308168) (xy 435.692703 -314.284821) (xy 435.743867 -314.268956) (xy 435.79683 -314.260934)
			(xy 435.850398 -314.260934) (xy 435.903361 -314.268956) (xy 435.954525 -314.284821) (xy 436.002737 -314.308168)
			(xy 436.046908 -314.338473) (xy 436.086042 -314.375052) (xy 436.119256 -314.417078) (xy 436.145802 -314.463606)
			(xy 436.16508 -314.513584) (xy 436.17134 -314.53963) (xy 436.18023 -314.579508) (xy 439.59272 -314.579508)
			(xy 439.601864 -314.540392) (xy 439.608341 -314.515155) (xy 439.628147 -314.466965) (xy 439.655263 -314.422477)
			(xy 439.68902 -314.38279) (xy 439.728582 -314.348888) (xy 439.772971 -314.321608) (xy 439.821087 -314.301626)
			(xy 439.871742 -314.289435) (xy 439.923682 -314.285338) (xy 439.975622 -314.289435) (xy 440.026277 -314.301626)
			(xy 440.074393 -314.321608) (xy 440.118782 -314.348888) (xy 440.158344 -314.38279) (xy 440.192101 -314.422477)
			(xy 440.219217 -314.466965) (xy 440.239023 -314.515155) (xy 440.2455 -314.540392) (xy 440.254644 -314.579508)
			(xy 441.80252 -314.579508) (xy 441.811664 -314.540392) (xy 441.818141 -314.515155) (xy 441.837947 -314.466965)
			(xy 441.865063 -314.422477) (xy 441.89882 -314.38279) (xy 441.938382 -314.348888) (xy 441.982771 -314.321608)
			(xy 442.030887 -314.301626) (xy 442.081542 -314.289435) (xy 442.133482 -314.285338) (xy 442.185422 -314.289435)
			(xy 442.236077 -314.301626) (xy 442.284193 -314.321608) (xy 442.328582 -314.348888) (xy 442.368144 -314.38279)
			(xy 442.401901 -314.422477) (xy 442.429017 -314.466965) (xy 442.448823 -314.515155) (xy 442.4553 -314.540392)
			(xy 442.464444 -314.579508) (xy 447.13652 -314.579508) (xy 447.145664 -314.540392) (xy 447.151772 -314.516557)
			(xy 447.170076 -314.470888) (xy 447.194945 -314.428433) (xy 447.225828 -314.390132) (xy 447.262045 -314.356829)
			(xy 447.302796 -314.329258) (xy 447.347182 -314.308028) (xy 447.394223 -314.293609) (xy 447.442881 -314.286317)
			(xy 447.467482 -314.285884) (xy 447.49176 -314.286317) (xy 447.539794 -314.293424) (xy 447.586273 -314.307475)
			(xy 447.6302 -314.328167) (xy 447.670632 -314.355057) (xy 447.68897 -314.370974) (xy 447.7008 -314.380943)
			(xy 447.728889 -314.393869) (xy 447.759561 -314.397786) (xy 447.789997 -314.392335) (xy 447.817402 -314.378015)
			(xy 447.82867 -314.367418) (xy 449.354956 -312.841132) (xy 449.358512 -312.828178) (xy 449.367395 -312.798782)
			(xy 449.394502 -312.743687) (xy 449.41236 -312.718704) (xy 449.41236 -310.56453) (xy 449.396898 -310.542965)
			(xy 449.372328 -310.495934) (xy 449.35559 -310.445582) (xy 449.347115 -310.393202) (xy 449.34712 -310.340141)
			(xy 449.355604 -310.287762) (xy 449.372351 -310.237413) (xy 449.396928 -310.190387) (xy 449.41236 -310.168798)
			(xy 449.41236 -308.864508) (xy 449.396891 -308.842942) (xy 449.372309 -308.79591) (xy 449.35556 -308.745554)
			(xy 449.347073 -308.693168) (xy 449.347068 -308.640099) (xy 449.355544 -308.587712) (xy 449.372283 -308.537352)
			(xy 449.396856 -308.490315) (xy 449.41236 -308.468776) (xy 449.41236 -307.164486) (xy 449.396893 -307.14292)
			(xy 449.372315 -307.095889) (xy 449.355569 -307.045534) (xy 449.347085 -306.993149) (xy 449.347083 -306.940083)
			(xy 449.355561 -306.887698) (xy 449.372302 -306.837341) (xy 449.396876 -306.790307) (xy 449.41236 -306.768754)
			(xy 449.41236 -305.464464) (xy 449.396895 -305.442898) (xy 449.37232 -305.395867) (xy 449.355577 -305.345513)
			(xy 449.347097 -305.293131) (xy 449.347097 -305.240066) (xy 449.355578 -305.187684) (xy 449.372321 -305.13733)
			(xy 449.396897 -305.090299) (xy 449.41236 -305.068732) (xy 449.41236 -303.764442) (xy 449.396897 -303.742876)
			(xy 449.372325 -303.695846) (xy 449.355586 -303.645493) (xy 449.347109 -303.593112) (xy 449.347112 -303.54005)
			(xy 449.355595 -303.48767) (xy 449.37234 -303.437319) (xy 449.396917 -303.390291) (xy 449.41236 -303.36871)
			(xy 449.41236 -301.214536) (xy 449.396897 -301.192971) (xy 449.372327 -301.14594) (xy 449.355588 -301.095588)
			(xy 449.347112 -301.043207) (xy 449.347116 -300.990145) (xy 449.355599 -300.937766) (xy 449.372345 -300.887416)
			(xy 449.396923 -300.840389) (xy 449.41236 -300.818804) (xy 449.41236 -299.514514) (xy 449.396891 -299.492948)
			(xy 449.372308 -299.445916) (xy 449.355558 -299.395559) (xy 449.34707 -299.343173) (xy 449.347064 -299.290104)
			(xy 449.355539 -299.237715) (xy 449.372278 -299.187355) (xy 449.39685 -299.140317) (xy 449.41236 -299.118782)
			(xy 449.41236 -297.814492) (xy 449.396893 -297.792926) (xy 449.372313 -297.745895) (xy 449.355566 -297.695539)
			(xy 449.347082 -297.643154) (xy 449.347079 -297.590087) (xy 449.355556 -297.537701) (xy 449.372297 -297.487344)
			(xy 449.39687 -297.440309) (xy 449.41236 -297.41876) (xy 449.41236 -296.11447) (xy 449.396894 -296.092904)
			(xy 449.372319 -296.045873) (xy 449.355575 -295.995519) (xy 449.347094 -295.943136) (xy 449.347093 -295.890071)
			(xy 449.355573 -295.837687) (xy 449.372316 -295.787333) (xy 449.396891 -295.740301) (xy 449.41236 -295.718738)
			(xy 449.41236 -294.414448) (xy 449.396896 -294.392882) (xy 449.372324 -294.345852) (xy 449.355583 -294.295499)
			(xy 449.347105 -294.243117) (xy 449.347108 -294.190054) (xy 449.35559 -294.137673) (xy 449.372335 -294.087322)
			(xy 449.396912 -294.040293) (xy 449.41236 -294.018716) (xy 449.41236 -291.864542) (xy 449.396897 -291.842976)
			(xy 449.372325 -291.795946) (xy 449.355586 -291.745593) (xy 449.347109 -291.693212) (xy 449.347112 -291.64015)
			(xy 449.355595 -291.58777) (xy 449.37234 -291.537419) (xy 449.396917 -291.490391) (xy 449.41236 -291.46881)
			(xy 449.41236 -290.16452) (xy 449.396898 -290.142955) (xy 449.37233 -290.095925) (xy 449.355594 -290.045573)
			(xy 449.34712 -289.993193) (xy 449.347126 -289.940133) (xy 449.355612 -289.887756) (xy 449.372359 -289.837407)
			(xy 449.396938 -289.790383) (xy 449.41236 -289.768788) (xy 449.41236 -288.464498) (xy 449.396892 -288.442932)
			(xy 449.372312 -288.3959) (xy 449.355564 -288.345545) (xy 449.347079 -288.29316) (xy 449.347075 -288.240092)
			(xy 449.355552 -288.187705) (xy 449.372292 -288.137347) (xy 449.396865 -288.090311) (xy 449.41236 -288.068766)
			(xy 449.41236 -286.764476) (xy 449.396894 -286.74291) (xy 449.372317 -286.695879) (xy 449.355572 -286.645524)
			(xy 449.34709 -286.593141) (xy 449.347089 -286.540075) (xy 449.355569 -286.487691) (xy 449.372311 -286.437336)
			(xy 449.396885 -286.390303) (xy 449.41236 -286.368744) (xy 449.41236 -285.064454) (xy 449.396896 -285.042888)
			(xy 449.372322 -284.995858) (xy 449.355581 -284.945504) (xy 449.347102 -284.893122) (xy 449.347104 -284.840059)
			(xy 449.355586 -284.787677) (xy 449.37233 -284.737325) (xy 449.396906 -284.690295) (xy 449.41236 -284.668722)
			(xy 449.41236 -282.514548) (xy 449.396896 -282.492982) (xy 449.372324 -282.445952) (xy 449.355583 -282.395599)
			(xy 449.347105 -282.343217) (xy 449.347108 -282.290154) (xy 449.35559 -282.237773) (xy 449.372335 -282.187422)
			(xy 449.396912 -282.140393) (xy 449.41236 -282.118816) (xy 449.41236 -280.814526) (xy 449.396898 -280.792961)
			(xy 449.372329 -280.74593) (xy 449.355592 -280.695578) (xy 449.347117 -280.643198) (xy 449.347122 -280.590138)
			(xy 449.355607 -280.537759) (xy 449.372354 -280.487411) (xy 449.396932 -280.440385) (xy 449.41236 -280.418794)
			(xy 449.41236 -279.114504) (xy 449.396892 -279.092938) (xy 449.37231 -279.045906) (xy 449.355561 -278.99555)
			(xy 449.347076 -278.943165) (xy 449.347071 -278.890096) (xy 449.355547 -278.837709) (xy 449.372287 -278.78735)
			(xy 449.396859 -278.740313) (xy 449.41236 -278.718772) (xy 449.41236 -277.414482) (xy 449.396893 -277.392916)
			(xy 449.372316 -277.345885) (xy 449.35557 -277.29553) (xy 449.347087 -277.243146) (xy 449.347085 -277.19008)
			(xy 449.355564 -277.137695) (xy 449.372306 -277.087339) (xy 449.39688 -277.040305) (xy 449.41236 -277.01875)
			(xy 449.41236 -275.71446) (xy 449.396895 -275.692894) (xy 449.372321 -275.645863) (xy 449.355579 -275.59551)
			(xy 449.347099 -275.543127) (xy 449.3471 -275.490063) (xy 449.355581 -275.437681) (xy 449.372325 -275.387328)
			(xy 449.3969 -275.340297) (xy 449.41236 -275.318728) (xy 449.41236 -273.164554) (xy 449.396896 -273.142988)
			(xy 449.372322 -273.095958) (xy 449.355581 -273.045604) (xy 449.347102 -272.993222) (xy 449.347104 -272.940159)
			(xy 449.355586 -272.887777) (xy 449.37233 -272.837425) (xy 449.396906 -272.790395) (xy 449.41236 -272.768822)
			(xy 449.41236 -271.464532) (xy 449.396897 -271.442967) (xy 449.372328 -271.395936) (xy 449.35559 -271.345584)
			(xy 449.347114 -271.293204) (xy 449.347118 -271.240142) (xy 449.355603 -271.187763) (xy 449.372349 -271.137414)
			(xy 449.396927 -271.090387) (xy 449.41236 -271.0688) (xy 449.41236 -269.76451) (xy 449.396891 -269.742944)
			(xy 449.372309 -269.695912) (xy 449.355559 -269.645556) (xy 449.347072 -269.59317) (xy 449.347067 -269.540101)
			(xy 449.355542 -269.487713) (xy 449.372281 -269.437353) (xy 449.396854 -269.390315) (xy 449.41236 -269.368778)
			(xy 449.41236 -268.064488) (xy 449.396893 -268.042922) (xy 449.372314 -267.995891) (xy 449.355568 -267.945535)
			(xy 449.347084 -267.893151) (xy 449.347081 -267.840084) (xy 449.355559 -267.787699) (xy 449.3723 -267.737342)
			(xy 449.396874 -267.690307) (xy 449.41236 -267.668756) (xy 449.41236 -266.364466) (xy 449.396895 -266.3429)
			(xy 449.372319 -266.295869) (xy 449.355576 -266.245515) (xy 449.347096 -266.193132) (xy 449.347096 -266.140068)
			(xy 449.355576 -266.087685) (xy 449.372319 -266.037331) (xy 449.396895 -265.9903) (xy 449.41236 -265.968734)
			(xy 449.41236 -264.664444) (xy 449.396897 -264.642878) (xy 449.372325 -264.595848) (xy 449.355585 -264.545495)
			(xy 449.347107 -264.493114) (xy 449.34711 -264.440051) (xy 449.355593 -264.387671) (xy 449.372338 -264.33732)
			(xy 449.396915 -264.290292) (xy 449.41236 -264.268712) (xy 449.41236 -262.964676) (xy 449.396894 -262.94311)
			(xy 449.372317 -262.896079) (xy 449.355572 -262.845724) (xy 449.34709 -262.793341) (xy 449.347089 -262.740275)
			(xy 449.355569 -262.687891) (xy 449.372311 -262.637536) (xy 449.396885 -262.590503) (xy 449.41236 -262.568944)
			(xy 449.41236 -261.264654) (xy 449.396896 -261.243088) (xy 449.372322 -261.196058) (xy 449.355581 -261.145704)
			(xy 449.347102 -261.093322) (xy 449.347104 -261.040259) (xy 449.355586 -260.987877) (xy 449.37233 -260.937525)
			(xy 449.396906 -260.890495) (xy 449.41236 -260.868922) (xy 449.41236 -258.714494) (xy 449.396893 -258.692928)
			(xy 449.372313 -258.645897) (xy 449.355565 -258.595541) (xy 449.347081 -258.543156) (xy 449.347077 -258.490089)
			(xy 449.355555 -258.437703) (xy 449.372295 -258.387345) (xy 449.396869 -258.34031) (xy 449.41236 -258.318762)
			(xy 449.41236 -251.064522) (xy 449.396898 -251.042957) (xy 449.37233 -250.995927) (xy 449.355593 -250.945575)
			(xy 449.347119 -250.893195) (xy 449.347125 -250.840135) (xy 449.35561 -250.787757) (xy 449.372357 -250.737408)
			(xy 449.396936 -250.690384) (xy 449.41236 -250.66879) (xy 449.41236 -249.3645) (xy 449.396892 -249.342934)
			(xy 449.372311 -249.295902) (xy 449.355563 -249.245547) (xy 449.347078 -249.193161) (xy 449.347073 -249.140093)
			(xy 449.35555 -249.087706) (xy 449.37229 -249.037348) (xy 449.396863 -248.990312) (xy 449.41236 -248.968768)
			(xy 449.41236 -247.664478) (xy 449.396894 -247.642912) (xy 449.372317 -247.595881) (xy 449.355572 -247.545526)
			(xy 449.347089 -247.493143) (xy 449.347088 -247.440077) (xy 449.355567 -247.387692) (xy 449.372309 -247.337337)
			(xy 449.396884 -247.290304) (xy 449.41236 -247.268746) (xy 449.41236 -245.964456) (xy 449.396896 -245.94289)
			(xy 449.372322 -245.89586) (xy 449.35558 -245.845506) (xy 449.347101 -245.793124) (xy 449.347102 -245.74006)
			(xy 449.355584 -245.687678) (xy 449.372328 -245.637326) (xy 449.396904 -245.590296) (xy 449.41236 -245.568724)
			(xy 449.41236 -244.264434) (xy 449.396897 -244.242869) (xy 449.372327 -244.195838) (xy 449.355589 -244.145486)
			(xy 449.347113 -244.093105) (xy 449.347117 -244.040044) (xy 449.355601 -243.987664) (xy 449.372347 -243.937315)
			(xy 449.396925 -243.890288) (xy 449.41236 -243.868702) (xy 449.41236 -241.714528) (xy 449.396898 -241.692963)
			(xy 449.372328 -241.645932) (xy 449.355591 -241.59558) (xy 449.347116 -241.5432) (xy 449.347121 -241.490139)
			(xy 449.355606 -241.437761) (xy 449.372352 -241.387412) (xy 449.39693 -241.340386) (xy 449.41236 -241.318796)
			(xy 449.41236 -240.014506) (xy 449.396892 -239.99294) (xy 449.37231 -239.945908) (xy 449.355561 -239.895552)
			(xy 449.347074 -239.843166) (xy 449.347069 -239.790098) (xy 449.355545 -239.73771) (xy 449.372285 -239.687351)
			(xy 449.396857 -239.640314) (xy 449.41236 -239.618774) (xy 449.41236 -238.314484) (xy 449.396893 -238.292918)
			(xy 449.372315 -238.245887) (xy 449.355569 -238.195532) (xy 449.347086 -238.143148) (xy 449.347084 -238.090081)
			(xy 449.355562 -238.037696) (xy 449.372304 -237.98734) (xy 449.396878 -237.940306) (xy 449.41236 -237.918752)
			(xy 449.41236 -235.764578) (xy 449.396894 -235.743012) (xy 449.372317 -235.695981) (xy 449.355572 -235.645626)
			(xy 449.347089 -235.593243) (xy 449.347088 -235.540177) (xy 449.355567 -235.487792) (xy 449.372309 -235.437437)
			(xy 449.396884 -235.390404) (xy 449.41236 -235.368846) (xy 449.41236 -234.064556) (xy 449.396896 -234.04299)
			(xy 449.372322 -233.99596) (xy 449.35558 -233.945606) (xy 449.347101 -233.893224) (xy 449.347102 -233.84016)
			(xy 449.355584 -233.787778) (xy 449.372328 -233.737426) (xy 449.396904 -233.690396) (xy 449.41236 -233.668824)
			(xy 449.41236 -232.364534) (xy 449.396897 -232.342969) (xy 449.372327 -232.295938) (xy 449.355589 -232.245586)
			(xy 449.347113 -232.193205) (xy 449.347117 -232.140144) (xy 449.355601 -232.087764) (xy 449.372347 -232.037415)
			(xy 449.396925 -231.990388) (xy 449.41236 -231.968802) (xy 449.41236 -230.664512) (xy 449.396891 -230.642946)
			(xy 449.372309 -230.595914) (xy 449.355558 -230.545558) (xy 449.347071 -230.493171) (xy 449.347065 -230.440102)
			(xy 449.355541 -230.387714) (xy 449.37228 -230.337354) (xy 449.396852 -230.290316) (xy 449.41236 -230.26878)
			(xy 449.41236 -228.96449) (xy 449.396893 -228.942924) (xy 449.372314 -228.895893) (xy 449.355567 -228.845537)
			(xy 449.347083 -228.793153) (xy 449.34708 -228.740086) (xy 449.355558 -228.6877) (xy 449.372299 -228.637343)
			(xy 449.396872 -228.590308) (xy 449.41236 -228.568758) (xy 449.41236 -226.414584) (xy 449.396893 -226.393018)
			(xy 449.372315 -226.345987) (xy 449.355569 -226.295632) (xy 449.347086 -226.243248) (xy 449.347084 -226.190181)
			(xy 449.355562 -226.137796) (xy 449.372304 -226.08744) (xy 449.396878 -226.040406) (xy 449.41236 -226.018852)
			(xy 449.41236 -224.714562) (xy 449.396895 -224.692996) (xy 449.37232 -224.645965) (xy 449.355578 -224.595611)
			(xy 449.347098 -224.543229) (xy 449.347098 -224.490165) (xy 449.355579 -224.437782) (xy 449.372323 -224.387429)
			(xy 449.396899 -224.340398) (xy 449.41236 -224.31883) (xy 449.41236 -223.01454) (xy 449.396897 -222.992974)
			(xy 449.372326 -222.945944) (xy 449.355586 -222.895591) (xy 449.34711 -222.84321) (xy 449.347113 -222.790148)
			(xy 449.355596 -222.737768) (xy 449.372342 -222.687418) (xy 449.396919 -222.64039) (xy 449.41236 -222.618808)
			(xy 449.41236 -221.314518) (xy 449.396899 -221.292953) (xy 449.372331 -221.245923) (xy 449.355595 -221.195571)
			(xy 449.347121 -221.143192) (xy 449.347127 -221.090132) (xy 449.355613 -221.037754) (xy 449.372361 -220.987406)
			(xy 449.39694 -220.940382) (xy 449.41236 -220.918786) (xy 449.41236 -219.614496) (xy 449.396892 -219.59293)
			(xy 449.372312 -219.545898) (xy 449.355565 -219.495543) (xy 449.34708 -219.443158) (xy 449.347076 -219.39009)
			(xy 449.355553 -219.337704) (xy 449.372294 -219.287346) (xy 449.396867 -219.24031) (xy 449.41236 -219.218764)
			(xy 449.41236 -217.06459) (xy 449.396893 -217.043024) (xy 449.372314 -216.995993) (xy 449.355567 -216.945637)
			(xy 449.347083 -216.893253) (xy 449.34708 -216.840186) (xy 449.355558 -216.7878) (xy 449.372299 -216.737443)
			(xy 449.396872 -216.690408) (xy 449.41236 -216.668858) (xy 449.41236 -215.364568) (xy 449.396895 -215.343002)
			(xy 449.372319 -215.295971) (xy 449.355576 -215.245617) (xy 449.347095 -215.193234) (xy 449.347094 -215.140169)
			(xy 449.355575 -215.087786) (xy 449.372318 -215.037432) (xy 449.396893 -214.9904) (xy 449.41236 -214.968836)
			(xy 449.41236 -213.664546) (xy 449.396896 -213.64298) (xy 449.372324 -213.59595) (xy 449.355584 -213.545597)
			(xy 449.347106 -213.493215) (xy 449.347109 -213.440153) (xy 449.355592 -213.387772) (xy 449.372337 -213.337421)
			(xy 449.396913 -213.290392) (xy 449.41236 -213.268814) (xy 449.41236 -211.964524) (xy 449.396898 -211.942959)
			(xy 449.372329 -211.895928) (xy 449.355593 -211.845576) (xy 449.347118 -211.793197) (xy 449.347124 -211.740136)
			(xy 449.355609 -211.687758) (xy 449.372356 -211.63741) (xy 449.396934 -211.590384) (xy 449.41236 -211.568792)
			(xy 449.41236 -210.264502) (xy 449.396892 -210.242936) (xy 449.372311 -210.195904) (xy 449.355562 -210.145548)
			(xy 449.347077 -210.093163) (xy 449.347072 -210.040095) (xy 449.355548 -209.987708) (xy 449.372288 -209.937349)
			(xy 449.396861 -209.890313) (xy 449.41236 -209.86877) (xy 449.41236 -207.714596) (xy 449.396892 -207.69303)
			(xy 449.372312 -207.645998) (xy 449.355565 -207.595643) (xy 449.34708 -207.543258) (xy 449.347076 -207.49019)
			(xy 449.355553 -207.437804) (xy 449.372294 -207.387446) (xy 449.396867 -207.34041) (xy 449.41236 -207.318864)
			(xy 449.41236 -206.014574) (xy 449.396894 -205.993008) (xy 449.372318 -205.945977) (xy 449.355573 -205.895623)
			(xy 449.347091 -205.843239) (xy 449.34709 -205.790174) (xy 449.35557 -205.73779) (xy 449.372313 -205.687435)
			(xy 449.396887 -205.640402) (xy 449.41236 -205.618842) (xy 449.41236 -204.314552) (xy 449.396896 -204.292986)
			(xy 449.372323 -204.245956) (xy 449.355582 -204.195602) (xy 449.347103 -204.143221) (xy 449.347105 -204.090157)
			(xy 449.355587 -204.037776) (xy 449.372332 -203.987424) (xy 449.396908 -203.940395) (xy 449.41236 -203.91882)
			(xy 449.41236 -202.61453) (xy 449.396898 -202.592965) (xy 449.372328 -202.545934) (xy 449.35559 -202.495582)
			(xy 449.347115 -202.443202) (xy 449.34712 -202.390141) (xy 449.355604 -202.337762) (xy 449.372351 -202.287413)
			(xy 449.396928 -202.240387) (xy 449.41236 -202.218798) (xy 449.41236 -200.914508) (xy 449.396891 -200.892942)
			(xy 449.372309 -200.84591) (xy 449.35556 -200.795554) (xy 449.347073 -200.743168) (xy 449.347068 -200.690099)
			(xy 449.355544 -200.637712) (xy 449.372283 -200.587352) (xy 449.396856 -200.540315) (xy 449.41236 -200.518776)
			(xy 449.41236 -198.364602) (xy 449.396892 -198.343036) (xy 449.372311 -198.296004) (xy 449.355562 -198.245648)
			(xy 449.347077 -198.193263) (xy 449.347072 -198.140195) (xy 449.355548 -198.087808) (xy 449.372288 -198.037449)
			(xy 449.396861 -197.990413) (xy 449.41236 -197.96887) (xy 449.41236 -196.66458) (xy 449.396894 -196.643014)
			(xy 449.372316 -196.595983) (xy 449.355571 -196.545628) (xy 449.347088 -196.493244) (xy 449.347086 -196.440178)
			(xy 449.355565 -196.387794) (xy 449.372307 -196.337438) (xy 449.396882 -196.290405) (xy 449.41236 -196.268848)
			(xy 449.41236 -195.727828) (xy 447.87312 -194.188588) (xy 406.68702 -194.188588) (xy 406.163547 -194.712061)
			(xy 407.51759 -194.712061) (xy 407.51759 -194.658763) (xy 407.525533 -194.606059) (xy 407.541243 -194.555129)
			(xy 407.564369 -194.507108) (xy 407.594393 -194.463071) (xy 407.630645 -194.424) (xy 407.672316 -194.390769)
			(xy 407.718474 -194.36412) (xy 407.768088 -194.344648) (xy 407.82005 -194.332788) (xy 407.8732 -194.328805)
			(xy 407.92635 -194.332788) (xy 407.978312 -194.344648) (xy 408.027926 -194.36412) (xy 408.074084 -194.390769)
			(xy 408.115755 -194.424) (xy 408.152007 -194.463071) (xy 408.182031 -194.507108) (xy 408.205157 -194.555129)
			(xy 408.220867 -194.606059) (xy 408.22881 -194.658763) (xy 408.229308 -194.685412) (xy 408.22881 -194.712061)
			(xy 408.220867 -194.764765) (xy 408.212052 -194.793341) (xy 412.836604 -194.793341) (xy 412.836604 -194.740043)
			(xy 412.844547 -194.687339) (xy 412.860257 -194.636409) (xy 412.883383 -194.588388) (xy 412.913407 -194.544351)
			(xy 412.949659 -194.50528) (xy 412.99133 -194.472049) (xy 413.037488 -194.4454) (xy 413.087102 -194.425928)
			(xy 413.139064 -194.414068) (xy 413.192214 -194.410085) (xy 413.245364 -194.414068) (xy 413.297326 -194.425928)
			(xy 413.34694 -194.4454) (xy 413.393098 -194.472049) (xy 413.434769 -194.50528) (xy 413.471021 -194.544351)
			(xy 413.501045 -194.588388) (xy 413.524171 -194.636409) (xy 413.539881 -194.687339) (xy 413.547824 -194.740043)
			(xy 413.548322 -194.766692) (xy 413.547824 -194.793341) (xy 420.380404 -194.793341) (xy 420.380404 -194.740043)
			(xy 420.388347 -194.687339) (xy 420.404057 -194.636409) (xy 420.427183 -194.588388) (xy 420.457207 -194.544351)
			(xy 420.493459 -194.50528) (xy 420.53513 -194.472049) (xy 420.581288 -194.4454) (xy 420.630902 -194.425928)
			(xy 420.682864 -194.414068) (xy 420.736014 -194.410085) (xy 420.789164 -194.414068) (xy 420.841126 -194.425928)
			(xy 420.89074 -194.4454) (xy 420.936898 -194.472049) (xy 420.978569 -194.50528) (xy 421.014821 -194.544351)
			(xy 421.044845 -194.588388) (xy 421.067971 -194.636409) (xy 421.083681 -194.687339) (xy 421.091624 -194.740043)
			(xy 421.092122 -194.766692) (xy 421.091624 -194.793341) (xy 427.898804 -194.793341) (xy 427.898804 -194.740043)
			(xy 427.906747 -194.687339) (xy 427.922457 -194.636409) (xy 427.945583 -194.588388) (xy 427.975607 -194.544351)
			(xy 428.011859 -194.50528) (xy 428.05353 -194.472049) (xy 428.099688 -194.4454) (xy 428.149302 -194.425928)
			(xy 428.201264 -194.414068) (xy 428.254414 -194.410085) (xy 428.307564 -194.414068) (xy 428.359526 -194.425928)
			(xy 428.40914 -194.4454) (xy 428.455298 -194.472049) (xy 428.496969 -194.50528) (xy 428.533221 -194.544351)
			(xy 428.563245 -194.588388) (xy 428.586371 -194.636409) (xy 428.602081 -194.687339) (xy 428.610024 -194.740043)
			(xy 428.610522 -194.766692) (xy 428.610024 -194.793341) (xy 435.468004 -194.793341) (xy 435.468004 -194.740043)
			(xy 435.475947 -194.687339) (xy 435.491657 -194.636409) (xy 435.514783 -194.588388) (xy 435.544807 -194.544351)
			(xy 435.581059 -194.50528) (xy 435.62273 -194.472049) (xy 435.668888 -194.4454) (xy 435.718502 -194.425928)
			(xy 435.770464 -194.414068) (xy 435.823614 -194.410085) (xy 435.876764 -194.414068) (xy 435.928726 -194.425928)
			(xy 435.97834 -194.4454) (xy 436.024498 -194.472049) (xy 436.066169 -194.50528) (xy 436.102421 -194.544351)
			(xy 436.132445 -194.588388) (xy 436.155571 -194.636409) (xy 436.171281 -194.687339) (xy 436.179224 -194.740043)
			(xy 436.179722 -194.766692) (xy 436.179224 -194.793341) (xy 443.011804 -194.793341) (xy 443.011804 -194.740043)
			(xy 443.019747 -194.687339) (xy 443.035457 -194.636409) (xy 443.058583 -194.588388) (xy 443.088607 -194.544351)
			(xy 443.124859 -194.50528) (xy 443.16653 -194.472049) (xy 443.212688 -194.4454) (xy 443.262302 -194.425928)
			(xy 443.314264 -194.414068) (xy 443.367414 -194.410085) (xy 443.420564 -194.414068) (xy 443.472526 -194.425928)
			(xy 443.52214 -194.4454) (xy 443.568298 -194.472049) (xy 443.609969 -194.50528) (xy 443.646221 -194.544351)
			(xy 443.676245 -194.588388) (xy 443.699371 -194.636409) (xy 443.715081 -194.687339) (xy 443.723024 -194.740043)
			(xy 443.723522 -194.766692) (xy 443.723024 -194.793341) (xy 443.715081 -194.846045) (xy 443.699371 -194.896975)
			(xy 443.676245 -194.944996) (xy 443.646221 -194.989033) (xy 443.609969 -195.028104) (xy 443.568298 -195.061335)
			(xy 443.52214 -195.087984) (xy 443.472526 -195.107456) (xy 443.420564 -195.119316) (xy 443.367414 -195.1233)
			(xy 443.314264 -195.119316) (xy 443.262302 -195.107456) (xy 443.212688 -195.087984) (xy 443.16653 -195.061335)
			(xy 443.124859 -195.028104) (xy 443.088607 -194.989033) (xy 443.058583 -194.944996) (xy 443.035457 -194.896975)
			(xy 443.019747 -194.846045) (xy 443.011804 -194.793341) (xy 436.179224 -194.793341) (xy 436.171281 -194.846045)
			(xy 436.155571 -194.896975) (xy 436.132445 -194.944996) (xy 436.102421 -194.989033) (xy 436.066169 -195.028104)
			(xy 436.024498 -195.061335) (xy 435.97834 -195.087984) (xy 435.928726 -195.107456) (xy 435.876764 -195.119316)
			(xy 435.823614 -195.1233) (xy 435.770464 -195.119316) (xy 435.718502 -195.107456) (xy 435.668888 -195.087984)
			(xy 435.62273 -195.061335) (xy 435.581059 -195.028104) (xy 435.544807 -194.989033) (xy 435.514783 -194.944996)
			(xy 435.491657 -194.896975) (xy 435.475947 -194.846045) (xy 435.468004 -194.793341) (xy 428.610024 -194.793341)
			(xy 428.602081 -194.846045) (xy 428.586371 -194.896975) (xy 428.563245 -194.944996) (xy 428.533221 -194.989033)
			(xy 428.496969 -195.028104) (xy 428.455298 -195.061335) (xy 428.40914 -195.087984) (xy 428.359526 -195.107456)
			(xy 428.307564 -195.119316) (xy 428.254414 -195.1233) (xy 428.201264 -195.119316) (xy 428.149302 -195.107456)
			(xy 428.099688 -195.087984) (xy 428.05353 -195.061335) (xy 428.011859 -195.028104) (xy 427.975607 -194.989033)
			(xy 427.945583 -194.944996) (xy 427.922457 -194.896975) (xy 427.906747 -194.846045) (xy 427.898804 -194.793341)
			(xy 421.091624 -194.793341) (xy 421.083681 -194.846045) (xy 421.067971 -194.896975) (xy 421.044845 -194.944996)
			(xy 421.014821 -194.989033) (xy 420.978569 -195.028104) (xy 420.936898 -195.061335) (xy 420.89074 -195.087984)
			(xy 420.841126 -195.107456) (xy 420.789164 -195.119316) (xy 420.736014 -195.1233) (xy 420.682864 -195.119316)
			(xy 420.630902 -195.107456) (xy 420.581288 -195.087984) (xy 420.53513 -195.061335) (xy 420.493459 -195.028104)
			(xy 420.457207 -194.989033) (xy 420.427183 -194.944996) (xy 420.404057 -194.896975) (xy 420.388347 -194.846045)
			(xy 420.380404 -194.793341) (xy 413.547824 -194.793341) (xy 413.539881 -194.846045) (xy 413.524171 -194.896975)
			(xy 413.501045 -194.944996) (xy 413.471021 -194.989033) (xy 413.434769 -195.028104) (xy 413.393098 -195.061335)
			(xy 413.34694 -195.087984) (xy 413.297326 -195.107456) (xy 413.245364 -195.119316) (xy 413.192214 -195.1233)
			(xy 413.139064 -195.119316) (xy 413.087102 -195.107456) (xy 413.037488 -195.087984) (xy 412.99133 -195.061335)
			(xy 412.949659 -195.028104) (xy 412.913407 -194.989033) (xy 412.883383 -194.944996) (xy 412.860257 -194.896975)
			(xy 412.844547 -194.846045) (xy 412.836604 -194.793341) (xy 408.212052 -194.793341) (xy 408.205157 -194.815695)
			(xy 408.182031 -194.863716) (xy 408.152007 -194.907753) (xy 408.115755 -194.946824) (xy 408.074084 -194.980055)
			(xy 408.027926 -195.006704) (xy 407.978312 -195.026176) (xy 407.92635 -195.038036) (xy 407.8732 -195.04202)
			(xy 407.82005 -195.038036) (xy 407.768088 -195.026176) (xy 407.718474 -195.006704) (xy 407.672316 -194.980055)
			(xy 407.630645 -194.946824) (xy 407.594393 -194.907753) (xy 407.564369 -194.863716) (xy 407.541243 -194.815695)
			(xy 407.525533 -194.764765) (xy 407.51759 -194.712061) (xy 406.163547 -194.712061) (xy 405.54656 -195.329048)
			(xy 405.54656 -195.643225) (xy 424.480472 -195.643225) (xy 424.480472 -195.589927) (xy 424.488415 -195.537223)
			(xy 424.504125 -195.486293) (xy 424.527251 -195.438272) (xy 424.557275 -195.394235) (xy 424.593527 -195.355164)
			(xy 424.635198 -195.321933) (xy 424.681356 -195.295284) (xy 424.73097 -195.275812) (xy 424.782932 -195.263952)
			(xy 424.836082 -195.259969) (xy 424.889232 -195.263952) (xy 424.941194 -195.275812) (xy 424.990808 -195.295284)
			(xy 425.036966 -195.321933) (xy 425.078637 -195.355164) (xy 425.114889 -195.394235) (xy 425.144913 -195.438272)
			(xy 425.168039 -195.486293) (xy 425.183749 -195.537223) (xy 425.191692 -195.589927) (xy 425.19219 -195.616576)
			(xy 425.191692 -195.643225) (xy 439.568072 -195.643225) (xy 439.568072 -195.589927) (xy 439.576015 -195.537223)
			(xy 439.591725 -195.486293) (xy 439.614851 -195.438272) (xy 439.644875 -195.394235) (xy 439.681127 -195.355164)
			(xy 439.722798 -195.321933) (xy 439.768956 -195.295284) (xy 439.81857 -195.275812) (xy 439.870532 -195.263952)
			(xy 439.923682 -195.259969) (xy 439.976832 -195.263952) (xy 440.028794 -195.275812) (xy 440.078408 -195.295284)
			(xy 440.124566 -195.321933) (xy 440.166237 -195.355164) (xy 440.202489 -195.394235) (xy 440.232513 -195.438272)
			(xy 440.255639 -195.486293) (xy 440.271349 -195.537223) (xy 440.279292 -195.589927) (xy 440.27979 -195.616576)
			(xy 440.279292 -195.643225) (xy 440.271349 -195.695929) (xy 440.255639 -195.746859) (xy 440.232513 -195.79488)
			(xy 440.202489 -195.838917) (xy 440.166237 -195.877988) (xy 440.124566 -195.911219) (xy 440.078408 -195.937868)
			(xy 440.028794 -195.95734) (xy 439.976832 -195.9692) (xy 439.923682 -195.973184) (xy 439.870532 -195.9692)
			(xy 439.81857 -195.95734) (xy 439.768956 -195.937868) (xy 439.722798 -195.911219) (xy 439.681127 -195.877988)
			(xy 439.644875 -195.838917) (xy 439.614851 -195.79488) (xy 439.591725 -195.746859) (xy 439.576015 -195.695929)
			(xy 439.568072 -195.643225) (xy 425.191692 -195.643225) (xy 425.183749 -195.695929) (xy 425.168039 -195.746859)
			(xy 425.144913 -195.79488) (xy 425.114889 -195.838917) (xy 425.078637 -195.877988) (xy 425.036966 -195.911219)
			(xy 424.990808 -195.937868) (xy 424.941194 -195.95734) (xy 424.889232 -195.9692) (xy 424.836082 -195.973184)
			(xy 424.782932 -195.9692) (xy 424.73097 -195.95734) (xy 424.681356 -195.937868) (xy 424.635198 -195.911219)
			(xy 424.593527 -195.877988) (xy 424.557275 -195.838917) (xy 424.527251 -195.79488) (xy 424.504125 -195.746859)
			(xy 424.488415 -195.695929) (xy 424.480472 -195.643225) (xy 405.54656 -195.643225) (xy 405.54656 -196.493363)
			(xy 420.380404 -196.493363) (xy 420.380404 -196.440065) (xy 420.388347 -196.387361) (xy 420.404057 -196.336431)
			(xy 420.427183 -196.28841) (xy 420.457207 -196.244373) (xy 420.493459 -196.205302) (xy 420.53513 -196.172071)
			(xy 420.581288 -196.145422) (xy 420.630902 -196.12595) (xy 420.682864 -196.11409) (xy 420.736014 -196.110107)
			(xy 420.789164 -196.11409) (xy 420.841126 -196.12595) (xy 420.89074 -196.145422) (xy 420.936898 -196.172071)
			(xy 420.978569 -196.205302) (xy 421.014821 -196.244373) (xy 421.044845 -196.28841) (xy 421.067971 -196.336431)
			(xy 421.083681 -196.387361) (xy 421.091624 -196.440065) (xy 421.092122 -196.466714) (xy 421.091624 -196.493363)
			(xy 435.468004 -196.493363) (xy 435.468004 -196.440065) (xy 435.475947 -196.387361) (xy 435.491657 -196.336431)
			(xy 435.514783 -196.28841) (xy 435.544807 -196.244373) (xy 435.581059 -196.205302) (xy 435.62273 -196.172071)
			(xy 435.668888 -196.145422) (xy 435.718502 -196.12595) (xy 435.770464 -196.11409) (xy 435.823614 -196.110107)
			(xy 435.876764 -196.11409) (xy 435.928726 -196.12595) (xy 435.97834 -196.145422) (xy 436.024498 -196.172071)
			(xy 436.066169 -196.205302) (xy 436.102421 -196.244373) (xy 436.132445 -196.28841) (xy 436.155571 -196.336431)
			(xy 436.171281 -196.387361) (xy 436.179224 -196.440065) (xy 436.179722 -196.466714) (xy 436.179224 -196.493363)
			(xy 436.171281 -196.546067) (xy 436.155571 -196.596997) (xy 436.132445 -196.645018) (xy 436.102421 -196.689055)
			(xy 436.066169 -196.728126) (xy 436.024498 -196.761357) (xy 435.97834 -196.788006) (xy 435.928726 -196.807478)
			(xy 435.876764 -196.819338) (xy 435.823614 -196.823322) (xy 435.770464 -196.819338) (xy 435.718502 -196.807478)
			(xy 435.668888 -196.788006) (xy 435.62273 -196.761357) (xy 435.581059 -196.728126) (xy 435.544807 -196.689055)
			(xy 435.514783 -196.645018) (xy 435.491657 -196.596997) (xy 435.475947 -196.546067) (xy 435.468004 -196.493363)
			(xy 421.091624 -196.493363) (xy 421.083681 -196.546067) (xy 421.067971 -196.596997) (xy 421.044845 -196.645018)
			(xy 421.014821 -196.689055) (xy 420.978569 -196.728126) (xy 420.936898 -196.761357) (xy 420.89074 -196.788006)
			(xy 420.841126 -196.807478) (xy 420.789164 -196.819338) (xy 420.736014 -196.823322) (xy 420.682864 -196.819338)
			(xy 420.630902 -196.807478) (xy 420.581288 -196.788006) (xy 420.53513 -196.761357) (xy 420.493459 -196.728126)
			(xy 420.457207 -196.689055) (xy 420.427183 -196.645018) (xy 420.404057 -196.596997) (xy 420.388347 -196.546067)
			(xy 420.380404 -196.493363) (xy 405.54656 -196.493363) (xy 405.54656 -197.343247) (xy 424.480472 -197.343247)
			(xy 424.480472 -197.289949) (xy 424.488415 -197.237245) (xy 424.504125 -197.186315) (xy 424.527251 -197.138294)
			(xy 424.557275 -197.094257) (xy 424.593527 -197.055186) (xy 424.635198 -197.021955) (xy 424.681356 -196.995306)
			(xy 424.73097 -196.975834) (xy 424.782932 -196.963974) (xy 424.836082 -196.959991) (xy 424.889232 -196.963974)
			(xy 424.941194 -196.975834) (xy 424.990808 -196.995306) (xy 425.036966 -197.021955) (xy 425.078637 -197.055186)
			(xy 425.114889 -197.094257) (xy 425.144913 -197.138294) (xy 425.168039 -197.186315) (xy 425.183749 -197.237245)
			(xy 425.191692 -197.289949) (xy 425.19219 -197.316598) (xy 425.191692 -197.343247) (xy 439.568072 -197.343247)
			(xy 439.568072 -197.289949) (xy 439.576015 -197.237245) (xy 439.591725 -197.186315) (xy 439.614851 -197.138294)
			(xy 439.644875 -197.094257) (xy 439.681127 -197.055186) (xy 439.722798 -197.021955) (xy 439.768956 -196.995306)
			(xy 439.81857 -196.975834) (xy 439.870532 -196.963974) (xy 439.923682 -196.959991) (xy 439.976832 -196.963974)
			(xy 440.028794 -196.975834) (xy 440.078408 -196.995306) (xy 440.124566 -197.021955) (xy 440.166237 -197.055186)
			(xy 440.202489 -197.094257) (xy 440.232513 -197.138294) (xy 440.255639 -197.186315) (xy 440.271349 -197.237245)
			(xy 440.279292 -197.289949) (xy 440.27979 -197.316598) (xy 440.279292 -197.343247) (xy 440.271349 -197.395951)
			(xy 440.255639 -197.446881) (xy 440.232513 -197.494902) (xy 440.202489 -197.538939) (xy 440.166237 -197.57801)
			(xy 440.124566 -197.611241) (xy 440.078408 -197.63789) (xy 440.028794 -197.657362) (xy 439.976832 -197.669222)
			(xy 439.923682 -197.673206) (xy 439.870532 -197.669222) (xy 439.81857 -197.657362) (xy 439.768956 -197.63789)
			(xy 439.722798 -197.611241) (xy 439.681127 -197.57801) (xy 439.644875 -197.538939) (xy 439.614851 -197.494902)
			(xy 439.591725 -197.446881) (xy 439.576015 -197.395951) (xy 439.568072 -197.343247) (xy 425.191692 -197.343247)
			(xy 425.183749 -197.395951) (xy 425.168039 -197.446881) (xy 425.144913 -197.494902) (xy 425.114889 -197.538939)
			(xy 425.078637 -197.57801) (xy 425.036966 -197.611241) (xy 424.990808 -197.63789) (xy 424.941194 -197.657362)
			(xy 424.889232 -197.669222) (xy 424.836082 -197.673206) (xy 424.782932 -197.669222) (xy 424.73097 -197.657362)
			(xy 424.681356 -197.63789) (xy 424.635198 -197.611241) (xy 424.593527 -197.57801) (xy 424.557275 -197.538939)
			(xy 424.527251 -197.494902) (xy 424.504125 -197.446881) (xy 424.488415 -197.395951) (xy 424.480472 -197.343247)
			(xy 405.54656 -197.343247) (xy 405.54656 -198.193385) (xy 420.380404 -198.193385) (xy 420.380404 -198.140087)
			(xy 420.388347 -198.087383) (xy 420.404057 -198.036453) (xy 420.427183 -197.988432) (xy 420.457207 -197.944395)
			(xy 420.493459 -197.905324) (xy 420.53513 -197.872093) (xy 420.581288 -197.845444) (xy 420.630902 -197.825972)
			(xy 420.682864 -197.814112) (xy 420.736014 -197.810129) (xy 420.789164 -197.814112) (xy 420.841126 -197.825972)
			(xy 420.89074 -197.845444) (xy 420.936898 -197.872093) (xy 420.978569 -197.905324) (xy 421.014821 -197.944395)
			(xy 421.044845 -197.988432) (xy 421.067971 -198.036453) (xy 421.083681 -198.087383) (xy 421.091624 -198.140087)
			(xy 421.092122 -198.166736) (xy 421.091624 -198.193385) (xy 435.468004 -198.193385) (xy 435.468004 -198.140087)
			(xy 435.475947 -198.087383) (xy 435.491657 -198.036453) (xy 435.514783 -197.988432) (xy 435.544807 -197.944395)
			(xy 435.581059 -197.905324) (xy 435.62273 -197.872093) (xy 435.668888 -197.845444) (xy 435.718502 -197.825972)
			(xy 435.770464 -197.814112) (xy 435.823614 -197.810129) (xy 435.876764 -197.814112) (xy 435.928726 -197.825972)
			(xy 435.97834 -197.845444) (xy 436.024498 -197.872093) (xy 436.066169 -197.905324) (xy 436.102421 -197.944395)
			(xy 436.132445 -197.988432) (xy 436.155571 -198.036453) (xy 436.171281 -198.087383) (xy 436.179224 -198.140087)
			(xy 436.179722 -198.166736) (xy 436.179224 -198.193385) (xy 436.171281 -198.246089) (xy 436.155571 -198.297019)
			(xy 436.132445 -198.34504) (xy 436.102421 -198.389077) (xy 436.066169 -198.428148) (xy 436.024498 -198.461379)
			(xy 435.97834 -198.488028) (xy 435.928726 -198.5075) (xy 435.876764 -198.51936) (xy 435.823614 -198.523344)
			(xy 435.770464 -198.51936) (xy 435.718502 -198.5075) (xy 435.668888 -198.488028) (xy 435.62273 -198.461379)
			(xy 435.581059 -198.428148) (xy 435.544807 -198.389077) (xy 435.514783 -198.34504) (xy 435.491657 -198.297019)
			(xy 435.475947 -198.246089) (xy 435.468004 -198.193385) (xy 421.091624 -198.193385) (xy 421.083681 -198.246089)
			(xy 421.067971 -198.297019) (xy 421.044845 -198.34504) (xy 421.014821 -198.389077) (xy 420.978569 -198.428148)
			(xy 420.936898 -198.461379) (xy 420.89074 -198.488028) (xy 420.841126 -198.5075) (xy 420.789164 -198.51936)
			(xy 420.736014 -198.523344) (xy 420.682864 -198.51936) (xy 420.630902 -198.5075) (xy 420.581288 -198.488028)
			(xy 420.53513 -198.461379) (xy 420.493459 -198.428148) (xy 420.457207 -198.389077) (xy 420.427183 -198.34504)
			(xy 420.404057 -198.297019) (xy 420.388347 -198.246089) (xy 420.380404 -198.193385) (xy 405.54656 -198.193385)
			(xy 405.54656 -199.043269) (xy 424.480472 -199.043269) (xy 424.480472 -198.989971) (xy 424.488415 -198.937267)
			(xy 424.504125 -198.886337) (xy 424.527251 -198.838316) (xy 424.557275 -198.794279) (xy 424.593527 -198.755208)
			(xy 424.635198 -198.721977) (xy 424.681356 -198.695328) (xy 424.73097 -198.675856) (xy 424.782932 -198.663996)
			(xy 424.836082 -198.660013) (xy 424.889232 -198.663996) (xy 424.941194 -198.675856) (xy 424.990808 -198.695328)
			(xy 425.036966 -198.721977) (xy 425.078637 -198.755208) (xy 425.114889 -198.794279) (xy 425.144913 -198.838316)
			(xy 425.168039 -198.886337) (xy 425.183749 -198.937267) (xy 425.191692 -198.989971) (xy 425.19219 -199.01662)
			(xy 425.191692 -199.043269) (xy 439.568072 -199.043269) (xy 439.568072 -198.989971) (xy 439.576015 -198.937267)
			(xy 439.591725 -198.886337) (xy 439.614851 -198.838316) (xy 439.644875 -198.794279) (xy 439.681127 -198.755208)
			(xy 439.722798 -198.721977) (xy 439.768956 -198.695328) (xy 439.81857 -198.675856) (xy 439.870532 -198.663996)
			(xy 439.923682 -198.660013) (xy 439.976832 -198.663996) (xy 440.028794 -198.675856) (xy 440.078408 -198.695328)
			(xy 440.124566 -198.721977) (xy 440.166237 -198.755208) (xy 440.202489 -198.794279) (xy 440.232513 -198.838316)
			(xy 440.255639 -198.886337) (xy 440.271349 -198.937267) (xy 440.279292 -198.989971) (xy 440.27979 -199.01662)
			(xy 440.279292 -199.043269) (xy 440.271349 -199.095973) (xy 440.255639 -199.146903) (xy 440.232513 -199.194924)
			(xy 440.202489 -199.238961) (xy 440.166237 -199.278032) (xy 440.124566 -199.311263) (xy 440.078408 -199.337912)
			(xy 440.028794 -199.357384) (xy 439.976832 -199.369244) (xy 439.923682 -199.373228) (xy 439.870532 -199.369244)
			(xy 439.81857 -199.357384) (xy 439.768956 -199.337912) (xy 439.722798 -199.311263) (xy 439.681127 -199.278032)
			(xy 439.644875 -199.238961) (xy 439.614851 -199.194924) (xy 439.591725 -199.146903) (xy 439.576015 -199.095973)
			(xy 439.568072 -199.043269) (xy 425.191692 -199.043269) (xy 425.183749 -199.095973) (xy 425.168039 -199.146903)
			(xy 425.144913 -199.194924) (xy 425.114889 -199.238961) (xy 425.078637 -199.278032) (xy 425.036966 -199.311263)
			(xy 424.990808 -199.337912) (xy 424.941194 -199.357384) (xy 424.889232 -199.369244) (xy 424.836082 -199.373228)
			(xy 424.782932 -199.369244) (xy 424.73097 -199.357384) (xy 424.681356 -199.337912) (xy 424.635198 -199.311263)
			(xy 424.593527 -199.278032) (xy 424.557275 -199.238961) (xy 424.527251 -199.194924) (xy 424.504125 -199.146903)
			(xy 424.488415 -199.095973) (xy 424.480472 -199.043269) (xy 405.54656 -199.043269) (xy 405.54656 -199.893407)
			(xy 420.380404 -199.893407) (xy 420.380404 -199.840109) (xy 420.388347 -199.787405) (xy 420.404057 -199.736475)
			(xy 420.427183 -199.688454) (xy 420.457207 -199.644417) (xy 420.493459 -199.605346) (xy 420.53513 -199.572115)
			(xy 420.581288 -199.545466) (xy 420.630902 -199.525994) (xy 420.682864 -199.514134) (xy 420.736014 -199.510151)
			(xy 420.789164 -199.514134) (xy 420.841126 -199.525994) (xy 420.89074 -199.545466) (xy 420.936898 -199.572115)
			(xy 420.978569 -199.605346) (xy 421.014821 -199.644417) (xy 421.044845 -199.688454) (xy 421.067971 -199.736475)
			(xy 421.083681 -199.787405) (xy 421.091624 -199.840109) (xy 421.092122 -199.866758) (xy 421.091624 -199.893407)
			(xy 424.480472 -199.893407) (xy 424.480472 -199.840109) (xy 424.488415 -199.787405) (xy 424.504125 -199.736475)
			(xy 424.527251 -199.688454) (xy 424.557275 -199.644417) (xy 424.593527 -199.605346) (xy 424.635198 -199.572115)
			(xy 424.681356 -199.545466) (xy 424.73097 -199.525994) (xy 424.782932 -199.514134) (xy 424.836082 -199.510151)
			(xy 424.889232 -199.514134) (xy 424.941194 -199.525994) (xy 424.990808 -199.545466) (xy 425.036966 -199.572115)
			(xy 425.078637 -199.605346) (xy 425.114889 -199.644417) (xy 425.144913 -199.688454) (xy 425.168039 -199.736475)
			(xy 425.183749 -199.787405) (xy 425.191692 -199.840109) (xy 425.19219 -199.866758) (xy 425.191692 -199.893407)
			(xy 435.468004 -199.893407) (xy 435.468004 -199.840109) (xy 435.475947 -199.787405) (xy 435.491657 -199.736475)
			(xy 435.514783 -199.688454) (xy 435.544807 -199.644417) (xy 435.581059 -199.605346) (xy 435.62273 -199.572115)
			(xy 435.668888 -199.545466) (xy 435.718502 -199.525994) (xy 435.770464 -199.514134) (xy 435.823614 -199.510151)
			(xy 435.876764 -199.514134) (xy 435.928726 -199.525994) (xy 435.97834 -199.545466) (xy 436.024498 -199.572115)
			(xy 436.066169 -199.605346) (xy 436.102421 -199.644417) (xy 436.132445 -199.688454) (xy 436.155571 -199.736475)
			(xy 436.171281 -199.787405) (xy 436.179224 -199.840109) (xy 436.179722 -199.866758) (xy 436.179224 -199.893407)
			(xy 439.568072 -199.893407) (xy 439.568072 -199.840109) (xy 439.576015 -199.787405) (xy 439.591725 -199.736475)
			(xy 439.614851 -199.688454) (xy 439.644875 -199.644417) (xy 439.681127 -199.605346) (xy 439.722798 -199.572115)
			(xy 439.768956 -199.545466) (xy 439.81857 -199.525994) (xy 439.870532 -199.514134) (xy 439.923682 -199.510151)
			(xy 439.976832 -199.514134) (xy 440.028794 -199.525994) (xy 440.078408 -199.545466) (xy 440.124566 -199.572115)
			(xy 440.166237 -199.605346) (xy 440.202489 -199.644417) (xy 440.232513 -199.688454) (xy 440.255639 -199.736475)
			(xy 440.271349 -199.787405) (xy 440.279292 -199.840109) (xy 440.27979 -199.866758) (xy 440.279292 -199.893407)
			(xy 440.271349 -199.946111) (xy 440.255639 -199.997041) (xy 440.232513 -200.045062) (xy 440.202489 -200.089099)
			(xy 440.166237 -200.12817) (xy 440.124566 -200.161401) (xy 440.078408 -200.18805) (xy 440.028794 -200.207522)
			(xy 439.976832 -200.219382) (xy 439.923682 -200.223366) (xy 439.870532 -200.219382) (xy 439.81857 -200.207522)
			(xy 439.768956 -200.18805) (xy 439.722798 -200.161401) (xy 439.681127 -200.12817) (xy 439.644875 -200.089099)
			(xy 439.614851 -200.045062) (xy 439.591725 -199.997041) (xy 439.576015 -199.946111) (xy 439.568072 -199.893407)
			(xy 436.179224 -199.893407) (xy 436.171281 -199.946111) (xy 436.155571 -199.997041) (xy 436.132445 -200.045062)
			(xy 436.102421 -200.089099) (xy 436.066169 -200.12817) (xy 436.024498 -200.161401) (xy 435.97834 -200.18805)
			(xy 435.928726 -200.207522) (xy 435.876764 -200.219382) (xy 435.823614 -200.223366) (xy 435.770464 -200.219382)
			(xy 435.718502 -200.207522) (xy 435.668888 -200.18805) (xy 435.62273 -200.161401) (xy 435.581059 -200.12817)
			(xy 435.544807 -200.089099) (xy 435.514783 -200.045062) (xy 435.491657 -199.997041) (xy 435.475947 -199.946111)
			(xy 435.468004 -199.893407) (xy 425.191692 -199.893407) (xy 425.183749 -199.946111) (xy 425.168039 -199.997041)
			(xy 425.144913 -200.045062) (xy 425.114889 -200.089099) (xy 425.078637 -200.12817) (xy 425.036966 -200.161401)
			(xy 424.990808 -200.18805) (xy 424.941194 -200.207522) (xy 424.889232 -200.219382) (xy 424.836082 -200.223366)
			(xy 424.782932 -200.219382) (xy 424.73097 -200.207522) (xy 424.681356 -200.18805) (xy 424.635198 -200.161401)
			(xy 424.593527 -200.12817) (xy 424.557275 -200.089099) (xy 424.527251 -200.045062) (xy 424.504125 -199.997041)
			(xy 424.488415 -199.946111) (xy 424.480472 -199.893407) (xy 421.091624 -199.893407) (xy 421.083681 -199.946111)
			(xy 421.067971 -199.997041) (xy 421.044845 -200.045062) (xy 421.014821 -200.089099) (xy 420.978569 -200.12817)
			(xy 420.936898 -200.161401) (xy 420.89074 -200.18805) (xy 420.841126 -200.207522) (xy 420.789164 -200.219382)
			(xy 420.736014 -200.223366) (xy 420.682864 -200.219382) (xy 420.630902 -200.207522) (xy 420.581288 -200.18805)
			(xy 420.53513 -200.161401) (xy 420.493459 -200.12817) (xy 420.457207 -200.089099) (xy 420.427183 -200.045062)
			(xy 420.404057 -199.997041) (xy 420.388347 -199.946111) (xy 420.380404 -199.893407) (xy 405.54656 -199.893407)
			(xy 405.54656 -200.743291) (xy 420.380404 -200.743291) (xy 420.380404 -200.689993) (xy 420.388347 -200.637289)
			(xy 420.404057 -200.586359) (xy 420.427183 -200.538338) (xy 420.457207 -200.494301) (xy 420.493459 -200.45523)
			(xy 420.53513 -200.421999) (xy 420.581288 -200.39535) (xy 420.630902 -200.375878) (xy 420.682864 -200.364018)
			(xy 420.736014 -200.360035) (xy 420.789164 -200.364018) (xy 420.841126 -200.375878) (xy 420.89074 -200.39535)
			(xy 420.936898 -200.421999) (xy 420.978569 -200.45523) (xy 421.014821 -200.494301) (xy 421.044845 -200.538338)
			(xy 421.067971 -200.586359) (xy 421.083681 -200.637289) (xy 421.091624 -200.689993) (xy 421.092122 -200.716642)
			(xy 421.091624 -200.743291) (xy 435.468004 -200.743291) (xy 435.468004 -200.689993) (xy 435.475947 -200.637289)
			(xy 435.491657 -200.586359) (xy 435.514783 -200.538338) (xy 435.544807 -200.494301) (xy 435.581059 -200.45523)
			(xy 435.62273 -200.421999) (xy 435.668888 -200.39535) (xy 435.718502 -200.375878) (xy 435.770464 -200.364018)
			(xy 435.823614 -200.360035) (xy 435.876764 -200.364018) (xy 435.928726 -200.375878) (xy 435.97834 -200.39535)
			(xy 436.024498 -200.421999) (xy 436.066169 -200.45523) (xy 436.102421 -200.494301) (xy 436.132445 -200.538338)
			(xy 436.155571 -200.586359) (xy 436.171281 -200.637289) (xy 436.179224 -200.689993) (xy 436.179722 -200.716642)
			(xy 436.179224 -200.743291) (xy 436.171281 -200.795995) (xy 436.155571 -200.846925) (xy 436.132445 -200.894946)
			(xy 436.102421 -200.938983) (xy 436.066169 -200.978054) (xy 436.024498 -201.011285) (xy 435.97834 -201.037934)
			(xy 435.928726 -201.057406) (xy 435.876764 -201.069266) (xy 435.823614 -201.07325) (xy 435.770464 -201.069266)
			(xy 435.718502 -201.057406) (xy 435.668888 -201.037934) (xy 435.62273 -201.011285) (xy 435.581059 -200.978054)
			(xy 435.544807 -200.938983) (xy 435.514783 -200.894946) (xy 435.491657 -200.846925) (xy 435.475947 -200.795995)
			(xy 435.468004 -200.743291) (xy 421.091624 -200.743291) (xy 421.083681 -200.795995) (xy 421.067971 -200.846925)
			(xy 421.044845 -200.894946) (xy 421.014821 -200.938983) (xy 420.978569 -200.978054) (xy 420.936898 -201.011285)
			(xy 420.89074 -201.037934) (xy 420.841126 -201.057406) (xy 420.789164 -201.069266) (xy 420.736014 -201.07325)
			(xy 420.682864 -201.069266) (xy 420.630902 -201.057406) (xy 420.581288 -201.037934) (xy 420.53513 -201.011285)
			(xy 420.493459 -200.978054) (xy 420.457207 -200.938983) (xy 420.427183 -200.894946) (xy 420.404057 -200.846925)
			(xy 420.388347 -200.795995) (xy 420.380404 -200.743291) (xy 405.54656 -200.743291) (xy 405.54656 -201.593429)
			(xy 424.480472 -201.593429) (xy 424.480472 -201.540131) (xy 424.488415 -201.487427) (xy 424.504125 -201.436497)
			(xy 424.527251 -201.388476) (xy 424.557275 -201.344439) (xy 424.593527 -201.305368) (xy 424.635198 -201.272137)
			(xy 424.681356 -201.245488) (xy 424.73097 -201.226016) (xy 424.782932 -201.214156) (xy 424.836082 -201.210173)
			(xy 424.889232 -201.214156) (xy 424.941194 -201.226016) (xy 424.990808 -201.245488) (xy 425.036966 -201.272137)
			(xy 425.078637 -201.305368) (xy 425.114889 -201.344439) (xy 425.144913 -201.388476) (xy 425.168039 -201.436497)
			(xy 425.183749 -201.487427) (xy 425.191692 -201.540131) (xy 425.19219 -201.56678) (xy 425.191692 -201.593429)
			(xy 439.568072 -201.593429) (xy 439.568072 -201.540131) (xy 439.576015 -201.487427) (xy 439.591725 -201.436497)
			(xy 439.614851 -201.388476) (xy 439.644875 -201.344439) (xy 439.681127 -201.305368) (xy 439.722798 -201.272137)
			(xy 439.768956 -201.245488) (xy 439.81857 -201.226016) (xy 439.870532 -201.214156) (xy 439.923682 -201.210173)
			(xy 439.976832 -201.214156) (xy 440.028794 -201.226016) (xy 440.078408 -201.245488) (xy 440.124566 -201.272137)
			(xy 440.166237 -201.305368) (xy 440.202489 -201.344439) (xy 440.232513 -201.388476) (xy 440.255639 -201.436497)
			(xy 440.271349 -201.487427) (xy 440.279292 -201.540131) (xy 440.27979 -201.56678) (xy 440.279292 -201.593429)
			(xy 440.271349 -201.646133) (xy 440.255639 -201.697063) (xy 440.232513 -201.745084) (xy 440.202489 -201.789121)
			(xy 440.166237 -201.828192) (xy 440.124566 -201.861423) (xy 440.078408 -201.888072) (xy 440.028794 -201.907544)
			(xy 439.976832 -201.919404) (xy 439.923682 -201.923388) (xy 439.870532 -201.919404) (xy 439.81857 -201.907544)
			(xy 439.768956 -201.888072) (xy 439.722798 -201.861423) (xy 439.681127 -201.828192) (xy 439.644875 -201.789121)
			(xy 439.614851 -201.745084) (xy 439.591725 -201.697063) (xy 439.576015 -201.646133) (xy 439.568072 -201.593429)
			(xy 425.191692 -201.593429) (xy 425.183749 -201.646133) (xy 425.168039 -201.697063) (xy 425.144913 -201.745084)
			(xy 425.114889 -201.789121) (xy 425.078637 -201.828192) (xy 425.036966 -201.861423) (xy 424.990808 -201.888072)
			(xy 424.941194 -201.907544) (xy 424.889232 -201.919404) (xy 424.836082 -201.923388) (xy 424.782932 -201.919404)
			(xy 424.73097 -201.907544) (xy 424.681356 -201.888072) (xy 424.635198 -201.861423) (xy 424.593527 -201.828192)
			(xy 424.557275 -201.789121) (xy 424.527251 -201.745084) (xy 424.504125 -201.697063) (xy 424.488415 -201.646133)
			(xy 424.480472 -201.593429) (xy 405.54656 -201.593429) (xy 405.54656 -202.443313) (xy 420.380404 -202.443313)
			(xy 420.380404 -202.390015) (xy 420.388347 -202.337311) (xy 420.404057 -202.286381) (xy 420.427183 -202.23836)
			(xy 420.457207 -202.194323) (xy 420.493459 -202.155252) (xy 420.53513 -202.122021) (xy 420.581288 -202.095372)
			(xy 420.630902 -202.0759) (xy 420.682864 -202.06404) (xy 420.736014 -202.060057) (xy 420.789164 -202.06404)
			(xy 420.841126 -202.0759) (xy 420.89074 -202.095372) (xy 420.936898 -202.122021) (xy 420.978569 -202.155252)
			(xy 421.014821 -202.194323) (xy 421.044845 -202.23836) (xy 421.067971 -202.286381) (xy 421.083681 -202.337311)
			(xy 421.091624 -202.390015) (xy 421.092122 -202.416664) (xy 421.091624 -202.443313) (xy 435.468004 -202.443313)
			(xy 435.468004 -202.390015) (xy 435.475947 -202.337311) (xy 435.491657 -202.286381) (xy 435.514783 -202.23836)
			(xy 435.544807 -202.194323) (xy 435.581059 -202.155252) (xy 435.62273 -202.122021) (xy 435.668888 -202.095372)
			(xy 435.718502 -202.0759) (xy 435.770464 -202.06404) (xy 435.823614 -202.060057) (xy 435.876764 -202.06404)
			(xy 435.928726 -202.0759) (xy 435.97834 -202.095372) (xy 436.024498 -202.122021) (xy 436.066169 -202.155252)
			(xy 436.102421 -202.194323) (xy 436.132445 -202.23836) (xy 436.155571 -202.286381) (xy 436.171281 -202.337311)
			(xy 436.179224 -202.390015) (xy 436.179722 -202.416664) (xy 436.179224 -202.443313) (xy 436.171281 -202.496017)
			(xy 436.155571 -202.546947) (xy 436.132445 -202.594968) (xy 436.102421 -202.639005) (xy 436.066169 -202.678076)
			(xy 436.024498 -202.711307) (xy 435.97834 -202.737956) (xy 435.928726 -202.757428) (xy 435.876764 -202.769288)
			(xy 435.823614 -202.773272) (xy 435.770464 -202.769288) (xy 435.718502 -202.757428) (xy 435.668888 -202.737956)
			(xy 435.62273 -202.711307) (xy 435.581059 -202.678076) (xy 435.544807 -202.639005) (xy 435.514783 -202.594968)
			(xy 435.491657 -202.546947) (xy 435.475947 -202.496017) (xy 435.468004 -202.443313) (xy 421.091624 -202.443313)
			(xy 421.083681 -202.496017) (xy 421.067971 -202.546947) (xy 421.044845 -202.594968) (xy 421.014821 -202.639005)
			(xy 420.978569 -202.678076) (xy 420.936898 -202.711307) (xy 420.89074 -202.737956) (xy 420.841126 -202.757428)
			(xy 420.789164 -202.769288) (xy 420.736014 -202.773272) (xy 420.682864 -202.769288) (xy 420.630902 -202.757428)
			(xy 420.581288 -202.737956) (xy 420.53513 -202.711307) (xy 420.493459 -202.678076) (xy 420.457207 -202.639005)
			(xy 420.427183 -202.594968) (xy 420.404057 -202.546947) (xy 420.388347 -202.496017) (xy 420.380404 -202.443313)
			(xy 405.54656 -202.443313) (xy 405.54656 -203.293451) (xy 424.480472 -203.293451) (xy 424.480472 -203.240153)
			(xy 424.488415 -203.187449) (xy 424.504125 -203.136519) (xy 424.527251 -203.088498) (xy 424.557275 -203.044461)
			(xy 424.593527 -203.00539) (xy 424.635198 -202.972159) (xy 424.681356 -202.94551) (xy 424.73097 -202.926038)
			(xy 424.782932 -202.914178) (xy 424.836082 -202.910195) (xy 424.889232 -202.914178) (xy 424.941194 -202.926038)
			(xy 424.990808 -202.94551) (xy 425.036966 -202.972159) (xy 425.078637 -203.00539) (xy 425.114889 -203.044461)
			(xy 425.144913 -203.088498) (xy 425.168039 -203.136519) (xy 425.183749 -203.187449) (xy 425.191692 -203.240153)
			(xy 425.19219 -203.266802) (xy 425.191692 -203.293451) (xy 439.568072 -203.293451) (xy 439.568072 -203.240153)
			(xy 439.576015 -203.187449) (xy 439.591725 -203.136519) (xy 439.614851 -203.088498) (xy 439.644875 -203.044461)
			(xy 439.681127 -203.00539) (xy 439.722798 -202.972159) (xy 439.768956 -202.94551) (xy 439.81857 -202.926038)
			(xy 439.870532 -202.914178) (xy 439.923682 -202.910195) (xy 439.976832 -202.914178) (xy 440.028794 -202.926038)
			(xy 440.078408 -202.94551) (xy 440.124566 -202.972159) (xy 440.166237 -203.00539) (xy 440.202489 -203.044461)
			(xy 440.232513 -203.088498) (xy 440.255639 -203.136519) (xy 440.271349 -203.187449) (xy 440.279292 -203.240153)
			(xy 440.27979 -203.266802) (xy 440.279292 -203.293451) (xy 440.271349 -203.346155) (xy 440.255639 -203.397085)
			(xy 440.232513 -203.445106) (xy 440.202489 -203.489143) (xy 440.166237 -203.528214) (xy 440.124566 -203.561445)
			(xy 440.078408 -203.588094) (xy 440.028794 -203.607566) (xy 439.976832 -203.619426) (xy 439.923682 -203.62341)
			(xy 439.870532 -203.619426) (xy 439.81857 -203.607566) (xy 439.768956 -203.588094) (xy 439.722798 -203.561445)
			(xy 439.681127 -203.528214) (xy 439.644875 -203.489143) (xy 439.614851 -203.445106) (xy 439.591725 -203.397085)
			(xy 439.576015 -203.346155) (xy 439.568072 -203.293451) (xy 425.191692 -203.293451) (xy 425.183749 -203.346155)
			(xy 425.168039 -203.397085) (xy 425.144913 -203.445106) (xy 425.114889 -203.489143) (xy 425.078637 -203.528214)
			(xy 425.036966 -203.561445) (xy 424.990808 -203.588094) (xy 424.941194 -203.607566) (xy 424.889232 -203.619426)
			(xy 424.836082 -203.62341) (xy 424.782932 -203.619426) (xy 424.73097 -203.607566) (xy 424.681356 -203.588094)
			(xy 424.635198 -203.561445) (xy 424.593527 -203.528214) (xy 424.557275 -203.489143) (xy 424.527251 -203.445106)
			(xy 424.504125 -203.397085) (xy 424.488415 -203.346155) (xy 424.480472 -203.293451) (xy 405.54656 -203.293451)
			(xy 405.54656 -204.143335) (xy 420.380404 -204.143335) (xy 420.380404 -204.090037) (xy 420.388347 -204.037333)
			(xy 420.404057 -203.986403) (xy 420.427183 -203.938382) (xy 420.457207 -203.894345) (xy 420.493459 -203.855274)
			(xy 420.53513 -203.822043) (xy 420.581288 -203.795394) (xy 420.630902 -203.775922) (xy 420.682864 -203.764062)
			(xy 420.736014 -203.760079) (xy 420.789164 -203.764062) (xy 420.841126 -203.775922) (xy 420.89074 -203.795394)
			(xy 420.936898 -203.822043) (xy 420.978569 -203.855274) (xy 421.014821 -203.894345) (xy 421.044845 -203.938382)
			(xy 421.067971 -203.986403) (xy 421.083681 -204.037333) (xy 421.091624 -204.090037) (xy 421.092122 -204.116686)
			(xy 421.091624 -204.143335) (xy 435.468004 -204.143335) (xy 435.468004 -204.090037) (xy 435.475947 -204.037333)
			(xy 435.491657 -203.986403) (xy 435.514783 -203.938382) (xy 435.544807 -203.894345) (xy 435.581059 -203.855274)
			(xy 435.62273 -203.822043) (xy 435.668888 -203.795394) (xy 435.718502 -203.775922) (xy 435.770464 -203.764062)
			(xy 435.823614 -203.760079) (xy 435.876764 -203.764062) (xy 435.928726 -203.775922) (xy 435.97834 -203.795394)
			(xy 436.024498 -203.822043) (xy 436.066169 -203.855274) (xy 436.102421 -203.894345) (xy 436.132445 -203.938382)
			(xy 436.155571 -203.986403) (xy 436.171281 -204.037333) (xy 436.179224 -204.090037) (xy 436.179722 -204.116686)
			(xy 436.179224 -204.143335) (xy 436.171281 -204.196039) (xy 436.155571 -204.246969) (xy 436.132445 -204.29499)
			(xy 436.102421 -204.339027) (xy 436.066169 -204.378098) (xy 436.024498 -204.411329) (xy 435.97834 -204.437978)
			(xy 435.928726 -204.45745) (xy 435.876764 -204.46931) (xy 435.823614 -204.473294) (xy 435.770464 -204.46931)
			(xy 435.718502 -204.45745) (xy 435.668888 -204.437978) (xy 435.62273 -204.411329) (xy 435.581059 -204.378098)
			(xy 435.544807 -204.339027) (xy 435.514783 -204.29499) (xy 435.491657 -204.246969) (xy 435.475947 -204.196039)
			(xy 435.468004 -204.143335) (xy 421.091624 -204.143335) (xy 421.083681 -204.196039) (xy 421.067971 -204.246969)
			(xy 421.044845 -204.29499) (xy 421.014821 -204.339027) (xy 420.978569 -204.378098) (xy 420.936898 -204.411329)
			(xy 420.89074 -204.437978) (xy 420.841126 -204.45745) (xy 420.789164 -204.46931) (xy 420.736014 -204.473294)
			(xy 420.682864 -204.46931) (xy 420.630902 -204.45745) (xy 420.581288 -204.437978) (xy 420.53513 -204.411329)
			(xy 420.493459 -204.378098) (xy 420.457207 -204.339027) (xy 420.427183 -204.29499) (xy 420.404057 -204.246969)
			(xy 420.388347 -204.196039) (xy 420.380404 -204.143335) (xy 405.54656 -204.143335) (xy 405.54656 -204.719682)
			(xy 405.565202 -204.736885) (xy 405.597504 -204.775994) (xy 405.62345 -204.81958) (xy 405.642432 -204.866618)
			(xy 405.654004 -204.916005) (xy 405.657894 -204.96658) (xy 405.655848 -204.993219) (xy 424.480472 -204.993219)
			(xy 424.480472 -204.939921) (xy 424.488415 -204.887217) (xy 424.504125 -204.836287) (xy 424.527251 -204.788266)
			(xy 424.557275 -204.744229) (xy 424.593527 -204.705158) (xy 424.635198 -204.671927) (xy 424.681356 -204.645278)
			(xy 424.73097 -204.625806) (xy 424.782932 -204.613946) (xy 424.836082 -204.609963) (xy 424.889232 -204.613946)
			(xy 424.941194 -204.625806) (xy 424.990808 -204.645278) (xy 425.036966 -204.671927) (xy 425.078637 -204.705158)
			(xy 425.114889 -204.744229) (xy 425.144913 -204.788266) (xy 425.168039 -204.836287) (xy 425.183749 -204.887217)
			(xy 425.191692 -204.939921) (xy 425.19219 -204.96657) (xy 425.191692 -204.993219) (xy 439.568072 -204.993219)
			(xy 439.568072 -204.939921) (xy 439.576015 -204.887217) (xy 439.591725 -204.836287) (xy 439.614851 -204.788266)
			(xy 439.644875 -204.744229) (xy 439.681127 -204.705158) (xy 439.722798 -204.671927) (xy 439.768956 -204.645278)
			(xy 439.81857 -204.625806) (xy 439.870532 -204.613946) (xy 439.923682 -204.609963) (xy 439.976832 -204.613946)
			(xy 440.028794 -204.625806) (xy 440.078408 -204.645278) (xy 440.124566 -204.671927) (xy 440.166237 -204.705158)
			(xy 440.202489 -204.744229) (xy 440.232513 -204.788266) (xy 440.255639 -204.836287) (xy 440.271349 -204.887217)
			(xy 440.279292 -204.939921) (xy 440.27979 -204.96657) (xy 440.279292 -204.993219) (xy 440.271349 -205.045923)
			(xy 440.255639 -205.096853) (xy 440.232513 -205.144874) (xy 440.202489 -205.188911) (xy 440.166237 -205.227982)
			(xy 440.124566 -205.261213) (xy 440.078408 -205.287862) (xy 440.028794 -205.307334) (xy 439.976832 -205.319194)
			(xy 439.923682 -205.323178) (xy 439.870532 -205.319194) (xy 439.81857 -205.307334) (xy 439.768956 -205.287862)
			(xy 439.722798 -205.261213) (xy 439.681127 -205.227982) (xy 439.644875 -205.188911) (xy 439.614851 -205.144874)
			(xy 439.591725 -205.096853) (xy 439.576015 -205.045923) (xy 439.568072 -204.993219) (xy 425.191692 -204.993219)
			(xy 425.183749 -205.045923) (xy 425.168039 -205.096853) (xy 425.144913 -205.144874) (xy 425.114889 -205.188911)
			(xy 425.078637 -205.227982) (xy 425.036966 -205.261213) (xy 424.990808 -205.287862) (xy 424.941194 -205.307334)
			(xy 424.889232 -205.319194) (xy 424.836082 -205.323178) (xy 424.782932 -205.319194) (xy 424.73097 -205.307334)
			(xy 424.681356 -205.287862) (xy 424.635198 -205.261213) (xy 424.593527 -205.227982) (xy 424.557275 -205.188911)
			(xy 424.527251 -205.144874) (xy 424.504125 -205.096853) (xy 424.488415 -205.045923) (xy 424.480472 -204.993219)
			(xy 405.655848 -204.993219) (xy 405.65401 -205.017155) (xy 405.642444 -205.066543) (xy 405.623468 -205.113584)
			(xy 405.597527 -205.157173) (xy 405.56523 -205.196287) (xy 405.54656 -205.213458) (xy 405.54656 -205.843357)
			(xy 420.380404 -205.843357) (xy 420.380404 -205.790059) (xy 420.388347 -205.737355) (xy 420.404057 -205.686425)
			(xy 420.427183 -205.638404) (xy 420.457207 -205.594367) (xy 420.493459 -205.555296) (xy 420.53513 -205.522065)
			(xy 420.581288 -205.495416) (xy 420.630902 -205.475944) (xy 420.682864 -205.464084) (xy 420.736014 -205.460101)
			(xy 420.789164 -205.464084) (xy 420.841126 -205.475944) (xy 420.89074 -205.495416) (xy 420.936898 -205.522065)
			(xy 420.978569 -205.555296) (xy 421.014821 -205.594367) (xy 421.044845 -205.638404) (xy 421.067971 -205.686425)
			(xy 421.083681 -205.737355) (xy 421.091624 -205.790059) (xy 421.092122 -205.816708) (xy 421.091624 -205.843357)
			(xy 435.468004 -205.843357) (xy 435.468004 -205.790059) (xy 435.475947 -205.737355) (xy 435.491657 -205.686425)
			(xy 435.514783 -205.638404) (xy 435.544807 -205.594367) (xy 435.581059 -205.555296) (xy 435.62273 -205.522065)
			(xy 435.668888 -205.495416) (xy 435.718502 -205.475944) (xy 435.770464 -205.464084) (xy 435.823614 -205.460101)
			(xy 435.876764 -205.464084) (xy 435.928726 -205.475944) (xy 435.97834 -205.495416) (xy 436.024498 -205.522065)
			(xy 436.066169 -205.555296) (xy 436.102421 -205.594367) (xy 436.132445 -205.638404) (xy 436.155571 -205.686425)
			(xy 436.171281 -205.737355) (xy 436.179224 -205.790059) (xy 436.179722 -205.816708) (xy 436.179224 -205.843357)
			(xy 436.171281 -205.896061) (xy 436.155571 -205.946991) (xy 436.132445 -205.995012) (xy 436.102421 -206.039049)
			(xy 436.066169 -206.07812) (xy 436.024498 -206.111351) (xy 435.97834 -206.138) (xy 435.928726 -206.157472)
			(xy 435.876764 -206.169332) (xy 435.823614 -206.173316) (xy 435.770464 -206.169332) (xy 435.718502 -206.157472)
			(xy 435.668888 -206.138) (xy 435.62273 -206.111351) (xy 435.581059 -206.07812) (xy 435.544807 -206.039049)
			(xy 435.514783 -205.995012) (xy 435.491657 -205.946991) (xy 435.475947 -205.896061) (xy 435.468004 -205.843357)
			(xy 421.091624 -205.843357) (xy 421.083681 -205.896061) (xy 421.067971 -205.946991) (xy 421.044845 -205.995012)
			(xy 421.014821 -206.039049) (xy 420.978569 -206.07812) (xy 420.936898 -206.111351) (xy 420.89074 -206.138)
			(xy 420.841126 -206.157472) (xy 420.789164 -206.169332) (xy 420.736014 -206.173316) (xy 420.682864 -206.169332)
			(xy 420.630902 -206.157472) (xy 420.581288 -206.138) (xy 420.53513 -206.111351) (xy 420.493459 -206.07812)
			(xy 420.457207 -206.039049) (xy 420.427183 -205.995012) (xy 420.404057 -205.946991) (xy 420.388347 -205.896061)
			(xy 420.380404 -205.843357) (xy 405.54656 -205.843357) (xy 405.54656 -206.35214) (xy 405.576278 -206.365602)
			(xy 405.599048 -206.37648) (xy 405.641276 -206.404105) (xy 405.678816 -206.437826) (xy 405.710796 -206.47686)
			(xy 405.736475 -206.520299) (xy 405.755255 -206.567136) (xy 405.7667 -206.616282) (xy 405.770546 -206.666597)
			(xy 405.76851 -206.693241) (xy 424.480472 -206.693241) (xy 424.480472 -206.639943) (xy 424.488415 -206.587239)
			(xy 424.504125 -206.536309) (xy 424.527251 -206.488288) (xy 424.557275 -206.444251) (xy 424.593527 -206.40518)
			(xy 424.635198 -206.371949) (xy 424.681356 -206.3453) (xy 424.73097 -206.325828) (xy 424.782932 -206.313968)
			(xy 424.836082 -206.309985) (xy 424.889232 -206.313968) (xy 424.941194 -206.325828) (xy 424.990808 -206.3453)
			(xy 425.036966 -206.371949) (xy 425.078637 -206.40518) (xy 425.114889 -206.444251) (xy 425.144913 -206.488288)
			(xy 425.168039 -206.536309) (xy 425.183749 -206.587239) (xy 425.191692 -206.639943) (xy 425.19219 -206.666592)
			(xy 425.191692 -206.693241) (xy 439.568072 -206.693241) (xy 439.568072 -206.639943) (xy 439.576015 -206.587239)
			(xy 439.591725 -206.536309) (xy 439.614851 -206.488288) (xy 439.644875 -206.444251) (xy 439.681127 -206.40518)
			(xy 439.722798 -206.371949) (xy 439.768956 -206.3453) (xy 439.81857 -206.325828) (xy 439.870532 -206.313968)
			(xy 439.923682 -206.309985) (xy 439.976832 -206.313968) (xy 440.028794 -206.325828) (xy 440.078408 -206.3453)
			(xy 440.124566 -206.371949) (xy 440.166237 -206.40518) (xy 440.202489 -206.444251) (xy 440.232513 -206.488288)
			(xy 440.255639 -206.536309) (xy 440.271349 -206.587239) (xy 440.279292 -206.639943) (xy 440.27979 -206.666592)
			(xy 440.279292 -206.693241) (xy 440.271349 -206.745945) (xy 440.255639 -206.796875) (xy 440.232513 -206.844896)
			(xy 440.202489 -206.888933) (xy 440.166237 -206.928004) (xy 440.124566 -206.961235) (xy 440.078408 -206.987884)
			(xy 440.028794 -207.007356) (xy 439.976832 -207.019216) (xy 439.923682 -207.0232) (xy 439.870532 -207.019216)
			(xy 439.81857 -207.007356) (xy 439.768956 -206.987884) (xy 439.722798 -206.961235) (xy 439.681127 -206.928004)
			(xy 439.644875 -206.888933) (xy 439.614851 -206.844896) (xy 439.591725 -206.796875) (xy 439.576015 -206.745945)
			(xy 439.568072 -206.693241) (xy 425.191692 -206.693241) (xy 425.183749 -206.745945) (xy 425.168039 -206.796875)
			(xy 425.144913 -206.844896) (xy 425.114889 -206.888933) (xy 425.078637 -206.928004) (xy 425.036966 -206.961235)
			(xy 424.990808 -206.987884) (xy 424.941194 -207.007356) (xy 424.889232 -207.019216) (xy 424.836082 -207.0232)
			(xy 424.782932 -207.019216) (xy 424.73097 -207.007356) (xy 424.681356 -206.987884) (xy 424.635198 -206.961235)
			(xy 424.593527 -206.928004) (xy 424.557275 -206.888933) (xy 424.527251 -206.844896) (xy 424.504125 -206.796875)
			(xy 424.488415 -206.745945) (xy 424.480472 -206.693241) (xy 405.76851 -206.693241) (xy 405.766701 -206.716911)
			(xy 405.755257 -206.766058) (xy 405.736478 -206.812895) (xy 405.7108 -206.856335) (xy 405.678821 -206.895369)
			(xy 405.641281 -206.929091) (xy 405.599054 -206.956717) (xy 405.576278 -206.967582) (xy 405.54656 -206.981044)
			(xy 405.54656 -207.543379) (xy 420.380404 -207.543379) (xy 420.380404 -207.490081) (xy 420.388347 -207.437377)
			(xy 420.404057 -207.386447) (xy 420.427183 -207.338426) (xy 420.457207 -207.294389) (xy 420.493459 -207.255318)
			(xy 420.53513 -207.222087) (xy 420.581288 -207.195438) (xy 420.630902 -207.175966) (xy 420.682864 -207.164106)
			(xy 420.736014 -207.160123) (xy 420.789164 -207.164106) (xy 420.841126 -207.175966) (xy 420.89074 -207.195438)
			(xy 420.936898 -207.222087) (xy 420.978569 -207.255318) (xy 421.014821 -207.294389) (xy 421.044845 -207.338426)
			(xy 421.067971 -207.386447) (xy 421.083681 -207.437377) (xy 421.091624 -207.490081) (xy 421.092122 -207.51673)
			(xy 421.091624 -207.543379) (xy 435.468004 -207.543379) (xy 435.468004 -207.490081) (xy 435.475947 -207.437377)
			(xy 435.491657 -207.386447) (xy 435.514783 -207.338426) (xy 435.544807 -207.294389) (xy 435.581059 -207.255318)
			(xy 435.62273 -207.222087) (xy 435.668888 -207.195438) (xy 435.718502 -207.175966) (xy 435.770464 -207.164106)
			(xy 435.823614 -207.160123) (xy 435.876764 -207.164106) (xy 435.928726 -207.175966) (xy 435.97834 -207.195438)
			(xy 436.024498 -207.222087) (xy 436.066169 -207.255318) (xy 436.102421 -207.294389) (xy 436.132445 -207.338426)
			(xy 436.155571 -207.386447) (xy 436.171281 -207.437377) (xy 436.179224 -207.490081) (xy 436.179722 -207.51673)
			(xy 436.179224 -207.543379) (xy 436.171281 -207.596083) (xy 436.155571 -207.647013) (xy 436.132445 -207.695034)
			(xy 436.102421 -207.739071) (xy 436.066169 -207.778142) (xy 436.024498 -207.811373) (xy 435.97834 -207.838022)
			(xy 435.928726 -207.857494) (xy 435.876764 -207.869354) (xy 435.823614 -207.873338) (xy 435.770464 -207.869354)
			(xy 435.718502 -207.857494) (xy 435.668888 -207.838022) (xy 435.62273 -207.811373) (xy 435.581059 -207.778142)
			(xy 435.544807 -207.739071) (xy 435.514783 -207.695034) (xy 435.491657 -207.647013) (xy 435.475947 -207.596083)
			(xy 435.468004 -207.543379) (xy 421.091624 -207.543379) (xy 421.083681 -207.596083) (xy 421.067971 -207.647013)
			(xy 421.044845 -207.695034) (xy 421.014821 -207.739071) (xy 420.978569 -207.778142) (xy 420.936898 -207.811373)
			(xy 420.89074 -207.838022) (xy 420.841126 -207.857494) (xy 420.789164 -207.869354) (xy 420.736014 -207.873338)
			(xy 420.682864 -207.869354) (xy 420.630902 -207.857494) (xy 420.581288 -207.838022) (xy 420.53513 -207.811373)
			(xy 420.493459 -207.778142) (xy 420.457207 -207.739071) (xy 420.427183 -207.695034) (xy 420.404057 -207.647013)
			(xy 420.388347 -207.596083) (xy 420.380404 -207.543379) (xy 405.54656 -207.543379) (xy 405.54656 -208.393263)
			(xy 424.480472 -208.393263) (xy 424.480472 -208.339965) (xy 424.488415 -208.287261) (xy 424.504125 -208.236331)
			(xy 424.527251 -208.18831) (xy 424.557275 -208.144273) (xy 424.593527 -208.105202) (xy 424.635198 -208.071971)
			(xy 424.681356 -208.045322) (xy 424.73097 -208.02585) (xy 424.782932 -208.01399) (xy 424.836082 -208.010007)
			(xy 424.889232 -208.01399) (xy 424.941194 -208.02585) (xy 424.990808 -208.045322) (xy 425.036966 -208.071971)
			(xy 425.078637 -208.105202) (xy 425.114889 -208.144273) (xy 425.144913 -208.18831) (xy 425.168039 -208.236331)
			(xy 425.183749 -208.287261) (xy 425.191692 -208.339965) (xy 425.19219 -208.366614) (xy 425.191692 -208.393263)
			(xy 439.568072 -208.393263) (xy 439.568072 -208.339965) (xy 439.576015 -208.287261) (xy 439.591725 -208.236331)
			(xy 439.614851 -208.18831) (xy 439.644875 -208.144273) (xy 439.681127 -208.105202) (xy 439.722798 -208.071971)
			(xy 439.768956 -208.045322) (xy 439.81857 -208.02585) (xy 439.870532 -208.01399) (xy 439.923682 -208.010007)
			(xy 439.976832 -208.01399) (xy 440.028794 -208.02585) (xy 440.078408 -208.045322) (xy 440.124566 -208.071971)
			(xy 440.166237 -208.105202) (xy 440.202489 -208.144273) (xy 440.232513 -208.18831) (xy 440.255639 -208.236331)
			(xy 440.271349 -208.287261) (xy 440.279292 -208.339965) (xy 440.27979 -208.366614) (xy 440.279292 -208.393263)
			(xy 440.271349 -208.445967) (xy 440.255639 -208.496897) (xy 440.232513 -208.544918) (xy 440.202489 -208.588955)
			(xy 440.166237 -208.628026) (xy 440.124566 -208.661257) (xy 440.078408 -208.687906) (xy 440.028794 -208.707378)
			(xy 439.976832 -208.719238) (xy 439.923682 -208.723222) (xy 439.870532 -208.719238) (xy 439.81857 -208.707378)
			(xy 439.768956 -208.687906) (xy 439.722798 -208.661257) (xy 439.681127 -208.628026) (xy 439.644875 -208.588955)
			(xy 439.614851 -208.544918) (xy 439.591725 -208.496897) (xy 439.576015 -208.445967) (xy 439.568072 -208.393263)
			(xy 425.191692 -208.393263) (xy 425.183749 -208.445967) (xy 425.168039 -208.496897) (xy 425.144913 -208.544918)
			(xy 425.114889 -208.588955) (xy 425.078637 -208.628026) (xy 425.036966 -208.661257) (xy 424.990808 -208.687906)
			(xy 424.941194 -208.707378) (xy 424.889232 -208.719238) (xy 424.836082 -208.723222) (xy 424.782932 -208.719238)
			(xy 424.73097 -208.707378) (xy 424.681356 -208.687906) (xy 424.635198 -208.661257) (xy 424.593527 -208.628026)
			(xy 424.557275 -208.588955) (xy 424.527251 -208.544918) (xy 424.504125 -208.496897) (xy 424.488415 -208.445967)
			(xy 424.480472 -208.393263) (xy 405.54656 -208.393263) (xy 405.54656 -209.243401) (xy 420.380404 -209.243401)
			(xy 420.380404 -209.190103) (xy 420.388347 -209.137399) (xy 420.404057 -209.086469) (xy 420.427183 -209.038448)
			(xy 420.457207 -208.994411) (xy 420.493459 -208.95534) (xy 420.53513 -208.922109) (xy 420.581288 -208.89546)
			(xy 420.630902 -208.875988) (xy 420.682864 -208.864128) (xy 420.736014 -208.860145) (xy 420.789164 -208.864128)
			(xy 420.841126 -208.875988) (xy 420.89074 -208.89546) (xy 420.936898 -208.922109) (xy 420.978569 -208.95534)
			(xy 421.014821 -208.994411) (xy 421.044845 -209.038448) (xy 421.067971 -209.086469) (xy 421.083681 -209.137399)
			(xy 421.091624 -209.190103) (xy 421.092122 -209.216752) (xy 421.091624 -209.243401) (xy 424.480472 -209.243401)
			(xy 424.480472 -209.190103) (xy 424.488415 -209.137399) (xy 424.504125 -209.086469) (xy 424.527251 -209.038448)
			(xy 424.557275 -208.994411) (xy 424.593527 -208.95534) (xy 424.635198 -208.922109) (xy 424.681356 -208.89546)
			(xy 424.73097 -208.875988) (xy 424.782932 -208.864128) (xy 424.836082 -208.860145) (xy 424.889232 -208.864128)
			(xy 424.941194 -208.875988) (xy 424.990808 -208.89546) (xy 425.036966 -208.922109) (xy 425.078637 -208.95534)
			(xy 425.114889 -208.994411) (xy 425.144913 -209.038448) (xy 425.168039 -209.086469) (xy 425.183749 -209.137399)
			(xy 425.191692 -209.190103) (xy 425.19219 -209.216752) (xy 425.191692 -209.243401) (xy 435.468004 -209.243401)
			(xy 435.468004 -209.190103) (xy 435.475947 -209.137399) (xy 435.491657 -209.086469) (xy 435.514783 -209.038448)
			(xy 435.544807 -208.994411) (xy 435.581059 -208.95534) (xy 435.62273 -208.922109) (xy 435.668888 -208.89546)
			(xy 435.718502 -208.875988) (xy 435.770464 -208.864128) (xy 435.823614 -208.860145) (xy 435.876764 -208.864128)
			(xy 435.928726 -208.875988) (xy 435.97834 -208.89546) (xy 436.024498 -208.922109) (xy 436.066169 -208.95534)
			(xy 436.102421 -208.994411) (xy 436.132445 -209.038448) (xy 436.155571 -209.086469) (xy 436.171281 -209.137399)
			(xy 436.179224 -209.190103) (xy 436.179722 -209.216752) (xy 436.179224 -209.243401) (xy 439.568072 -209.243401)
			(xy 439.568072 -209.190103) (xy 439.576015 -209.137399) (xy 439.591725 -209.086469) (xy 439.614851 -209.038448)
			(xy 439.644875 -208.994411) (xy 439.681127 -208.95534) (xy 439.722798 -208.922109) (xy 439.768956 -208.89546)
			(xy 439.81857 -208.875988) (xy 439.870532 -208.864128) (xy 439.923682 -208.860145) (xy 439.976832 -208.864128)
			(xy 440.028794 -208.875988) (xy 440.078408 -208.89546) (xy 440.124566 -208.922109) (xy 440.166237 -208.95534)
			(xy 440.202489 -208.994411) (xy 440.232513 -209.038448) (xy 440.255639 -209.086469) (xy 440.271349 -209.137399)
			(xy 440.279292 -209.190103) (xy 440.27979 -209.216752) (xy 440.279292 -209.243401) (xy 440.271349 -209.296105)
			(xy 440.255639 -209.347035) (xy 440.232513 -209.395056) (xy 440.202489 -209.439093) (xy 440.166237 -209.478164)
			(xy 440.124566 -209.511395) (xy 440.078408 -209.538044) (xy 440.028794 -209.557516) (xy 439.976832 -209.569376)
			(xy 439.923682 -209.57336) (xy 439.870532 -209.569376) (xy 439.81857 -209.557516) (xy 439.768956 -209.538044)
			(xy 439.722798 -209.511395) (xy 439.681127 -209.478164) (xy 439.644875 -209.439093) (xy 439.614851 -209.395056)
			(xy 439.591725 -209.347035) (xy 439.576015 -209.296105) (xy 439.568072 -209.243401) (xy 436.179224 -209.243401)
			(xy 436.171281 -209.296105) (xy 436.155571 -209.347035) (xy 436.132445 -209.395056) (xy 436.102421 -209.439093)
			(xy 436.066169 -209.478164) (xy 436.024498 -209.511395) (xy 435.97834 -209.538044) (xy 435.928726 -209.557516)
			(xy 435.876764 -209.569376) (xy 435.823614 -209.57336) (xy 435.770464 -209.569376) (xy 435.718502 -209.557516)
			(xy 435.668888 -209.538044) (xy 435.62273 -209.511395) (xy 435.581059 -209.478164) (xy 435.544807 -209.439093)
			(xy 435.514783 -209.395056) (xy 435.491657 -209.347035) (xy 435.475947 -209.296105) (xy 435.468004 -209.243401)
			(xy 425.191692 -209.243401) (xy 425.183749 -209.296105) (xy 425.168039 -209.347035) (xy 425.144913 -209.395056)
			(xy 425.114889 -209.439093) (xy 425.078637 -209.478164) (xy 425.036966 -209.511395) (xy 424.990808 -209.538044)
			(xy 424.941194 -209.557516) (xy 424.889232 -209.569376) (xy 424.836082 -209.57336) (xy 424.782932 -209.569376)
			(xy 424.73097 -209.557516) (xy 424.681356 -209.538044) (xy 424.635198 -209.511395) (xy 424.593527 -209.478164)
			(xy 424.557275 -209.439093) (xy 424.527251 -209.395056) (xy 424.504125 -209.347035) (xy 424.488415 -209.296105)
			(xy 424.480472 -209.243401) (xy 421.091624 -209.243401) (xy 421.083681 -209.296105) (xy 421.067971 -209.347035)
			(xy 421.044845 -209.395056) (xy 421.014821 -209.439093) (xy 420.978569 -209.478164) (xy 420.936898 -209.511395)
			(xy 420.89074 -209.538044) (xy 420.841126 -209.557516) (xy 420.789164 -209.569376) (xy 420.736014 -209.57336)
			(xy 420.682864 -209.569376) (xy 420.630902 -209.557516) (xy 420.581288 -209.538044) (xy 420.53513 -209.511395)
			(xy 420.493459 -209.478164) (xy 420.457207 -209.439093) (xy 420.427183 -209.395056) (xy 420.404057 -209.347035)
			(xy 420.388347 -209.296105) (xy 420.380404 -209.243401) (xy 405.54656 -209.243401) (xy 405.54656 -210.093285)
			(xy 420.380404 -210.093285) (xy 420.380404 -210.039987) (xy 420.388347 -209.987283) (xy 420.404057 -209.936353)
			(xy 420.427183 -209.888332) (xy 420.457207 -209.844295) (xy 420.493459 -209.805224) (xy 420.53513 -209.771993)
			(xy 420.581288 -209.745344) (xy 420.630902 -209.725872) (xy 420.682864 -209.714012) (xy 420.736014 -209.710029)
			(xy 420.789164 -209.714012) (xy 420.841126 -209.725872) (xy 420.89074 -209.745344) (xy 420.936898 -209.771993)
			(xy 420.978569 -209.805224) (xy 421.014821 -209.844295) (xy 421.044845 -209.888332) (xy 421.067971 -209.936353)
			(xy 421.083681 -209.987283) (xy 421.091624 -210.039987) (xy 421.092122 -210.066636) (xy 421.091624 -210.093285)
			(xy 435.468004 -210.093285) (xy 435.468004 -210.039987) (xy 435.475947 -209.987283) (xy 435.491657 -209.936353)
			(xy 435.514783 -209.888332) (xy 435.544807 -209.844295) (xy 435.581059 -209.805224) (xy 435.62273 -209.771993)
			(xy 435.668888 -209.745344) (xy 435.718502 -209.725872) (xy 435.770464 -209.714012) (xy 435.823614 -209.710029)
			(xy 435.876764 -209.714012) (xy 435.928726 -209.725872) (xy 435.97834 -209.745344) (xy 436.024498 -209.771993)
			(xy 436.066169 -209.805224) (xy 436.102421 -209.844295) (xy 436.132445 -209.888332) (xy 436.155571 -209.936353)
			(xy 436.171281 -209.987283) (xy 436.179224 -210.039987) (xy 436.179722 -210.066636) (xy 436.179224 -210.093285)
			(xy 436.171281 -210.145989) (xy 436.155571 -210.196919) (xy 436.132445 -210.24494) (xy 436.102421 -210.288977)
			(xy 436.066169 -210.328048) (xy 436.024498 -210.361279) (xy 435.97834 -210.387928) (xy 435.928726 -210.4074)
			(xy 435.876764 -210.41926) (xy 435.823614 -210.423244) (xy 435.770464 -210.41926) (xy 435.718502 -210.4074)
			(xy 435.668888 -210.387928) (xy 435.62273 -210.361279) (xy 435.581059 -210.328048) (xy 435.544807 -210.288977)
			(xy 435.514783 -210.24494) (xy 435.491657 -210.196919) (xy 435.475947 -210.145989) (xy 435.468004 -210.093285)
			(xy 421.091624 -210.093285) (xy 421.083681 -210.145989) (xy 421.067971 -210.196919) (xy 421.044845 -210.24494)
			(xy 421.014821 -210.288977) (xy 420.978569 -210.328048) (xy 420.936898 -210.361279) (xy 420.89074 -210.387928)
			(xy 420.841126 -210.4074) (xy 420.789164 -210.41926) (xy 420.736014 -210.423244) (xy 420.682864 -210.41926)
			(xy 420.630902 -210.4074) (xy 420.581288 -210.387928) (xy 420.53513 -210.361279) (xy 420.493459 -210.328048)
			(xy 420.457207 -210.288977) (xy 420.427183 -210.24494) (xy 420.404057 -210.196919) (xy 420.388347 -210.145989)
			(xy 420.380404 -210.093285) (xy 405.54656 -210.093285) (xy 405.54656 -210.943423) (xy 424.480472 -210.943423)
			(xy 424.480472 -210.890125) (xy 424.488415 -210.837421) (xy 424.504125 -210.786491) (xy 424.527251 -210.73847)
			(xy 424.557275 -210.694433) (xy 424.593527 -210.655362) (xy 424.635198 -210.622131) (xy 424.681356 -210.595482)
			(xy 424.73097 -210.57601) (xy 424.782932 -210.56415) (xy 424.836082 -210.560167) (xy 424.889232 -210.56415)
			(xy 424.941194 -210.57601) (xy 424.990808 -210.595482) (xy 425.036966 -210.622131) (xy 425.078637 -210.655362)
			(xy 425.114889 -210.694433) (xy 425.144913 -210.73847) (xy 425.168039 -210.786491) (xy 425.183749 -210.837421)
			(xy 425.191692 -210.890125) (xy 425.19219 -210.916774) (xy 425.191692 -210.943423) (xy 439.568072 -210.943423)
			(xy 439.568072 -210.890125) (xy 439.576015 -210.837421) (xy 439.591725 -210.786491) (xy 439.614851 -210.73847)
			(xy 439.644875 -210.694433) (xy 439.681127 -210.655362) (xy 439.722798 -210.622131) (xy 439.768956 -210.595482)
			(xy 439.81857 -210.57601) (xy 439.870532 -210.56415) (xy 439.923682 -210.560167) (xy 439.976832 -210.56415)
			(xy 440.028794 -210.57601) (xy 440.078408 -210.595482) (xy 440.124566 -210.622131) (xy 440.166237 -210.655362)
			(xy 440.202489 -210.694433) (xy 440.232513 -210.73847) (xy 440.255639 -210.786491) (xy 440.271349 -210.837421)
			(xy 440.279292 -210.890125) (xy 440.27979 -210.916774) (xy 440.279292 -210.943423) (xy 440.271349 -210.996127)
			(xy 440.255639 -211.047057) (xy 440.232513 -211.095078) (xy 440.202489 -211.139115) (xy 440.166237 -211.178186)
			(xy 440.124566 -211.211417) (xy 440.078408 -211.238066) (xy 440.028794 -211.257538) (xy 439.976832 -211.269398)
			(xy 439.923682 -211.273382) (xy 439.870532 -211.269398) (xy 439.81857 -211.257538) (xy 439.768956 -211.238066)
			(xy 439.722798 -211.211417) (xy 439.681127 -211.178186) (xy 439.644875 -211.139115) (xy 439.614851 -211.095078)
			(xy 439.591725 -211.047057) (xy 439.576015 -210.996127) (xy 439.568072 -210.943423) (xy 425.191692 -210.943423)
			(xy 425.183749 -210.996127) (xy 425.168039 -211.047057) (xy 425.144913 -211.095078) (xy 425.114889 -211.139115)
			(xy 425.078637 -211.178186) (xy 425.036966 -211.211417) (xy 424.990808 -211.238066) (xy 424.941194 -211.257538)
			(xy 424.889232 -211.269398) (xy 424.836082 -211.273382) (xy 424.782932 -211.269398) (xy 424.73097 -211.257538)
			(xy 424.681356 -211.238066) (xy 424.635198 -211.211417) (xy 424.593527 -211.178186) (xy 424.557275 -211.139115)
			(xy 424.527251 -211.095078) (xy 424.504125 -211.047057) (xy 424.488415 -210.996127) (xy 424.480472 -210.943423)
			(xy 405.54656 -210.943423) (xy 405.54656 -211.793307) (xy 420.380404 -211.793307) (xy 420.380404 -211.740009)
			(xy 420.388347 -211.687305) (xy 420.404057 -211.636375) (xy 420.427183 -211.588354) (xy 420.457207 -211.544317)
			(xy 420.493459 -211.505246) (xy 420.53513 -211.472015) (xy 420.581288 -211.445366) (xy 420.630902 -211.425894)
			(xy 420.682864 -211.414034) (xy 420.736014 -211.410051) (xy 420.789164 -211.414034) (xy 420.841126 -211.425894)
			(xy 420.89074 -211.445366) (xy 420.936898 -211.472015) (xy 420.978569 -211.505246) (xy 421.014821 -211.544317)
			(xy 421.044845 -211.588354) (xy 421.067971 -211.636375) (xy 421.083681 -211.687305) (xy 421.091624 -211.740009)
			(xy 421.092122 -211.766658) (xy 421.091624 -211.793307) (xy 435.468004 -211.793307) (xy 435.468004 -211.740009)
			(xy 435.475947 -211.687305) (xy 435.491657 -211.636375) (xy 435.514783 -211.588354) (xy 435.544807 -211.544317)
			(xy 435.581059 -211.505246) (xy 435.62273 -211.472015) (xy 435.668888 -211.445366) (xy 435.718502 -211.425894)
			(xy 435.770464 -211.414034) (xy 435.823614 -211.410051) (xy 435.876764 -211.414034) (xy 435.928726 -211.425894)
			(xy 435.97834 -211.445366) (xy 436.024498 -211.472015) (xy 436.066169 -211.505246) (xy 436.102421 -211.544317)
			(xy 436.132445 -211.588354) (xy 436.155571 -211.636375) (xy 436.171281 -211.687305) (xy 436.179224 -211.740009)
			(xy 436.179722 -211.766658) (xy 436.179224 -211.793307) (xy 436.171281 -211.846011) (xy 436.155571 -211.896941)
			(xy 436.132445 -211.944962) (xy 436.102421 -211.988999) (xy 436.066169 -212.02807) (xy 436.024498 -212.061301)
			(xy 435.97834 -212.08795) (xy 435.928726 -212.107422) (xy 435.876764 -212.119282) (xy 435.823614 -212.123266)
			(xy 435.770464 -212.119282) (xy 435.718502 -212.107422) (xy 435.668888 -212.08795) (xy 435.62273 -212.061301)
			(xy 435.581059 -212.02807) (xy 435.544807 -211.988999) (xy 435.514783 -211.944962) (xy 435.491657 -211.896941)
			(xy 435.475947 -211.846011) (xy 435.468004 -211.793307) (xy 421.091624 -211.793307) (xy 421.083681 -211.846011)
			(xy 421.067971 -211.896941) (xy 421.044845 -211.944962) (xy 421.014821 -211.988999) (xy 420.978569 -212.02807)
			(xy 420.936898 -212.061301) (xy 420.89074 -212.08795) (xy 420.841126 -212.107422) (xy 420.789164 -212.119282)
			(xy 420.736014 -212.123266) (xy 420.682864 -212.119282) (xy 420.630902 -212.107422) (xy 420.581288 -212.08795)
			(xy 420.53513 -212.061301) (xy 420.493459 -212.02807) (xy 420.457207 -211.988999) (xy 420.427183 -211.944962)
			(xy 420.404057 -211.896941) (xy 420.388347 -211.846011) (xy 420.380404 -211.793307) (xy 405.54656 -211.793307)
			(xy 405.54656 -212.643445) (xy 424.480472 -212.643445) (xy 424.480472 -212.590147) (xy 424.488415 -212.537443)
			(xy 424.504125 -212.486513) (xy 424.527251 -212.438492) (xy 424.557275 -212.394455) (xy 424.593527 -212.355384)
			(xy 424.635198 -212.322153) (xy 424.681356 -212.295504) (xy 424.73097 -212.276032) (xy 424.782932 -212.264172)
			(xy 424.836082 -212.260189) (xy 424.889232 -212.264172) (xy 424.941194 -212.276032) (xy 424.990808 -212.295504)
			(xy 425.036966 -212.322153) (xy 425.078637 -212.355384) (xy 425.114889 -212.394455) (xy 425.144913 -212.438492)
			(xy 425.168039 -212.486513) (xy 425.183749 -212.537443) (xy 425.191692 -212.590147) (xy 425.19219 -212.616796)
			(xy 425.191692 -212.643445) (xy 439.568072 -212.643445) (xy 439.568072 -212.590147) (xy 439.576015 -212.537443)
			(xy 439.591725 -212.486513) (xy 439.614851 -212.438492) (xy 439.644875 -212.394455) (xy 439.681127 -212.355384)
			(xy 439.722798 -212.322153) (xy 439.768956 -212.295504) (xy 439.81857 -212.276032) (xy 439.870532 -212.264172)
			(xy 439.923682 -212.260189) (xy 439.976832 -212.264172) (xy 440.028794 -212.276032) (xy 440.078408 -212.295504)
			(xy 440.124566 -212.322153) (xy 440.166237 -212.355384) (xy 440.202489 -212.394455) (xy 440.232513 -212.438492)
			(xy 440.255639 -212.486513) (xy 440.271349 -212.537443) (xy 440.279292 -212.590147) (xy 440.27979 -212.616796)
			(xy 440.279292 -212.643445) (xy 440.271349 -212.696149) (xy 440.255639 -212.747079) (xy 440.232513 -212.7951)
			(xy 440.202489 -212.839137) (xy 440.166237 -212.878208) (xy 440.124566 -212.911439) (xy 440.078408 -212.938088)
			(xy 440.028794 -212.95756) (xy 439.976832 -212.96942) (xy 439.923682 -212.973404) (xy 439.870532 -212.96942)
			(xy 439.81857 -212.95756) (xy 439.768956 -212.938088) (xy 439.722798 -212.911439) (xy 439.681127 -212.878208)
			(xy 439.644875 -212.839137) (xy 439.614851 -212.7951) (xy 439.591725 -212.747079) (xy 439.576015 -212.696149)
			(xy 439.568072 -212.643445) (xy 425.191692 -212.643445) (xy 425.183749 -212.696149) (xy 425.168039 -212.747079)
			(xy 425.144913 -212.7951) (xy 425.114889 -212.839137) (xy 425.078637 -212.878208) (xy 425.036966 -212.911439)
			(xy 424.990808 -212.938088) (xy 424.941194 -212.95756) (xy 424.889232 -212.96942) (xy 424.836082 -212.973404)
			(xy 424.782932 -212.96942) (xy 424.73097 -212.95756) (xy 424.681356 -212.938088) (xy 424.635198 -212.911439)
			(xy 424.593527 -212.878208) (xy 424.557275 -212.839137) (xy 424.527251 -212.7951) (xy 424.504125 -212.747079)
			(xy 424.488415 -212.696149) (xy 424.480472 -212.643445) (xy 405.54656 -212.643445) (xy 405.54656 -213.493329)
			(xy 420.380404 -213.493329) (xy 420.380404 -213.440031) (xy 420.388347 -213.387327) (xy 420.404057 -213.336397)
			(xy 420.427183 -213.288376) (xy 420.457207 -213.244339) (xy 420.493459 -213.205268) (xy 420.53513 -213.172037)
			(xy 420.581288 -213.145388) (xy 420.630902 -213.125916) (xy 420.682864 -213.114056) (xy 420.736014 -213.110073)
			(xy 420.789164 -213.114056) (xy 420.841126 -213.125916) (xy 420.89074 -213.145388) (xy 420.936898 -213.172037)
			(xy 420.978569 -213.205268) (xy 421.014821 -213.244339) (xy 421.044845 -213.288376) (xy 421.067971 -213.336397)
			(xy 421.083681 -213.387327) (xy 421.091624 -213.440031) (xy 421.092122 -213.46668) (xy 421.091624 -213.493329)
			(xy 435.468004 -213.493329) (xy 435.468004 -213.440031) (xy 435.475947 -213.387327) (xy 435.491657 -213.336397)
			(xy 435.514783 -213.288376) (xy 435.544807 -213.244339) (xy 435.581059 -213.205268) (xy 435.62273 -213.172037)
			(xy 435.668888 -213.145388) (xy 435.718502 -213.125916) (xy 435.770464 -213.114056) (xy 435.823614 -213.110073)
			(xy 435.876764 -213.114056) (xy 435.928726 -213.125916) (xy 435.97834 -213.145388) (xy 436.024498 -213.172037)
			(xy 436.066169 -213.205268) (xy 436.102421 -213.244339) (xy 436.132445 -213.288376) (xy 436.155571 -213.336397)
			(xy 436.171281 -213.387327) (xy 436.179224 -213.440031) (xy 436.179722 -213.46668) (xy 436.179224 -213.493329)
			(xy 436.171281 -213.546033) (xy 436.155571 -213.596963) (xy 436.132445 -213.644984) (xy 436.102421 -213.689021)
			(xy 436.066169 -213.728092) (xy 436.024498 -213.761323) (xy 435.97834 -213.787972) (xy 435.928726 -213.807444)
			(xy 435.876764 -213.819304) (xy 435.823614 -213.823288) (xy 435.770464 -213.819304) (xy 435.718502 -213.807444)
			(xy 435.668888 -213.787972) (xy 435.62273 -213.761323) (xy 435.581059 -213.728092) (xy 435.544807 -213.689021)
			(xy 435.514783 -213.644984) (xy 435.491657 -213.596963) (xy 435.475947 -213.546033) (xy 435.468004 -213.493329)
			(xy 421.091624 -213.493329) (xy 421.083681 -213.546033) (xy 421.067971 -213.596963) (xy 421.044845 -213.644984)
			(xy 421.014821 -213.689021) (xy 420.978569 -213.728092) (xy 420.936898 -213.761323) (xy 420.89074 -213.787972)
			(xy 420.841126 -213.807444) (xy 420.789164 -213.819304) (xy 420.736014 -213.823288) (xy 420.682864 -213.819304)
			(xy 420.630902 -213.807444) (xy 420.581288 -213.787972) (xy 420.53513 -213.761323) (xy 420.493459 -213.728092)
			(xy 420.457207 -213.689021) (xy 420.427183 -213.644984) (xy 420.404057 -213.596963) (xy 420.388347 -213.546033)
			(xy 420.380404 -213.493329) (xy 405.54656 -213.493329) (xy 405.54656 -214.343213) (xy 424.480472 -214.343213)
			(xy 424.480472 -214.289915) (xy 424.488415 -214.237211) (xy 424.504125 -214.186281) (xy 424.527251 -214.13826)
			(xy 424.557275 -214.094223) (xy 424.593527 -214.055152) (xy 424.635198 -214.021921) (xy 424.681356 -213.995272)
			(xy 424.73097 -213.9758) (xy 424.782932 -213.96394) (xy 424.836082 -213.959957) (xy 424.889232 -213.96394)
			(xy 424.941194 -213.9758) (xy 424.990808 -213.995272) (xy 425.036966 -214.021921) (xy 425.078637 -214.055152)
			(xy 425.114889 -214.094223) (xy 425.144913 -214.13826) (xy 425.168039 -214.186281) (xy 425.183749 -214.237211)
			(xy 425.191692 -214.289915) (xy 425.19219 -214.316564) (xy 425.191692 -214.343213) (xy 439.568072 -214.343213)
			(xy 439.568072 -214.289915) (xy 439.576015 -214.237211) (xy 439.591725 -214.186281) (xy 439.614851 -214.13826)
			(xy 439.644875 -214.094223) (xy 439.681127 -214.055152) (xy 439.722798 -214.021921) (xy 439.768956 -213.995272)
			(xy 439.81857 -213.9758) (xy 439.870532 -213.96394) (xy 439.923682 -213.959957) (xy 439.976832 -213.96394)
			(xy 440.028794 -213.9758) (xy 440.078408 -213.995272) (xy 440.124566 -214.021921) (xy 440.166237 -214.055152)
			(xy 440.202489 -214.094223) (xy 440.232513 -214.13826) (xy 440.255639 -214.186281) (xy 440.271349 -214.237211)
			(xy 440.279292 -214.289915) (xy 440.27979 -214.316564) (xy 440.279292 -214.343213) (xy 440.271349 -214.395917)
			(xy 440.255639 -214.446847) (xy 440.232513 -214.494868) (xy 440.202489 -214.538905) (xy 440.166237 -214.577976)
			(xy 440.124566 -214.611207) (xy 440.078408 -214.637856) (xy 440.028794 -214.657328) (xy 439.976832 -214.669188)
			(xy 439.923682 -214.673172) (xy 439.870532 -214.669188) (xy 439.81857 -214.657328) (xy 439.768956 -214.637856)
			(xy 439.722798 -214.611207) (xy 439.681127 -214.577976) (xy 439.644875 -214.538905) (xy 439.614851 -214.494868)
			(xy 439.591725 -214.446847) (xy 439.576015 -214.395917) (xy 439.568072 -214.343213) (xy 425.191692 -214.343213)
			(xy 425.183749 -214.395917) (xy 425.168039 -214.446847) (xy 425.144913 -214.494868) (xy 425.114889 -214.538905)
			(xy 425.078637 -214.577976) (xy 425.036966 -214.611207) (xy 424.990808 -214.637856) (xy 424.941194 -214.657328)
			(xy 424.889232 -214.669188) (xy 424.836082 -214.673172) (xy 424.782932 -214.669188) (xy 424.73097 -214.657328)
			(xy 424.681356 -214.637856) (xy 424.635198 -214.611207) (xy 424.593527 -214.577976) (xy 424.557275 -214.538905)
			(xy 424.527251 -214.494868) (xy 424.504125 -214.446847) (xy 424.488415 -214.395917) (xy 424.480472 -214.343213)
			(xy 405.54656 -214.343213) (xy 405.54656 -215.193351) (xy 420.380404 -215.193351) (xy 420.380404 -215.140053)
			(xy 420.388347 -215.087349) (xy 420.404057 -215.036419) (xy 420.427183 -214.988398) (xy 420.457207 -214.944361)
			(xy 420.493459 -214.90529) (xy 420.53513 -214.872059) (xy 420.581288 -214.84541) (xy 420.630902 -214.825938)
			(xy 420.682864 -214.814078) (xy 420.736014 -214.810095) (xy 420.789164 -214.814078) (xy 420.841126 -214.825938)
			(xy 420.89074 -214.84541) (xy 420.936898 -214.872059) (xy 420.978569 -214.90529) (xy 421.014821 -214.944361)
			(xy 421.044845 -214.988398) (xy 421.067971 -215.036419) (xy 421.083681 -215.087349) (xy 421.091624 -215.140053)
			(xy 421.092122 -215.166702) (xy 421.091624 -215.193351) (xy 435.468004 -215.193351) (xy 435.468004 -215.140053)
			(xy 435.475947 -215.087349) (xy 435.491657 -215.036419) (xy 435.514783 -214.988398) (xy 435.544807 -214.944361)
			(xy 435.581059 -214.90529) (xy 435.62273 -214.872059) (xy 435.668888 -214.84541) (xy 435.718502 -214.825938)
			(xy 435.770464 -214.814078) (xy 435.823614 -214.810095) (xy 435.876764 -214.814078) (xy 435.928726 -214.825938)
			(xy 435.97834 -214.84541) (xy 436.024498 -214.872059) (xy 436.066169 -214.90529) (xy 436.102421 -214.944361)
			(xy 436.132445 -214.988398) (xy 436.155571 -215.036419) (xy 436.171281 -215.087349) (xy 436.179224 -215.140053)
			(xy 436.179722 -215.166702) (xy 436.179224 -215.193351) (xy 436.171281 -215.246055) (xy 436.155571 -215.296985)
			(xy 436.132445 -215.345006) (xy 436.102421 -215.389043) (xy 436.066169 -215.428114) (xy 436.024498 -215.461345)
			(xy 435.97834 -215.487994) (xy 435.928726 -215.507466) (xy 435.876764 -215.519326) (xy 435.823614 -215.52331)
			(xy 435.770464 -215.519326) (xy 435.718502 -215.507466) (xy 435.668888 -215.487994) (xy 435.62273 -215.461345)
			(xy 435.581059 -215.428114) (xy 435.544807 -215.389043) (xy 435.514783 -215.345006) (xy 435.491657 -215.296985)
			(xy 435.475947 -215.246055) (xy 435.468004 -215.193351) (xy 421.091624 -215.193351) (xy 421.083681 -215.246055)
			(xy 421.067971 -215.296985) (xy 421.044845 -215.345006) (xy 421.014821 -215.389043) (xy 420.978569 -215.428114)
			(xy 420.936898 -215.461345) (xy 420.89074 -215.487994) (xy 420.841126 -215.507466) (xy 420.789164 -215.519326)
			(xy 420.736014 -215.52331) (xy 420.682864 -215.519326) (xy 420.630902 -215.507466) (xy 420.581288 -215.487994)
			(xy 420.53513 -215.461345) (xy 420.493459 -215.428114) (xy 420.457207 -215.389043) (xy 420.427183 -215.345006)
			(xy 420.404057 -215.296985) (xy 420.388347 -215.246055) (xy 420.380404 -215.193351) (xy 405.54656 -215.193351)
			(xy 405.54656 -215.708992) (xy 405.573992 -215.723216) (xy 405.596637 -215.735558) (xy 405.638134 -215.766179)
			(xy 405.674375 -215.802869) (xy 405.704481 -215.84474) (xy 405.727724 -215.890776) (xy 405.74354 -215.939862)
			(xy 405.751546 -215.990808) (xy 405.751547 -216.042379) (xy 405.751413 -216.043235) (xy 424.480472 -216.043235)
			(xy 424.480472 -215.989937) (xy 424.488415 -215.937233) (xy 424.504125 -215.886303) (xy 424.527251 -215.838282)
			(xy 424.557275 -215.794245) (xy 424.593527 -215.755174) (xy 424.635198 -215.721943) (xy 424.681356 -215.695294)
			(xy 424.73097 -215.675822) (xy 424.782932 -215.663962) (xy 424.836082 -215.659979) (xy 424.889232 -215.663962)
			(xy 424.941194 -215.675822) (xy 424.990808 -215.695294) (xy 425.036966 -215.721943) (xy 425.078637 -215.755174)
			(xy 425.114889 -215.794245) (xy 425.144913 -215.838282) (xy 425.168039 -215.886303) (xy 425.183749 -215.937233)
			(xy 425.191692 -215.989937) (xy 425.19219 -216.016586) (xy 425.191692 -216.043235) (xy 439.568072 -216.043235)
			(xy 439.568072 -215.989937) (xy 439.576015 -215.937233) (xy 439.591725 -215.886303) (xy 439.614851 -215.838282)
			(xy 439.644875 -215.794245) (xy 439.681127 -215.755174) (xy 439.722798 -215.721943) (xy 439.768956 -215.695294)
			(xy 439.81857 -215.675822) (xy 439.870532 -215.663962) (xy 439.923682 -215.659979) (xy 439.976832 -215.663962)
			(xy 440.028794 -215.675822) (xy 440.078408 -215.695294) (xy 440.124566 -215.721943) (xy 440.166237 -215.755174)
			(xy 440.202489 -215.794245) (xy 440.232513 -215.838282) (xy 440.255639 -215.886303) (xy 440.271349 -215.937233)
			(xy 440.279292 -215.989937) (xy 440.27979 -216.016586) (xy 440.279292 -216.043235) (xy 440.271349 -216.095939)
			(xy 440.255639 -216.146869) (xy 440.232513 -216.19489) (xy 440.202489 -216.238927) (xy 440.166237 -216.277998)
			(xy 440.124566 -216.311229) (xy 440.078408 -216.337878) (xy 440.028794 -216.35735) (xy 439.976832 -216.36921)
			(xy 439.923682 -216.373194) (xy 439.870532 -216.36921) (xy 439.81857 -216.35735) (xy 439.768956 -216.337878)
			(xy 439.722798 -216.311229) (xy 439.681127 -216.277998) (xy 439.644875 -216.238927) (xy 439.614851 -216.19489)
			(xy 439.591725 -216.146869) (xy 439.576015 -216.095939) (xy 439.568072 -216.043235) (xy 425.191692 -216.043235)
			(xy 425.183749 -216.095939) (xy 425.168039 -216.146869) (xy 425.144913 -216.19489) (xy 425.114889 -216.238927)
			(xy 425.078637 -216.277998) (xy 425.036966 -216.311229) (xy 424.990808 -216.337878) (xy 424.941194 -216.35735)
			(xy 424.889232 -216.36921) (xy 424.836082 -216.373194) (xy 424.782932 -216.36921) (xy 424.73097 -216.35735)
			(xy 424.681356 -216.337878) (xy 424.635198 -216.311229) (xy 424.593527 -216.277998) (xy 424.557275 -216.238927)
			(xy 424.527251 -216.19489) (xy 424.504125 -216.146869) (xy 424.488415 -216.095939) (xy 424.480472 -216.043235)
			(xy 405.751413 -216.043235) (xy 405.743543 -216.093325) (xy 405.727729 -216.142412) (xy 405.704488 -216.188449)
			(xy 405.674383 -216.230321) (xy 405.638144 -216.267013) (xy 405.596648 -216.297635) (xy 405.573992 -216.309956)
			(xy 405.54656 -216.32418) (xy 405.54656 -216.893373) (xy 420.380404 -216.893373) (xy 420.380404 -216.840075)
			(xy 420.388347 -216.787371) (xy 420.404057 -216.736441) (xy 420.427183 -216.68842) (xy 420.457207 -216.644383)
			(xy 420.493459 -216.605312) (xy 420.53513 -216.572081) (xy 420.581288 -216.545432) (xy 420.630902 -216.52596)
			(xy 420.682864 -216.5141) (xy 420.736014 -216.510117) (xy 420.789164 -216.5141) (xy 420.841126 -216.52596)
			(xy 420.89074 -216.545432) (xy 420.936898 -216.572081) (xy 420.978569 -216.605312) (xy 421.014821 -216.644383)
			(xy 421.044845 -216.68842) (xy 421.067971 -216.736441) (xy 421.083681 -216.787371) (xy 421.091624 -216.840075)
			(xy 421.092122 -216.866724) (xy 421.091624 -216.893373) (xy 435.468004 -216.893373) (xy 435.468004 -216.840075)
			(xy 435.475947 -216.787371) (xy 435.491657 -216.736441) (xy 435.514783 -216.68842) (xy 435.544807 -216.644383)
			(xy 435.581059 -216.605312) (xy 435.62273 -216.572081) (xy 435.668888 -216.545432) (xy 435.718502 -216.52596)
			(xy 435.770464 -216.5141) (xy 435.823614 -216.510117) (xy 435.876764 -216.5141) (xy 435.928726 -216.52596)
			(xy 435.97834 -216.545432) (xy 436.024498 -216.572081) (xy 436.066169 -216.605312) (xy 436.102421 -216.644383)
			(xy 436.132445 -216.68842) (xy 436.155571 -216.736441) (xy 436.171281 -216.787371) (xy 436.179224 -216.840075)
			(xy 436.179722 -216.866724) (xy 436.179224 -216.893373) (xy 436.171281 -216.946077) (xy 436.155571 -216.997007)
			(xy 436.132445 -217.045028) (xy 436.102421 -217.089065) (xy 436.066169 -217.128136) (xy 436.024498 -217.161367)
			(xy 435.97834 -217.188016) (xy 435.928726 -217.207488) (xy 435.876764 -217.219348) (xy 435.823614 -217.223332)
			(xy 435.770464 -217.219348) (xy 435.718502 -217.207488) (xy 435.668888 -217.188016) (xy 435.62273 -217.161367)
			(xy 435.581059 -217.128136) (xy 435.544807 -217.089065) (xy 435.514783 -217.045028) (xy 435.491657 -216.997007)
			(xy 435.475947 -216.946077) (xy 435.468004 -216.893373) (xy 421.091624 -216.893373) (xy 421.083681 -216.946077)
			(xy 421.067971 -216.997007) (xy 421.044845 -217.045028) (xy 421.014821 -217.089065) (xy 420.978569 -217.128136)
			(xy 420.936898 -217.161367) (xy 420.89074 -217.188016) (xy 420.841126 -217.207488) (xy 420.789164 -217.219348)
			(xy 420.736014 -217.223332) (xy 420.682864 -217.219348) (xy 420.630902 -217.207488) (xy 420.581288 -217.188016)
			(xy 420.53513 -217.161367) (xy 420.493459 -217.128136) (xy 420.457207 -217.089065) (xy 420.427183 -217.045028)
			(xy 420.404057 -216.997007) (xy 420.388347 -216.946077) (xy 420.380404 -216.893373) (xy 405.54656 -216.893373)
			(xy 405.54656 -217.40368) (xy 405.57577 -217.417396) (xy 405.598138 -217.428437) (xy 405.639558 -217.456232)
			(xy 405.676334 -217.489931) (xy 405.707633 -217.528771) (xy 405.732745 -217.57187) (xy 405.751099 -217.618252)
			(xy 405.762281 -217.666864) (xy 405.766037 -217.716603) (xy 405.764024 -217.743257) (xy 424.480472 -217.743257)
			(xy 424.480472 -217.689959) (xy 424.488415 -217.637255) (xy 424.504125 -217.586325) (xy 424.527251 -217.538304)
			(xy 424.557275 -217.494267) (xy 424.593527 -217.455196) (xy 424.635198 -217.421965) (xy 424.681356 -217.395316)
			(xy 424.73097 -217.375844) (xy 424.782932 -217.363984) (xy 424.836082 -217.360001) (xy 424.889232 -217.363984)
			(xy 424.941194 -217.375844) (xy 424.990808 -217.395316) (xy 425.036966 -217.421965) (xy 425.078637 -217.455196)
			(xy 425.114889 -217.494267) (xy 425.144913 -217.538304) (xy 425.168039 -217.586325) (xy 425.183749 -217.637255)
			(xy 425.191692 -217.689959) (xy 425.19219 -217.716608) (xy 425.191692 -217.743257) (xy 439.568072 -217.743257)
			(xy 439.568072 -217.689959) (xy 439.576015 -217.637255) (xy 439.591725 -217.586325) (xy 439.614851 -217.538304)
			(xy 439.644875 -217.494267) (xy 439.681127 -217.455196) (xy 439.722798 -217.421965) (xy 439.768956 -217.395316)
			(xy 439.81857 -217.375844) (xy 439.870532 -217.363984) (xy 439.923682 -217.360001) (xy 439.976832 -217.363984)
			(xy 440.028794 -217.375844) (xy 440.078408 -217.395316) (xy 440.124566 -217.421965) (xy 440.166237 -217.455196)
			(xy 440.202489 -217.494267) (xy 440.232513 -217.538304) (xy 440.255639 -217.586325) (xy 440.271349 -217.637255)
			(xy 440.279292 -217.689959) (xy 440.27979 -217.716608) (xy 440.279292 -217.743257) (xy 440.271349 -217.795961)
			(xy 440.255639 -217.846891) (xy 440.232513 -217.894912) (xy 440.202489 -217.938949) (xy 440.166237 -217.97802)
			(xy 440.124566 -218.011251) (xy 440.078408 -218.0379) (xy 440.028794 -218.057372) (xy 439.976832 -218.069232)
			(xy 439.923682 -218.073216) (xy 439.870532 -218.069232) (xy 439.81857 -218.057372) (xy 439.768956 -218.0379)
			(xy 439.722798 -218.011251) (xy 439.681127 -217.97802) (xy 439.644875 -217.938949) (xy 439.614851 -217.894912)
			(xy 439.591725 -217.846891) (xy 439.576015 -217.795961) (xy 439.568072 -217.743257) (xy 425.191692 -217.743257)
			(xy 425.183749 -217.795961) (xy 425.168039 -217.846891) (xy 425.144913 -217.894912) (xy 425.114889 -217.938949)
			(xy 425.078637 -217.97802) (xy 425.036966 -218.011251) (xy 424.990808 -218.0379) (xy 424.941194 -218.057372)
			(xy 424.889232 -218.069232) (xy 424.836082 -218.073216) (xy 424.782932 -218.069232) (xy 424.73097 -218.057372)
			(xy 424.681356 -218.0379) (xy 424.635198 -218.011251) (xy 424.593527 -217.97802) (xy 424.557275 -217.938949)
			(xy 424.527251 -217.894912) (xy 424.504125 -217.846891) (xy 424.488415 -217.795961) (xy 424.480472 -217.743257)
			(xy 405.764024 -217.743257) (xy 405.76228 -217.766343) (xy 405.751097 -217.814955) (xy 405.732742 -217.861336)
			(xy 405.707629 -217.904435) (xy 405.67633 -217.943274) (xy 405.639553 -217.976973) (xy 405.598133 -218.004767)
			(xy 405.57577 -218.01582) (xy 405.54656 -218.029536) (xy 405.54656 -218.593395) (xy 420.380404 -218.593395)
			(xy 420.380404 -218.540097) (xy 420.388347 -218.487393) (xy 420.404057 -218.436463) (xy 420.427183 -218.388442)
			(xy 420.457207 -218.344405) (xy 420.493459 -218.305334) (xy 420.53513 -218.272103) (xy 420.581288 -218.245454)
			(xy 420.630902 -218.225982) (xy 420.682864 -218.214122) (xy 420.736014 -218.210139) (xy 420.789164 -218.214122)
			(xy 420.841126 -218.225982) (xy 420.89074 -218.245454) (xy 420.936898 -218.272103) (xy 420.978569 -218.305334)
			(xy 421.014821 -218.344405) (xy 421.044845 -218.388442) (xy 421.067971 -218.436463) (xy 421.083681 -218.487393)
			(xy 421.091624 -218.540097) (xy 421.092122 -218.566746) (xy 421.091624 -218.593395) (xy 424.480472 -218.593395)
			(xy 424.480472 -218.540097) (xy 424.488415 -218.487393) (xy 424.504125 -218.436463) (xy 424.527251 -218.388442)
			(xy 424.557275 -218.344405) (xy 424.593527 -218.305334) (xy 424.635198 -218.272103) (xy 424.681356 -218.245454)
			(xy 424.73097 -218.225982) (xy 424.782932 -218.214122) (xy 424.836082 -218.210139) (xy 424.889232 -218.214122)
			(xy 424.941194 -218.225982) (xy 424.990808 -218.245454) (xy 425.036966 -218.272103) (xy 425.078637 -218.305334)
			(xy 425.114889 -218.344405) (xy 425.144913 -218.388442) (xy 425.168039 -218.436463) (xy 425.183749 -218.487393)
			(xy 425.191692 -218.540097) (xy 425.19219 -218.566746) (xy 425.191692 -218.593395) (xy 435.468004 -218.593395)
			(xy 435.468004 -218.540097) (xy 435.475947 -218.487393) (xy 435.491657 -218.436463) (xy 435.514783 -218.388442)
			(xy 435.544807 -218.344405) (xy 435.581059 -218.305334) (xy 435.62273 -218.272103) (xy 435.668888 -218.245454)
			(xy 435.718502 -218.225982) (xy 435.770464 -218.214122) (xy 435.823614 -218.210139) (xy 435.876764 -218.214122)
			(xy 435.928726 -218.225982) (xy 435.97834 -218.245454) (xy 436.024498 -218.272103) (xy 436.066169 -218.305334)
			(xy 436.102421 -218.344405) (xy 436.132445 -218.388442) (xy 436.155571 -218.436463) (xy 436.171281 -218.487393)
			(xy 436.179224 -218.540097) (xy 436.179722 -218.566746) (xy 436.179224 -218.593395) (xy 439.568072 -218.593395)
			(xy 439.568072 -218.540097) (xy 439.576015 -218.487393) (xy 439.591725 -218.436463) (xy 439.614851 -218.388442)
			(xy 439.644875 -218.344405) (xy 439.681127 -218.305334) (xy 439.722798 -218.272103) (xy 439.768956 -218.245454)
			(xy 439.81857 -218.225982) (xy 439.870532 -218.214122) (xy 439.923682 -218.210139) (xy 439.976832 -218.214122)
			(xy 440.028794 -218.225982) (xy 440.078408 -218.245454) (xy 440.124566 -218.272103) (xy 440.166237 -218.305334)
			(xy 440.202489 -218.344405) (xy 440.232513 -218.388442) (xy 440.255639 -218.436463) (xy 440.271349 -218.487393)
			(xy 440.279292 -218.540097) (xy 440.27979 -218.566746) (xy 440.279292 -218.593395) (xy 440.271349 -218.646099)
			(xy 440.255639 -218.697029) (xy 440.232513 -218.74505) (xy 440.202489 -218.789087) (xy 440.166237 -218.828158)
			(xy 440.124566 -218.861389) (xy 440.078408 -218.888038) (xy 440.028794 -218.90751) (xy 439.976832 -218.91937)
			(xy 439.923682 -218.923354) (xy 439.870532 -218.91937) (xy 439.81857 -218.90751) (xy 439.768956 -218.888038)
			(xy 439.722798 -218.861389) (xy 439.681127 -218.828158) (xy 439.644875 -218.789087) (xy 439.614851 -218.74505)
			(xy 439.591725 -218.697029) (xy 439.576015 -218.646099) (xy 439.568072 -218.593395) (xy 436.179224 -218.593395)
			(xy 436.171281 -218.646099) (xy 436.155571 -218.697029) (xy 436.132445 -218.74505) (xy 436.102421 -218.789087)
			(xy 436.066169 -218.828158) (xy 436.024498 -218.861389) (xy 435.97834 -218.888038) (xy 435.928726 -218.90751)
			(xy 435.876764 -218.91937) (xy 435.823614 -218.923354) (xy 435.770464 -218.91937) (xy 435.718502 -218.90751)
			(xy 435.668888 -218.888038) (xy 435.62273 -218.861389) (xy 435.581059 -218.828158) (xy 435.544807 -218.789087)
			(xy 435.514783 -218.74505) (xy 435.491657 -218.697029) (xy 435.475947 -218.646099) (xy 435.468004 -218.593395)
			(xy 425.191692 -218.593395) (xy 425.183749 -218.646099) (xy 425.168039 -218.697029) (xy 425.144913 -218.74505)
			(xy 425.114889 -218.789087) (xy 425.078637 -218.828158) (xy 425.036966 -218.861389) (xy 424.990808 -218.888038)
			(xy 424.941194 -218.90751) (xy 424.889232 -218.91937) (xy 424.836082 -218.923354) (xy 424.782932 -218.91937)
			(xy 424.73097 -218.90751) (xy 424.681356 -218.888038) (xy 424.635198 -218.861389) (xy 424.593527 -218.828158)
			(xy 424.557275 -218.789087) (xy 424.527251 -218.74505) (xy 424.504125 -218.697029) (xy 424.488415 -218.646099)
			(xy 424.480472 -218.593395) (xy 421.091624 -218.593395) (xy 421.083681 -218.646099) (xy 421.067971 -218.697029)
			(xy 421.044845 -218.74505) (xy 421.014821 -218.789087) (xy 420.978569 -218.828158) (xy 420.936898 -218.861389)
			(xy 420.89074 -218.888038) (xy 420.841126 -218.90751) (xy 420.789164 -218.91937) (xy 420.736014 -218.923354)
			(xy 420.682864 -218.91937) (xy 420.630902 -218.90751) (xy 420.581288 -218.888038) (xy 420.53513 -218.861389)
			(xy 420.493459 -218.828158) (xy 420.457207 -218.789087) (xy 420.427183 -218.74505) (xy 420.404057 -218.697029)
			(xy 420.388347 -218.646099) (xy 420.380404 -218.593395) (xy 405.54656 -218.593395) (xy 405.54656 -219.443279)
			(xy 420.380404 -219.443279) (xy 420.380404 -219.389981) (xy 420.388347 -219.337277) (xy 420.404057 -219.286347)
			(xy 420.427183 -219.238326) (xy 420.457207 -219.194289) (xy 420.493459 -219.155218) (xy 420.53513 -219.121987)
			(xy 420.581288 -219.095338) (xy 420.630902 -219.075866) (xy 420.682864 -219.064006) (xy 420.736014 -219.060023)
			(xy 420.789164 -219.064006) (xy 420.841126 -219.075866) (xy 420.89074 -219.095338) (xy 420.936898 -219.121987)
			(xy 420.978569 -219.155218) (xy 421.014821 -219.194289) (xy 421.044845 -219.238326) (xy 421.067971 -219.286347)
			(xy 421.083681 -219.337277) (xy 421.091624 -219.389981) (xy 421.092122 -219.41663) (xy 421.091624 -219.443279)
			(xy 435.468004 -219.443279) (xy 435.468004 -219.389981) (xy 435.475947 -219.337277) (xy 435.491657 -219.286347)
			(xy 435.514783 -219.238326) (xy 435.544807 -219.194289) (xy 435.581059 -219.155218) (xy 435.62273 -219.121987)
			(xy 435.668888 -219.095338) (xy 435.718502 -219.075866) (xy 435.770464 -219.064006) (xy 435.823614 -219.060023)
			(xy 435.876764 -219.064006) (xy 435.928726 -219.075866) (xy 435.97834 -219.095338) (xy 436.024498 -219.121987)
			(xy 436.066169 -219.155218) (xy 436.102421 -219.194289) (xy 436.132445 -219.238326) (xy 436.155571 -219.286347)
			(xy 436.171281 -219.337277) (xy 436.179224 -219.389981) (xy 436.179722 -219.41663) (xy 436.179224 -219.443279)
			(xy 436.171281 -219.495983) (xy 436.155571 -219.546913) (xy 436.132445 -219.594934) (xy 436.102421 -219.638971)
			(xy 436.066169 -219.678042) (xy 436.024498 -219.711273) (xy 435.97834 -219.737922) (xy 435.928726 -219.757394)
			(xy 435.876764 -219.769254) (xy 435.823614 -219.773238) (xy 435.770464 -219.769254) (xy 435.718502 -219.757394)
			(xy 435.668888 -219.737922) (xy 435.62273 -219.711273) (xy 435.581059 -219.678042) (xy 435.544807 -219.638971)
			(xy 435.514783 -219.594934) (xy 435.491657 -219.546913) (xy 435.475947 -219.495983) (xy 435.468004 -219.443279)
			(xy 421.091624 -219.443279) (xy 421.083681 -219.495983) (xy 421.067971 -219.546913) (xy 421.044845 -219.594934)
			(xy 421.014821 -219.638971) (xy 420.978569 -219.678042) (xy 420.936898 -219.711273) (xy 420.89074 -219.737922)
			(xy 420.841126 -219.757394) (xy 420.789164 -219.769254) (xy 420.736014 -219.773238) (xy 420.682864 -219.769254)
			(xy 420.630902 -219.757394) (xy 420.581288 -219.737922) (xy 420.53513 -219.711273) (xy 420.493459 -219.678042)
			(xy 420.457207 -219.638971) (xy 420.427183 -219.594934) (xy 420.404057 -219.546913) (xy 420.388347 -219.495983)
			(xy 420.380404 -219.443279) (xy 405.54656 -219.443279) (xy 405.54656 -220.293417) (xy 424.480472 -220.293417)
			(xy 424.480472 -220.240119) (xy 424.488415 -220.187415) (xy 424.504125 -220.136485) (xy 424.527251 -220.088464)
			(xy 424.557275 -220.044427) (xy 424.593527 -220.005356) (xy 424.635198 -219.972125) (xy 424.681356 -219.945476)
			(xy 424.73097 -219.926004) (xy 424.782932 -219.914144) (xy 424.836082 -219.910161) (xy 424.889232 -219.914144)
			(xy 424.941194 -219.926004) (xy 424.990808 -219.945476) (xy 425.036966 -219.972125) (xy 425.078637 -220.005356)
			(xy 425.114889 -220.044427) (xy 425.144913 -220.088464) (xy 425.168039 -220.136485) (xy 425.183749 -220.187415)
			(xy 425.191692 -220.240119) (xy 425.19219 -220.266768) (xy 425.191692 -220.293417) (xy 439.568072 -220.293417)
			(xy 439.568072 -220.240119) (xy 439.576015 -220.187415) (xy 439.591725 -220.136485) (xy 439.614851 -220.088464)
			(xy 439.644875 -220.044427) (xy 439.681127 -220.005356) (xy 439.722798 -219.972125) (xy 439.768956 -219.945476)
			(xy 439.81857 -219.926004) (xy 439.870532 -219.914144) (xy 439.923682 -219.910161) (xy 439.976832 -219.914144)
			(xy 440.028794 -219.926004) (xy 440.078408 -219.945476) (xy 440.124566 -219.972125) (xy 440.166237 -220.005356)
			(xy 440.202489 -220.044427) (xy 440.232513 -220.088464) (xy 440.255639 -220.136485) (xy 440.271349 -220.187415)
			(xy 440.279292 -220.240119) (xy 440.27979 -220.266768) (xy 440.279292 -220.293417) (xy 440.271349 -220.346121)
			(xy 440.255639 -220.397051) (xy 440.232513 -220.445072) (xy 440.202489 -220.489109) (xy 440.166237 -220.52818)
			(xy 440.124566 -220.561411) (xy 440.078408 -220.58806) (xy 440.028794 -220.607532) (xy 439.976832 -220.619392)
			(xy 439.923682 -220.623376) (xy 439.870532 -220.619392) (xy 439.81857 -220.607532) (xy 439.768956 -220.58806)
			(xy 439.722798 -220.561411) (xy 439.681127 -220.52818) (xy 439.644875 -220.489109) (xy 439.614851 -220.445072)
			(xy 439.591725 -220.397051) (xy 439.576015 -220.346121) (xy 439.568072 -220.293417) (xy 425.191692 -220.293417)
			(xy 425.183749 -220.346121) (xy 425.168039 -220.397051) (xy 425.144913 -220.445072) (xy 425.114889 -220.489109)
			(xy 425.078637 -220.52818) (xy 425.036966 -220.561411) (xy 424.990808 -220.58806) (xy 424.941194 -220.607532)
			(xy 424.889232 -220.619392) (xy 424.836082 -220.623376) (xy 424.782932 -220.619392) (xy 424.73097 -220.607532)
			(xy 424.681356 -220.58806) (xy 424.635198 -220.561411) (xy 424.593527 -220.52818) (xy 424.557275 -220.489109)
			(xy 424.527251 -220.445072) (xy 424.504125 -220.397051) (xy 424.488415 -220.346121) (xy 424.480472 -220.293417)
			(xy 405.54656 -220.293417) (xy 405.54656 -221.143301) (xy 420.380404 -221.143301) (xy 420.380404 -221.090003)
			(xy 420.388347 -221.037299) (xy 420.404057 -220.986369) (xy 420.427183 -220.938348) (xy 420.457207 -220.894311)
			(xy 420.493459 -220.85524) (xy 420.53513 -220.822009) (xy 420.581288 -220.79536) (xy 420.630902 -220.775888)
			(xy 420.682864 -220.764028) (xy 420.736014 -220.760045) (xy 420.789164 -220.764028) (xy 420.841126 -220.775888)
			(xy 420.89074 -220.79536) (xy 420.936898 -220.822009) (xy 420.978569 -220.85524) (xy 421.014821 -220.894311)
			(xy 421.044845 -220.938348) (xy 421.067971 -220.986369) (xy 421.083681 -221.037299) (xy 421.091624 -221.090003)
			(xy 421.092122 -221.116652) (xy 421.091624 -221.143301) (xy 435.468004 -221.143301) (xy 435.468004 -221.090003)
			(xy 435.475947 -221.037299) (xy 435.491657 -220.986369) (xy 435.514783 -220.938348) (xy 435.544807 -220.894311)
			(xy 435.581059 -220.85524) (xy 435.62273 -220.822009) (xy 435.668888 -220.79536) (xy 435.718502 -220.775888)
			(xy 435.770464 -220.764028) (xy 435.823614 -220.760045) (xy 435.876764 -220.764028) (xy 435.928726 -220.775888)
			(xy 435.97834 -220.79536) (xy 436.024498 -220.822009) (xy 436.066169 -220.85524) (xy 436.102421 -220.894311)
			(xy 436.132445 -220.938348) (xy 436.155571 -220.986369) (xy 436.171281 -221.037299) (xy 436.179224 -221.090003)
			(xy 436.179722 -221.116652) (xy 436.179224 -221.143301) (xy 436.171281 -221.196005) (xy 436.155571 -221.246935)
			(xy 436.132445 -221.294956) (xy 436.102421 -221.338993) (xy 436.066169 -221.378064) (xy 436.024498 -221.411295)
			(xy 435.97834 -221.437944) (xy 435.928726 -221.457416) (xy 435.876764 -221.469276) (xy 435.823614 -221.47326)
			(xy 435.770464 -221.469276) (xy 435.718502 -221.457416) (xy 435.668888 -221.437944) (xy 435.62273 -221.411295)
			(xy 435.581059 -221.378064) (xy 435.544807 -221.338993) (xy 435.514783 -221.294956) (xy 435.491657 -221.246935)
			(xy 435.475947 -221.196005) (xy 435.468004 -221.143301) (xy 421.091624 -221.143301) (xy 421.083681 -221.196005)
			(xy 421.067971 -221.246935) (xy 421.044845 -221.294956) (xy 421.014821 -221.338993) (xy 420.978569 -221.378064)
			(xy 420.936898 -221.411295) (xy 420.89074 -221.437944) (xy 420.841126 -221.457416) (xy 420.789164 -221.469276)
			(xy 420.736014 -221.47326) (xy 420.682864 -221.469276) (xy 420.630902 -221.457416) (xy 420.581288 -221.437944)
			(xy 420.53513 -221.411295) (xy 420.493459 -221.378064) (xy 420.457207 -221.338993) (xy 420.427183 -221.294956)
			(xy 420.404057 -221.246935) (xy 420.388347 -221.196005) (xy 420.380404 -221.143301) (xy 405.54656 -221.143301)
			(xy 405.54656 -221.993439) (xy 424.480472 -221.993439) (xy 424.480472 -221.940141) (xy 424.488415 -221.887437)
			(xy 424.504125 -221.836507) (xy 424.527251 -221.788486) (xy 424.557275 -221.744449) (xy 424.593527 -221.705378)
			(xy 424.635198 -221.672147) (xy 424.681356 -221.645498) (xy 424.73097 -221.626026) (xy 424.782932 -221.614166)
			(xy 424.836082 -221.610183) (xy 424.889232 -221.614166) (xy 424.941194 -221.626026) (xy 424.990808 -221.645498)
			(xy 425.036966 -221.672147) (xy 425.078637 -221.705378) (xy 425.114889 -221.744449) (xy 425.144913 -221.788486)
			(xy 425.168039 -221.836507) (xy 425.183749 -221.887437) (xy 425.191692 -221.940141) (xy 425.19219 -221.96679)
			(xy 425.191692 -221.993439) (xy 439.568072 -221.993439) (xy 439.568072 -221.940141) (xy 439.576015 -221.887437)
			(xy 439.591725 -221.836507) (xy 439.614851 -221.788486) (xy 439.644875 -221.744449) (xy 439.681127 -221.705378)
			(xy 439.722798 -221.672147) (xy 439.768956 -221.645498) (xy 439.81857 -221.626026) (xy 439.870532 -221.614166)
			(xy 439.923682 -221.610183) (xy 439.976832 -221.614166) (xy 440.028794 -221.626026) (xy 440.078408 -221.645498)
			(xy 440.124566 -221.672147) (xy 440.166237 -221.705378) (xy 440.202489 -221.744449) (xy 440.232513 -221.788486)
			(xy 440.255639 -221.836507) (xy 440.271349 -221.887437) (xy 440.279292 -221.940141) (xy 440.27979 -221.96679)
			(xy 440.279292 -221.993439) (xy 440.271349 -222.046143) (xy 440.255639 -222.097073) (xy 440.232513 -222.145094)
			(xy 440.202489 -222.189131) (xy 440.166237 -222.228202) (xy 440.124566 -222.261433) (xy 440.078408 -222.288082)
			(xy 440.028794 -222.307554) (xy 439.976832 -222.319414) (xy 439.923682 -222.323398) (xy 439.870532 -222.319414)
			(xy 439.81857 -222.307554) (xy 439.768956 -222.288082) (xy 439.722798 -222.261433) (xy 439.681127 -222.228202)
			(xy 439.644875 -222.189131) (xy 439.614851 -222.145094) (xy 439.591725 -222.097073) (xy 439.576015 -222.046143)
			(xy 439.568072 -221.993439) (xy 425.191692 -221.993439) (xy 425.183749 -222.046143) (xy 425.168039 -222.097073)
			(xy 425.144913 -222.145094) (xy 425.114889 -222.189131) (xy 425.078637 -222.228202) (xy 425.036966 -222.261433)
			(xy 424.990808 -222.288082) (xy 424.941194 -222.307554) (xy 424.889232 -222.319414) (xy 424.836082 -222.323398)
			(xy 424.782932 -222.319414) (xy 424.73097 -222.307554) (xy 424.681356 -222.288082) (xy 424.635198 -222.261433)
			(xy 424.593527 -222.228202) (xy 424.557275 -222.189131) (xy 424.527251 -222.145094) (xy 424.504125 -222.097073)
			(xy 424.488415 -222.046143) (xy 424.480472 -221.993439) (xy 405.54656 -221.993439) (xy 405.54656 -222.843323)
			(xy 420.380404 -222.843323) (xy 420.380404 -222.790025) (xy 420.388347 -222.737321) (xy 420.404057 -222.686391)
			(xy 420.427183 -222.63837) (xy 420.457207 -222.594333) (xy 420.493459 -222.555262) (xy 420.53513 -222.522031)
			(xy 420.581288 -222.495382) (xy 420.630902 -222.47591) (xy 420.682864 -222.46405) (xy 420.736014 -222.460067)
			(xy 420.789164 -222.46405) (xy 420.841126 -222.47591) (xy 420.89074 -222.495382) (xy 420.936898 -222.522031)
			(xy 420.978569 -222.555262) (xy 421.014821 -222.594333) (xy 421.044845 -222.63837) (xy 421.067971 -222.686391)
			(xy 421.083681 -222.737321) (xy 421.091624 -222.790025) (xy 421.092122 -222.816674) (xy 421.091624 -222.843323)
			(xy 435.468004 -222.843323) (xy 435.468004 -222.790025) (xy 435.475947 -222.737321) (xy 435.491657 -222.686391)
			(xy 435.514783 -222.63837) (xy 435.544807 -222.594333) (xy 435.581059 -222.555262) (xy 435.62273 -222.522031)
			(xy 435.668888 -222.495382) (xy 435.718502 -222.47591) (xy 435.770464 -222.46405) (xy 435.823614 -222.460067)
			(xy 435.876764 -222.46405) (xy 435.928726 -222.47591) (xy 435.97834 -222.495382) (xy 436.024498 -222.522031)
			(xy 436.066169 -222.555262) (xy 436.102421 -222.594333) (xy 436.132445 -222.63837) (xy 436.155571 -222.686391)
			(xy 436.171281 -222.737321) (xy 436.179224 -222.790025) (xy 436.179722 -222.816674) (xy 436.179224 -222.843323)
			(xy 436.171281 -222.896027) (xy 436.155571 -222.946957) (xy 436.132445 -222.994978) (xy 436.102421 -223.039015)
			(xy 436.066169 -223.078086) (xy 436.024498 -223.111317) (xy 435.97834 -223.137966) (xy 435.928726 -223.157438)
			(xy 435.876764 -223.169298) (xy 435.823614 -223.173282) (xy 435.770464 -223.169298) (xy 435.718502 -223.157438)
			(xy 435.668888 -223.137966) (xy 435.62273 -223.111317) (xy 435.581059 -223.078086) (xy 435.544807 -223.039015)
			(xy 435.514783 -222.994978) (xy 435.491657 -222.946957) (xy 435.475947 -222.896027) (xy 435.468004 -222.843323)
			(xy 421.091624 -222.843323) (xy 421.083681 -222.896027) (xy 421.067971 -222.946957) (xy 421.044845 -222.994978)
			(xy 421.014821 -223.039015) (xy 420.978569 -223.078086) (xy 420.936898 -223.111317) (xy 420.89074 -223.137966)
			(xy 420.841126 -223.157438) (xy 420.789164 -223.169298) (xy 420.736014 -223.173282) (xy 420.682864 -223.169298)
			(xy 420.630902 -223.157438) (xy 420.581288 -223.137966) (xy 420.53513 -223.111317) (xy 420.493459 -223.078086)
			(xy 420.457207 -223.039015) (xy 420.427183 -222.994978) (xy 420.404057 -222.946957) (xy 420.388347 -222.896027)
			(xy 420.380404 -222.843323) (xy 405.54656 -222.843323) (xy 405.54656 -223.693207) (xy 409.367472 -223.693207)
			(xy 409.367472 -223.639909) (xy 409.375415 -223.587205) (xy 409.391125 -223.536275) (xy 409.414251 -223.488254)
			(xy 409.444275 -223.444217) (xy 409.480527 -223.405146) (xy 409.522198 -223.371915) (xy 409.568356 -223.345266)
			(xy 409.61797 -223.325794) (xy 409.669932 -223.313934) (xy 409.723082 -223.309951) (xy 409.776232 -223.313934)
			(xy 409.828194 -223.325794) (xy 409.877808 -223.345266) (xy 409.923966 -223.371915) (xy 409.965637 -223.405146)
			(xy 410.001889 -223.444217) (xy 410.031913 -223.488254) (xy 410.055039 -223.536275) (xy 410.070749 -223.587205)
			(xy 410.078692 -223.639909) (xy 410.07919 -223.666558) (xy 410.078692 -223.693207) (xy 424.480472 -223.693207)
			(xy 424.480472 -223.639909) (xy 424.488415 -223.587205) (xy 424.504125 -223.536275) (xy 424.527251 -223.488254)
			(xy 424.557275 -223.444217) (xy 424.593527 -223.405146) (xy 424.635198 -223.371915) (xy 424.681356 -223.345266)
			(xy 424.73097 -223.325794) (xy 424.782932 -223.313934) (xy 424.836082 -223.309951) (xy 424.889232 -223.313934)
			(xy 424.941194 -223.325794) (xy 424.990808 -223.345266) (xy 425.036966 -223.371915) (xy 425.078637 -223.405146)
			(xy 425.114889 -223.444217) (xy 425.144913 -223.488254) (xy 425.168039 -223.536275) (xy 425.183749 -223.587205)
			(xy 425.191692 -223.639909) (xy 425.19219 -223.666558) (xy 425.191692 -223.693207) (xy 439.568072 -223.693207)
			(xy 439.568072 -223.639909) (xy 439.576015 -223.587205) (xy 439.591725 -223.536275) (xy 439.614851 -223.488254)
			(xy 439.644875 -223.444217) (xy 439.681127 -223.405146) (xy 439.722798 -223.371915) (xy 439.768956 -223.345266)
			(xy 439.81857 -223.325794) (xy 439.870532 -223.313934) (xy 439.923682 -223.309951) (xy 439.976832 -223.313934)
			(xy 440.028794 -223.325794) (xy 440.078408 -223.345266) (xy 440.124566 -223.371915) (xy 440.166237 -223.405146)
			(xy 440.202489 -223.444217) (xy 440.232513 -223.488254) (xy 440.255639 -223.536275) (xy 440.271349 -223.587205)
			(xy 440.279292 -223.639909) (xy 440.27979 -223.666558) (xy 440.279292 -223.693207) (xy 440.271349 -223.745911)
			(xy 440.255639 -223.796841) (xy 440.232513 -223.844862) (xy 440.202489 -223.888899) (xy 440.166237 -223.92797)
			(xy 440.124566 -223.961201) (xy 440.078408 -223.98785) (xy 440.028794 -224.007322) (xy 439.976832 -224.019182)
			(xy 439.923682 -224.023166) (xy 439.870532 -224.019182) (xy 439.81857 -224.007322) (xy 439.768956 -223.98785)
			(xy 439.722798 -223.961201) (xy 439.681127 -223.92797) (xy 439.644875 -223.888899) (xy 439.614851 -223.844862)
			(xy 439.591725 -223.796841) (xy 439.576015 -223.745911) (xy 439.568072 -223.693207) (xy 425.191692 -223.693207)
			(xy 425.183749 -223.745911) (xy 425.168039 -223.796841) (xy 425.144913 -223.844862) (xy 425.114889 -223.888899)
			(xy 425.078637 -223.92797) (xy 425.036966 -223.961201) (xy 424.990808 -223.98785) (xy 424.941194 -224.007322)
			(xy 424.889232 -224.019182) (xy 424.836082 -224.023166) (xy 424.782932 -224.019182) (xy 424.73097 -224.007322)
			(xy 424.681356 -223.98785) (xy 424.635198 -223.961201) (xy 424.593527 -223.92797) (xy 424.557275 -223.888899)
			(xy 424.527251 -223.844862) (xy 424.504125 -223.796841) (xy 424.488415 -223.745911) (xy 424.480472 -223.693207)
			(xy 410.078692 -223.693207) (xy 410.070749 -223.745911) (xy 410.055039 -223.796841) (xy 410.031913 -223.844862)
			(xy 410.001889 -223.888899) (xy 409.965637 -223.92797) (xy 409.923966 -223.961201) (xy 409.877808 -223.98785)
			(xy 409.828194 -224.007322) (xy 409.776232 -224.019182) (xy 409.723082 -224.023166) (xy 409.669932 -224.019182)
			(xy 409.61797 -224.007322) (xy 409.568356 -223.98785) (xy 409.522198 -223.961201) (xy 409.480527 -223.92797)
			(xy 409.444275 -223.888899) (xy 409.414251 -223.844862) (xy 409.391125 -223.796841) (xy 409.375415 -223.745911)
			(xy 409.367472 -223.693207) (xy 405.54656 -223.693207) (xy 405.54656 -224.05975) (xy 405.547094 -224.075183)
			(xy 405.556305 -224.104642) (xy 405.573901 -224.13) (xy 405.598272 -224.148939) (xy 405.627191 -224.159728)
			(xy 405.642572 -224.161096) (xy 405.66951 -224.163079) (xy 405.722374 -224.174157) (xy 405.772959 -224.19309)
			(xy 405.820105 -224.219445) (xy 405.862731 -224.252617) (xy 405.899859 -224.291844) (xy 405.930638 -224.336229)
			(xy 405.954362 -224.384752) (xy 405.970486 -224.436301) (xy 405.978642 -224.489694) (xy 405.978642 -224.543345)
			(xy 420.380404 -224.543345) (xy 420.380404 -224.490047) (xy 420.388347 -224.437343) (xy 420.404057 -224.386413)
			(xy 420.427183 -224.338392) (xy 420.457207 -224.294355) (xy 420.493459 -224.255284) (xy 420.53513 -224.222053)
			(xy 420.581288 -224.195404) (xy 420.630902 -224.175932) (xy 420.682864 -224.164072) (xy 420.736014 -224.160089)
			(xy 420.789164 -224.164072) (xy 420.841126 -224.175932) (xy 420.89074 -224.195404) (xy 420.936898 -224.222053)
			(xy 420.978569 -224.255284) (xy 421.014821 -224.294355) (xy 421.044845 -224.338392) (xy 421.067971 -224.386413)
			(xy 421.083681 -224.437343) (xy 421.091624 -224.490047) (xy 421.092122 -224.516696) (xy 421.091624 -224.543345)
			(xy 435.468004 -224.543345) (xy 435.468004 -224.490047) (xy 435.475947 -224.437343) (xy 435.491657 -224.386413)
			(xy 435.514783 -224.338392) (xy 435.544807 -224.294355) (xy 435.581059 -224.255284) (xy 435.62273 -224.222053)
			(xy 435.668888 -224.195404) (xy 435.718502 -224.175932) (xy 435.770464 -224.164072) (xy 435.823614 -224.160089)
			(xy 435.876764 -224.164072) (xy 435.928726 -224.175932) (xy 435.97834 -224.195404) (xy 436.024498 -224.222053)
			(xy 436.066169 -224.255284) (xy 436.102421 -224.294355) (xy 436.132445 -224.338392) (xy 436.155571 -224.386413)
			(xy 436.171281 -224.437343) (xy 436.179224 -224.490047) (xy 436.179722 -224.516696) (xy 436.179224 -224.543345)
			(xy 436.171281 -224.596049) (xy 436.155571 -224.646979) (xy 436.132445 -224.695) (xy 436.102421 -224.739037)
			(xy 436.066169 -224.778108) (xy 436.024498 -224.811339) (xy 435.97834 -224.837988) (xy 435.928726 -224.85746)
			(xy 435.876764 -224.86932) (xy 435.823614 -224.873304) (xy 435.770464 -224.86932) (xy 435.718502 -224.85746)
			(xy 435.668888 -224.837988) (xy 435.62273 -224.811339) (xy 435.581059 -224.778108) (xy 435.544807 -224.739037)
			(xy 435.514783 -224.695) (xy 435.491657 -224.646979) (xy 435.475947 -224.596049) (xy 435.468004 -224.543345)
			(xy 421.091624 -224.543345) (xy 421.083681 -224.596049) (xy 421.067971 -224.646979) (xy 421.044845 -224.695)
			(xy 421.014821 -224.739037) (xy 420.978569 -224.778108) (xy 420.936898 -224.811339) (xy 420.89074 -224.837988)
			(xy 420.841126 -224.85746) (xy 420.789164 -224.86932) (xy 420.736014 -224.873304) (xy 420.682864 -224.86932)
			(xy 420.630902 -224.85746) (xy 420.581288 -224.837988) (xy 420.53513 -224.811339) (xy 420.493459 -224.778108)
			(xy 420.457207 -224.739037) (xy 420.427183 -224.695) (xy 420.404057 -224.646979) (xy 420.388347 -224.596049)
			(xy 420.380404 -224.543345) (xy 405.978642 -224.543345) (xy 405.978642 -224.543706) (xy 405.970486 -224.597099)
			(xy 405.954362 -224.648648) (xy 405.930638 -224.697171) (xy 405.899859 -224.741555) (xy 405.862731 -224.780783)
			(xy 405.820105 -224.813955) (xy 405.772959 -224.840309) (xy 405.722374 -224.859243) (xy 405.66951 -224.870321)
			(xy 405.642572 -224.872296) (xy 405.627199 -224.873686) (xy 405.598303 -224.884501) (xy 405.573947 -224.903441)
			(xy 405.556346 -224.928781) (xy 405.547101 -224.958216) (xy 405.54656 -224.973642) (xy 405.54656 -225.393229)
			(xy 409.367472 -225.393229) (xy 409.367472 -225.339931) (xy 409.375415 -225.287227) (xy 409.391125 -225.236297)
			(xy 409.414251 -225.188276) (xy 409.444275 -225.144239) (xy 409.480527 -225.105168) (xy 409.522198 -225.071937)
			(xy 409.568356 -225.045288) (xy 409.61797 -225.025816) (xy 409.669932 -225.013956) (xy 409.723082 -225.009973)
			(xy 409.776232 -225.013956) (xy 409.828194 -225.025816) (xy 409.877808 -225.045288) (xy 409.923966 -225.071937)
			(xy 409.965637 -225.105168) (xy 410.001889 -225.144239) (xy 410.031913 -225.188276) (xy 410.055039 -225.236297)
			(xy 410.070749 -225.287227) (xy 410.078692 -225.339931) (xy 410.07919 -225.36658) (xy 410.078692 -225.393229)
			(xy 424.480472 -225.393229) (xy 424.480472 -225.339931) (xy 424.488415 -225.287227) (xy 424.504125 -225.236297)
			(xy 424.527251 -225.188276) (xy 424.557275 -225.144239) (xy 424.593527 -225.105168) (xy 424.635198 -225.071937)
			(xy 424.681356 -225.045288) (xy 424.73097 -225.025816) (xy 424.782932 -225.013956) (xy 424.836082 -225.009973)
			(xy 424.889232 -225.013956) (xy 424.941194 -225.025816) (xy 424.990808 -225.045288) (xy 425.036966 -225.071937)
			(xy 425.078637 -225.105168) (xy 425.114889 -225.144239) (xy 425.144913 -225.188276) (xy 425.168039 -225.236297)
			(xy 425.183749 -225.287227) (xy 425.191692 -225.339931) (xy 425.19219 -225.36658) (xy 425.191692 -225.393229)
			(xy 439.568072 -225.393229) (xy 439.568072 -225.339931) (xy 439.576015 -225.287227) (xy 439.591725 -225.236297)
			(xy 439.614851 -225.188276) (xy 439.644875 -225.144239) (xy 439.681127 -225.105168) (xy 439.722798 -225.071937)
			(xy 439.768956 -225.045288) (xy 439.81857 -225.025816) (xy 439.870532 -225.013956) (xy 439.923682 -225.009973)
			(xy 439.976832 -225.013956) (xy 440.028794 -225.025816) (xy 440.078408 -225.045288) (xy 440.124566 -225.071937)
			(xy 440.166237 -225.105168) (xy 440.202489 -225.144239) (xy 440.232513 -225.188276) (xy 440.255639 -225.236297)
			(xy 440.271349 -225.287227) (xy 440.279292 -225.339931) (xy 440.27979 -225.36658) (xy 440.279292 -225.393229)
			(xy 440.271349 -225.445933) (xy 440.255639 -225.496863) (xy 440.232513 -225.544884) (xy 440.202489 -225.588921)
			(xy 440.166237 -225.627992) (xy 440.124566 -225.661223) (xy 440.078408 -225.687872) (xy 440.028794 -225.707344)
			(xy 439.976832 -225.719204) (xy 439.923682 -225.723188) (xy 439.870532 -225.719204) (xy 439.81857 -225.707344)
			(xy 439.768956 -225.687872) (xy 439.722798 -225.661223) (xy 439.681127 -225.627992) (xy 439.644875 -225.588921)
			(xy 439.614851 -225.544884) (xy 439.591725 -225.496863) (xy 439.576015 -225.445933) (xy 439.568072 -225.393229)
			(xy 425.191692 -225.393229) (xy 425.183749 -225.445933) (xy 425.168039 -225.496863) (xy 425.144913 -225.544884)
			(xy 425.114889 -225.588921) (xy 425.078637 -225.627992) (xy 425.036966 -225.661223) (xy 424.990808 -225.687872)
			(xy 424.941194 -225.707344) (xy 424.889232 -225.719204) (xy 424.836082 -225.723188) (xy 424.782932 -225.719204)
			(xy 424.73097 -225.707344) (xy 424.681356 -225.687872) (xy 424.635198 -225.661223) (xy 424.593527 -225.627992)
			(xy 424.557275 -225.588921) (xy 424.527251 -225.544884) (xy 424.504125 -225.496863) (xy 424.488415 -225.445933)
			(xy 424.480472 -225.393229) (xy 410.078692 -225.393229) (xy 410.070749 -225.445933) (xy 410.055039 -225.496863)
			(xy 410.031913 -225.544884) (xy 410.001889 -225.588921) (xy 409.965637 -225.627992) (xy 409.923966 -225.661223)
			(xy 409.877808 -225.687872) (xy 409.828194 -225.707344) (xy 409.776232 -225.719204) (xy 409.723082 -225.723188)
			(xy 409.669932 -225.719204) (xy 409.61797 -225.707344) (xy 409.568356 -225.687872) (xy 409.522198 -225.661223)
			(xy 409.480527 -225.627992) (xy 409.444275 -225.588921) (xy 409.414251 -225.544884) (xy 409.391125 -225.496863)
			(xy 409.375415 -225.445933) (xy 409.367472 -225.393229) (xy 405.54656 -225.393229) (xy 405.54656 -225.759772)
			(xy 405.547097 -225.775203) (xy 405.556312 -225.804656) (xy 405.573909 -225.830008) (xy 405.598279 -225.848943)
			(xy 405.627194 -225.859729) (xy 405.642572 -225.861118) (xy 405.669508 -225.863101) (xy 405.722369 -225.874179)
			(xy 405.772951 -225.893111) (xy 405.820094 -225.919464) (xy 405.862717 -225.952634) (xy 405.899842 -225.991859)
			(xy 405.930619 -226.036241) (xy 405.954342 -226.084761) (xy 405.970465 -226.136307) (xy 405.97862 -226.189697)
			(xy 405.97862 -226.243367) (xy 420.380404 -226.243367) (xy 420.380404 -226.190069) (xy 420.388347 -226.137365)
			(xy 420.404057 -226.086435) (xy 420.427183 -226.038414) (xy 420.457207 -225.994377) (xy 420.493459 -225.955306)
			(xy 420.53513 -225.922075) (xy 420.581288 -225.895426) (xy 420.630902 -225.875954) (xy 420.682864 -225.864094)
			(xy 420.736014 -225.860111) (xy 420.789164 -225.864094) (xy 420.841126 -225.875954) (xy 420.89074 -225.895426)
			(xy 420.936898 -225.922075) (xy 420.978569 -225.955306) (xy 421.014821 -225.994377) (xy 421.044845 -226.038414)
			(xy 421.067971 -226.086435) (xy 421.083681 -226.137365) (xy 421.091624 -226.190069) (xy 421.092122 -226.216718)
			(xy 421.091624 -226.243367) (xy 435.468004 -226.243367) (xy 435.468004 -226.190069) (xy 435.475947 -226.137365)
			(xy 435.491657 -226.086435) (xy 435.514783 -226.038414) (xy 435.544807 -225.994377) (xy 435.581059 -225.955306)
			(xy 435.62273 -225.922075) (xy 435.668888 -225.895426) (xy 435.718502 -225.875954) (xy 435.770464 -225.864094)
			(xy 435.823614 -225.860111) (xy 435.876764 -225.864094) (xy 435.928726 -225.875954) (xy 435.97834 -225.895426)
			(xy 436.024498 -225.922075) (xy 436.066169 -225.955306) (xy 436.102421 -225.994377) (xy 436.132445 -226.038414)
			(xy 436.155571 -226.086435) (xy 436.171281 -226.137365) (xy 436.179224 -226.190069) (xy 436.179722 -226.216718)
			(xy 436.179224 -226.243367) (xy 436.171281 -226.296071) (xy 436.155571 -226.347001) (xy 436.132445 -226.395022)
			(xy 436.102421 -226.439059) (xy 436.066169 -226.47813) (xy 436.024498 -226.511361) (xy 435.97834 -226.53801)
			(xy 435.928726 -226.557482) (xy 435.876764 -226.569342) (xy 435.823614 -226.573326) (xy 435.770464 -226.569342)
			(xy 435.718502 -226.557482) (xy 435.668888 -226.53801) (xy 435.62273 -226.511361) (xy 435.581059 -226.47813)
			(xy 435.544807 -226.439059) (xy 435.514783 -226.395022) (xy 435.491657 -226.347001) (xy 435.475947 -226.296071)
			(xy 435.468004 -226.243367) (xy 421.091624 -226.243367) (xy 421.083681 -226.296071) (xy 421.067971 -226.347001)
			(xy 421.044845 -226.395022) (xy 421.014821 -226.439059) (xy 420.978569 -226.47813) (xy 420.936898 -226.511361)
			(xy 420.89074 -226.53801) (xy 420.841126 -226.557482) (xy 420.789164 -226.569342) (xy 420.736014 -226.573326)
			(xy 420.682864 -226.569342) (xy 420.630902 -226.557482) (xy 420.581288 -226.53801) (xy 420.53513 -226.511361)
			(xy 420.493459 -226.47813) (xy 420.457207 -226.439059) (xy 420.427183 -226.395022) (xy 420.404057 -226.347001)
			(xy 420.388347 -226.296071) (xy 420.380404 -226.243367) (xy 405.97862 -226.243367) (xy 405.97862 -226.243705)
			(xy 405.970465 -226.297095) (xy 405.954341 -226.348641) (xy 405.930618 -226.397161) (xy 405.899841 -226.441542)
			(xy 405.862715 -226.480768) (xy 405.820092 -226.513937) (xy 405.772949 -226.54029) (xy 405.722367 -226.559222)
			(xy 405.669506 -226.570299) (xy 405.642572 -226.572318) (xy 405.6272 -226.573708) (xy 405.598307 -226.584524)
			(xy 405.573955 -226.603464) (xy 405.556359 -226.628805) (xy 405.547119 -226.658239) (xy 405.54656 -226.673664)
			(xy 405.54656 -227.093251) (xy 409.367472 -227.093251) (xy 409.367472 -227.039953) (xy 409.375415 -226.987249)
			(xy 409.391125 -226.936319) (xy 409.414251 -226.888298) (xy 409.444275 -226.844261) (xy 409.480527 -226.80519)
			(xy 409.522198 -226.771959) (xy 409.568356 -226.74531) (xy 409.61797 -226.725838) (xy 409.669932 -226.713978)
			(xy 409.723082 -226.709995) (xy 409.776232 -226.713978) (xy 409.828194 -226.725838) (xy 409.877808 -226.74531)
			(xy 409.923966 -226.771959) (xy 409.965637 -226.80519) (xy 410.001889 -226.844261) (xy 410.031913 -226.888298)
			(xy 410.055039 -226.936319) (xy 410.070749 -226.987249) (xy 410.078692 -227.039953) (xy 410.07919 -227.066602)
			(xy 410.078692 -227.093251) (xy 424.480472 -227.093251) (xy 424.480472 -227.039953) (xy 424.488415 -226.987249)
			(xy 424.504125 -226.936319) (xy 424.527251 -226.888298) (xy 424.557275 -226.844261) (xy 424.593527 -226.80519)
			(xy 424.635198 -226.771959) (xy 424.681356 -226.74531) (xy 424.73097 -226.725838) (xy 424.782932 -226.713978)
			(xy 424.836082 -226.709995) (xy 424.889232 -226.713978) (xy 424.941194 -226.725838) (xy 424.990808 -226.74531)
			(xy 425.036966 -226.771959) (xy 425.078637 -226.80519) (xy 425.114889 -226.844261) (xy 425.144913 -226.888298)
			(xy 425.168039 -226.936319) (xy 425.183749 -226.987249) (xy 425.191692 -227.039953) (xy 425.19219 -227.066602)
			(xy 425.191692 -227.093251) (xy 439.568072 -227.093251) (xy 439.568072 -227.039953) (xy 439.576015 -226.987249)
			(xy 439.591725 -226.936319) (xy 439.614851 -226.888298) (xy 439.644875 -226.844261) (xy 439.681127 -226.80519)
			(xy 439.722798 -226.771959) (xy 439.768956 -226.74531) (xy 439.81857 -226.725838) (xy 439.870532 -226.713978)
			(xy 439.923682 -226.709995) (xy 439.976832 -226.713978) (xy 440.028794 -226.725838) (xy 440.078408 -226.74531)
			(xy 440.124566 -226.771959) (xy 440.166237 -226.80519) (xy 440.202489 -226.844261) (xy 440.232513 -226.888298)
			(xy 440.255639 -226.936319) (xy 440.271349 -226.987249) (xy 440.279292 -227.039953) (xy 440.27979 -227.066602)
			(xy 440.279292 -227.093251) (xy 440.271349 -227.145955) (xy 440.255639 -227.196885) (xy 440.232513 -227.244906)
			(xy 440.202489 -227.288943) (xy 440.166237 -227.328014) (xy 440.124566 -227.361245) (xy 440.078408 -227.387894)
			(xy 440.028794 -227.407366) (xy 439.976832 -227.419226) (xy 439.923682 -227.42321) (xy 439.870532 -227.419226)
			(xy 439.81857 -227.407366) (xy 439.768956 -227.387894) (xy 439.722798 -227.361245) (xy 439.681127 -227.328014)
			(xy 439.644875 -227.288943) (xy 439.614851 -227.244906) (xy 439.591725 -227.196885) (xy 439.576015 -227.145955)
			(xy 439.568072 -227.093251) (xy 425.191692 -227.093251) (xy 425.183749 -227.145955) (xy 425.168039 -227.196885)
			(xy 425.144913 -227.244906) (xy 425.114889 -227.288943) (xy 425.078637 -227.328014) (xy 425.036966 -227.361245)
			(xy 424.990808 -227.387894) (xy 424.941194 -227.407366) (xy 424.889232 -227.419226) (xy 424.836082 -227.42321)
			(xy 424.782932 -227.419226) (xy 424.73097 -227.407366) (xy 424.681356 -227.387894) (xy 424.635198 -227.361245)
			(xy 424.593527 -227.328014) (xy 424.557275 -227.288943) (xy 424.527251 -227.244906) (xy 424.504125 -227.196885)
			(xy 424.488415 -227.145955) (xy 424.480472 -227.093251) (xy 410.078692 -227.093251) (xy 410.070749 -227.145955)
			(xy 410.055039 -227.196885) (xy 410.031913 -227.244906) (xy 410.001889 -227.288943) (xy 409.965637 -227.328014)
			(xy 409.923966 -227.361245) (xy 409.877808 -227.387894) (xy 409.828194 -227.407366) (xy 409.776232 -227.419226)
			(xy 409.723082 -227.42321) (xy 409.669932 -227.419226) (xy 409.61797 -227.407366) (xy 409.568356 -227.387894)
			(xy 409.522198 -227.361245) (xy 409.480527 -227.328014) (xy 409.444275 -227.288943) (xy 409.414251 -227.244906)
			(xy 409.391125 -227.196885) (xy 409.375415 -227.145955) (xy 409.367472 -227.093251) (xy 405.54656 -227.093251)
			(xy 405.54656 -227.459794) (xy 405.547086 -227.475232) (xy 405.556287 -227.504705) (xy 405.573881 -227.530078)
			(xy 405.598256 -227.54903) (xy 405.627182 -227.559827) (xy 405.642572 -227.56114) (xy 405.669508 -227.563123)
			(xy 405.722369 -227.574202) (xy 405.772951 -227.593135) (xy 405.820094 -227.61949) (xy 405.862715 -227.652662)
			(xy 405.899839 -227.69189) (xy 405.930613 -227.736274) (xy 405.954332 -227.784797) (xy 405.970451 -227.836344)
			(xy 405.978601 -227.889735) (xy 405.979122 -227.91674) (xy 405.978596 -227.943389) (xy 409.367472 -227.943389)
			(xy 409.367472 -227.890091) (xy 409.375415 -227.837387) (xy 409.391125 -227.786457) (xy 409.414251 -227.738436)
			(xy 409.444275 -227.694399) (xy 409.480527 -227.655328) (xy 409.522198 -227.622097) (xy 409.568356 -227.595448)
			(xy 409.61797 -227.575976) (xy 409.669932 -227.564116) (xy 409.723082 -227.560133) (xy 409.776232 -227.564116)
			(xy 409.828194 -227.575976) (xy 409.877808 -227.595448) (xy 409.923966 -227.622097) (xy 409.965637 -227.655328)
			(xy 410.001889 -227.694399) (xy 410.031913 -227.738436) (xy 410.055039 -227.786457) (xy 410.070749 -227.837387)
			(xy 410.078692 -227.890091) (xy 410.07919 -227.91674) (xy 410.078692 -227.943389) (xy 420.380404 -227.943389)
			(xy 420.380404 -227.890091) (xy 420.388347 -227.837387) (xy 420.404057 -227.786457) (xy 420.427183 -227.738436)
			(xy 420.457207 -227.694399) (xy 420.493459 -227.655328) (xy 420.53513 -227.622097) (xy 420.581288 -227.595448)
			(xy 420.630902 -227.575976) (xy 420.682864 -227.564116) (xy 420.736014 -227.560133) (xy 420.789164 -227.564116)
			(xy 420.841126 -227.575976) (xy 420.89074 -227.595448) (xy 420.936898 -227.622097) (xy 420.978569 -227.655328)
			(xy 421.014821 -227.694399) (xy 421.044845 -227.738436) (xy 421.067971 -227.786457) (xy 421.083681 -227.837387)
			(xy 421.091624 -227.890091) (xy 421.092122 -227.91674) (xy 421.091624 -227.943389) (xy 424.480472 -227.943389)
			(xy 424.480472 -227.890091) (xy 424.488415 -227.837387) (xy 424.504125 -227.786457) (xy 424.527251 -227.738436)
			(xy 424.557275 -227.694399) (xy 424.593527 -227.655328) (xy 424.635198 -227.622097) (xy 424.681356 -227.595448)
			(xy 424.73097 -227.575976) (xy 424.782932 -227.564116) (xy 424.836082 -227.560133) (xy 424.889232 -227.564116)
			(xy 424.941194 -227.575976) (xy 424.990808 -227.595448) (xy 425.036966 -227.622097) (xy 425.078637 -227.655328)
			(xy 425.114889 -227.694399) (xy 425.144913 -227.738436) (xy 425.168039 -227.786457) (xy 425.183749 -227.837387)
			(xy 425.191692 -227.890091) (xy 425.19219 -227.91674) (xy 425.191692 -227.943389) (xy 435.468004 -227.943389)
			(xy 435.468004 -227.890091) (xy 435.475947 -227.837387) (xy 435.491657 -227.786457) (xy 435.514783 -227.738436)
			(xy 435.544807 -227.694399) (xy 435.581059 -227.655328) (xy 435.62273 -227.622097) (xy 435.668888 -227.595448)
			(xy 435.718502 -227.575976) (xy 435.770464 -227.564116) (xy 435.823614 -227.560133) (xy 435.876764 -227.564116)
			(xy 435.928726 -227.575976) (xy 435.97834 -227.595448) (xy 436.024498 -227.622097) (xy 436.066169 -227.655328)
			(xy 436.102421 -227.694399) (xy 436.132445 -227.738436) (xy 436.155571 -227.786457) (xy 436.171281 -227.837387)
			(xy 436.179224 -227.890091) (xy 436.179722 -227.91674) (xy 436.179224 -227.943389) (xy 439.568072 -227.943389)
			(xy 439.568072 -227.890091) (xy 439.576015 -227.837387) (xy 439.591725 -227.786457) (xy 439.614851 -227.738436)
			(xy 439.644875 -227.694399) (xy 439.681127 -227.655328) (xy 439.722798 -227.622097) (xy 439.768956 -227.595448)
			(xy 439.81857 -227.575976) (xy 439.870532 -227.564116) (xy 439.923682 -227.560133) (xy 439.976832 -227.564116)
			(xy 440.028794 -227.575976) (xy 440.078408 -227.595448) (xy 440.124566 -227.622097) (xy 440.166237 -227.655328)
			(xy 440.202489 -227.694399) (xy 440.232513 -227.738436) (xy 440.255639 -227.786457) (xy 440.271349 -227.837387)
			(xy 440.279292 -227.890091) (xy 440.27979 -227.91674) (xy 440.279292 -227.943389) (xy 440.271349 -227.996093)
			(xy 440.255639 -228.047023) (xy 440.232513 -228.095044) (xy 440.202489 -228.139081) (xy 440.166237 -228.178152)
			(xy 440.124566 -228.211383) (xy 440.078408 -228.238032) (xy 440.028794 -228.257504) (xy 439.976832 -228.269364)
			(xy 439.923682 -228.273348) (xy 439.870532 -228.269364) (xy 439.81857 -228.257504) (xy 439.768956 -228.238032)
			(xy 439.722798 -228.211383) (xy 439.681127 -228.178152) (xy 439.644875 -228.139081) (xy 439.614851 -228.095044)
			(xy 439.591725 -228.047023) (xy 439.576015 -227.996093) (xy 439.568072 -227.943389) (xy 436.179224 -227.943389)
			(xy 436.171281 -227.996093) (xy 436.155571 -228.047023) (xy 436.132445 -228.095044) (xy 436.102421 -228.139081)
			(xy 436.066169 -228.178152) (xy 436.024498 -228.211383) (xy 435.97834 -228.238032) (xy 435.928726 -228.257504)
			(xy 435.876764 -228.269364) (xy 435.823614 -228.273348) (xy 435.770464 -228.269364) (xy 435.718502 -228.257504)
			(xy 435.668888 -228.238032) (xy 435.62273 -228.211383) (xy 435.581059 -228.178152) (xy 435.544807 -228.139081)
			(xy 435.514783 -228.095044) (xy 435.491657 -228.047023) (xy 435.475947 -227.996093) (xy 435.468004 -227.943389)
			(xy 425.191692 -227.943389) (xy 425.183749 -227.996093) (xy 425.168039 -228.047023) (xy 425.144913 -228.095044)
			(xy 425.114889 -228.139081) (xy 425.078637 -228.178152) (xy 425.036966 -228.211383) (xy 424.990808 -228.238032)
			(xy 424.941194 -228.257504) (xy 424.889232 -228.269364) (xy 424.836082 -228.273348) (xy 424.782932 -228.269364)
			(xy 424.73097 -228.257504) (xy 424.681356 -228.238032) (xy 424.635198 -228.211383) (xy 424.593527 -228.178152)
			(xy 424.557275 -228.139081) (xy 424.527251 -228.095044) (xy 424.504125 -228.047023) (xy 424.488415 -227.996093)
			(xy 424.480472 -227.943389) (xy 421.091624 -227.943389) (xy 421.083681 -227.996093) (xy 421.067971 -228.047023)
			(xy 421.044845 -228.095044) (xy 421.014821 -228.139081) (xy 420.978569 -228.178152) (xy 420.936898 -228.211383)
			(xy 420.89074 -228.238032) (xy 420.841126 -228.257504) (xy 420.789164 -228.269364) (xy 420.736014 -228.273348)
			(xy 420.682864 -228.269364) (xy 420.630902 -228.257504) (xy 420.581288 -228.238032) (xy 420.53513 -228.211383)
			(xy 420.493459 -228.178152) (xy 420.457207 -228.139081) (xy 420.427183 -228.095044) (xy 420.404057 -228.047023)
			(xy 420.388347 -227.996093) (xy 420.380404 -227.943389) (xy 410.078692 -227.943389) (xy 410.070749 -227.996093)
			(xy 410.055039 -228.047023) (xy 410.031913 -228.095044) (xy 410.001889 -228.139081) (xy 409.965637 -228.178152)
			(xy 409.923966 -228.211383) (xy 409.877808 -228.238032) (xy 409.828194 -228.257504) (xy 409.776232 -228.269364)
			(xy 409.723082 -228.273348) (xy 409.669932 -228.269364) (xy 409.61797 -228.257504) (xy 409.568356 -228.238032)
			(xy 409.522198 -228.211383) (xy 409.480527 -228.178152) (xy 409.444275 -228.139081) (xy 409.414251 -228.095044)
			(xy 409.391125 -228.047023) (xy 409.375415 -227.996093) (xy 409.367472 -227.943389) (xy 405.978596 -227.943389)
			(xy 405.97857 -227.944721) (xy 405.96981 -227.999995) (xy 405.952512 -228.053217) (xy 405.927102 -228.103079)
			(xy 405.894206 -228.148352) (xy 405.854632 -228.187923) (xy 405.809357 -228.220816) (xy 405.759493 -228.246222)
			(xy 405.706269 -228.263516) (xy 405.650995 -228.272272) (xy 405.623014 -228.272848) (xy 405.600662 -228.272086)
			(xy 405.590237 -228.271897) (xy 405.570618 -228.278894) (xy 405.555399 -228.293117) (xy 405.54709 -228.312218)
			(xy 405.54656 -228.322632) (xy 405.54656 -228.360732) (xy 405.54712 -228.371128) (xy 405.55547 -228.390178)
			(xy 405.570673 -228.404372) (xy 405.59025 -228.411397) (xy 405.600662 -228.411278) (xy 405.623014 -228.410516)
			(xy 405.650998 -228.411038) (xy 405.706276 -228.419795) (xy 405.759504 -228.437093) (xy 405.809371 -228.462504)
			(xy 405.854648 -228.495403) (xy 405.894221 -228.534981) (xy 405.927116 -228.580262) (xy 405.952522 -228.630131)
			(xy 405.969814 -228.683361) (xy 405.978565 -228.73864) (xy 405.979122 -228.766624) (xy 405.978627 -228.793273)
			(xy 420.380404 -228.793273) (xy 420.380404 -228.739975) (xy 420.388347 -228.687271) (xy 420.404057 -228.636341)
			(xy 420.427183 -228.58832) (xy 420.457207 -228.544283) (xy 420.493459 -228.505212) (xy 420.53513 -228.471981)
			(xy 420.581288 -228.445332) (xy 420.630902 -228.42586) (xy 420.682864 -228.414) (xy 420.736014 -228.410017)
			(xy 420.789164 -228.414) (xy 420.841126 -228.42586) (xy 420.89074 -228.445332) (xy 420.936898 -228.471981)
			(xy 420.978569 -228.505212) (xy 421.014821 -228.544283) (xy 421.044845 -228.58832) (xy 421.067971 -228.636341)
			(xy 421.083681 -228.687271) (xy 421.091624 -228.739975) (xy 421.092122 -228.766624) (xy 421.091624 -228.793273)
			(xy 435.468004 -228.793273) (xy 435.468004 -228.739975) (xy 435.475947 -228.687271) (xy 435.491657 -228.636341)
			(xy 435.514783 -228.58832) (xy 435.544807 -228.544283) (xy 435.581059 -228.505212) (xy 435.62273 -228.471981)
			(xy 435.668888 -228.445332) (xy 435.718502 -228.42586) (xy 435.770464 -228.414) (xy 435.823614 -228.410017)
			(xy 435.876764 -228.414) (xy 435.928726 -228.42586) (xy 435.97834 -228.445332) (xy 436.024498 -228.471981)
			(xy 436.066169 -228.505212) (xy 436.102421 -228.544283) (xy 436.132445 -228.58832) (xy 436.155571 -228.636341)
			(xy 436.171281 -228.687271) (xy 436.179224 -228.739975) (xy 436.179722 -228.766624) (xy 436.179224 -228.793273)
			(xy 436.171281 -228.845977) (xy 436.155571 -228.896907) (xy 436.132445 -228.944928) (xy 436.102421 -228.988965)
			(xy 436.066169 -229.028036) (xy 436.024498 -229.061267) (xy 435.97834 -229.087916) (xy 435.928726 -229.107388)
			(xy 435.876764 -229.119248) (xy 435.823614 -229.123232) (xy 435.770464 -229.119248) (xy 435.718502 -229.107388)
			(xy 435.668888 -229.087916) (xy 435.62273 -229.061267) (xy 435.581059 -229.028036) (xy 435.544807 -228.988965)
			(xy 435.514783 -228.944928) (xy 435.491657 -228.896907) (xy 435.475947 -228.845977) (xy 435.468004 -228.793273)
			(xy 421.091624 -228.793273) (xy 421.083681 -228.845977) (xy 421.067971 -228.896907) (xy 421.044845 -228.944928)
			(xy 421.014821 -228.988965) (xy 420.978569 -229.028036) (xy 420.936898 -229.061267) (xy 420.89074 -229.087916)
			(xy 420.841126 -229.107388) (xy 420.789164 -229.119248) (xy 420.736014 -229.123232) (xy 420.682864 -229.119248)
			(xy 420.630902 -229.107388) (xy 420.581288 -229.087916) (xy 420.53513 -229.061267) (xy 420.493459 -229.028036)
			(xy 420.457207 -228.988965) (xy 420.427183 -228.944928) (xy 420.404057 -228.896907) (xy 420.388347 -228.845977)
			(xy 420.380404 -228.793273) (xy 405.978627 -228.793273) (xy 405.97862 -228.793627) (xy 405.970462 -228.847014)
			(xy 405.954336 -228.898558) (xy 405.930612 -228.947075) (xy 405.899834 -228.991453) (xy 405.862709 -229.030676)
			(xy 405.820086 -229.063843) (xy 405.772944 -229.090194) (xy 405.722364 -229.109125) (xy 405.669505 -229.120201)
			(xy 405.642572 -229.122224) (xy 405.6272 -229.123614) (xy 405.598309 -229.13443) (xy 405.573957 -229.153371)
			(xy 405.556362 -229.178711) (xy 405.547124 -229.208146) (xy 405.54656 -229.22357) (xy 405.54656 -229.643411)
			(xy 409.367472 -229.643411) (xy 409.367472 -229.590113) (xy 409.375415 -229.537409) (xy 409.391125 -229.486479)
			(xy 409.414251 -229.438458) (xy 409.444275 -229.394421) (xy 409.480527 -229.35535) (xy 409.522198 -229.322119)
			(xy 409.568356 -229.29547) (xy 409.61797 -229.275998) (xy 409.669932 -229.264138) (xy 409.723082 -229.260155)
			(xy 409.776232 -229.264138) (xy 409.828194 -229.275998) (xy 409.877808 -229.29547) (xy 409.923966 -229.322119)
			(xy 409.965637 -229.35535) (xy 410.001889 -229.394421) (xy 410.031913 -229.438458) (xy 410.055039 -229.486479)
			(xy 410.070749 -229.537409) (xy 410.078692 -229.590113) (xy 410.07919 -229.616762) (xy 410.078692 -229.643411)
			(xy 424.480472 -229.643411) (xy 424.480472 -229.590113) (xy 424.488415 -229.537409) (xy 424.504125 -229.486479)
			(xy 424.527251 -229.438458) (xy 424.557275 -229.394421) (xy 424.593527 -229.35535) (xy 424.635198 -229.322119)
			(xy 424.681356 -229.29547) (xy 424.73097 -229.275998) (xy 424.782932 -229.264138) (xy 424.836082 -229.260155)
			(xy 424.889232 -229.264138) (xy 424.941194 -229.275998) (xy 424.990808 -229.29547) (xy 425.036966 -229.322119)
			(xy 425.078637 -229.35535) (xy 425.114889 -229.394421) (xy 425.144913 -229.438458) (xy 425.168039 -229.486479)
			(xy 425.183749 -229.537409) (xy 425.191692 -229.590113) (xy 425.19219 -229.616762) (xy 425.191692 -229.643411)
			(xy 439.568072 -229.643411) (xy 439.568072 -229.590113) (xy 439.576015 -229.537409) (xy 439.591725 -229.486479)
			(xy 439.614851 -229.438458) (xy 439.644875 -229.394421) (xy 439.681127 -229.35535) (xy 439.722798 -229.322119)
			(xy 439.768956 -229.29547) (xy 439.81857 -229.275998) (xy 439.870532 -229.264138) (xy 439.923682 -229.260155)
			(xy 439.976832 -229.264138) (xy 440.028794 -229.275998) (xy 440.078408 -229.29547) (xy 440.124566 -229.322119)
			(xy 440.166237 -229.35535) (xy 440.202489 -229.394421) (xy 440.232513 -229.438458) (xy 440.255639 -229.486479)
			(xy 440.271349 -229.537409) (xy 440.279292 -229.590113) (xy 440.27979 -229.616762) (xy 440.279292 -229.643411)
			(xy 440.271349 -229.696115) (xy 440.255639 -229.747045) (xy 440.232513 -229.795066) (xy 440.202489 -229.839103)
			(xy 440.166237 -229.878174) (xy 440.124566 -229.911405) (xy 440.078408 -229.938054) (xy 440.028794 -229.957526)
			(xy 439.976832 -229.969386) (xy 439.923682 -229.97337) (xy 439.870532 -229.969386) (xy 439.81857 -229.957526)
			(xy 439.768956 -229.938054) (xy 439.722798 -229.911405) (xy 439.681127 -229.878174) (xy 439.644875 -229.839103)
			(xy 439.614851 -229.795066) (xy 439.591725 -229.747045) (xy 439.576015 -229.696115) (xy 439.568072 -229.643411)
			(xy 425.191692 -229.643411) (xy 425.183749 -229.696115) (xy 425.168039 -229.747045) (xy 425.144913 -229.795066)
			(xy 425.114889 -229.839103) (xy 425.078637 -229.878174) (xy 425.036966 -229.911405) (xy 424.990808 -229.938054)
			(xy 424.941194 -229.957526) (xy 424.889232 -229.969386) (xy 424.836082 -229.97337) (xy 424.782932 -229.969386)
			(xy 424.73097 -229.957526) (xy 424.681356 -229.938054) (xy 424.635198 -229.911405) (xy 424.593527 -229.878174)
			(xy 424.557275 -229.839103) (xy 424.527251 -229.795066) (xy 424.504125 -229.747045) (xy 424.488415 -229.696115)
			(xy 424.480472 -229.643411) (xy 410.078692 -229.643411) (xy 410.070749 -229.696115) (xy 410.055039 -229.747045)
			(xy 410.031913 -229.795066) (xy 410.001889 -229.839103) (xy 409.965637 -229.878174) (xy 409.923966 -229.911405)
			(xy 409.877808 -229.938054) (xy 409.828194 -229.957526) (xy 409.776232 -229.969386) (xy 409.723082 -229.97337)
			(xy 409.669932 -229.969386) (xy 409.61797 -229.957526) (xy 409.568356 -229.938054) (xy 409.522198 -229.911405)
			(xy 409.480527 -229.878174) (xy 409.444275 -229.839103) (xy 409.414251 -229.795066) (xy 409.391125 -229.747045)
			(xy 409.375415 -229.696115) (xy 409.367472 -229.643411) (xy 405.54656 -229.643411) (xy 405.54656 -230.0097)
			(xy 405.547087 -230.025138) (xy 405.556289 -230.054609) (xy 405.573883 -230.079981) (xy 405.598257 -230.098931)
			(xy 405.627183 -230.109727) (xy 405.642572 -230.111046) (xy 405.669506 -230.113029) (xy 405.722362 -230.124106)
			(xy 405.77294 -230.143037) (xy 405.820079 -230.169388) (xy 405.862699 -230.202555) (xy 405.899822 -230.241778)
			(xy 405.930596 -230.286156) (xy 405.954316 -230.334673) (xy 405.970438 -230.386215) (xy 405.978593 -230.4396)
			(xy 405.978592 -230.493295) (xy 420.380404 -230.493295) (xy 420.380404 -230.439997) (xy 420.388347 -230.387293)
			(xy 420.404057 -230.336363) (xy 420.427183 -230.288342) (xy 420.457207 -230.244305) (xy 420.493459 -230.205234)
			(xy 420.53513 -230.172003) (xy 420.581288 -230.145354) (xy 420.630902 -230.125882) (xy 420.682864 -230.114022)
			(xy 420.736014 -230.110039) (xy 420.789164 -230.114022) (xy 420.841126 -230.125882) (xy 420.89074 -230.145354)
			(xy 420.936898 -230.172003) (xy 420.978569 -230.205234) (xy 421.014821 -230.244305) (xy 421.044845 -230.288342)
			(xy 421.067971 -230.336363) (xy 421.083681 -230.387293) (xy 421.091624 -230.439997) (xy 421.092122 -230.466646)
			(xy 421.091624 -230.493295) (xy 435.468004 -230.493295) (xy 435.468004 -230.439997) (xy 435.475947 -230.387293)
			(xy 435.491657 -230.336363) (xy 435.514783 -230.288342) (xy 435.544807 -230.244305) (xy 435.581059 -230.205234)
			(xy 435.62273 -230.172003) (xy 435.668888 -230.145354) (xy 435.718502 -230.125882) (xy 435.770464 -230.114022)
			(xy 435.823614 -230.110039) (xy 435.876764 -230.114022) (xy 435.928726 -230.125882) (xy 435.97834 -230.145354)
			(xy 436.024498 -230.172003) (xy 436.066169 -230.205234) (xy 436.102421 -230.244305) (xy 436.132445 -230.288342)
			(xy 436.155571 -230.336363) (xy 436.171281 -230.387293) (xy 436.179224 -230.439997) (xy 436.179722 -230.466646)
			(xy 436.179224 -230.493295) (xy 436.171281 -230.545999) (xy 436.155571 -230.596929) (xy 436.132445 -230.64495)
			(xy 436.102421 -230.688987) (xy 436.066169 -230.728058) (xy 436.024498 -230.761289) (xy 435.97834 -230.787938)
			(xy 435.928726 -230.80741) (xy 435.876764 -230.81927) (xy 435.823614 -230.823254) (xy 435.770464 -230.81927)
			(xy 435.718502 -230.80741) (xy 435.668888 -230.787938) (xy 435.62273 -230.761289) (xy 435.581059 -230.728058)
			(xy 435.544807 -230.688987) (xy 435.514783 -230.64495) (xy 435.491657 -230.596929) (xy 435.475947 -230.545999)
			(xy 435.468004 -230.493295) (xy 421.091624 -230.493295) (xy 421.083681 -230.545999) (xy 421.067971 -230.596929)
			(xy 421.044845 -230.64495) (xy 421.014821 -230.688987) (xy 420.978569 -230.728058) (xy 420.936898 -230.761289)
			(xy 420.89074 -230.787938) (xy 420.841126 -230.80741) (xy 420.789164 -230.81927) (xy 420.736014 -230.823254)
			(xy 420.682864 -230.81927) (xy 420.630902 -230.80741) (xy 420.581288 -230.787938) (xy 420.53513 -230.761289)
			(xy 420.493459 -230.728058) (xy 420.457207 -230.688987) (xy 420.427183 -230.64495) (xy 420.404057 -230.596929)
			(xy 420.388347 -230.545999) (xy 420.380404 -230.493295) (xy 405.978592 -230.493295) (xy 405.978592 -230.493605)
			(xy 405.970437 -230.54699) (xy 405.954314 -230.598532) (xy 405.930593 -230.647048) (xy 405.899818 -230.691426)
			(xy 405.862695 -230.730648) (xy 405.820075 -230.763815) (xy 405.772936 -230.790165) (xy 405.722358 -230.809096)
			(xy 405.669501 -230.820172) (xy 405.642572 -230.822246) (xy 405.627196 -230.823635) (xy 405.598294 -230.834449)
			(xy 405.573929 -230.853387) (xy 405.556316 -230.878726) (xy 405.547058 -230.908163) (xy 405.54656 -230.923592)
			(xy 405.54656 -231.343433) (xy 409.367472 -231.343433) (xy 409.367472 -231.290135) (xy 409.375415 -231.237431)
			(xy 409.391125 -231.186501) (xy 409.414251 -231.13848) (xy 409.444275 -231.094443) (xy 409.480527 -231.055372)
			(xy 409.522198 -231.022141) (xy 409.568356 -230.995492) (xy 409.61797 -230.97602) (xy 409.669932 -230.96416)
			(xy 409.723082 -230.960177) (xy 409.776232 -230.96416) (xy 409.828194 -230.97602) (xy 409.877808 -230.995492)
			(xy 409.923966 -231.022141) (xy 409.965637 -231.055372) (xy 410.001889 -231.094443) (xy 410.031913 -231.13848)
			(xy 410.055039 -231.186501) (xy 410.070749 -231.237431) (xy 410.078692 -231.290135) (xy 410.07919 -231.316784)
			(xy 410.078692 -231.343433) (xy 424.480472 -231.343433) (xy 424.480472 -231.290135) (xy 424.488415 -231.237431)
			(xy 424.504125 -231.186501) (xy 424.527251 -231.13848) (xy 424.557275 -231.094443) (xy 424.593527 -231.055372)
			(xy 424.635198 -231.022141) (xy 424.681356 -230.995492) (xy 424.73097 -230.97602) (xy 424.782932 -230.96416)
			(xy 424.836082 -230.960177) (xy 424.889232 -230.96416) (xy 424.941194 -230.97602) (xy 424.990808 -230.995492)
			(xy 425.036966 -231.022141) (xy 425.078637 -231.055372) (xy 425.114889 -231.094443) (xy 425.144913 -231.13848)
			(xy 425.168039 -231.186501) (xy 425.183749 -231.237431) (xy 425.191692 -231.290135) (xy 425.19219 -231.316784)
			(xy 425.191692 -231.343433) (xy 439.568072 -231.343433) (xy 439.568072 -231.290135) (xy 439.576015 -231.237431)
			(xy 439.591725 -231.186501) (xy 439.614851 -231.13848) (xy 439.644875 -231.094443) (xy 439.681127 -231.055372)
			(xy 439.722798 -231.022141) (xy 439.768956 -230.995492) (xy 439.81857 -230.97602) (xy 439.870532 -230.96416)
			(xy 439.923682 -230.960177) (xy 439.976832 -230.96416) (xy 440.028794 -230.97602) (xy 440.078408 -230.995492)
			(xy 440.124566 -231.022141) (xy 440.166237 -231.055372) (xy 440.202489 -231.094443) (xy 440.232513 -231.13848)
			(xy 440.255639 -231.186501) (xy 440.271349 -231.237431) (xy 440.279292 -231.290135) (xy 440.27979 -231.316784)
			(xy 440.279292 -231.343433) (xy 440.271349 -231.396137) (xy 440.255639 -231.447067) (xy 440.232513 -231.495088)
			(xy 440.202489 -231.539125) (xy 440.166237 -231.578196) (xy 440.124566 -231.611427) (xy 440.078408 -231.638076)
			(xy 440.028794 -231.657548) (xy 439.976832 -231.669408) (xy 439.923682 -231.673392) (xy 439.870532 -231.669408)
			(xy 439.81857 -231.657548) (xy 439.768956 -231.638076) (xy 439.722798 -231.611427) (xy 439.681127 -231.578196)
			(xy 439.644875 -231.539125) (xy 439.614851 -231.495088) (xy 439.591725 -231.447067) (xy 439.576015 -231.396137)
			(xy 439.568072 -231.343433) (xy 425.191692 -231.343433) (xy 425.183749 -231.396137) (xy 425.168039 -231.447067)
			(xy 425.144913 -231.495088) (xy 425.114889 -231.539125) (xy 425.078637 -231.578196) (xy 425.036966 -231.611427)
			(xy 424.990808 -231.638076) (xy 424.941194 -231.657548) (xy 424.889232 -231.669408) (xy 424.836082 -231.673392)
			(xy 424.782932 -231.669408) (xy 424.73097 -231.657548) (xy 424.681356 -231.638076) (xy 424.635198 -231.611427)
			(xy 424.593527 -231.578196) (xy 424.557275 -231.539125) (xy 424.527251 -231.495088) (xy 424.504125 -231.447067)
			(xy 424.488415 -231.396137) (xy 424.480472 -231.343433) (xy 410.078692 -231.343433) (xy 410.070749 -231.396137)
			(xy 410.055039 -231.447067) (xy 410.031913 -231.495088) (xy 410.001889 -231.539125) (xy 409.965637 -231.578196)
			(xy 409.923966 -231.611427) (xy 409.877808 -231.638076) (xy 409.828194 -231.657548) (xy 409.776232 -231.669408)
			(xy 409.723082 -231.673392) (xy 409.669932 -231.669408) (xy 409.61797 -231.657548) (xy 409.568356 -231.638076)
			(xy 409.522198 -231.611427) (xy 409.480527 -231.578196) (xy 409.444275 -231.539125) (xy 409.414251 -231.495088)
			(xy 409.391125 -231.447067) (xy 409.375415 -231.396137) (xy 409.367472 -231.343433) (xy 405.54656 -231.343433)
			(xy 405.54656 -231.709722) (xy 405.54709 -231.725158) (xy 405.556296 -231.754623) (xy 405.573891 -231.779989)
			(xy 405.598264 -231.798935) (xy 405.627186 -231.809727) (xy 405.642572 -231.811068) (xy 405.669512 -231.813051)
			(xy 405.72238 -231.82413) (xy 405.772969 -231.843064) (xy 405.820119 -231.869421) (xy 405.862748 -231.902595)
			(xy 405.899879 -231.941826) (xy 405.930661 -231.986213) (xy 405.954387 -232.03474) (xy 405.970513 -232.086293)
			(xy 405.97867 -232.13969) (xy 405.97867 -232.193317) (xy 420.380404 -232.193317) (xy 420.380404 -232.140019)
			(xy 420.388347 -232.087315) (xy 420.404057 -232.036385) (xy 420.427183 -231.988364) (xy 420.457207 -231.944327)
			(xy 420.493459 -231.905256) (xy 420.53513 -231.872025) (xy 420.581288 -231.845376) (xy 420.630902 -231.825904)
			(xy 420.682864 -231.814044) (xy 420.736014 -231.810061) (xy 420.789164 -231.814044) (xy 420.841126 -231.825904)
			(xy 420.89074 -231.845376) (xy 420.936898 -231.872025) (xy 420.978569 -231.905256) (xy 421.014821 -231.944327)
			(xy 421.044845 -231.988364) (xy 421.067971 -232.036385) (xy 421.083681 -232.087315) (xy 421.091624 -232.140019)
			(xy 421.092122 -232.166668) (xy 421.091624 -232.193317) (xy 435.468004 -232.193317) (xy 435.468004 -232.140019)
			(xy 435.475947 -232.087315) (xy 435.491657 -232.036385) (xy 435.514783 -231.988364) (xy 435.544807 -231.944327)
			(xy 435.581059 -231.905256) (xy 435.62273 -231.872025) (xy 435.668888 -231.845376) (xy 435.718502 -231.825904)
			(xy 435.770464 -231.814044) (xy 435.823614 -231.810061) (xy 435.876764 -231.814044) (xy 435.928726 -231.825904)
			(xy 435.97834 -231.845376) (xy 436.024498 -231.872025) (xy 436.066169 -231.905256) (xy 436.102421 -231.944327)
			(xy 436.132445 -231.988364) (xy 436.155571 -232.036385) (xy 436.171281 -232.087315) (xy 436.179224 -232.140019)
			(xy 436.179722 -232.166668) (xy 436.179224 -232.193317) (xy 436.171281 -232.246021) (xy 436.155571 -232.296951)
			(xy 436.132445 -232.344972) (xy 436.102421 -232.389009) (xy 436.066169 -232.42808) (xy 436.024498 -232.461311)
			(xy 435.97834 -232.48796) (xy 435.928726 -232.507432) (xy 435.876764 -232.519292) (xy 435.823614 -232.523276)
			(xy 435.770464 -232.519292) (xy 435.718502 -232.507432) (xy 435.668888 -232.48796) (xy 435.62273 -232.461311)
			(xy 435.581059 -232.42808) (xy 435.544807 -232.389009) (xy 435.514783 -232.344972) (xy 435.491657 -232.296951)
			(xy 435.475947 -232.246021) (xy 435.468004 -232.193317) (xy 421.091624 -232.193317) (xy 421.083681 -232.246021)
			(xy 421.067971 -232.296951) (xy 421.044845 -232.344972) (xy 421.014821 -232.389009) (xy 420.978569 -232.42808)
			(xy 420.936898 -232.461311) (xy 420.89074 -232.48796) (xy 420.841126 -232.507432) (xy 420.789164 -232.519292)
			(xy 420.736014 -232.523276) (xy 420.682864 -232.519292) (xy 420.630902 -232.507432) (xy 420.581288 -232.48796)
			(xy 420.53513 -232.461311) (xy 420.493459 -232.42808) (xy 420.457207 -232.389009) (xy 420.427183 -232.344972)
			(xy 420.404057 -232.296951) (xy 420.388347 -232.246021) (xy 420.380404 -232.193317) (xy 405.97867 -232.193317)
			(xy 405.97867 -232.193706) (xy 405.970514 -232.247104) (xy 405.954388 -232.298657) (xy 405.930663 -232.347184)
			(xy 405.899882 -232.391572) (xy 405.862751 -232.430803) (xy 405.820122 -232.463977) (xy 405.772972 -232.490334)
			(xy 405.722383 -232.509269) (xy 405.669515 -232.520348) (xy 405.642572 -232.522268) (xy 405.627197 -232.523657)
			(xy 405.598298 -232.534472) (xy 405.573937 -232.55341) (xy 405.556329 -232.57875) (xy 405.547076 -232.608187)
			(xy 405.54656 -232.623614) (xy 405.54656 -233.043455) (xy 424.480472 -233.043455) (xy 424.480472 -232.990157)
			(xy 424.488415 -232.937453) (xy 424.504125 -232.886523) (xy 424.527251 -232.838502) (xy 424.557275 -232.794465)
			(xy 424.593527 -232.755394) (xy 424.635198 -232.722163) (xy 424.681356 -232.695514) (xy 424.73097 -232.676042)
			(xy 424.782932 -232.664182) (xy 424.836082 -232.660199) (xy 424.889232 -232.664182) (xy 424.941194 -232.676042)
			(xy 424.990808 -232.695514) (xy 425.036966 -232.722163) (xy 425.078637 -232.755394) (xy 425.114889 -232.794465)
			(xy 425.144913 -232.838502) (xy 425.168039 -232.886523) (xy 425.183749 -232.937453) (xy 425.191692 -232.990157)
			(xy 425.19219 -233.016806) (xy 425.191692 -233.043455) (xy 439.568072 -233.043455) (xy 439.568072 -232.990157)
			(xy 439.576015 -232.937453) (xy 439.591725 -232.886523) (xy 439.614851 -232.838502) (xy 439.644875 -232.794465)
			(xy 439.681127 -232.755394) (xy 439.722798 -232.722163) (xy 439.768956 -232.695514) (xy 439.81857 -232.676042)
			(xy 439.870532 -232.664182) (xy 439.923682 -232.660199) (xy 439.976832 -232.664182) (xy 440.028794 -232.676042)
			(xy 440.078408 -232.695514) (xy 440.124566 -232.722163) (xy 440.166237 -232.755394) (xy 440.202489 -232.794465)
			(xy 440.232513 -232.838502) (xy 440.255639 -232.886523) (xy 440.271349 -232.937453) (xy 440.279292 -232.990157)
			(xy 440.27979 -233.016806) (xy 440.279292 -233.043455) (xy 440.271349 -233.096159) (xy 440.255639 -233.147089)
			(xy 440.232513 -233.19511) (xy 440.202489 -233.239147) (xy 440.166237 -233.278218) (xy 440.124566 -233.311449)
			(xy 440.078408 -233.338098) (xy 440.028794 -233.35757) (xy 439.976832 -233.36943) (xy 439.923682 -233.373414)
			(xy 439.870532 -233.36943) (xy 439.81857 -233.35757) (xy 439.768956 -233.338098) (xy 439.722798 -233.311449)
			(xy 439.681127 -233.278218) (xy 439.644875 -233.239147) (xy 439.614851 -233.19511) (xy 439.591725 -233.147089)
			(xy 439.576015 -233.096159) (xy 439.568072 -233.043455) (xy 425.191692 -233.043455) (xy 425.183749 -233.096159)
			(xy 425.168039 -233.147089) (xy 425.144913 -233.19511) (xy 425.114889 -233.239147) (xy 425.078637 -233.278218)
			(xy 425.036966 -233.311449) (xy 424.990808 -233.338098) (xy 424.941194 -233.35757) (xy 424.889232 -233.36943)
			(xy 424.836082 -233.373414) (xy 424.782932 -233.36943) (xy 424.73097 -233.35757) (xy 424.681356 -233.338098)
			(xy 424.635198 -233.311449) (xy 424.593527 -233.278218) (xy 424.557275 -233.239147) (xy 424.527251 -233.19511)
			(xy 424.504125 -233.147089) (xy 424.488415 -233.096159) (xy 424.480472 -233.043455) (xy 405.54656 -233.043455)
			(xy 405.54656 -233.893339) (xy 420.380404 -233.893339) (xy 420.380404 -233.840041) (xy 420.388347 -233.787337)
			(xy 420.404057 -233.736407) (xy 420.427183 -233.688386) (xy 420.457207 -233.644349) (xy 420.493459 -233.605278)
			(xy 420.53513 -233.572047) (xy 420.581288 -233.545398) (xy 420.630902 -233.525926) (xy 420.682864 -233.514066)
			(xy 420.736014 -233.510083) (xy 420.789164 -233.514066) (xy 420.841126 -233.525926) (xy 420.89074 -233.545398)
			(xy 420.936898 -233.572047) (xy 420.978569 -233.605278) (xy 421.014821 -233.644349) (xy 421.044845 -233.688386)
			(xy 421.067971 -233.736407) (xy 421.083681 -233.787337) (xy 421.091624 -233.840041) (xy 421.092122 -233.86669)
			(xy 421.091624 -233.893339) (xy 435.468004 -233.893339) (xy 435.468004 -233.840041) (xy 435.475947 -233.787337)
			(xy 435.491657 -233.736407) (xy 435.514783 -233.688386) (xy 435.544807 -233.644349) (xy 435.581059 -233.605278)
			(xy 435.62273 -233.572047) (xy 435.668888 -233.545398) (xy 435.718502 -233.525926) (xy 435.770464 -233.514066)
			(xy 435.823614 -233.510083) (xy 435.876764 -233.514066) (xy 435.928726 -233.525926) (xy 435.97834 -233.545398)
			(xy 436.024498 -233.572047) (xy 436.066169 -233.605278) (xy 436.102421 -233.644349) (xy 436.132445 -233.688386)
			(xy 436.155571 -233.736407) (xy 436.171281 -233.787337) (xy 436.179224 -233.840041) (xy 436.179722 -233.86669)
			(xy 436.179224 -233.893339) (xy 436.171281 -233.946043) (xy 436.155571 -233.996973) (xy 436.132445 -234.044994)
			(xy 436.102421 -234.089031) (xy 436.066169 -234.128102) (xy 436.024498 -234.161333) (xy 435.97834 -234.187982)
			(xy 435.928726 -234.207454) (xy 435.876764 -234.219314) (xy 435.823614 -234.223298) (xy 435.770464 -234.219314)
			(xy 435.718502 -234.207454) (xy 435.668888 -234.187982) (xy 435.62273 -234.161333) (xy 435.581059 -234.128102)
			(xy 435.544807 -234.089031) (xy 435.514783 -234.044994) (xy 435.491657 -233.996973) (xy 435.475947 -233.946043)
			(xy 435.468004 -233.893339) (xy 421.091624 -233.893339) (xy 421.083681 -233.946043) (xy 421.067971 -233.996973)
			(xy 421.044845 -234.044994) (xy 421.014821 -234.089031) (xy 420.978569 -234.128102) (xy 420.936898 -234.161333)
			(xy 420.89074 -234.187982) (xy 420.841126 -234.207454) (xy 420.789164 -234.219314) (xy 420.736014 -234.223298)
			(xy 420.682864 -234.219314) (xy 420.630902 -234.207454) (xy 420.581288 -234.187982) (xy 420.53513 -234.161333)
			(xy 420.493459 -234.128102) (xy 420.457207 -234.089031) (xy 420.427183 -234.044994) (xy 420.404057 -233.996973)
			(xy 420.388347 -233.946043) (xy 420.380404 -233.893339) (xy 405.54656 -233.893339) (xy 405.54656 -234.743223)
			(xy 424.480472 -234.743223) (xy 424.480472 -234.689925) (xy 424.488415 -234.637221) (xy 424.504125 -234.586291)
			(xy 424.527251 -234.53827) (xy 424.557275 -234.494233) (xy 424.593527 -234.455162) (xy 424.635198 -234.421931)
			(xy 424.681356 -234.395282) (xy 424.73097 -234.37581) (xy 424.782932 -234.36395) (xy 424.836082 -234.359967)
			(xy 424.889232 -234.36395) (xy 424.941194 -234.37581) (xy 424.990808 -234.395282) (xy 425.036966 -234.421931)
			(xy 425.078637 -234.455162) (xy 425.114889 -234.494233) (xy 425.144913 -234.53827) (xy 425.168039 -234.586291)
			(xy 425.183749 -234.637221) (xy 425.191692 -234.689925) (xy 425.19219 -234.716574) (xy 425.191692 -234.743223)
			(xy 439.568072 -234.743223) (xy 439.568072 -234.689925) (xy 439.576015 -234.637221) (xy 439.591725 -234.586291)
			(xy 439.614851 -234.53827) (xy 439.644875 -234.494233) (xy 439.681127 -234.455162) (xy 439.722798 -234.421931)
			(xy 439.768956 -234.395282) (xy 439.81857 -234.37581) (xy 439.870532 -234.36395) (xy 439.923682 -234.359967)
			(xy 439.976832 -234.36395) (xy 440.028794 -234.37581) (xy 440.078408 -234.395282) (xy 440.124566 -234.421931)
			(xy 440.166237 -234.455162) (xy 440.202489 -234.494233) (xy 440.232513 -234.53827) (xy 440.255639 -234.586291)
			(xy 440.271349 -234.637221) (xy 440.279292 -234.689925) (xy 440.27979 -234.716574) (xy 440.279292 -234.743223)
			(xy 440.271349 -234.795927) (xy 440.255639 -234.846857) (xy 440.232513 -234.894878) (xy 440.202489 -234.938915)
			(xy 440.166237 -234.977986) (xy 440.124566 -235.011217) (xy 440.078408 -235.037866) (xy 440.028794 -235.057338)
			(xy 439.976832 -235.069198) (xy 439.923682 -235.073182) (xy 439.870532 -235.069198) (xy 439.81857 -235.057338)
			(xy 439.768956 -235.037866) (xy 439.722798 -235.011217) (xy 439.681127 -234.977986) (xy 439.644875 -234.938915)
			(xy 439.614851 -234.894878) (xy 439.591725 -234.846857) (xy 439.576015 -234.795927) (xy 439.568072 -234.743223)
			(xy 425.191692 -234.743223) (xy 425.183749 -234.795927) (xy 425.168039 -234.846857) (xy 425.144913 -234.894878)
			(xy 425.114889 -234.938915) (xy 425.078637 -234.977986) (xy 425.036966 -235.011217) (xy 424.990808 -235.037866)
			(xy 424.941194 -235.057338) (xy 424.889232 -235.069198) (xy 424.836082 -235.073182) (xy 424.782932 -235.069198)
			(xy 424.73097 -235.057338) (xy 424.681356 -235.037866) (xy 424.635198 -235.011217) (xy 424.593527 -234.977986)
			(xy 424.557275 -234.938915) (xy 424.527251 -234.894878) (xy 424.504125 -234.846857) (xy 424.488415 -234.795927)
			(xy 424.480472 -234.743223) (xy 405.54656 -234.743223) (xy 405.54656 -235.593361) (xy 420.380404 -235.593361)
			(xy 420.380404 -235.540063) (xy 420.388347 -235.487359) (xy 420.404057 -235.436429) (xy 420.427183 -235.388408)
			(xy 420.457207 -235.344371) (xy 420.493459 -235.3053) (xy 420.53513 -235.272069) (xy 420.581288 -235.24542)
			(xy 420.630902 -235.225948) (xy 420.682864 -235.214088) (xy 420.736014 -235.210105) (xy 420.789164 -235.214088)
			(xy 420.841126 -235.225948) (xy 420.89074 -235.24542) (xy 420.936898 -235.272069) (xy 420.978569 -235.3053)
			(xy 421.014821 -235.344371) (xy 421.044845 -235.388408) (xy 421.067971 -235.436429) (xy 421.083681 -235.487359)
			(xy 421.091624 -235.540063) (xy 421.092122 -235.566712) (xy 421.091624 -235.593361) (xy 435.468004 -235.593361)
			(xy 435.468004 -235.540063) (xy 435.475947 -235.487359) (xy 435.491657 -235.436429) (xy 435.514783 -235.388408)
			(xy 435.544807 -235.344371) (xy 435.581059 -235.3053) (xy 435.62273 -235.272069) (xy 435.668888 -235.24542)
			(xy 435.718502 -235.225948) (xy 435.770464 -235.214088) (xy 435.823614 -235.210105) (xy 435.876764 -235.214088)
			(xy 435.928726 -235.225948) (xy 435.97834 -235.24542) (xy 436.024498 -235.272069) (xy 436.066169 -235.3053)
			(xy 436.102421 -235.344371) (xy 436.132445 -235.388408) (xy 436.155571 -235.436429) (xy 436.171281 -235.487359)
			(xy 436.179224 -235.540063) (xy 436.179722 -235.566712) (xy 436.179224 -235.593361) (xy 436.171281 -235.646065)
			(xy 436.155571 -235.696995) (xy 436.132445 -235.745016) (xy 436.102421 -235.789053) (xy 436.066169 -235.828124)
			(xy 436.024498 -235.861355) (xy 435.97834 -235.888004) (xy 435.928726 -235.907476) (xy 435.876764 -235.919336)
			(xy 435.823614 -235.92332) (xy 435.770464 -235.919336) (xy 435.718502 -235.907476) (xy 435.668888 -235.888004)
			(xy 435.62273 -235.861355) (xy 435.581059 -235.828124) (xy 435.544807 -235.789053) (xy 435.514783 -235.745016)
			(xy 435.491657 -235.696995) (xy 435.475947 -235.646065) (xy 435.468004 -235.593361) (xy 421.091624 -235.593361)
			(xy 421.083681 -235.646065) (xy 421.067971 -235.696995) (xy 421.044845 -235.745016) (xy 421.014821 -235.789053)
			(xy 420.978569 -235.828124) (xy 420.936898 -235.861355) (xy 420.89074 -235.888004) (xy 420.841126 -235.907476)
			(xy 420.789164 -235.919336) (xy 420.736014 -235.92332) (xy 420.682864 -235.919336) (xy 420.630902 -235.907476)
			(xy 420.581288 -235.888004) (xy 420.53513 -235.861355) (xy 420.493459 -235.828124) (xy 420.457207 -235.789053)
			(xy 420.427183 -235.745016) (xy 420.404057 -235.696995) (xy 420.388347 -235.646065) (xy 420.380404 -235.593361)
			(xy 405.54656 -235.593361) (xy 405.54656 -236.12221) (xy 405.569425 -236.13448) (xy 405.611358 -236.165044)
			(xy 405.648002 -236.201782) (xy 405.67846 -236.243792) (xy 405.701982 -236.290044) (xy 405.717991 -236.339401)
			(xy 405.726096 -236.390654) (xy 405.726096 -236.442543) (xy 405.725985 -236.443245) (xy 424.480472 -236.443245)
			(xy 424.480472 -236.389947) (xy 424.488415 -236.337243) (xy 424.504125 -236.286313) (xy 424.527251 -236.238292)
			(xy 424.557275 -236.194255) (xy 424.593527 -236.155184) (xy 424.635198 -236.121953) (xy 424.681356 -236.095304)
			(xy 424.73097 -236.075832) (xy 424.782932 -236.063972) (xy 424.836082 -236.059989) (xy 424.889232 -236.063972)
			(xy 424.941194 -236.075832) (xy 424.990808 -236.095304) (xy 425.036966 -236.121953) (xy 425.078637 -236.155184)
			(xy 425.114889 -236.194255) (xy 425.144913 -236.238292) (xy 425.168039 -236.286313) (xy 425.183749 -236.337243)
			(xy 425.191692 -236.389947) (xy 425.19219 -236.416596) (xy 425.191692 -236.443245) (xy 439.568072 -236.443245)
			(xy 439.568072 -236.389947) (xy 439.576015 -236.337243) (xy 439.591725 -236.286313) (xy 439.614851 -236.238292)
			(xy 439.644875 -236.194255) (xy 439.681127 -236.155184) (xy 439.722798 -236.121953) (xy 439.768956 -236.095304)
			(xy 439.81857 -236.075832) (xy 439.870532 -236.063972) (xy 439.923682 -236.059989) (xy 439.976832 -236.063972)
			(xy 440.028794 -236.075832) (xy 440.078408 -236.095304) (xy 440.124566 -236.121953) (xy 440.166237 -236.155184)
			(xy 440.202489 -236.194255) (xy 440.232513 -236.238292) (xy 440.255639 -236.286313) (xy 440.271349 -236.337243)
			(xy 440.279292 -236.389947) (xy 440.27979 -236.416596) (xy 440.279292 -236.443245) (xy 440.271349 -236.495949)
			(xy 440.255639 -236.546879) (xy 440.232513 -236.5949) (xy 440.202489 -236.638937) (xy 440.166237 -236.678008)
			(xy 440.124566 -236.711239) (xy 440.078408 -236.737888) (xy 440.028794 -236.75736) (xy 439.976832 -236.76922)
			(xy 439.923682 -236.773204) (xy 439.870532 -236.76922) (xy 439.81857 -236.75736) (xy 439.768956 -236.737888)
			(xy 439.722798 -236.711239) (xy 439.681127 -236.678008) (xy 439.644875 -236.638937) (xy 439.614851 -236.5949)
			(xy 439.591725 -236.546879) (xy 439.576015 -236.495949) (xy 439.568072 -236.443245) (xy 425.191692 -236.443245)
			(xy 425.183749 -236.495949) (xy 425.168039 -236.546879) (xy 425.144913 -236.5949) (xy 425.114889 -236.638937)
			(xy 425.078637 -236.678008) (xy 425.036966 -236.711239) (xy 424.990808 -236.737888) (xy 424.941194 -236.75736)
			(xy 424.889232 -236.76922) (xy 424.836082 -236.773204) (xy 424.782932 -236.76922) (xy 424.73097 -236.75736)
			(xy 424.681356 -236.737888) (xy 424.635198 -236.711239) (xy 424.593527 -236.678008) (xy 424.557275 -236.638937)
			(xy 424.527251 -236.5949) (xy 424.504125 -236.546879) (xy 424.488415 -236.495949) (xy 424.480472 -236.443245)
			(xy 405.725985 -236.443245) (xy 405.717992 -236.493795) (xy 405.701983 -236.543153) (xy 405.678461 -236.589405)
			(xy 405.648005 -236.631415) (xy 405.611361 -236.668154) (xy 405.569428 -236.698718) (xy 405.54656 -236.710982)
			(xy 405.54656 -237.293383) (xy 420.380404 -237.293383) (xy 420.380404 -237.240085) (xy 420.388347 -237.187381)
			(xy 420.404057 -237.136451) (xy 420.427183 -237.08843) (xy 420.457207 -237.044393) (xy 420.493459 -237.005322)
			(xy 420.53513 -236.972091) (xy 420.581288 -236.945442) (xy 420.630902 -236.92597) (xy 420.682864 -236.91411)
			(xy 420.736014 -236.910127) (xy 420.789164 -236.91411) (xy 420.841126 -236.92597) (xy 420.89074 -236.945442)
			(xy 420.936898 -236.972091) (xy 420.978569 -237.005322) (xy 421.014821 -237.044393) (xy 421.044845 -237.08843)
			(xy 421.067971 -237.136451) (xy 421.083681 -237.187381) (xy 421.091624 -237.240085) (xy 421.092122 -237.266734)
			(xy 421.091624 -237.293383) (xy 424.480472 -237.293383) (xy 424.480472 -237.240085) (xy 424.488415 -237.187381)
			(xy 424.504125 -237.136451) (xy 424.527251 -237.08843) (xy 424.557275 -237.044393) (xy 424.593527 -237.005322)
			(xy 424.635198 -236.972091) (xy 424.681356 -236.945442) (xy 424.73097 -236.92597) (xy 424.782932 -236.91411)
			(xy 424.836082 -236.910127) (xy 424.889232 -236.91411) (xy 424.941194 -236.92597) (xy 424.990808 -236.945442)
			(xy 425.036966 -236.972091) (xy 425.078637 -237.005322) (xy 425.114889 -237.044393) (xy 425.144913 -237.08843)
			(xy 425.168039 -237.136451) (xy 425.183749 -237.187381) (xy 425.191692 -237.240085) (xy 425.19219 -237.266734)
			(xy 425.191692 -237.293383) (xy 435.468004 -237.293383) (xy 435.468004 -237.240085) (xy 435.475947 -237.187381)
			(xy 435.491657 -237.136451) (xy 435.514783 -237.08843) (xy 435.544807 -237.044393) (xy 435.581059 -237.005322)
			(xy 435.62273 -236.972091) (xy 435.668888 -236.945442) (xy 435.718502 -236.92597) (xy 435.770464 -236.91411)
			(xy 435.823614 -236.910127) (xy 435.876764 -236.91411) (xy 435.928726 -236.92597) (xy 435.97834 -236.945442)
			(xy 436.024498 -236.972091) (xy 436.066169 -237.005322) (xy 436.102421 -237.044393) (xy 436.132445 -237.08843)
			(xy 436.155571 -237.136451) (xy 436.171281 -237.187381) (xy 436.179224 -237.240085) (xy 436.179722 -237.266734)
			(xy 436.179224 -237.293383) (xy 439.568072 -237.293383) (xy 439.568072 -237.240085) (xy 439.576015 -237.187381)
			(xy 439.591725 -237.136451) (xy 439.614851 -237.08843) (xy 439.644875 -237.044393) (xy 439.681127 -237.005322)
			(xy 439.722798 -236.972091) (xy 439.768956 -236.945442) (xy 439.81857 -236.92597) (xy 439.870532 -236.91411)
			(xy 439.923682 -236.910127) (xy 439.976832 -236.91411) (xy 440.028794 -236.92597) (xy 440.078408 -236.945442)
			(xy 440.124566 -236.972091) (xy 440.166237 -237.005322) (xy 440.202489 -237.044393) (xy 440.232513 -237.08843)
			(xy 440.255639 -237.136451) (xy 440.271349 -237.187381) (xy 440.279292 -237.240085) (xy 440.27979 -237.266734)
			(xy 440.279292 -237.293383) (xy 440.271349 -237.346087) (xy 440.255639 -237.397017) (xy 440.232513 -237.445038)
			(xy 440.202489 -237.489075) (xy 440.166237 -237.528146) (xy 440.124566 -237.561377) (xy 440.078408 -237.588026)
			(xy 440.028794 -237.607498) (xy 439.976832 -237.619358) (xy 439.923682 -237.623342) (xy 439.870532 -237.619358)
			(xy 439.81857 -237.607498) (xy 439.768956 -237.588026) (xy 439.722798 -237.561377) (xy 439.681127 -237.528146)
			(xy 439.644875 -237.489075) (xy 439.614851 -237.445038) (xy 439.591725 -237.397017) (xy 439.576015 -237.346087)
			(xy 439.568072 -237.293383) (xy 436.179224 -237.293383) (xy 436.171281 -237.346087) (xy 436.155571 -237.397017)
			(xy 436.132445 -237.445038) (xy 436.102421 -237.489075) (xy 436.066169 -237.528146) (xy 436.024498 -237.561377)
			(xy 435.97834 -237.588026) (xy 435.928726 -237.607498) (xy 435.876764 -237.619358) (xy 435.823614 -237.623342)
			(xy 435.770464 -237.619358) (xy 435.718502 -237.607498) (xy 435.668888 -237.588026) (xy 435.62273 -237.561377)
			(xy 435.581059 -237.528146) (xy 435.544807 -237.489075) (xy 435.514783 -237.445038) (xy 435.491657 -237.397017)
			(xy 435.475947 -237.346087) (xy 435.468004 -237.293383) (xy 425.191692 -237.293383) (xy 425.183749 -237.346087)
			(xy 425.168039 -237.397017) (xy 425.144913 -237.445038) (xy 425.114889 -237.489075) (xy 425.078637 -237.528146)
			(xy 425.036966 -237.561377) (xy 424.990808 -237.588026) (xy 424.941194 -237.607498) (xy 424.889232 -237.619358)
			(xy 424.836082 -237.623342) (xy 424.782932 -237.619358) (xy 424.73097 -237.607498) (xy 424.681356 -237.588026)
			(xy 424.635198 -237.561377) (xy 424.593527 -237.528146) (xy 424.557275 -237.489075) (xy 424.527251 -237.445038)
			(xy 424.504125 -237.397017) (xy 424.488415 -237.346087) (xy 424.480472 -237.293383) (xy 421.091624 -237.293383)
			(xy 421.083681 -237.346087) (xy 421.067971 -237.397017) (xy 421.044845 -237.445038) (xy 421.014821 -237.489075)
			(xy 420.978569 -237.528146) (xy 420.936898 -237.561377) (xy 420.89074 -237.588026) (xy 420.841126 -237.607498)
			(xy 420.789164 -237.619358) (xy 420.736014 -237.623342) (xy 420.682864 -237.619358) (xy 420.630902 -237.607498)
			(xy 420.581288 -237.588026) (xy 420.53513 -237.561377) (xy 420.493459 -237.528146) (xy 420.457207 -237.489075)
			(xy 420.427183 -237.445038) (xy 420.404057 -237.397017) (xy 420.388347 -237.346087) (xy 420.380404 -237.293383)
			(xy 405.54656 -237.293383) (xy 405.54656 -238.143267) (xy 420.380404 -238.143267) (xy 420.380404 -238.089969)
			(xy 420.388347 -238.037265) (xy 420.404057 -237.986335) (xy 420.427183 -237.938314) (xy 420.457207 -237.894277)
			(xy 420.493459 -237.855206) (xy 420.53513 -237.821975) (xy 420.581288 -237.795326) (xy 420.630902 -237.775854)
			(xy 420.682864 -237.763994) (xy 420.736014 -237.760011) (xy 420.789164 -237.763994) (xy 420.841126 -237.775854)
			(xy 420.89074 -237.795326) (xy 420.936898 -237.821975) (xy 420.978569 -237.855206) (xy 421.014821 -237.894277)
			(xy 421.044845 -237.938314) (xy 421.067971 -237.986335) (xy 421.083681 -238.037265) (xy 421.091624 -238.089969)
			(xy 421.092122 -238.116618) (xy 421.091624 -238.143267) (xy 435.468004 -238.143267) (xy 435.468004 -238.089969)
			(xy 435.475947 -238.037265) (xy 435.491657 -237.986335) (xy 435.514783 -237.938314) (xy 435.544807 -237.894277)
			(xy 435.581059 -237.855206) (xy 435.62273 -237.821975) (xy 435.668888 -237.795326) (xy 435.718502 -237.775854)
			(xy 435.770464 -237.763994) (xy 435.823614 -237.760011) (xy 435.876764 -237.763994) (xy 435.928726 -237.775854)
			(xy 435.97834 -237.795326) (xy 436.024498 -237.821975) (xy 436.066169 -237.855206) (xy 436.102421 -237.894277)
			(xy 436.132445 -237.938314) (xy 436.155571 -237.986335) (xy 436.171281 -238.037265) (xy 436.179224 -238.089969)
			(xy 436.179722 -238.116618) (xy 436.179224 -238.143267) (xy 436.171281 -238.195971) (xy 436.155571 -238.246901)
			(xy 436.132445 -238.294922) (xy 436.102421 -238.338959) (xy 436.066169 -238.37803) (xy 436.024498 -238.411261)
			(xy 435.97834 -238.43791) (xy 435.928726 -238.457382) (xy 435.876764 -238.469242) (xy 435.823614 -238.473226)
			(xy 435.770464 -238.469242) (xy 435.718502 -238.457382) (xy 435.668888 -238.43791) (xy 435.62273 -238.411261)
			(xy 435.581059 -238.37803) (xy 435.544807 -238.338959) (xy 435.514783 -238.294922) (xy 435.491657 -238.246901)
			(xy 435.475947 -238.195971) (xy 435.468004 -238.143267) (xy 421.091624 -238.143267) (xy 421.083681 -238.195971)
			(xy 421.067971 -238.246901) (xy 421.044845 -238.294922) (xy 421.014821 -238.338959) (xy 420.978569 -238.37803)
			(xy 420.936898 -238.411261) (xy 420.89074 -238.43791) (xy 420.841126 -238.457382) (xy 420.789164 -238.469242)
			(xy 420.736014 -238.473226) (xy 420.682864 -238.469242) (xy 420.630902 -238.457382) (xy 420.581288 -238.43791)
			(xy 420.53513 -238.411261) (xy 420.493459 -238.37803) (xy 420.457207 -238.338959) (xy 420.427183 -238.294922)
			(xy 420.404057 -238.246901) (xy 420.388347 -238.195971) (xy 420.380404 -238.143267) (xy 405.54656 -238.143267)
			(xy 405.54656 -238.663734) (xy 405.572468 -238.678212) (xy 405.594111 -238.690859) (xy 405.633652 -238.721666)
			(xy 405.668092 -238.758086) (xy 405.696642 -238.799286) (xy 405.718648 -238.844323) (xy 405.733606 -238.892165)
			(xy 405.741173 -238.941716) (xy 405.741176 -238.991841) (xy 405.740937 -238.993405) (xy 424.480472 -238.993405)
			(xy 424.480472 -238.940107) (xy 424.488415 -238.887403) (xy 424.504125 -238.836473) (xy 424.527251 -238.788452)
			(xy 424.557275 -238.744415) (xy 424.593527 -238.705344) (xy 424.635198 -238.672113) (xy 424.681356 -238.645464)
			(xy 424.73097 -238.625992) (xy 424.782932 -238.614132) (xy 424.836082 -238.610149) (xy 424.889232 -238.614132)
			(xy 424.941194 -238.625992) (xy 424.990808 -238.645464) (xy 425.036966 -238.672113) (xy 425.078637 -238.705344)
			(xy 425.114889 -238.744415) (xy 425.144913 -238.788452) (xy 425.168039 -238.836473) (xy 425.183749 -238.887403)
			(xy 425.191692 -238.940107) (xy 425.19219 -238.966756) (xy 425.191692 -238.993405) (xy 439.568072 -238.993405)
			(xy 439.568072 -238.940107) (xy 439.576015 -238.887403) (xy 439.591725 -238.836473) (xy 439.614851 -238.788452)
			(xy 439.644875 -238.744415) (xy 439.681127 -238.705344) (xy 439.722798 -238.672113) (xy 439.768956 -238.645464)
			(xy 439.81857 -238.625992) (xy 439.870532 -238.614132) (xy 439.923682 -238.610149) (xy 439.976832 -238.614132)
			(xy 440.028794 -238.625992) (xy 440.078408 -238.645464) (xy 440.124566 -238.672113) (xy 440.166237 -238.705344)
			(xy 440.202489 -238.744415) (xy 440.232513 -238.788452) (xy 440.255639 -238.836473) (xy 440.271349 -238.887403)
			(xy 440.279292 -238.940107) (xy 440.27979 -238.966756) (xy 440.279292 -238.993405) (xy 440.271349 -239.046109)
			(xy 440.255639 -239.097039) (xy 440.232513 -239.14506) (xy 440.202489 -239.189097) (xy 440.166237 -239.228168)
			(xy 440.124566 -239.261399) (xy 440.078408 -239.288048) (xy 440.028794 -239.30752) (xy 439.976832 -239.31938)
			(xy 439.923682 -239.323364) (xy 439.870532 -239.31938) (xy 439.81857 -239.30752) (xy 439.768956 -239.288048)
			(xy 439.722798 -239.261399) (xy 439.681127 -239.228168) (xy 439.644875 -239.189097) (xy 439.614851 -239.14506)
			(xy 439.591725 -239.097039) (xy 439.576015 -239.046109) (xy 439.568072 -238.993405) (xy 425.191692 -238.993405)
			(xy 425.183749 -239.046109) (xy 425.168039 -239.097039) (xy 425.144913 -239.14506) (xy 425.114889 -239.189097)
			(xy 425.078637 -239.228168) (xy 425.036966 -239.261399) (xy 424.990808 -239.288048) (xy 424.941194 -239.30752)
			(xy 424.889232 -239.31938) (xy 424.836082 -239.323364) (xy 424.782932 -239.31938) (xy 424.73097 -239.30752)
			(xy 424.681356 -239.288048) (xy 424.635198 -239.261399) (xy 424.593527 -239.228168) (xy 424.557275 -239.189097)
			(xy 424.527251 -239.14506) (xy 424.504125 -239.097039) (xy 424.488415 -239.046109) (xy 424.480472 -238.993405)
			(xy 405.740937 -238.993405) (xy 405.733615 -239.041393) (xy 405.718664 -239.089237) (xy 405.696664 -239.134276)
			(xy 405.668119 -239.17548) (xy 405.633684 -239.211905) (xy 405.594146 -239.242717) (xy 405.572468 -239.2553)
			(xy 405.54656 -239.269778) (xy 405.54656 -239.843289) (xy 420.380404 -239.843289) (xy 420.380404 -239.789991)
			(xy 420.388347 -239.737287) (xy 420.404057 -239.686357) (xy 420.427183 -239.638336) (xy 420.457207 -239.594299)
			(xy 420.493459 -239.555228) (xy 420.53513 -239.521997) (xy 420.581288 -239.495348) (xy 420.630902 -239.475876)
			(xy 420.682864 -239.464016) (xy 420.736014 -239.460033) (xy 420.789164 -239.464016) (xy 420.841126 -239.475876)
			(xy 420.89074 -239.495348) (xy 420.936898 -239.521997) (xy 420.978569 -239.555228) (xy 421.014821 -239.594299)
			(xy 421.044845 -239.638336) (xy 421.067971 -239.686357) (xy 421.083681 -239.737287) (xy 421.091624 -239.789991)
			(xy 421.092122 -239.81664) (xy 421.091624 -239.843289) (xy 435.468004 -239.843289) (xy 435.468004 -239.789991)
			(xy 435.475947 -239.737287) (xy 435.491657 -239.686357) (xy 435.514783 -239.638336) (xy 435.544807 -239.594299)
			(xy 435.581059 -239.555228) (xy 435.62273 -239.521997) (xy 435.668888 -239.495348) (xy 435.718502 -239.475876)
			(xy 435.770464 -239.464016) (xy 435.823614 -239.460033) (xy 435.876764 -239.464016) (xy 435.928726 -239.475876)
			(xy 435.97834 -239.495348) (xy 436.024498 -239.521997) (xy 436.066169 -239.555228) (xy 436.102421 -239.594299)
			(xy 436.132445 -239.638336) (xy 436.155571 -239.686357) (xy 436.171281 -239.737287) (xy 436.179224 -239.789991)
			(xy 436.179722 -239.81664) (xy 436.179224 -239.843289) (xy 436.171281 -239.895993) (xy 436.155571 -239.946923)
			(xy 436.132445 -239.994944) (xy 436.102421 -240.038981) (xy 436.066169 -240.078052) (xy 436.024498 -240.111283)
			(xy 435.97834 -240.137932) (xy 435.928726 -240.157404) (xy 435.876764 -240.169264) (xy 435.823614 -240.173248)
			(xy 435.770464 -240.169264) (xy 435.718502 -240.157404) (xy 435.668888 -240.137932) (xy 435.62273 -240.111283)
			(xy 435.581059 -240.078052) (xy 435.544807 -240.038981) (xy 435.514783 -239.994944) (xy 435.491657 -239.946923)
			(xy 435.475947 -239.895993) (xy 435.468004 -239.843289) (xy 421.091624 -239.843289) (xy 421.083681 -239.895993)
			(xy 421.067971 -239.946923) (xy 421.044845 -239.994944) (xy 421.014821 -240.038981) (xy 420.978569 -240.078052)
			(xy 420.936898 -240.111283) (xy 420.89074 -240.137932) (xy 420.841126 -240.157404) (xy 420.789164 -240.169264)
			(xy 420.736014 -240.173248) (xy 420.682864 -240.169264) (xy 420.630902 -240.157404) (xy 420.581288 -240.137932)
			(xy 420.53513 -240.111283) (xy 420.493459 -240.078052) (xy 420.457207 -240.038981) (xy 420.427183 -239.994944)
			(xy 420.404057 -239.946923) (xy 420.388347 -239.895993) (xy 420.380404 -239.843289) (xy 405.54656 -239.843289)
			(xy 405.54656 -240.693427) (xy 424.480472 -240.693427) (xy 424.480472 -240.640129) (xy 424.488415 -240.587425)
			(xy 424.504125 -240.536495) (xy 424.527251 -240.488474) (xy 424.557275 -240.444437) (xy 424.593527 -240.405366)
			(xy 424.635198 -240.372135) (xy 424.681356 -240.345486) (xy 424.73097 -240.326014) (xy 424.782932 -240.314154)
			(xy 424.836082 -240.310171) (xy 424.889232 -240.314154) (xy 424.941194 -240.326014) (xy 424.990808 -240.345486)
			(xy 425.036966 -240.372135) (xy 425.078637 -240.405366) (xy 425.114889 -240.444437) (xy 425.144913 -240.488474)
			(xy 425.168039 -240.536495) (xy 425.183749 -240.587425) (xy 425.191692 -240.640129) (xy 425.19219 -240.666778)
			(xy 425.191692 -240.693427) (xy 439.568072 -240.693427) (xy 439.568072 -240.640129) (xy 439.576015 -240.587425)
			(xy 439.591725 -240.536495) (xy 439.614851 -240.488474) (xy 439.644875 -240.444437) (xy 439.681127 -240.405366)
			(xy 439.722798 -240.372135) (xy 439.768956 -240.345486) (xy 439.81857 -240.326014) (xy 439.870532 -240.314154)
			(xy 439.923682 -240.310171) (xy 439.976832 -240.314154) (xy 440.028794 -240.326014) (xy 440.078408 -240.345486)
			(xy 440.124566 -240.372135) (xy 440.166237 -240.405366) (xy 440.202489 -240.444437) (xy 440.232513 -240.488474)
			(xy 440.255639 -240.536495) (xy 440.271349 -240.587425) (xy 440.279292 -240.640129) (xy 440.27979 -240.666778)
			(xy 440.279292 -240.693427) (xy 440.271349 -240.746131) (xy 440.255639 -240.797061) (xy 440.232513 -240.845082)
			(xy 440.202489 -240.889119) (xy 440.166237 -240.92819) (xy 440.124566 -240.961421) (xy 440.078408 -240.98807)
			(xy 440.028794 -241.007542) (xy 439.976832 -241.019402) (xy 439.923682 -241.023386) (xy 439.870532 -241.019402)
			(xy 439.81857 -241.007542) (xy 439.768956 -240.98807) (xy 439.722798 -240.961421) (xy 439.681127 -240.92819)
			(xy 439.644875 -240.889119) (xy 439.614851 -240.845082) (xy 439.591725 -240.797061) (xy 439.576015 -240.746131)
			(xy 439.568072 -240.693427) (xy 425.191692 -240.693427) (xy 425.183749 -240.746131) (xy 425.168039 -240.797061)
			(xy 425.144913 -240.845082) (xy 425.114889 -240.889119) (xy 425.078637 -240.92819) (xy 425.036966 -240.961421)
			(xy 424.990808 -240.98807) (xy 424.941194 -241.007542) (xy 424.889232 -241.019402) (xy 424.836082 -241.023386)
			(xy 424.782932 -241.019402) (xy 424.73097 -241.007542) (xy 424.681356 -240.98807) (xy 424.635198 -240.961421)
			(xy 424.593527 -240.92819) (xy 424.557275 -240.889119) (xy 424.527251 -240.845082) (xy 424.504125 -240.797061)
			(xy 424.488415 -240.746131) (xy 424.480472 -240.693427) (xy 405.54656 -240.693427) (xy 405.54656 -241.543311)
			(xy 420.380404 -241.543311) (xy 420.380404 -241.490013) (xy 420.388347 -241.437309) (xy 420.404057 -241.386379)
			(xy 420.427183 -241.338358) (xy 420.457207 -241.294321) (xy 420.493459 -241.25525) (xy 420.53513 -241.222019)
			(xy 420.581288 -241.19537) (xy 420.630902 -241.175898) (xy 420.682864 -241.164038) (xy 420.736014 -241.160055)
			(xy 420.789164 -241.164038) (xy 420.841126 -241.175898) (xy 420.89074 -241.19537) (xy 420.936898 -241.222019)
			(xy 420.978569 -241.25525) (xy 421.014821 -241.294321) (xy 421.044845 -241.338358) (xy 421.067971 -241.386379)
			(xy 421.083681 -241.437309) (xy 421.091624 -241.490013) (xy 421.092122 -241.516662) (xy 421.091624 -241.543311)
			(xy 435.468004 -241.543311) (xy 435.468004 -241.490013) (xy 435.475947 -241.437309) (xy 435.491657 -241.386379)
			(xy 435.514783 -241.338358) (xy 435.544807 -241.294321) (xy 435.581059 -241.25525) (xy 435.62273 -241.222019)
			(xy 435.668888 -241.19537) (xy 435.718502 -241.175898) (xy 435.770464 -241.164038) (xy 435.823614 -241.160055)
			(xy 435.876764 -241.164038) (xy 435.928726 -241.175898) (xy 435.97834 -241.19537) (xy 436.024498 -241.222019)
			(xy 436.066169 -241.25525) (xy 436.102421 -241.294321) (xy 436.132445 -241.338358) (xy 436.155571 -241.386379)
			(xy 436.171281 -241.437309) (xy 436.179224 -241.490013) (xy 436.179722 -241.516662) (xy 436.179224 -241.543311)
			(xy 436.171281 -241.596015) (xy 436.155571 -241.646945) (xy 436.132445 -241.694966) (xy 436.102421 -241.739003)
			(xy 436.066169 -241.778074) (xy 436.024498 -241.811305) (xy 435.97834 -241.837954) (xy 435.928726 -241.857426)
			(xy 435.876764 -241.869286) (xy 435.823614 -241.87327) (xy 435.770464 -241.869286) (xy 435.718502 -241.857426)
			(xy 435.668888 -241.837954) (xy 435.62273 -241.811305) (xy 435.581059 -241.778074) (xy 435.544807 -241.739003)
			(xy 435.514783 -241.694966) (xy 435.491657 -241.646945) (xy 435.475947 -241.596015) (xy 435.468004 -241.543311)
			(xy 421.091624 -241.543311) (xy 421.083681 -241.596015) (xy 421.067971 -241.646945) (xy 421.044845 -241.694966)
			(xy 421.014821 -241.739003) (xy 420.978569 -241.778074) (xy 420.936898 -241.811305) (xy 420.89074 -241.837954)
			(xy 420.841126 -241.857426) (xy 420.789164 -241.869286) (xy 420.736014 -241.87327) (xy 420.682864 -241.869286)
			(xy 420.630902 -241.857426) (xy 420.581288 -241.837954) (xy 420.53513 -241.811305) (xy 420.493459 -241.778074)
			(xy 420.457207 -241.739003) (xy 420.427183 -241.694966) (xy 420.404057 -241.646945) (xy 420.388347 -241.596015)
			(xy 420.380404 -241.543311) (xy 405.54656 -241.543311) (xy 405.54656 -242.393449) (xy 409.367472 -242.393449)
			(xy 409.367472 -242.340151) (xy 409.375415 -242.287447) (xy 409.391125 -242.236517) (xy 409.414251 -242.188496)
			(xy 409.444275 -242.144459) (xy 409.480527 -242.105388) (xy 409.522198 -242.072157) (xy 409.568356 -242.045508)
			(xy 409.61797 -242.026036) (xy 409.669932 -242.014176) (xy 409.723082 -242.010193) (xy 409.776232 -242.014176)
			(xy 409.828194 -242.026036) (xy 409.877808 -242.045508) (xy 409.923966 -242.072157) (xy 409.965637 -242.105388)
			(xy 410.001889 -242.144459) (xy 410.031913 -242.188496) (xy 410.055039 -242.236517) (xy 410.070749 -242.287447)
			(xy 410.078692 -242.340151) (xy 410.07919 -242.3668) (xy 410.078692 -242.393449) (xy 416.911272 -242.393449)
			(xy 416.911272 -242.340151) (xy 416.919215 -242.287447) (xy 416.934925 -242.236517) (xy 416.958051 -242.188496)
			(xy 416.988075 -242.144459) (xy 417.024327 -242.105388) (xy 417.065998 -242.072157) (xy 417.112156 -242.045508)
			(xy 417.16177 -242.026036) (xy 417.213732 -242.014176) (xy 417.266882 -242.010193) (xy 417.320032 -242.014176)
			(xy 417.371994 -242.026036) (xy 417.421608 -242.045508) (xy 417.467766 -242.072157) (xy 417.509437 -242.105388)
			(xy 417.545689 -242.144459) (xy 417.575713 -242.188496) (xy 417.598839 -242.236517) (xy 417.614549 -242.287447)
			(xy 417.622492 -242.340151) (xy 417.62299 -242.3668) (xy 417.622492 -242.393449) (xy 424.480472 -242.393449)
			(xy 424.480472 -242.340151) (xy 424.488415 -242.287447) (xy 424.504125 -242.236517) (xy 424.527251 -242.188496)
			(xy 424.557275 -242.144459) (xy 424.593527 -242.105388) (xy 424.635198 -242.072157) (xy 424.681356 -242.045508)
			(xy 424.73097 -242.026036) (xy 424.782932 -242.014176) (xy 424.836082 -242.010193) (xy 424.889232 -242.014176)
			(xy 424.941194 -242.026036) (xy 424.990808 -242.045508) (xy 425.036966 -242.072157) (xy 425.078637 -242.105388)
			(xy 425.114889 -242.144459) (xy 425.144913 -242.188496) (xy 425.168039 -242.236517) (xy 425.183749 -242.287447)
			(xy 425.191692 -242.340151) (xy 425.19219 -242.3668) (xy 425.191692 -242.393449) (xy 431.998872 -242.393449)
			(xy 431.998872 -242.340151) (xy 432.006815 -242.287447) (xy 432.022525 -242.236517) (xy 432.045651 -242.188496)
			(xy 432.075675 -242.144459) (xy 432.111927 -242.105388) (xy 432.153598 -242.072157) (xy 432.199756 -242.045508)
			(xy 432.24937 -242.026036) (xy 432.301332 -242.014176) (xy 432.354482 -242.010193) (xy 432.407632 -242.014176)
			(xy 432.459594 -242.026036) (xy 432.509208 -242.045508) (xy 432.555366 -242.072157) (xy 432.597037 -242.105388)
			(xy 432.633289 -242.144459) (xy 432.663313 -242.188496) (xy 432.686439 -242.236517) (xy 432.702149 -242.287447)
			(xy 432.710092 -242.340151) (xy 432.71059 -242.3668) (xy 432.710092 -242.393449) (xy 439.568072 -242.393449)
			(xy 439.568072 -242.340151) (xy 439.576015 -242.287447) (xy 439.591725 -242.236517) (xy 439.614851 -242.188496)
			(xy 439.644875 -242.144459) (xy 439.681127 -242.105388) (xy 439.722798 -242.072157) (xy 439.768956 -242.045508)
			(xy 439.81857 -242.026036) (xy 439.870532 -242.014176) (xy 439.923682 -242.010193) (xy 439.976832 -242.014176)
			(xy 440.028794 -242.026036) (xy 440.078408 -242.045508) (xy 440.124566 -242.072157) (xy 440.166237 -242.105388)
			(xy 440.202489 -242.144459) (xy 440.232513 -242.188496) (xy 440.255639 -242.236517) (xy 440.271349 -242.287447)
			(xy 440.279292 -242.340151) (xy 440.27979 -242.3668) (xy 440.279292 -242.393449) (xy 447.111872 -242.393449)
			(xy 447.111872 -242.340151) (xy 447.119815 -242.287447) (xy 447.135525 -242.236517) (xy 447.158651 -242.188496)
			(xy 447.188675 -242.144459) (xy 447.224927 -242.105388) (xy 447.266598 -242.072157) (xy 447.312756 -242.045508)
			(xy 447.36237 -242.026036) (xy 447.414332 -242.014176) (xy 447.467482 -242.010193) (xy 447.520632 -242.014176)
			(xy 447.572594 -242.026036) (xy 447.622208 -242.045508) (xy 447.668366 -242.072157) (xy 447.710037 -242.105388)
			(xy 447.746289 -242.144459) (xy 447.776313 -242.188496) (xy 447.799439 -242.236517) (xy 447.815149 -242.287447)
			(xy 447.823092 -242.340151) (xy 447.82359 -242.3668) (xy 447.823092 -242.393449) (xy 447.815149 -242.446153)
			(xy 447.799439 -242.497083) (xy 447.776313 -242.545104) (xy 447.746289 -242.589141) (xy 447.710037 -242.628212)
			(xy 447.668366 -242.661443) (xy 447.622208 -242.688092) (xy 447.572594 -242.707564) (xy 447.520632 -242.719424)
			(xy 447.467482 -242.723408) (xy 447.414332 -242.719424) (xy 447.36237 -242.707564) (xy 447.312756 -242.688092)
			(xy 447.266598 -242.661443) (xy 447.224927 -242.628212) (xy 447.188675 -242.589141) (xy 447.158651 -242.545104)
			(xy 447.135525 -242.497083) (xy 447.119815 -242.446153) (xy 447.111872 -242.393449) (xy 440.279292 -242.393449)
			(xy 440.271349 -242.446153) (xy 440.255639 -242.497083) (xy 440.232513 -242.545104) (xy 440.202489 -242.589141)
			(xy 440.166237 -242.628212) (xy 440.124566 -242.661443) (xy 440.078408 -242.688092) (xy 440.028794 -242.707564)
			(xy 439.976832 -242.719424) (xy 439.923682 -242.723408) (xy 439.870532 -242.719424) (xy 439.81857 -242.707564)
			(xy 439.768956 -242.688092) (xy 439.722798 -242.661443) (xy 439.681127 -242.628212) (xy 439.644875 -242.589141)
			(xy 439.614851 -242.545104) (xy 439.591725 -242.497083) (xy 439.576015 -242.446153) (xy 439.568072 -242.393449)
			(xy 432.710092 -242.393449) (xy 432.702149 -242.446153) (xy 432.686439 -242.497083) (xy 432.663313 -242.545104)
			(xy 432.633289 -242.589141) (xy 432.597037 -242.628212) (xy 432.555366 -242.661443) (xy 432.509208 -242.688092)
			(xy 432.459594 -242.707564) (xy 432.407632 -242.719424) (xy 432.354482 -242.723408) (xy 432.301332 -242.719424)
			(xy 432.24937 -242.707564) (xy 432.199756 -242.688092) (xy 432.153598 -242.661443) (xy 432.111927 -242.628212)
			(xy 432.075675 -242.589141) (xy 432.045651 -242.545104) (xy 432.022525 -242.497083) (xy 432.006815 -242.446153)
			(xy 431.998872 -242.393449) (xy 425.191692 -242.393449) (xy 425.183749 -242.446153) (xy 425.168039 -242.497083)
			(xy 425.144913 -242.545104) (xy 425.114889 -242.589141) (xy 425.078637 -242.628212) (xy 425.036966 -242.661443)
			(xy 424.990808 -242.688092) (xy 424.941194 -242.707564) (xy 424.889232 -242.719424) (xy 424.836082 -242.723408)
			(xy 424.782932 -242.719424) (xy 424.73097 -242.707564) (xy 424.681356 -242.688092) (xy 424.635198 -242.661443)
			(xy 424.593527 -242.628212) (xy 424.557275 -242.589141) (xy 424.527251 -242.545104) (xy 424.504125 -242.497083)
			(xy 424.488415 -242.446153) (xy 424.480472 -242.393449) (xy 417.622492 -242.393449) (xy 417.614549 -242.446153)
			(xy 417.598839 -242.497083) (xy 417.575713 -242.545104) (xy 417.545689 -242.589141) (xy 417.509437 -242.628212)
			(xy 417.467766 -242.661443) (xy 417.421608 -242.688092) (xy 417.371994 -242.707564) (xy 417.320032 -242.719424)
			(xy 417.266882 -242.723408) (xy 417.213732 -242.719424) (xy 417.16177 -242.707564) (xy 417.112156 -242.688092)
			(xy 417.065998 -242.661443) (xy 417.024327 -242.628212) (xy 416.988075 -242.589141) (xy 416.958051 -242.545104)
			(xy 416.934925 -242.497083) (xy 416.919215 -242.446153) (xy 416.911272 -242.393449) (xy 410.078692 -242.393449)
			(xy 410.070749 -242.446153) (xy 410.055039 -242.497083) (xy 410.031913 -242.545104) (xy 410.001889 -242.589141)
			(xy 409.965637 -242.628212) (xy 409.923966 -242.661443) (xy 409.877808 -242.688092) (xy 409.828194 -242.707564)
			(xy 409.776232 -242.719424) (xy 409.723082 -242.723408) (xy 409.669932 -242.719424) (xy 409.61797 -242.707564)
			(xy 409.568356 -242.688092) (xy 409.522198 -242.661443) (xy 409.480527 -242.628212) (xy 409.444275 -242.589141)
			(xy 409.414251 -242.545104) (xy 409.391125 -242.497083) (xy 409.375415 -242.446153) (xy 409.367472 -242.393449)
			(xy 405.54656 -242.393449) (xy 405.54656 -242.759738) (xy 405.547092 -242.775172) (xy 405.556301 -242.804634)
			(xy 405.573897 -242.829995) (xy 405.598269 -242.848938) (xy 405.627189 -242.859728) (xy 405.642572 -242.861084)
			(xy 405.669507 -242.863068) (xy 405.722365 -242.874146) (xy 405.772944 -242.893081) (xy 405.820083 -242.919436)
			(xy 405.862702 -242.952609) (xy 405.899821 -242.991837) (xy 405.93059 -243.036222) (xy 405.954304 -243.084744)
			(xy 405.970417 -243.136291) (xy 405.978561 -243.18968) (xy 405.979122 -243.216684) (xy 405.978628 -243.243333)
			(xy 409.367472 -243.243333) (xy 409.367472 -243.190035) (xy 409.375415 -243.137331) (xy 409.391125 -243.086401)
			(xy 409.414251 -243.03838) (xy 409.444275 -242.994343) (xy 409.480527 -242.955272) (xy 409.522198 -242.922041)
			(xy 409.568356 -242.895392) (xy 409.61797 -242.87592) (xy 409.669932 -242.86406) (xy 409.723082 -242.860077)
			(xy 409.776232 -242.86406) (xy 409.828194 -242.87592) (xy 409.877808 -242.895392) (xy 409.923966 -242.922041)
			(xy 409.965637 -242.955272) (xy 410.001889 -242.994343) (xy 410.031913 -243.03838) (xy 410.055039 -243.086401)
			(xy 410.070749 -243.137331) (xy 410.078692 -243.190035) (xy 410.07919 -243.216684) (xy 410.078692 -243.243333)
			(xy 412.811204 -243.243333) (xy 412.811204 -243.190035) (xy 412.819147 -243.137331) (xy 412.834857 -243.086401)
			(xy 412.857983 -243.03838) (xy 412.888007 -242.994343) (xy 412.924259 -242.955272) (xy 412.96593 -242.922041)
			(xy 413.012088 -242.895392) (xy 413.061702 -242.87592) (xy 413.113664 -242.86406) (xy 413.166814 -242.860077)
			(xy 413.219964 -242.86406) (xy 413.271926 -242.87592) (xy 413.32154 -242.895392) (xy 413.367698 -242.922041)
			(xy 413.409369 -242.955272) (xy 413.445621 -242.994343) (xy 413.475645 -243.03838) (xy 413.498771 -243.086401)
			(xy 413.514481 -243.137331) (xy 413.522424 -243.190035) (xy 413.522922 -243.216684) (xy 413.522424 -243.243333)
			(xy 416.911272 -243.243333) (xy 416.911272 -243.190035) (xy 416.919215 -243.137331) (xy 416.934925 -243.086401)
			(xy 416.958051 -243.03838) (xy 416.988075 -242.994343) (xy 417.024327 -242.955272) (xy 417.065998 -242.922041)
			(xy 417.112156 -242.895392) (xy 417.16177 -242.87592) (xy 417.213732 -242.86406) (xy 417.266882 -242.860077)
			(xy 417.320032 -242.86406) (xy 417.371994 -242.87592) (xy 417.421608 -242.895392) (xy 417.467766 -242.922041)
			(xy 417.509437 -242.955272) (xy 417.545689 -242.994343) (xy 417.575713 -243.03838) (xy 417.598839 -243.086401)
			(xy 417.614549 -243.137331) (xy 417.622492 -243.190035) (xy 417.62299 -243.216684) (xy 417.622492 -243.243333)
			(xy 420.380404 -243.243333) (xy 420.380404 -243.190035) (xy 420.388347 -243.137331) (xy 420.404057 -243.086401)
			(xy 420.427183 -243.03838) (xy 420.457207 -242.994343) (xy 420.493459 -242.955272) (xy 420.53513 -242.922041)
			(xy 420.581288 -242.895392) (xy 420.630902 -242.87592) (xy 420.682864 -242.86406) (xy 420.736014 -242.860077)
			(xy 420.789164 -242.86406) (xy 420.841126 -242.87592) (xy 420.89074 -242.895392) (xy 420.936898 -242.922041)
			(xy 420.978569 -242.955272) (xy 421.014821 -242.994343) (xy 421.044845 -243.03838) (xy 421.067971 -243.086401)
			(xy 421.083681 -243.137331) (xy 421.091624 -243.190035) (xy 421.092122 -243.216684) (xy 421.091624 -243.243333)
			(xy 424.480472 -243.243333) (xy 424.480472 -243.190035) (xy 424.488415 -243.137331) (xy 424.504125 -243.086401)
			(xy 424.527251 -243.03838) (xy 424.557275 -242.994343) (xy 424.593527 -242.955272) (xy 424.635198 -242.922041)
			(xy 424.681356 -242.895392) (xy 424.73097 -242.87592) (xy 424.782932 -242.86406) (xy 424.836082 -242.860077)
			(xy 424.889232 -242.86406) (xy 424.941194 -242.87592) (xy 424.990808 -242.895392) (xy 425.036966 -242.922041)
			(xy 425.078637 -242.955272) (xy 425.114889 -242.994343) (xy 425.144913 -243.03838) (xy 425.168039 -243.086401)
			(xy 425.183749 -243.137331) (xy 425.191692 -243.190035) (xy 425.19219 -243.216684) (xy 425.191692 -243.243333)
			(xy 427.898804 -243.243333) (xy 427.898804 -243.190035) (xy 427.906747 -243.137331) (xy 427.922457 -243.086401)
			(xy 427.945583 -243.03838) (xy 427.975607 -242.994343) (xy 428.011859 -242.955272) (xy 428.05353 -242.922041)
			(xy 428.099688 -242.895392) (xy 428.149302 -242.87592) (xy 428.201264 -242.86406) (xy 428.254414 -242.860077)
			(xy 428.307564 -242.86406) (xy 428.359526 -242.87592) (xy 428.40914 -242.895392) (xy 428.455298 -242.922041)
			(xy 428.496969 -242.955272) (xy 428.533221 -242.994343) (xy 428.563245 -243.03838) (xy 428.586371 -243.086401)
			(xy 428.602081 -243.137331) (xy 428.610024 -243.190035) (xy 428.610522 -243.216684) (xy 428.610024 -243.243333)
			(xy 431.998872 -243.243333) (xy 431.998872 -243.190035) (xy 432.006815 -243.137331) (xy 432.022525 -243.086401)
			(xy 432.045651 -243.03838) (xy 432.075675 -242.994343) (xy 432.111927 -242.955272) (xy 432.153598 -242.922041)
			(xy 432.199756 -242.895392) (xy 432.24937 -242.87592) (xy 432.301332 -242.86406) (xy 432.354482 -242.860077)
			(xy 432.407632 -242.86406) (xy 432.459594 -242.87592) (xy 432.509208 -242.895392) (xy 432.555366 -242.922041)
			(xy 432.597037 -242.955272) (xy 432.633289 -242.994343) (xy 432.663313 -243.03838) (xy 432.686439 -243.086401)
			(xy 432.702149 -243.137331) (xy 432.710092 -243.190035) (xy 432.71059 -243.216684) (xy 432.710092 -243.243333)
			(xy 435.468004 -243.243333) (xy 435.468004 -243.190035) (xy 435.475947 -243.137331) (xy 435.491657 -243.086401)
			(xy 435.514783 -243.03838) (xy 435.544807 -242.994343) (xy 435.581059 -242.955272) (xy 435.62273 -242.922041)
			(xy 435.668888 -242.895392) (xy 435.718502 -242.87592) (xy 435.770464 -242.86406) (xy 435.823614 -242.860077)
			(xy 435.876764 -242.86406) (xy 435.928726 -242.87592) (xy 435.97834 -242.895392) (xy 436.024498 -242.922041)
			(xy 436.066169 -242.955272) (xy 436.102421 -242.994343) (xy 436.132445 -243.03838) (xy 436.155571 -243.086401)
			(xy 436.171281 -243.137331) (xy 436.179224 -243.190035) (xy 436.179722 -243.216684) (xy 436.179224 -243.243333)
			(xy 439.568072 -243.243333) (xy 439.568072 -243.190035) (xy 439.576015 -243.137331) (xy 439.591725 -243.086401)
			(xy 439.614851 -243.03838) (xy 439.644875 -242.994343) (xy 439.681127 -242.955272) (xy 439.722798 -242.922041)
			(xy 439.768956 -242.895392) (xy 439.81857 -242.87592) (xy 439.870532 -242.86406) (xy 439.923682 -242.860077)
			(xy 439.976832 -242.86406) (xy 440.028794 -242.87592) (xy 440.078408 -242.895392) (xy 440.124566 -242.922041)
			(xy 440.166237 -242.955272) (xy 440.202489 -242.994343) (xy 440.232513 -243.03838) (xy 440.255639 -243.086401)
			(xy 440.271349 -243.137331) (xy 440.279292 -243.190035) (xy 440.27979 -243.216684) (xy 440.279292 -243.243333)
			(xy 443.011804 -243.243333) (xy 443.011804 -243.190035) (xy 443.019747 -243.137331) (xy 443.035457 -243.086401)
			(xy 443.058583 -243.03838) (xy 443.088607 -242.994343) (xy 443.124859 -242.955272) (xy 443.16653 -242.922041)
			(xy 443.212688 -242.895392) (xy 443.262302 -242.87592) (xy 443.314264 -242.86406) (xy 443.367414 -242.860077)
			(xy 443.420564 -242.86406) (xy 443.472526 -242.87592) (xy 443.52214 -242.895392) (xy 443.568298 -242.922041)
			(xy 443.609969 -242.955272) (xy 443.646221 -242.994343) (xy 443.676245 -243.03838) (xy 443.699371 -243.086401)
			(xy 443.715081 -243.137331) (xy 443.723024 -243.190035) (xy 443.723522 -243.216684) (xy 443.723024 -243.243333)
			(xy 447.111872 -243.243333) (xy 447.111872 -243.190035) (xy 447.119815 -243.137331) (xy 447.135525 -243.086401)
			(xy 447.158651 -243.03838) (xy 447.188675 -242.994343) (xy 447.224927 -242.955272) (xy 447.266598 -242.922041)
			(xy 447.312756 -242.895392) (xy 447.36237 -242.87592) (xy 447.414332 -242.86406) (xy 447.467482 -242.860077)
			(xy 447.520632 -242.86406) (xy 447.572594 -242.87592) (xy 447.622208 -242.895392) (xy 447.668366 -242.922041)
			(xy 447.710037 -242.955272) (xy 447.746289 -242.994343) (xy 447.776313 -243.03838) (xy 447.799439 -243.086401)
			(xy 447.815149 -243.137331) (xy 447.823092 -243.190035) (xy 447.82359 -243.216684) (xy 447.823092 -243.243333)
			(xy 447.815149 -243.296037) (xy 447.799439 -243.346967) (xy 447.776313 -243.394988) (xy 447.746289 -243.439025)
			(xy 447.710037 -243.478096) (xy 447.668366 -243.511327) (xy 447.622208 -243.537976) (xy 447.572594 -243.557448)
			(xy 447.520632 -243.569308) (xy 447.467482 -243.573292) (xy 447.414332 -243.569308) (xy 447.36237 -243.557448)
			(xy 447.312756 -243.537976) (xy 447.266598 -243.511327) (xy 447.224927 -243.478096) (xy 447.188675 -243.439025)
			(xy 447.158651 -243.394988) (xy 447.135525 -243.346967) (xy 447.119815 -243.296037) (xy 447.111872 -243.243333)
			(xy 443.723024 -243.243333) (xy 443.715081 -243.296037) (xy 443.699371 -243.346967) (xy 443.676245 -243.394988)
			(xy 443.646221 -243.439025) (xy 443.609969 -243.478096) (xy 443.568298 -243.511327) (xy 443.52214 -243.537976)
			(xy 443.472526 -243.557448) (xy 443.420564 -243.569308) (xy 443.367414 -243.573292) (xy 443.314264 -243.569308)
			(xy 443.262302 -243.557448) (xy 443.212688 -243.537976) (xy 443.16653 -243.511327) (xy 443.124859 -243.478096)
			(xy 443.088607 -243.439025) (xy 443.058583 -243.394988) (xy 443.035457 -243.346967) (xy 443.019747 -243.296037)
			(xy 443.011804 -243.243333) (xy 440.279292 -243.243333) (xy 440.271349 -243.296037) (xy 440.255639 -243.346967)
			(xy 440.232513 -243.394988) (xy 440.202489 -243.439025) (xy 440.166237 -243.478096) (xy 440.124566 -243.511327)
			(xy 440.078408 -243.537976) (xy 440.028794 -243.557448) (xy 439.976832 -243.569308) (xy 439.923682 -243.573292)
			(xy 439.870532 -243.569308) (xy 439.81857 -243.557448) (xy 439.768956 -243.537976) (xy 439.722798 -243.511327)
			(xy 439.681127 -243.478096) (xy 439.644875 -243.439025) (xy 439.614851 -243.394988) (xy 439.591725 -243.346967)
			(xy 439.576015 -243.296037) (xy 439.568072 -243.243333) (xy 436.179224 -243.243333) (xy 436.171281 -243.296037)
			(xy 436.155571 -243.346967) (xy 436.132445 -243.394988) (xy 436.102421 -243.439025) (xy 436.066169 -243.478096)
			(xy 436.024498 -243.511327) (xy 435.97834 -243.537976) (xy 435.928726 -243.557448) (xy 435.876764 -243.569308)
			(xy 435.823614 -243.573292) (xy 435.770464 -243.569308) (xy 435.718502 -243.557448) (xy 435.668888 -243.537976)
			(xy 435.62273 -243.511327) (xy 435.581059 -243.478096) (xy 435.544807 -243.439025) (xy 435.514783 -243.394988)
			(xy 435.491657 -243.346967) (xy 435.475947 -243.296037) (xy 435.468004 -243.243333) (xy 432.710092 -243.243333)
			(xy 432.702149 -243.296037) (xy 432.686439 -243.346967) (xy 432.663313 -243.394988) (xy 432.633289 -243.439025)
			(xy 432.597037 -243.478096) (xy 432.555366 -243.511327) (xy 432.509208 -243.537976) (xy 432.459594 -243.557448)
			(xy 432.407632 -243.569308) (xy 432.354482 -243.573292) (xy 432.301332 -243.569308) (xy 432.24937 -243.557448)
			(xy 432.199756 -243.537976) (xy 432.153598 -243.511327) (xy 432.111927 -243.478096) (xy 432.075675 -243.439025)
			(xy 432.045651 -243.394988) (xy 432.022525 -243.346967) (xy 432.006815 -243.296037) (xy 431.998872 -243.243333)
			(xy 428.610024 -243.243333) (xy 428.602081 -243.296037) (xy 428.586371 -243.346967) (xy 428.563245 -243.394988)
			(xy 428.533221 -243.439025) (xy 428.496969 -243.478096) (xy 428.455298 -243.511327) (xy 428.40914 -243.537976)
			(xy 428.359526 -243.557448) (xy 428.307564 -243.569308) (xy 428.254414 -243.573292) (xy 428.201264 -243.569308)
			(xy 428.149302 -243.557448) (xy 428.099688 -243.537976) (xy 428.05353 -243.511327) (xy 428.011859 -243.478096)
			(xy 427.975607 -243.439025) (xy 427.945583 -243.394988) (xy 427.922457 -243.346967) (xy 427.906747 -243.296037)
			(xy 427.898804 -243.243333) (xy 425.191692 -243.243333) (xy 425.183749 -243.296037) (xy 425.168039 -243.346967)
			(xy 425.144913 -243.394988) (xy 425.114889 -243.439025) (xy 425.078637 -243.478096) (xy 425.036966 -243.511327)
			(xy 424.990808 -243.537976) (xy 424.941194 -243.557448) (xy 424.889232 -243.569308) (xy 424.836082 -243.573292)
			(xy 424.782932 -243.569308) (xy 424.73097 -243.557448) (xy 424.681356 -243.537976) (xy 424.635198 -243.511327)
			(xy 424.593527 -243.478096) (xy 424.557275 -243.439025) (xy 424.527251 -243.394988) (xy 424.504125 -243.346967)
			(xy 424.488415 -243.296037) (xy 424.480472 -243.243333) (xy 421.091624 -243.243333) (xy 421.083681 -243.296037)
			(xy 421.067971 -243.346967) (xy 421.044845 -243.394988) (xy 421.014821 -243.439025) (xy 420.978569 -243.478096)
			(xy 420.936898 -243.511327) (xy 420.89074 -243.537976) (xy 420.841126 -243.557448) (xy 420.789164 -243.569308)
			(xy 420.736014 -243.573292) (xy 420.682864 -243.569308) (xy 420.630902 -243.557448) (xy 420.581288 -243.537976)
			(xy 420.53513 -243.511327) (xy 420.493459 -243.478096) (xy 420.457207 -243.439025) (xy 420.427183 -243.394988)
			(xy 420.404057 -243.346967) (xy 420.388347 -243.296037) (xy 420.380404 -243.243333) (xy 417.622492 -243.243333)
			(xy 417.614549 -243.296037) (xy 417.598839 -243.346967) (xy 417.575713 -243.394988) (xy 417.545689 -243.439025)
			(xy 417.509437 -243.478096) (xy 417.467766 -243.511327) (xy 417.421608 -243.537976) (xy 417.371994 -243.557448)
			(xy 417.320032 -243.569308) (xy 417.266882 -243.573292) (xy 417.213732 -243.569308) (xy 417.16177 -243.557448)
			(xy 417.112156 -243.537976) (xy 417.065998 -243.511327) (xy 417.024327 -243.478096) (xy 416.988075 -243.439025)
			(xy 416.958051 -243.394988) (xy 416.934925 -243.346967) (xy 416.919215 -243.296037) (xy 416.911272 -243.243333)
			(xy 413.522424 -243.243333) (xy 413.514481 -243.296037) (xy 413.498771 -243.346967) (xy 413.475645 -243.394988)
			(xy 413.445621 -243.439025) (xy 413.409369 -243.478096) (xy 413.367698 -243.511327) (xy 413.32154 -243.537976)
			(xy 413.271926 -243.557448) (xy 413.219964 -243.569308) (xy 413.166814 -243.573292) (xy 413.113664 -243.569308)
			(xy 413.061702 -243.557448) (xy 413.012088 -243.537976) (xy 412.96593 -243.511327) (xy 412.924259 -243.478096)
			(xy 412.888007 -243.439025) (xy 412.857983 -243.394988) (xy 412.834857 -243.346967) (xy 412.819147 -243.296037)
			(xy 412.811204 -243.243333) (xy 410.078692 -243.243333) (xy 410.070749 -243.296037) (xy 410.055039 -243.346967)
			(xy 410.031913 -243.394988) (xy 410.001889 -243.439025) (xy 409.965637 -243.478096) (xy 409.923966 -243.511327)
			(xy 409.877808 -243.537976) (xy 409.828194 -243.557448) (xy 409.776232 -243.569308) (xy 409.723082 -243.573292)
			(xy 409.669932 -243.569308) (xy 409.61797 -243.557448) (xy 409.568356 -243.537976) (xy 409.522198 -243.511327)
			(xy 409.480527 -243.478096) (xy 409.444275 -243.439025) (xy 409.414251 -243.394988) (xy 409.391125 -243.346967)
			(xy 409.375415 -243.296037) (xy 409.367472 -243.243333) (xy 405.978628 -243.243333) (xy 405.978603 -243.244671)
			(xy 405.969849 -243.299955) (xy 405.952555 -243.353189) (xy 405.927146 -243.403063) (xy 405.894248 -243.448348)
			(xy 405.85467 -243.487928) (xy 405.809389 -243.52083) (xy 405.759517 -243.546244) (xy 405.706284 -243.563542)
			(xy 405.651001 -243.572301) (xy 405.623014 -243.572792) (xy 405.600662 -243.57203) (xy 405.590233 -243.57184)
			(xy 405.570604 -243.578837) (xy 405.555372 -243.593056) (xy 405.547045 -243.612158) (xy 405.54656 -243.622576)
			(xy 405.54656 -243.660676) (xy 405.547127 -243.671066) (xy 405.555485 -243.6901) (xy 405.570685 -243.70428)
			(xy 405.590253 -243.711298) (xy 405.600662 -243.711222) (xy 405.623014 -243.71046) (xy 405.650997 -243.71101)
			(xy 405.706275 -243.719767) (xy 405.759502 -243.737062) (xy 405.809368 -243.76247) (xy 405.854647 -243.795366)
			(xy 405.894222 -243.834939) (xy 405.92712 -243.880216) (xy 405.952531 -243.930081) (xy 405.969829 -243.983308)
			(xy 405.978589 -244.038585) (xy 405.979122 -244.066568) (xy 405.978627 -244.093216) (xy 405.978627 -244.093217)
			(xy 412.811204 -244.093217) (xy 412.811204 -244.039919) (xy 412.819147 -243.987215) (xy 412.834857 -243.936285)
			(xy 412.857983 -243.888264) (xy 412.888007 -243.844227) (xy 412.924259 -243.805156) (xy 412.96593 -243.771925)
			(xy 413.012088 -243.745276) (xy 413.061702 -243.725804) (xy 413.113664 -243.713944) (xy 413.166814 -243.709961)
			(xy 413.219964 -243.713944) (xy 413.271926 -243.725804) (xy 413.32154 -243.745276) (xy 413.367698 -243.771925)
			(xy 413.409369 -243.805156) (xy 413.445621 -243.844227) (xy 413.475645 -243.888264) (xy 413.498771 -243.936285)
			(xy 413.514481 -243.987215) (xy 413.522424 -244.039919) (xy 413.522922 -244.066568) (xy 413.522424 -244.093217)
			(xy 420.380404 -244.093217) (xy 420.380404 -244.039919) (xy 420.388347 -243.987215) (xy 420.404057 -243.936285)
			(xy 420.427183 -243.888264) (xy 420.457207 -243.844227) (xy 420.493459 -243.805156) (xy 420.53513 -243.771925)
			(xy 420.581288 -243.745276) (xy 420.630902 -243.725804) (xy 420.682864 -243.713944) (xy 420.736014 -243.709961)
			(xy 420.789164 -243.713944) (xy 420.841126 -243.725804) (xy 420.89074 -243.745276) (xy 420.936898 -243.771925)
			(xy 420.978569 -243.805156) (xy 421.014821 -243.844227) (xy 421.044845 -243.888264) (xy 421.067971 -243.936285)
			(xy 421.083681 -243.987215) (xy 421.091624 -244.039919) (xy 421.092122 -244.066568) (xy 421.091624 -244.093217)
			(xy 427.898804 -244.093217) (xy 427.898804 -244.039919) (xy 427.906747 -243.987215) (xy 427.922457 -243.936285)
			(xy 427.945583 -243.888264) (xy 427.975607 -243.844227) (xy 428.011859 -243.805156) (xy 428.05353 -243.771925)
			(xy 428.099688 -243.745276) (xy 428.149302 -243.725804) (xy 428.201264 -243.713944) (xy 428.254414 -243.709961)
			(xy 428.307564 -243.713944) (xy 428.359526 -243.725804) (xy 428.40914 -243.745276) (xy 428.455298 -243.771925)
			(xy 428.496969 -243.805156) (xy 428.533221 -243.844227) (xy 428.563245 -243.888264) (xy 428.586371 -243.936285)
			(xy 428.602081 -243.987215) (xy 428.610024 -244.039919) (xy 428.610522 -244.066568) (xy 428.610024 -244.093217)
			(xy 435.468004 -244.093217) (xy 435.468004 -244.039919) (xy 435.475947 -243.987215) (xy 435.491657 -243.936285)
			(xy 435.514783 -243.888264) (xy 435.544807 -243.844227) (xy 435.581059 -243.805156) (xy 435.62273 -243.771925)
			(xy 435.668888 -243.745276) (xy 435.718502 -243.725804) (xy 435.770464 -243.713944) (xy 435.823614 -243.709961)
			(xy 435.876764 -243.713944) (xy 435.928726 -243.725804) (xy 435.97834 -243.745276) (xy 436.024498 -243.771925)
			(xy 436.066169 -243.805156) (xy 436.102421 -243.844227) (xy 436.132445 -243.888264) (xy 436.155571 -243.936285)
			(xy 436.171281 -243.987215) (xy 436.179224 -244.039919) (xy 436.179722 -244.066568) (xy 436.179224 -244.093217)
			(xy 443.011804 -244.093217) (xy 443.011804 -244.039919) (xy 443.019747 -243.987215) (xy 443.035457 -243.936285)
			(xy 443.058583 -243.888264) (xy 443.088607 -243.844227) (xy 443.124859 -243.805156) (xy 443.16653 -243.771925)
			(xy 443.212688 -243.745276) (xy 443.262302 -243.725804) (xy 443.314264 -243.713944) (xy 443.367414 -243.709961)
			(xy 443.420564 -243.713944) (xy 443.472526 -243.725804) (xy 443.52214 -243.745276) (xy 443.568298 -243.771925)
			(xy 443.609969 -243.805156) (xy 443.646221 -243.844227) (xy 443.676245 -243.888264) (xy 443.699371 -243.936285)
			(xy 443.715081 -243.987215) (xy 443.723024 -244.039919) (xy 443.723522 -244.066568) (xy 443.723024 -244.093217)
			(xy 443.715081 -244.145921) (xy 443.699371 -244.196851) (xy 443.676245 -244.244872) (xy 443.646221 -244.288909)
			(xy 443.609969 -244.32798) (xy 443.568298 -244.361211) (xy 443.52214 -244.38786) (xy 443.472526 -244.407332)
			(xy 443.420564 -244.419192) (xy 443.367414 -244.423176) (xy 443.314264 -244.419192) (xy 443.262302 -244.407332)
			(xy 443.212688 -244.38786) (xy 443.16653 -244.361211) (xy 443.124859 -244.32798) (xy 443.088607 -244.288909)
			(xy 443.058583 -244.244872) (xy 443.035457 -244.196851) (xy 443.019747 -244.145921) (xy 443.011804 -244.093217)
			(xy 436.179224 -244.093217) (xy 436.171281 -244.145921) (xy 436.155571 -244.196851) (xy 436.132445 -244.244872)
			(xy 436.102421 -244.288909) (xy 436.066169 -244.32798) (xy 436.024498 -244.361211) (xy 435.97834 -244.38786)
			(xy 435.928726 -244.407332) (xy 435.876764 -244.419192) (xy 435.823614 -244.423176) (xy 435.770464 -244.419192)
			(xy 435.718502 -244.407332) (xy 435.668888 -244.38786) (xy 435.62273 -244.361211) (xy 435.581059 -244.32798)
			(xy 435.544807 -244.288909) (xy 435.514783 -244.244872) (xy 435.491657 -244.196851) (xy 435.475947 -244.145921)
			(xy 435.468004 -244.093217) (xy 428.610024 -244.093217) (xy 428.602081 -244.145921) (xy 428.586371 -244.196851)
			(xy 428.563245 -244.244872) (xy 428.533221 -244.288909) (xy 428.496969 -244.32798) (xy 428.455298 -244.361211)
			(xy 428.40914 -244.38786) (xy 428.359526 -244.407332) (xy 428.307564 -244.419192) (xy 428.254414 -244.423176)
			(xy 428.201264 -244.419192) (xy 428.149302 -244.407332) (xy 428.099688 -244.38786) (xy 428.05353 -244.361211)
			(xy 428.011859 -244.32798) (xy 427.975607 -244.288909) (xy 427.945583 -244.244872) (xy 427.922457 -244.196851)
			(xy 427.906747 -244.145921) (xy 427.898804 -244.093217) (xy 421.091624 -244.093217) (xy 421.083681 -244.145921)
			(xy 421.067971 -244.196851) (xy 421.044845 -244.244872) (xy 421.014821 -244.288909) (xy 420.978569 -244.32798)
			(xy 420.936898 -244.361211) (xy 420.89074 -244.38786) (xy 420.841126 -244.407332) (xy 420.789164 -244.419192)
			(xy 420.736014 -244.423176) (xy 420.682864 -244.419192) (xy 420.630902 -244.407332) (xy 420.581288 -244.38786)
			(xy 420.53513 -244.361211) (xy 420.493459 -244.32798) (xy 420.457207 -244.288909) (xy 420.427183 -244.244872)
			(xy 420.404057 -244.196851) (xy 420.388347 -244.145921) (xy 420.380404 -244.093217) (xy 413.522424 -244.093217)
			(xy 413.514481 -244.145921) (xy 413.498771 -244.196851) (xy 413.475645 -244.244872) (xy 413.445621 -244.288909)
			(xy 413.409369 -244.32798) (xy 413.367698 -244.361211) (xy 413.32154 -244.38786) (xy 413.271926 -244.407332)
			(xy 413.219964 -244.419192) (xy 413.166814 -244.423176) (xy 413.113664 -244.419192) (xy 413.061702 -244.407332)
			(xy 413.012088 -244.38786) (xy 412.96593 -244.361211) (xy 412.924259 -244.32798) (xy 412.888007 -244.288909)
			(xy 412.857983 -244.244872) (xy 412.834857 -244.196851) (xy 412.819147 -244.145921) (xy 412.811204 -244.093217)
			(xy 405.978627 -244.093217) (xy 405.970689 -244.145918) (xy 405.954985 -244.196848) (xy 405.931867 -244.24487)
			(xy 405.90185 -244.288909) (xy 405.865605 -244.327984) (xy 405.823942 -244.36122) (xy 405.777791 -244.387877)
			(xy 405.728182 -244.407357) (xy 405.676225 -244.419227) (xy 405.649684 -244.42166) (xy 405.635786 -244.423134)
			(xy 405.609534 -244.43269) (xy 405.586862 -244.449014) (xy 405.569472 -244.47088) (xy 405.558672 -244.496645)
			(xy 405.555272 -244.524375) (xy 405.556974 -244.538246) (xy 405.618094 -244.943355) (xy 424.480472 -244.943355)
			(xy 424.480472 -244.890057) (xy 424.488415 -244.837353) (xy 424.504125 -244.786423) (xy 424.527251 -244.738402)
			(xy 424.557275 -244.694365) (xy 424.593527 -244.655294) (xy 424.635198 -244.622063) (xy 424.681356 -244.595414)
			(xy 424.73097 -244.575942) (xy 424.782932 -244.564082) (xy 424.836082 -244.560099) (xy 424.889232 -244.564082)
			(xy 424.941194 -244.575942) (xy 424.990808 -244.595414) (xy 425.036966 -244.622063) (xy 425.078637 -244.655294)
			(xy 425.114889 -244.694365) (xy 425.144913 -244.738402) (xy 425.168039 -244.786423) (xy 425.183749 -244.837353)
			(xy 425.191692 -244.890057) (xy 425.19219 -244.916706) (xy 425.191692 -244.943355) (xy 432.024272 -244.943355)
			(xy 432.024272 -244.890057) (xy 432.032215 -244.837353) (xy 432.047925 -244.786423) (xy 432.071051 -244.738402)
			(xy 432.101075 -244.694365) (xy 432.137327 -244.655294) (xy 432.178998 -244.622063) (xy 432.225156 -244.595414)
			(xy 432.27477 -244.575942) (xy 432.326732 -244.564082) (xy 432.379882 -244.560099) (xy 432.433032 -244.564082)
			(xy 432.484994 -244.575942) (xy 432.534608 -244.595414) (xy 432.580766 -244.622063) (xy 432.622437 -244.655294)
			(xy 432.658689 -244.694365) (xy 432.688713 -244.738402) (xy 432.711839 -244.786423) (xy 432.727549 -244.837353)
			(xy 432.735492 -244.890057) (xy 432.73599 -244.916706) (xy 432.735492 -244.943355) (xy 439.568072 -244.943355)
			(xy 439.568072 -244.890057) (xy 439.576015 -244.837353) (xy 439.591725 -244.786423) (xy 439.614851 -244.738402)
			(xy 439.644875 -244.694365) (xy 439.681127 -244.655294) (xy 439.722798 -244.622063) (xy 439.768956 -244.595414)
			(xy 439.81857 -244.575942) (xy 439.870532 -244.564082) (xy 439.923682 -244.560099) (xy 439.976832 -244.564082)
			(xy 440.028794 -244.575942) (xy 440.078408 -244.595414) (xy 440.124566 -244.622063) (xy 440.166237 -244.655294)
			(xy 440.202489 -244.694365) (xy 440.232513 -244.738402) (xy 440.255639 -244.786423) (xy 440.271349 -244.837353)
			(xy 440.279292 -244.890057) (xy 440.27979 -244.916706) (xy 440.279292 -244.943355) (xy 447.111872 -244.943355)
			(xy 447.111872 -244.890057) (xy 447.119815 -244.837353) (xy 447.135525 -244.786423) (xy 447.158651 -244.738402)
			(xy 447.188675 -244.694365) (xy 447.224927 -244.655294) (xy 447.266598 -244.622063) (xy 447.312756 -244.595414)
			(xy 447.36237 -244.575942) (xy 447.414332 -244.564082) (xy 447.467482 -244.560099) (xy 447.520632 -244.564082)
			(xy 447.572594 -244.575942) (xy 447.622208 -244.595414) (xy 447.668366 -244.622063) (xy 447.710037 -244.655294)
			(xy 447.746289 -244.694365) (xy 447.776313 -244.738402) (xy 447.799439 -244.786423) (xy 447.815149 -244.837353)
			(xy 447.823092 -244.890057) (xy 447.82359 -244.916706) (xy 447.823092 -244.943355) (xy 447.815149 -244.996059)
			(xy 447.799439 -245.046989) (xy 447.776313 -245.09501) (xy 447.746289 -245.139047) (xy 447.710037 -245.178118)
			(xy 447.668366 -245.211349) (xy 447.622208 -245.237998) (xy 447.572594 -245.25747) (xy 447.520632 -245.26933)
			(xy 447.467482 -245.273314) (xy 447.414332 -245.26933) (xy 447.36237 -245.25747) (xy 447.312756 -245.237998)
			(xy 447.266598 -245.211349) (xy 447.224927 -245.178118) (xy 447.188675 -245.139047) (xy 447.158651 -245.09501)
			(xy 447.135525 -245.046989) (xy 447.119815 -244.996059) (xy 447.111872 -244.943355) (xy 440.279292 -244.943355)
			(xy 440.271349 -244.996059) (xy 440.255639 -245.046989) (xy 440.232513 -245.09501) (xy 440.202489 -245.139047)
			(xy 440.166237 -245.178118) (xy 440.124566 -245.211349) (xy 440.078408 -245.237998) (xy 440.028794 -245.25747)
			(xy 439.976832 -245.26933) (xy 439.923682 -245.273314) (xy 439.870532 -245.26933) (xy 439.81857 -245.25747)
			(xy 439.768956 -245.237998) (xy 439.722798 -245.211349) (xy 439.681127 -245.178118) (xy 439.644875 -245.139047)
			(xy 439.614851 -245.09501) (xy 439.591725 -245.046989) (xy 439.576015 -244.996059) (xy 439.568072 -244.943355)
			(xy 432.735492 -244.943355) (xy 432.727549 -244.996059) (xy 432.711839 -245.046989) (xy 432.688713 -245.09501)
			(xy 432.658689 -245.139047) (xy 432.622437 -245.178118) (xy 432.580766 -245.211349) (xy 432.534608 -245.237998)
			(xy 432.484994 -245.25747) (xy 432.433032 -245.26933) (xy 432.379882 -245.273314) (xy 432.326732 -245.26933)
			(xy 432.27477 -245.25747) (xy 432.225156 -245.237998) (xy 432.178998 -245.211349) (xy 432.137327 -245.178118)
			(xy 432.101075 -245.139047) (xy 432.071051 -245.09501) (xy 432.047925 -245.046989) (xy 432.032215 -244.996059)
			(xy 432.024272 -244.943355) (xy 425.191692 -244.943355) (xy 425.183749 -244.996059) (xy 425.168039 -245.046989)
			(xy 425.144913 -245.09501) (xy 425.114889 -245.139047) (xy 425.078637 -245.178118) (xy 425.036966 -245.211349)
			(xy 424.990808 -245.237998) (xy 424.941194 -245.25747) (xy 424.889232 -245.26933) (xy 424.836082 -245.273314)
			(xy 424.782932 -245.26933) (xy 424.73097 -245.25747) (xy 424.681356 -245.237998) (xy 424.635198 -245.211349)
			(xy 424.593527 -245.178118) (xy 424.557275 -245.139047) (xy 424.527251 -245.09501) (xy 424.504125 -245.046989)
			(xy 424.488415 -244.996059) (xy 424.480472 -244.943355) (xy 405.618094 -244.943355) (xy 405.74632 -245.793239)
			(xy 420.380404 -245.793239) (xy 420.380404 -245.739941) (xy 420.388347 -245.687237) (xy 420.404057 -245.636307)
			(xy 420.427183 -245.588286) (xy 420.457207 -245.544249) (xy 420.493459 -245.505178) (xy 420.53513 -245.471947)
			(xy 420.581288 -245.445298) (xy 420.630902 -245.425826) (xy 420.682864 -245.413966) (xy 420.736014 -245.409983)
			(xy 420.789164 -245.413966) (xy 420.841126 -245.425826) (xy 420.89074 -245.445298) (xy 420.936898 -245.471947)
			(xy 420.978569 -245.505178) (xy 421.014821 -245.544249) (xy 421.044845 -245.588286) (xy 421.067971 -245.636307)
			(xy 421.083681 -245.687237) (xy 421.091624 -245.739941) (xy 421.092122 -245.76659) (xy 421.091624 -245.793239)
			(xy 427.924204 -245.793239) (xy 427.924204 -245.739941) (xy 427.932147 -245.687237) (xy 427.947857 -245.636307)
			(xy 427.970983 -245.588286) (xy 428.001007 -245.544249) (xy 428.037259 -245.505178) (xy 428.07893 -245.471947)
			(xy 428.125088 -245.445298) (xy 428.174702 -245.425826) (xy 428.226664 -245.413966) (xy 428.279814 -245.409983)
			(xy 428.332964 -245.413966) (xy 428.384926 -245.425826) (xy 428.43454 -245.445298) (xy 428.480698 -245.471947)
			(xy 428.522369 -245.505178) (xy 428.558621 -245.544249) (xy 428.588645 -245.588286) (xy 428.611771 -245.636307)
			(xy 428.627481 -245.687237) (xy 428.635424 -245.739941) (xy 428.635922 -245.76659) (xy 428.635424 -245.793239)
			(xy 435.468004 -245.793239) (xy 435.468004 -245.739941) (xy 435.475947 -245.687237) (xy 435.491657 -245.636307)
			(xy 435.514783 -245.588286) (xy 435.544807 -245.544249) (xy 435.581059 -245.505178) (xy 435.62273 -245.471947)
			(xy 435.668888 -245.445298) (xy 435.718502 -245.425826) (xy 435.770464 -245.413966) (xy 435.823614 -245.409983)
			(xy 435.876764 -245.413966) (xy 435.928726 -245.425826) (xy 435.97834 -245.445298) (xy 436.024498 -245.471947)
			(xy 436.066169 -245.505178) (xy 436.102421 -245.544249) (xy 436.132445 -245.588286) (xy 436.155571 -245.636307)
			(xy 436.171281 -245.687237) (xy 436.179224 -245.739941) (xy 436.179722 -245.76659) (xy 436.179224 -245.793239)
			(xy 443.011804 -245.793239) (xy 443.011804 -245.739941) (xy 443.019747 -245.687237) (xy 443.035457 -245.636307)
			(xy 443.058583 -245.588286) (xy 443.088607 -245.544249) (xy 443.124859 -245.505178) (xy 443.16653 -245.471947)
			(xy 443.212688 -245.445298) (xy 443.262302 -245.425826) (xy 443.314264 -245.413966) (xy 443.367414 -245.409983)
			(xy 443.420564 -245.413966) (xy 443.472526 -245.425826) (xy 443.52214 -245.445298) (xy 443.568298 -245.471947)
			(xy 443.609969 -245.505178) (xy 443.646221 -245.544249) (xy 443.676245 -245.588286) (xy 443.699371 -245.636307)
			(xy 443.715081 -245.687237) (xy 443.723024 -245.739941) (xy 443.723522 -245.76659) (xy 443.723024 -245.793239)
			(xy 443.715081 -245.845943) (xy 443.699371 -245.896873) (xy 443.676245 -245.944894) (xy 443.646221 -245.988931)
			(xy 443.609969 -246.028002) (xy 443.568298 -246.061233) (xy 443.52214 -246.087882) (xy 443.472526 -246.107354)
			(xy 443.420564 -246.119214) (xy 443.367414 -246.123198) (xy 443.314264 -246.119214) (xy 443.262302 -246.107354)
			(xy 443.212688 -246.087882) (xy 443.16653 -246.061233) (xy 443.124859 -246.028002) (xy 443.088607 -245.988931)
			(xy 443.058583 -245.944894) (xy 443.035457 -245.896873) (xy 443.019747 -245.845943) (xy 443.011804 -245.793239)
			(xy 436.179224 -245.793239) (xy 436.171281 -245.845943) (xy 436.155571 -245.896873) (xy 436.132445 -245.944894)
			(xy 436.102421 -245.988931) (xy 436.066169 -246.028002) (xy 436.024498 -246.061233) (xy 435.97834 -246.087882)
			(xy 435.928726 -246.107354) (xy 435.876764 -246.119214) (xy 435.823614 -246.123198) (xy 435.770464 -246.119214)
			(xy 435.718502 -246.107354) (xy 435.668888 -246.087882) (xy 435.62273 -246.061233) (xy 435.581059 -246.028002)
			(xy 435.544807 -245.988931) (xy 435.514783 -245.944894) (xy 435.491657 -245.896873) (xy 435.475947 -245.845943)
			(xy 435.468004 -245.793239) (xy 428.635424 -245.793239) (xy 428.627481 -245.845943) (xy 428.611771 -245.896873)
			(xy 428.588645 -245.944894) (xy 428.558621 -245.988931) (xy 428.522369 -246.028002) (xy 428.480698 -246.061233)
			(xy 428.43454 -246.087882) (xy 428.384926 -246.107354) (xy 428.332964 -246.119214) (xy 428.279814 -246.123198)
			(xy 428.226664 -246.119214) (xy 428.174702 -246.107354) (xy 428.125088 -246.087882) (xy 428.07893 -246.061233)
			(xy 428.037259 -246.028002) (xy 428.001007 -245.988931) (xy 427.970983 -245.944894) (xy 427.947857 -245.896873)
			(xy 427.932147 -245.845943) (xy 427.924204 -245.793239) (xy 421.091624 -245.793239) (xy 421.083681 -245.845943)
			(xy 421.067971 -245.896873) (xy 421.044845 -245.944894) (xy 421.014821 -245.988931) (xy 420.978569 -246.028002)
			(xy 420.936898 -246.061233) (xy 420.89074 -246.087882) (xy 420.841126 -246.107354) (xy 420.789164 -246.119214)
			(xy 420.736014 -246.123198) (xy 420.682864 -246.119214) (xy 420.630902 -246.107354) (xy 420.581288 -246.087882)
			(xy 420.53513 -246.061233) (xy 420.493459 -246.028002) (xy 420.457207 -245.988931) (xy 420.427183 -245.944894)
			(xy 420.404057 -245.896873) (xy 420.388347 -245.845943) (xy 420.380404 -245.793239) (xy 405.74632 -245.793239)
			(xy 405.828754 -246.339614) (xy 405.851442 -246.354998) (xy 405.891847 -246.392039) (xy 405.925583 -246.435242)
			(xy 405.951724 -246.483422) (xy 405.969553 -246.535255) (xy 405.978581 -246.589321) (xy 405.979122 -246.616728)
			(xy 405.978525 -246.643377) (xy 424.480472 -246.643377) (xy 424.480472 -246.590079) (xy 424.488415 -246.537375)
			(xy 424.504125 -246.486445) (xy 424.527251 -246.438424) (xy 424.557275 -246.394387) (xy 424.593527 -246.355316)
			(xy 424.635198 -246.322085) (xy 424.681356 -246.295436) (xy 424.73097 -246.275964) (xy 424.782932 -246.264104)
			(xy 424.836082 -246.260121) (xy 424.889232 -246.264104) (xy 424.941194 -246.275964) (xy 424.990808 -246.295436)
			(xy 425.036966 -246.322085) (xy 425.078637 -246.355316) (xy 425.114889 -246.394387) (xy 425.144913 -246.438424)
			(xy 425.168039 -246.486445) (xy 425.183749 -246.537375) (xy 425.191692 -246.590079) (xy 425.19219 -246.616728)
			(xy 425.191692 -246.643377) (xy 439.542672 -246.643377) (xy 439.542672 -246.590079) (xy 439.550615 -246.537375)
			(xy 439.566325 -246.486445) (xy 439.589451 -246.438424) (xy 439.619475 -246.394387) (xy 439.655727 -246.355316)
			(xy 439.697398 -246.322085) (xy 439.743556 -246.295436) (xy 439.79317 -246.275964) (xy 439.845132 -246.264104)
			(xy 439.898282 -246.260121) (xy 439.951432 -246.264104) (xy 440.003394 -246.275964) (xy 440.053008 -246.295436)
			(xy 440.099166 -246.322085) (xy 440.140837 -246.355316) (xy 440.177089 -246.394387) (xy 440.207113 -246.438424)
			(xy 440.230239 -246.486445) (xy 440.245949 -246.537375) (xy 440.253892 -246.590079) (xy 440.25439 -246.616728)
			(xy 440.253892 -246.643377) (xy 440.245949 -246.696081) (xy 440.230239 -246.747011) (xy 440.207113 -246.795032)
			(xy 440.177089 -246.839069) (xy 440.140837 -246.87814) (xy 440.099166 -246.911371) (xy 440.053008 -246.93802)
			(xy 440.003394 -246.957492) (xy 439.951432 -246.969352) (xy 439.898282 -246.973336) (xy 439.845132 -246.969352)
			(xy 439.79317 -246.957492) (xy 439.743556 -246.93802) (xy 439.697398 -246.911371) (xy 439.655727 -246.87814)
			(xy 439.619475 -246.839069) (xy 439.589451 -246.795032) (xy 439.566325 -246.747011) (xy 439.550615 -246.696081)
			(xy 439.542672 -246.643377) (xy 425.191692 -246.643377) (xy 425.183749 -246.696081) (xy 425.168039 -246.747011)
			(xy 425.144913 -246.795032) (xy 425.114889 -246.839069) (xy 425.078637 -246.87814) (xy 425.036966 -246.911371)
			(xy 424.990808 -246.93802) (xy 424.941194 -246.957492) (xy 424.889232 -246.969352) (xy 424.836082 -246.973336)
			(xy 424.782932 -246.969352) (xy 424.73097 -246.957492) (xy 424.681356 -246.93802) (xy 424.635198 -246.911371)
			(xy 424.593527 -246.87814) (xy 424.557275 -246.839069) (xy 424.527251 -246.795032) (xy 424.504125 -246.747011)
			(xy 424.488415 -246.696081) (xy 424.480472 -246.643377) (xy 405.978525 -246.643377) (xy 405.978479 -246.64545)
			(xy 405.968511 -246.702024) (xy 405.948929 -246.756029) (xy 405.920322 -246.805845) (xy 405.902414 -246.82831)
			(xy 405.997664 -247.458992) (xy 406.001724 -247.48748) (xy 406.00225 -247.493261) (xy 420.380404 -247.493261)
			(xy 420.380404 -247.439963) (xy 420.388347 -247.387259) (xy 420.404057 -247.336329) (xy 420.427183 -247.288308)
			(xy 420.457207 -247.244271) (xy 420.493459 -247.2052) (xy 420.53513 -247.171969) (xy 420.581288 -247.14532)
			(xy 420.630902 -247.125848) (xy 420.682864 -247.113988) (xy 420.736014 -247.110005) (xy 420.789164 -247.113988)
			(xy 420.841126 -247.125848) (xy 420.89074 -247.14532) (xy 420.936898 -247.171969) (xy 420.978569 -247.2052)
			(xy 421.014821 -247.244271) (xy 421.044845 -247.288308) (xy 421.067971 -247.336329) (xy 421.083681 -247.387259)
			(xy 421.091624 -247.439963) (xy 421.092122 -247.466612) (xy 421.091624 -247.493261) (xy 435.468004 -247.493261)
			(xy 435.468004 -247.439963) (xy 435.475947 -247.387259) (xy 435.491657 -247.336329) (xy 435.514783 -247.288308)
			(xy 435.544807 -247.244271) (xy 435.581059 -247.2052) (xy 435.62273 -247.171969) (xy 435.668888 -247.14532)
			(xy 435.718502 -247.125848) (xy 435.770464 -247.113988) (xy 435.823614 -247.110005) (xy 435.876764 -247.113988)
			(xy 435.928726 -247.125848) (xy 435.97834 -247.14532) (xy 436.024498 -247.171969) (xy 436.066169 -247.2052)
			(xy 436.102421 -247.244271) (xy 436.132445 -247.288308) (xy 436.155571 -247.336329) (xy 436.171281 -247.387259)
			(xy 436.179224 -247.439963) (xy 436.179722 -247.466612) (xy 436.179224 -247.493261) (xy 436.171281 -247.545965)
			(xy 436.155571 -247.596895) (xy 436.132445 -247.644916) (xy 436.102421 -247.688953) (xy 436.066169 -247.728024)
			(xy 436.024498 -247.761255) (xy 435.97834 -247.787904) (xy 435.928726 -247.807376) (xy 435.876764 -247.819236)
			(xy 435.823614 -247.82322) (xy 435.770464 -247.819236) (xy 435.718502 -247.807376) (xy 435.668888 -247.787904)
			(xy 435.62273 -247.761255) (xy 435.581059 -247.728024) (xy 435.544807 -247.688953) (xy 435.514783 -247.644916)
			(xy 435.491657 -247.596895) (xy 435.475947 -247.545965) (xy 435.468004 -247.493261) (xy 421.091624 -247.493261)
			(xy 421.083681 -247.545965) (xy 421.067971 -247.596895) (xy 421.044845 -247.644916) (xy 421.014821 -247.688953)
			(xy 420.978569 -247.728024) (xy 420.936898 -247.761255) (xy 420.89074 -247.787904) (xy 420.841126 -247.807376)
			(xy 420.789164 -247.819236) (xy 420.736014 -247.82322) (xy 420.682864 -247.819236) (xy 420.630902 -247.807376)
			(xy 420.581288 -247.787904) (xy 420.53513 -247.761255) (xy 420.493459 -247.728024) (xy 420.457207 -247.688953)
			(xy 420.427183 -247.644916) (xy 420.404057 -247.596895) (xy 420.388347 -247.545965) (xy 420.380404 -247.493261)
			(xy 406.00225 -247.493261) (xy 406.006937 -247.544793) (xy 406.008078 -247.573546) (xy 406.033905 -248.343399)
			(xy 424.480472 -248.343399) (xy 424.480472 -248.290101) (xy 424.488415 -248.237397) (xy 424.504125 -248.186467)
			(xy 424.527251 -248.138446) (xy 424.557275 -248.094409) (xy 424.593527 -248.055338) (xy 424.635198 -248.022107)
			(xy 424.681356 -247.995458) (xy 424.73097 -247.975986) (xy 424.782932 -247.964126) (xy 424.836082 -247.960143)
			(xy 424.889232 -247.964126) (xy 424.941194 -247.975986) (xy 424.990808 -247.995458) (xy 425.036966 -248.022107)
			(xy 425.078637 -248.055338) (xy 425.114889 -248.094409) (xy 425.144913 -248.138446) (xy 425.168039 -248.186467)
			(xy 425.183749 -248.237397) (xy 425.191692 -248.290101) (xy 425.19219 -248.31675) (xy 425.191692 -248.343399)
			(xy 439.568072 -248.343399) (xy 439.568072 -248.290101) (xy 439.576015 -248.237397) (xy 439.591725 -248.186467)
			(xy 439.614851 -248.138446) (xy 439.644875 -248.094409) (xy 439.681127 -248.055338) (xy 439.722798 -248.022107)
			(xy 439.768956 -247.995458) (xy 439.81857 -247.975986) (xy 439.870532 -247.964126) (xy 439.923682 -247.960143)
			(xy 439.976832 -247.964126) (xy 440.028794 -247.975986) (xy 440.078408 -247.995458) (xy 440.124566 -248.022107)
			(xy 440.166237 -248.055338) (xy 440.202489 -248.094409) (xy 440.232513 -248.138446) (xy 440.255639 -248.186467)
			(xy 440.271349 -248.237397) (xy 440.279292 -248.290101) (xy 440.27979 -248.31675) (xy 440.279292 -248.343399)
			(xy 440.271349 -248.396103) (xy 440.255639 -248.447033) (xy 440.232513 -248.495054) (xy 440.202489 -248.539091)
			(xy 440.166237 -248.578162) (xy 440.124566 -248.611393) (xy 440.078408 -248.638042) (xy 440.028794 -248.657514)
			(xy 439.976832 -248.669374) (xy 439.923682 -248.673358) (xy 439.870532 -248.669374) (xy 439.81857 -248.657514)
			(xy 439.768956 -248.638042) (xy 439.722798 -248.611393) (xy 439.681127 -248.578162) (xy 439.644875 -248.539091)
			(xy 439.614851 -248.495054) (xy 439.591725 -248.447033) (xy 439.576015 -248.396103) (xy 439.568072 -248.343399)
			(xy 425.191692 -248.343399) (xy 425.183749 -248.396103) (xy 425.168039 -248.447033) (xy 425.144913 -248.495054)
			(xy 425.114889 -248.539091) (xy 425.078637 -248.578162) (xy 425.036966 -248.611393) (xy 424.990808 -248.638042)
			(xy 424.941194 -248.657514) (xy 424.889232 -248.669374) (xy 424.836082 -248.673358) (xy 424.782932 -248.669374)
			(xy 424.73097 -248.657514) (xy 424.681356 -248.638042) (xy 424.635198 -248.611393) (xy 424.593527 -248.578162)
			(xy 424.557275 -248.539091) (xy 424.527251 -248.495054) (xy 424.504125 -248.447033) (xy 424.488415 -248.396103)
			(xy 424.480472 -248.343399) (xy 406.033905 -248.343399) (xy 406.062416 -249.193283) (xy 420.380404 -249.193283)
			(xy 420.380404 -249.139985) (xy 420.388347 -249.087281) (xy 420.404057 -249.036351) (xy 420.427183 -248.98833)
			(xy 420.457207 -248.944293) (xy 420.493459 -248.905222) (xy 420.53513 -248.871991) (xy 420.581288 -248.845342)
			(xy 420.630902 -248.82587) (xy 420.682864 -248.81401) (xy 420.736014 -248.810027) (xy 420.789164 -248.81401)
			(xy 420.841126 -248.82587) (xy 420.89074 -248.845342) (xy 420.936898 -248.871991) (xy 420.978569 -248.905222)
			(xy 421.014821 -248.944293) (xy 421.044845 -248.98833) (xy 421.067971 -249.036351) (xy 421.083681 -249.087281)
			(xy 421.091624 -249.139985) (xy 421.092122 -249.166634) (xy 421.091624 -249.193283) (xy 435.468004 -249.193283)
			(xy 435.468004 -249.139985) (xy 435.475947 -249.087281) (xy 435.491657 -249.036351) (xy 435.514783 -248.98833)
			(xy 435.544807 -248.944293) (xy 435.581059 -248.905222) (xy 435.62273 -248.871991) (xy 435.668888 -248.845342)
			(xy 435.718502 -248.82587) (xy 435.770464 -248.81401) (xy 435.823614 -248.810027) (xy 435.876764 -248.81401)
			(xy 435.928726 -248.82587) (xy 435.97834 -248.845342) (xy 436.024498 -248.871991) (xy 436.066169 -248.905222)
			(xy 436.102421 -248.944293) (xy 436.132445 -248.98833) (xy 436.155571 -249.036351) (xy 436.171281 -249.087281)
			(xy 436.179224 -249.139985) (xy 436.179722 -249.166634) (xy 436.179224 -249.193283) (xy 436.171281 -249.245987)
			(xy 436.155571 -249.296917) (xy 436.132445 -249.344938) (xy 436.102421 -249.388975) (xy 436.066169 -249.428046)
			(xy 436.024498 -249.461277) (xy 435.97834 -249.487926) (xy 435.928726 -249.507398) (xy 435.876764 -249.519258)
			(xy 435.823614 -249.523242) (xy 435.770464 -249.519258) (xy 435.718502 -249.507398) (xy 435.668888 -249.487926)
			(xy 435.62273 -249.461277) (xy 435.581059 -249.428046) (xy 435.544807 -249.388975) (xy 435.514783 -249.344938)
			(xy 435.491657 -249.296917) (xy 435.475947 -249.245987) (xy 435.468004 -249.193283) (xy 421.091624 -249.193283)
			(xy 421.083681 -249.245987) (xy 421.067971 -249.296917) (xy 421.044845 -249.344938) (xy 421.014821 -249.388975)
			(xy 420.978569 -249.428046) (xy 420.936898 -249.461277) (xy 420.89074 -249.487926) (xy 420.841126 -249.507398)
			(xy 420.789164 -249.519258) (xy 420.736014 -249.523242) (xy 420.682864 -249.519258) (xy 420.630902 -249.507398)
			(xy 420.581288 -249.487926) (xy 420.53513 -249.461277) (xy 420.493459 -249.428046) (xy 420.457207 -249.388975)
			(xy 420.427183 -249.344938) (xy 420.404057 -249.296917) (xy 420.388347 -249.245987) (xy 420.380404 -249.193283)
			(xy 406.062416 -249.193283) (xy 406.090936 -250.043421) (xy 424.480472 -250.043421) (xy 424.480472 -249.990123)
			(xy 424.488415 -249.937419) (xy 424.504125 -249.886489) (xy 424.527251 -249.838468) (xy 424.557275 -249.794431)
			(xy 424.593527 -249.75536) (xy 424.635198 -249.722129) (xy 424.681356 -249.69548) (xy 424.73097 -249.676008)
			(xy 424.782932 -249.664148) (xy 424.836082 -249.660165) (xy 424.889232 -249.664148) (xy 424.941194 -249.676008)
			(xy 424.990808 -249.69548) (xy 425.036966 -249.722129) (xy 425.078637 -249.75536) (xy 425.114889 -249.794431)
			(xy 425.144913 -249.838468) (xy 425.168039 -249.886489) (xy 425.183749 -249.937419) (xy 425.191692 -249.990123)
			(xy 425.19219 -250.016772) (xy 425.191692 -250.043421) (xy 439.568072 -250.043421) (xy 439.568072 -249.990123)
			(xy 439.576015 -249.937419) (xy 439.591725 -249.886489) (xy 439.614851 -249.838468) (xy 439.644875 -249.794431)
			(xy 439.681127 -249.75536) (xy 439.722798 -249.722129) (xy 439.768956 -249.69548) (xy 439.81857 -249.676008)
			(xy 439.870532 -249.664148) (xy 439.923682 -249.660165) (xy 439.976832 -249.664148) (xy 440.028794 -249.676008)
			(xy 440.078408 -249.69548) (xy 440.124566 -249.722129) (xy 440.166237 -249.75536) (xy 440.202489 -249.794431)
			(xy 440.232513 -249.838468) (xy 440.255639 -249.886489) (xy 440.271349 -249.937419) (xy 440.279292 -249.990123)
			(xy 440.27979 -250.016772) (xy 440.279292 -250.043421) (xy 440.271349 -250.096125) (xy 440.255639 -250.147055)
			(xy 440.232513 -250.195076) (xy 440.202489 -250.239113) (xy 440.166237 -250.278184) (xy 440.124566 -250.311415)
			(xy 440.078408 -250.338064) (xy 440.028794 -250.357536) (xy 439.976832 -250.369396) (xy 439.923682 -250.37338)
			(xy 439.870532 -250.369396) (xy 439.81857 -250.357536) (xy 439.768956 -250.338064) (xy 439.722798 -250.311415)
			(xy 439.681127 -250.278184) (xy 439.644875 -250.239113) (xy 439.614851 -250.195076) (xy 439.591725 -250.147055)
			(xy 439.576015 -250.096125) (xy 439.568072 -250.043421) (xy 425.191692 -250.043421) (xy 425.183749 -250.096125)
			(xy 425.168039 -250.147055) (xy 425.144913 -250.195076) (xy 425.114889 -250.239113) (xy 425.078637 -250.278184)
			(xy 425.036966 -250.311415) (xy 424.990808 -250.338064) (xy 424.941194 -250.357536) (xy 424.889232 -250.369396)
			(xy 424.836082 -250.37338) (xy 424.782932 -250.369396) (xy 424.73097 -250.357536) (xy 424.681356 -250.338064)
			(xy 424.635198 -250.311415) (xy 424.593527 -250.278184) (xy 424.557275 -250.239113) (xy 424.527251 -250.195076)
			(xy 424.504125 -250.147055) (xy 424.488415 -250.096125) (xy 424.480472 -250.043421) (xy 406.090936 -250.043421)
			(xy 406.119447 -250.893305) (xy 420.380404 -250.893305) (xy 420.380404 -250.840007) (xy 420.388347 -250.787303)
			(xy 420.404057 -250.736373) (xy 420.427183 -250.688352) (xy 420.457207 -250.644315) (xy 420.493459 -250.605244)
			(xy 420.53513 -250.572013) (xy 420.581288 -250.545364) (xy 420.630902 -250.525892) (xy 420.682864 -250.514032)
			(xy 420.736014 -250.510049) (xy 420.789164 -250.514032) (xy 420.841126 -250.525892) (xy 420.89074 -250.545364)
			(xy 420.936898 -250.572013) (xy 420.978569 -250.605244) (xy 421.014821 -250.644315) (xy 421.044845 -250.688352)
			(xy 421.067971 -250.736373) (xy 421.083681 -250.787303) (xy 421.091624 -250.840007) (xy 421.092122 -250.866656)
			(xy 421.091624 -250.893305) (xy 435.468004 -250.893305) (xy 435.468004 -250.840007) (xy 435.475947 -250.787303)
			(xy 435.491657 -250.736373) (xy 435.514783 -250.688352) (xy 435.544807 -250.644315) (xy 435.581059 -250.605244)
			(xy 435.62273 -250.572013) (xy 435.668888 -250.545364) (xy 435.718502 -250.525892) (xy 435.770464 -250.514032)
			(xy 435.823614 -250.510049) (xy 435.876764 -250.514032) (xy 435.928726 -250.525892) (xy 435.97834 -250.545364)
			(xy 436.024498 -250.572013) (xy 436.066169 -250.605244) (xy 436.102421 -250.644315) (xy 436.132445 -250.688352)
			(xy 436.155571 -250.736373) (xy 436.171281 -250.787303) (xy 436.179224 -250.840007) (xy 436.179722 -250.866656)
			(xy 436.179224 -250.893305) (xy 436.171281 -250.946009) (xy 436.155571 -250.996939) (xy 436.132445 -251.04496)
			(xy 436.102421 -251.088997) (xy 436.066169 -251.128068) (xy 436.024498 -251.161299) (xy 435.97834 -251.187948)
			(xy 435.928726 -251.20742) (xy 435.876764 -251.21928) (xy 435.823614 -251.223264) (xy 435.770464 -251.21928)
			(xy 435.718502 -251.20742) (xy 435.668888 -251.187948) (xy 435.62273 -251.161299) (xy 435.581059 -251.128068)
			(xy 435.544807 -251.088997) (xy 435.514783 -251.04496) (xy 435.491657 -250.996939) (xy 435.475947 -250.946009)
			(xy 435.468004 -250.893305) (xy 421.091624 -250.893305) (xy 421.083681 -250.946009) (xy 421.067971 -250.996939)
			(xy 421.044845 -251.04496) (xy 421.014821 -251.088997) (xy 420.978569 -251.128068) (xy 420.936898 -251.161299)
			(xy 420.89074 -251.187948) (xy 420.841126 -251.20742) (xy 420.789164 -251.21928) (xy 420.736014 -251.223264)
			(xy 420.682864 -251.21928) (xy 420.630902 -251.20742) (xy 420.581288 -251.187948) (xy 420.53513 -251.161299)
			(xy 420.493459 -251.128068) (xy 420.457207 -251.088997) (xy 420.427183 -251.04496) (xy 420.404057 -250.996939)
			(xy 420.388347 -250.946009) (xy 420.380404 -250.893305) (xy 406.119447 -250.893305) (xy 406.147967 -251.743443)
			(xy 424.480472 -251.743443) (xy 424.480472 -251.690145) (xy 424.488415 -251.637441) (xy 424.504125 -251.586511)
			(xy 424.527251 -251.53849) (xy 424.557275 -251.494453) (xy 424.593527 -251.455382) (xy 424.635198 -251.422151)
			(xy 424.681356 -251.395502) (xy 424.73097 -251.37603) (xy 424.782932 -251.36417) (xy 424.836082 -251.360187)
			(xy 424.889232 -251.36417) (xy 424.941194 -251.37603) (xy 424.990808 -251.395502) (xy 425.036966 -251.422151)
			(xy 425.078637 -251.455382) (xy 425.114889 -251.494453) (xy 425.144913 -251.53849) (xy 425.168039 -251.586511)
			(xy 425.183749 -251.637441) (xy 425.191692 -251.690145) (xy 425.19219 -251.716794) (xy 425.191692 -251.743443)
			(xy 439.568072 -251.743443) (xy 439.568072 -251.690145) (xy 439.576015 -251.637441) (xy 439.591725 -251.586511)
			(xy 439.614851 -251.53849) (xy 439.644875 -251.494453) (xy 439.681127 -251.455382) (xy 439.722798 -251.422151)
			(xy 439.768956 -251.395502) (xy 439.81857 -251.37603) (xy 439.870532 -251.36417) (xy 439.923682 -251.360187)
			(xy 439.976832 -251.36417) (xy 440.028794 -251.37603) (xy 440.078408 -251.395502) (xy 440.124566 -251.422151)
			(xy 440.166237 -251.455382) (xy 440.202489 -251.494453) (xy 440.232513 -251.53849) (xy 440.255639 -251.586511)
			(xy 440.271349 -251.637441) (xy 440.279292 -251.690145) (xy 440.27979 -251.716794) (xy 440.279292 -251.743443)
			(xy 440.271349 -251.796147) (xy 440.255639 -251.847077) (xy 440.232513 -251.895098) (xy 440.202489 -251.939135)
			(xy 440.166237 -251.978206) (xy 440.124566 -252.011437) (xy 440.078408 -252.038086) (xy 440.028794 -252.057558)
			(xy 439.976832 -252.069418) (xy 439.923682 -252.073402) (xy 439.870532 -252.069418) (xy 439.81857 -252.057558)
			(xy 439.768956 -252.038086) (xy 439.722798 -252.011437) (xy 439.681127 -251.978206) (xy 439.644875 -251.939135)
			(xy 439.614851 -251.895098) (xy 439.591725 -251.847077) (xy 439.576015 -251.796147) (xy 439.568072 -251.743443)
			(xy 425.191692 -251.743443) (xy 425.183749 -251.796147) (xy 425.168039 -251.847077) (xy 425.144913 -251.895098)
			(xy 425.114889 -251.939135) (xy 425.078637 -251.978206) (xy 425.036966 -252.011437) (xy 424.990808 -252.038086)
			(xy 424.941194 -252.057558) (xy 424.889232 -252.069418) (xy 424.836082 -252.073402) (xy 424.782932 -252.069418)
			(xy 424.73097 -252.057558) (xy 424.681356 -252.038086) (xy 424.635198 -252.011437) (xy 424.593527 -251.978206)
			(xy 424.557275 -251.939135) (xy 424.527251 -251.895098) (xy 424.504125 -251.847077) (xy 424.488415 -251.796147)
			(xy 424.480472 -251.743443) (xy 406.147967 -251.743443) (xy 406.176478 -252.593327) (xy 420.380404 -252.593327)
			(xy 420.380404 -252.540029) (xy 420.388347 -252.487325) (xy 420.404057 -252.436395) (xy 420.427183 -252.388374)
			(xy 420.457207 -252.344337) (xy 420.493459 -252.305266) (xy 420.53513 -252.272035) (xy 420.581288 -252.245386)
			(xy 420.630902 -252.225914) (xy 420.682864 -252.214054) (xy 420.736014 -252.210071) (xy 420.789164 -252.214054)
			(xy 420.841126 -252.225914) (xy 420.89074 -252.245386) (xy 420.936898 -252.272035) (xy 420.978569 -252.305266)
			(xy 421.014821 -252.344337) (xy 421.044845 -252.388374) (xy 421.067971 -252.436395) (xy 421.083681 -252.487325)
			(xy 421.091624 -252.540029) (xy 421.092122 -252.566678) (xy 421.091624 -252.593327) (xy 424.480472 -252.593327)
			(xy 424.480472 -252.540029) (xy 424.488415 -252.487325) (xy 424.504125 -252.436395) (xy 424.527251 -252.388374)
			(xy 424.557275 -252.344337) (xy 424.593527 -252.305266) (xy 424.635198 -252.272035) (xy 424.681356 -252.245386)
			(xy 424.73097 -252.225914) (xy 424.782932 -252.214054) (xy 424.836082 -252.210071) (xy 424.889232 -252.214054)
			(xy 424.941194 -252.225914) (xy 424.990808 -252.245386) (xy 425.036966 -252.272035) (xy 425.078637 -252.305266)
			(xy 425.114889 -252.344337) (xy 425.144913 -252.388374) (xy 425.168039 -252.436395) (xy 425.183749 -252.487325)
			(xy 425.191692 -252.540029) (xy 425.19219 -252.566678) (xy 425.191692 -252.593327) (xy 431.998872 -252.593327)
			(xy 431.998872 -252.540029) (xy 432.006815 -252.487325) (xy 432.022525 -252.436395) (xy 432.045651 -252.388374)
			(xy 432.075675 -252.344337) (xy 432.111927 -252.305266) (xy 432.153598 -252.272035) (xy 432.199756 -252.245386)
			(xy 432.24937 -252.225914) (xy 432.301332 -252.214054) (xy 432.354482 -252.210071) (xy 432.407632 -252.214054)
			(xy 432.459594 -252.225914) (xy 432.509208 -252.245386) (xy 432.555366 -252.272035) (xy 432.597037 -252.305266)
			(xy 432.633289 -252.344337) (xy 432.663313 -252.388374) (xy 432.686439 -252.436395) (xy 432.702149 -252.487325)
			(xy 432.710092 -252.540029) (xy 432.71059 -252.566678) (xy 432.710092 -252.593327) (xy 435.468004 -252.593327)
			(xy 435.468004 -252.540029) (xy 435.475947 -252.487325) (xy 435.491657 -252.436395) (xy 435.514783 -252.388374)
			(xy 435.544807 -252.344337) (xy 435.581059 -252.305266) (xy 435.62273 -252.272035) (xy 435.668888 -252.245386)
			(xy 435.718502 -252.225914) (xy 435.770464 -252.214054) (xy 435.823614 -252.210071) (xy 435.876764 -252.214054)
			(xy 435.928726 -252.225914) (xy 435.97834 -252.245386) (xy 436.024498 -252.272035) (xy 436.066169 -252.305266)
			(xy 436.102421 -252.344337) (xy 436.132445 -252.388374) (xy 436.155571 -252.436395) (xy 436.171281 -252.487325)
			(xy 436.179224 -252.540029) (xy 436.179722 -252.566678) (xy 436.179224 -252.593327) (xy 439.568072 -252.593327)
			(xy 439.568072 -252.540029) (xy 439.576015 -252.487325) (xy 439.591725 -252.436395) (xy 439.614851 -252.388374)
			(xy 439.644875 -252.344337) (xy 439.681127 -252.305266) (xy 439.722798 -252.272035) (xy 439.768956 -252.245386)
			(xy 439.81857 -252.225914) (xy 439.870532 -252.214054) (xy 439.923682 -252.210071) (xy 439.976832 -252.214054)
			(xy 440.028794 -252.225914) (xy 440.078408 -252.245386) (xy 440.124566 -252.272035) (xy 440.166237 -252.305266)
			(xy 440.202489 -252.344337) (xy 440.232513 -252.388374) (xy 440.255639 -252.436395) (xy 440.271349 -252.487325)
			(xy 440.279292 -252.540029) (xy 440.27979 -252.566678) (xy 440.279292 -252.593327) (xy 447.111872 -252.593327)
			(xy 447.111872 -252.540029) (xy 447.119815 -252.487325) (xy 447.135525 -252.436395) (xy 447.158651 -252.388374)
			(xy 447.188675 -252.344337) (xy 447.224927 -252.305266) (xy 447.266598 -252.272035) (xy 447.312756 -252.245386)
			(xy 447.36237 -252.225914) (xy 447.414332 -252.214054) (xy 447.467482 -252.210071) (xy 447.520632 -252.214054)
			(xy 447.572594 -252.225914) (xy 447.622208 -252.245386) (xy 447.668366 -252.272035) (xy 447.710037 -252.305266)
			(xy 447.746289 -252.344337) (xy 447.776313 -252.388374) (xy 447.799439 -252.436395) (xy 447.815149 -252.487325)
			(xy 447.823092 -252.540029) (xy 447.82359 -252.566678) (xy 447.823092 -252.593327) (xy 447.815149 -252.646031)
			(xy 447.799439 -252.696961) (xy 447.776313 -252.744982) (xy 447.746289 -252.789019) (xy 447.710037 -252.82809)
			(xy 447.668366 -252.861321) (xy 447.622208 -252.88797) (xy 447.572594 -252.907442) (xy 447.520632 -252.919302)
			(xy 447.467482 -252.923286) (xy 447.414332 -252.919302) (xy 447.36237 -252.907442) (xy 447.312756 -252.88797)
			(xy 447.266598 -252.861321) (xy 447.224927 -252.82809) (xy 447.188675 -252.789019) (xy 447.158651 -252.744982)
			(xy 447.135525 -252.696961) (xy 447.119815 -252.646031) (xy 447.111872 -252.593327) (xy 440.279292 -252.593327)
			(xy 440.271349 -252.646031) (xy 440.255639 -252.696961) (xy 440.232513 -252.744982) (xy 440.202489 -252.789019)
			(xy 440.166237 -252.82809) (xy 440.124566 -252.861321) (xy 440.078408 -252.88797) (xy 440.028794 -252.907442)
			(xy 439.976832 -252.919302) (xy 439.923682 -252.923286) (xy 439.870532 -252.919302) (xy 439.81857 -252.907442)
			(xy 439.768956 -252.88797) (xy 439.722798 -252.861321) (xy 439.681127 -252.82809) (xy 439.644875 -252.789019)
			(xy 439.614851 -252.744982) (xy 439.591725 -252.696961) (xy 439.576015 -252.646031) (xy 439.568072 -252.593327)
			(xy 436.179224 -252.593327) (xy 436.171281 -252.646031) (xy 436.155571 -252.696961) (xy 436.132445 -252.744982)
			(xy 436.102421 -252.789019) (xy 436.066169 -252.82809) (xy 436.024498 -252.861321) (xy 435.97834 -252.88797)
			(xy 435.928726 -252.907442) (xy 435.876764 -252.919302) (xy 435.823614 -252.923286) (xy 435.770464 -252.919302)
			(xy 435.718502 -252.907442) (xy 435.668888 -252.88797) (xy 435.62273 -252.861321) (xy 435.581059 -252.82809)
			(xy 435.544807 -252.789019) (xy 435.514783 -252.744982) (xy 435.491657 -252.696961) (xy 435.475947 -252.646031)
			(xy 435.468004 -252.593327) (xy 432.710092 -252.593327) (xy 432.702149 -252.646031) (xy 432.686439 -252.696961)
			(xy 432.663313 -252.744982) (xy 432.633289 -252.789019) (xy 432.597037 -252.82809) (xy 432.555366 -252.861321)
			(xy 432.509208 -252.88797) (xy 432.459594 -252.907442) (xy 432.407632 -252.919302) (xy 432.354482 -252.923286)
			(xy 432.301332 -252.919302) (xy 432.24937 -252.907442) (xy 432.199756 -252.88797) (xy 432.153598 -252.861321)
			(xy 432.111927 -252.82809) (xy 432.075675 -252.789019) (xy 432.045651 -252.744982) (xy 432.022525 -252.696961)
			(xy 432.006815 -252.646031) (xy 431.998872 -252.593327) (xy 425.191692 -252.593327) (xy 425.183749 -252.646031)
			(xy 425.168039 -252.696961) (xy 425.144913 -252.744982) (xy 425.114889 -252.789019) (xy 425.078637 -252.82809)
			(xy 425.036966 -252.861321) (xy 424.990808 -252.88797) (xy 424.941194 -252.907442) (xy 424.889232 -252.919302)
			(xy 424.836082 -252.923286) (xy 424.782932 -252.919302) (xy 424.73097 -252.907442) (xy 424.681356 -252.88797)
			(xy 424.635198 -252.861321) (xy 424.593527 -252.82809) (xy 424.557275 -252.789019) (xy 424.527251 -252.744982)
			(xy 424.504125 -252.696961) (xy 424.488415 -252.646031) (xy 424.480472 -252.593327) (xy 421.091624 -252.593327)
			(xy 421.083681 -252.646031) (xy 421.067971 -252.696961) (xy 421.044845 -252.744982) (xy 421.014821 -252.789019)
			(xy 420.978569 -252.82809) (xy 420.936898 -252.861321) (xy 420.89074 -252.88797) (xy 420.841126 -252.907442)
			(xy 420.789164 -252.919302) (xy 420.736014 -252.923286) (xy 420.682864 -252.919302) (xy 420.630902 -252.907442)
			(xy 420.581288 -252.88797) (xy 420.53513 -252.861321) (xy 420.493459 -252.82809) (xy 420.457207 -252.789019)
			(xy 420.427183 -252.744982) (xy 420.404057 -252.696961) (xy 420.388347 -252.646031) (xy 420.380404 -252.593327)
			(xy 406.176478 -252.593327) (xy 406.205944 -253.47168) (xy 406.206452 -253.5047) (xy 406.206452 -253.508002)
			(xy 406.20688 -253.518273) (xy 406.214846 -253.537205) (xy 406.229586 -253.551508) (xy 406.248749 -253.5589)
			(xy 406.25903 -253.559056) (xy 406.270206 -253.558802) (xy 406.295111 -253.55922) (xy 406.344433 -253.56617)
			(xy 406.392304 -253.579933) (xy 406.437786 -253.60024) (xy 406.47999 -253.626693) (xy 406.518091 -253.658777)
			(xy 406.551344 -253.695861) (xy 406.565608 -253.716282) (xy 406.574748 -253.72886) (xy 406.59905 -253.748229)
			(xy 406.628048 -253.759405) (xy 406.659063 -253.761356) (xy 406.689232 -253.753901) (xy 406.702768 -253.746254)
			(xy 406.723799 -253.7339) (xy 406.76852 -253.71443) (xy 406.81548 -253.701249) (xy 406.8638 -253.694602)
			(xy 406.888188 -253.694184) (xy 406.91484 -253.694656) (xy 406.96755 -253.702599) (xy 407.018487 -253.71831)
			(xy 407.066513 -253.741437) (xy 407.110556 -253.771463) (xy 407.149632 -253.807719) (xy 407.182867 -253.849394)
			(xy 407.20952 -253.895557) (xy 407.228995 -253.945176) (xy 407.240856 -253.997144) (xy 407.24484 -254.0503)
			(xy 407.240856 -254.103456) (xy 407.228995 -254.155424) (xy 407.20952 -254.205043) (xy 407.182867 -254.251206)
			(xy 407.149632 -254.292881) (xy 407.110556 -254.329137) (xy 407.066513 -254.359163) (xy 407.018487 -254.38229)
			(xy 406.96755 -254.398001) (xy 406.91484 -254.405944) (xy 406.888188 -254.4064) (xy 406.863283 -254.405982)
			(xy 406.813961 -254.399031) (xy 406.766091 -254.385268) (xy 406.72061 -254.36496) (xy 406.678406 -254.338506)
			(xy 406.640305 -254.306423) (xy 406.607053 -254.269338) (xy 406.592786 -254.24892) (xy 406.583646 -254.236343)
			(xy 406.559344 -254.216975) (xy 406.530347 -254.2058) (xy 406.499333 -254.203851) (xy 406.469165 -254.211307)
			(xy 406.455626 -254.218948) (xy 406.434595 -254.231302) (xy 406.389874 -254.25077) (xy 406.342914 -254.263951)
			(xy 406.294594 -254.270597) (xy 406.270206 -254.271018) (xy 406.249886 -254.27051) (xy 406.236765 -254.270209)
			(xy 406.21107 -254.275512) (xy 406.187573 -254.287183) (xy 406.167823 -254.304453) (xy 406.153121 -254.326183)
			(xy 406.144438 -254.350941) (xy 406.142952 -254.363982) (xy 406.109424 -254.79629) (xy 410.227018 -254.79629)
			(xy 410.227511 -254.768199) (xy 410.236357 -254.712719) (xy 410.253811 -254.659317) (xy 410.27944 -254.609322)
			(xy 410.312607 -254.563976) (xy 410.332174 -254.543814) (xy 410.342335 -254.532941) (xy 410.35649 -254.506781)
			(xy 410.36252 -254.477654) (xy 410.359915 -254.448024) (xy 410.348897 -254.420396) (xy 410.340048 -254.408432)
			(xy 410.321888 -254.38462) (xy 410.292959 -254.332193) (xy 410.273208 -254.275665) (xy 410.263192 -254.21663)
			(xy 410.262578 -254.18669) (xy 410.263076 -254.160041) (xy 410.271019 -254.107337) (xy 410.286729 -254.056407)
			(xy 410.309855 -254.008386) (xy 410.339879 -253.964349) (xy 410.376131 -253.925278) (xy 410.417802 -253.892047)
			(xy 410.46396 -253.865398) (xy 410.513574 -253.845926) (xy 410.565536 -253.834066) (xy 410.618686 -253.830083)
			(xy 410.671836 -253.834066) (xy 410.723798 -253.845926) (xy 410.773412 -253.865398) (xy 410.81957 -253.892047)
			(xy 410.861241 -253.925278) (xy 410.897493 -253.964349) (xy 410.927517 -254.008386) (xy 410.950643 -254.056407)
			(xy 410.958707 -254.08255) (xy 411.225238 -254.08255) (xy 411.225695 -254.054563) (xy 411.234459 -253.99928)
			(xy 411.251763 -253.946048) (xy 411.277181 -253.896179) (xy 411.310088 -253.8509) (xy 411.349673 -253.811326)
			(xy 411.394961 -253.778431) (xy 411.444837 -253.753026) (xy 411.498073 -253.735736) (xy 411.553359 -253.726987)
			(xy 411.581346 -253.726442) (xy 411.606804 -253.726877) (xy 411.6572 -253.734134) (xy 411.706049 -253.748494)
			(xy 411.752356 -253.769664) (xy 411.795176 -253.797212) (xy 411.833637 -253.830577) (xy 411.866954 -253.869079)
			(xy 411.881066 -253.890272) (xy 411.88872 -253.90139) (xy 411.908742 -253.919477) (xy 411.932802 -253.93169)
			(xy 411.95922 -253.937176) (xy 411.986154 -253.935554) (xy 412.011722 -253.926936) (xy 412.034143 -253.911924)
			(xy 412.05185 -253.891565) (xy 412.058104 -253.879604) (xy 412.070993 -253.854129) (xy 412.103686 -253.807328)
			(xy 412.143425 -253.76634) (xy 412.189193 -253.732215) (xy 412.239817 -253.705827) (xy 412.294003 -253.68785)
			(xy 412.350361 -253.678746) (xy 412.378906 -253.678182) (xy 412.406889 -253.678735) (xy 412.409679 -253.679177)
			(xy 418.28846 -253.679177) (xy 418.28846 -253.625879) (xy 418.296403 -253.573175) (xy 418.312113 -253.522245)
			(xy 418.335239 -253.474224) (xy 418.365263 -253.430187) (xy 418.401515 -253.391116) (xy 418.443186 -253.357885)
			(xy 418.489344 -253.331236) (xy 418.538958 -253.311764) (xy 418.59092 -253.299904) (xy 418.64407 -253.295921)
			(xy 418.69722 -253.299904) (xy 418.749182 -253.311764) (xy 418.798796 -253.331236) (xy 418.844954 -253.357885)
			(xy 418.886625 -253.391116) (xy 418.922877 -253.430187) (xy 418.952901 -253.474224) (xy 418.976027 -253.522245)
			(xy 418.991737 -253.573175) (xy 418.99968 -253.625879) (xy 419.000178 -253.652528) (xy 418.99968 -253.679177)
			(xy 418.991737 -253.731881) (xy 418.976027 -253.782811) (xy 418.952901 -253.830832) (xy 418.922877 -253.874869)
			(xy 418.886625 -253.91394) (xy 418.844954 -253.947171) (xy 418.798796 -253.97382) (xy 418.749182 -253.993292)
			(xy 418.69722 -254.005152) (xy 418.64407 -254.009136) (xy 418.59092 -254.005152) (xy 418.538958 -253.993292)
			(xy 418.489344 -253.97382) (xy 418.443186 -253.947171) (xy 418.401515 -253.91394) (xy 418.365263 -253.874869)
			(xy 418.335239 -253.830832) (xy 418.312113 -253.782811) (xy 418.296403 -253.731881) (xy 418.28846 -253.679177)
			(xy 412.409679 -253.679177) (xy 412.462165 -253.687491) (xy 412.515391 -253.704786) (xy 412.565257 -253.730194)
			(xy 412.610534 -253.763089) (xy 412.650108 -253.802663) (xy 412.683004 -253.84794) (xy 412.708413 -253.897805)
			(xy 412.725708 -253.951031) (xy 412.734464 -254.006307) (xy 412.735014 -254.03429) (xy 412.734574 -254.059267)
			(xy 412.727578 -254.108729) (xy 412.713736 -254.156728) (xy 412.69332 -254.20232) (xy 412.66673 -254.24461)
			(xy 412.63449 -254.282768) (xy 412.616142 -254.29972) (xy 412.605596 -254.309813) (xy 412.590214 -254.334605)
			(xy 412.58247 -254.362735) (xy 412.582996 -254.391907) (xy 412.591748 -254.41974) (xy 412.608014 -254.443962)
			(xy 412.618936 -254.453644) (xy 412.627342 -254.460693) (xy 412.643355 -254.47569) (xy 412.65094 -254.483616)
			(xy 412.660917 -254.493546) (xy 412.6851 -254.507936) (xy 412.71229 -254.515189) (xy 412.740428 -254.514756)
			(xy 412.767381 -254.506669) (xy 412.791111 -254.491542) (xy 412.8008 -254.48133) (xy 412.817761 -254.462822)
			(xy 412.856004 -254.4303) (xy 412.898438 -254.403475) (xy 412.944219 -254.382877) (xy 412.992441 -254.368916)
			(xy 413.042145 -254.361869) (xy 413.067246 -254.361442) (xy 413.093897 -254.361843) (xy 413.146602 -254.369793)
			(xy 413.197534 -254.38551) (xy 413.245555 -254.408641) (xy 413.289593 -254.43867) (xy 413.328663 -254.474927)
			(xy 413.361894 -254.516602) (xy 413.388543 -254.562764) (xy 413.408015 -254.612382) (xy 413.419875 -254.664347)
			(xy 413.423858 -254.7175) (xy 413.419875 -254.770653) (xy 413.408015 -254.822618) (xy 413.388543 -254.872236)
			(xy 413.361894 -254.918398) (xy 413.328663 -254.960073) (xy 413.289593 -254.99633) (xy 413.245555 -255.026359)
			(xy 413.197534 -255.04949) (xy 413.146602 -255.065207) (xy 413.093897 -255.073157) (xy 413.067246 -255.073658)
			(xy 413.038181 -255.073067) (xy 412.98082 -255.063644) (xy 412.925752 -255.045026) (xy 412.874441 -255.017707)
			(xy 412.828252 -254.982414) (xy 412.807912 -254.961644) (xy 412.797885 -254.95177) (xy 412.773715 -254.937383)
			(xy 412.746539 -254.930127) (xy 412.718414 -254.93055) (xy 412.691469 -254.938621) (xy 412.667743 -254.953728)
			(xy 412.658052 -254.96393) (xy 412.641056 -254.982405) (xy 412.602821 -255.014931) (xy 412.560396 -255.041762)
			(xy 412.514621 -255.062366) (xy 412.466405 -255.076333) (xy 412.416705 -255.083387) (xy 412.391606 -255.083818)
			(xy 412.363241 -255.083281) (xy 412.307225 -255.074307) (xy 412.25334 -255.056568) (xy 412.202948 -255.030512)
			(xy 412.157322 -254.9968) (xy 412.117616 -254.956282) (xy 412.100776 -254.93345) (xy 412.091544 -254.921413)
			(xy 412.067574 -254.902855) (xy 412.039209 -254.89216) (xy 412.008954 -254.890272) (xy 411.979479 -254.897359)
			(xy 411.953389 -254.912794) (xy 411.932987 -254.935215) (xy 411.926024 -254.94869) (xy 411.91485 -254.9712)
			(xy 411.88718 -255.01315) (xy 411.853886 -255.050792) (xy 411.815629 -255.083378) (xy 411.77317 -255.110259)
			(xy 411.727352 -255.130903) (xy 411.679087 -255.144897) (xy 411.629333 -255.151965) (xy 411.604206 -255.152398)
			(xy 411.57622 -255.151882) (xy 411.520938 -255.143127) (xy 411.467706 -255.125831) (xy 411.417835 -255.100421)
			(xy 411.372553 -255.067522) (xy 411.332976 -255.027944) (xy 411.300077 -254.982662) (xy 411.274667 -254.93279)
			(xy 411.257372 -254.879558) (xy 411.248618 -254.824276) (xy 411.248098 -254.79629) (xy 411.248535 -254.770677)
			(xy 411.255865 -254.719977) (xy 411.270385 -254.670852) (xy 411.291797 -254.624315) (xy 411.319657 -254.581327)
			(xy 411.353392 -254.542777) (xy 411.372558 -254.52578) (xy 411.383768 -254.515513) (xy 411.400024 -254.489842)
			(xy 411.408015 -254.460527) (xy 411.407036 -254.430157) (xy 411.397172 -254.401418) (xy 411.379296 -254.376848)
			(xy 411.367478 -254.367284) (xy 411.345821 -254.35031) (xy 411.307428 -254.3109) (xy 411.275554 -254.266053)
			(xy 411.250958 -254.216837) (xy 411.234225 -254.164424) (xy 411.225754 -254.11006) (xy 411.225238 -254.08255)
			(xy 410.958707 -254.08255) (xy 410.966353 -254.107337) (xy 410.974296 -254.160041) (xy 410.974794 -254.18669)
			(xy 410.974285 -254.21478) (xy 410.965443 -254.27026) (xy 410.947992 -254.323661) (xy 410.922367 -254.373656)
			(xy 410.889203 -254.419004) (xy 410.869638 -254.439166) (xy 410.859495 -254.450055) (xy 410.845337 -254.47621)
			(xy 410.839303 -254.505332) (xy 410.841903 -254.534959) (xy 410.852917 -254.562585) (xy 410.861764 -254.574548)
			(xy 410.879916 -254.598365) (xy 410.908847 -254.65079) (xy 410.9286 -254.707317) (xy 410.938618 -254.766351)
			(xy 410.939234 -254.79629) (xy 410.938736 -254.822939) (xy 410.930793 -254.875643) (xy 410.915083 -254.926573)
			(xy 410.891957 -254.974594) (xy 410.861933 -255.018631) (xy 410.825681 -255.057702) (xy 410.78401 -255.090933)
			(xy 410.737852 -255.117582) (xy 410.688238 -255.137054) (xy 410.636276 -255.148914) (xy 410.583126 -255.152898)
			(xy 410.529976 -255.148914) (xy 410.478014 -255.137054) (xy 410.4284 -255.117582) (xy 410.382242 -255.090933)
			(xy 410.340571 -255.057702) (xy 410.304319 -255.018631) (xy 410.274295 -254.974594) (xy 410.251169 -254.926573)
			(xy 410.235459 -254.875643) (xy 410.227516 -254.822939) (xy 410.227018 -254.79629) (xy 406.109424 -254.79629)
			(xy 405.841708 -258.24815) (xy 405.862603 -258.263818) (xy 405.899645 -258.30063) (xy 405.930445 -258.342804)
			(xy 405.954239 -258.389292) (xy 405.970437 -258.43894) (xy 405.978635 -258.490516) (xy 405.979122 -258.516628)
			(xy 405.978641 -258.54266) (xy 405.970492 -258.594083) (xy 405.954384 -258.643593) (xy 405.930716 -258.689966)
			(xy 405.900072 -258.732057) (xy 405.86321 -258.768824) (xy 405.821041 -258.79936) (xy 405.79802 -258.811522)
			(xy 405.752901 -259.393415) (xy 420.380404 -259.393415) (xy 420.380404 -259.340117) (xy 420.388347 -259.287413)
			(xy 420.404057 -259.236483) (xy 420.427183 -259.188462) (xy 420.457207 -259.144425) (xy 420.493459 -259.105354)
			(xy 420.53513 -259.072123) (xy 420.581288 -259.045474) (xy 420.630902 -259.026002) (xy 420.682864 -259.014142)
			(xy 420.736014 -259.010159) (xy 420.789164 -259.014142) (xy 420.841126 -259.026002) (xy 420.89074 -259.045474)
			(xy 420.936898 -259.072123) (xy 420.978569 -259.105354) (xy 421.014821 -259.144425) (xy 421.044845 -259.188462)
			(xy 421.067971 -259.236483) (xy 421.083681 -259.287413) (xy 421.091624 -259.340117) (xy 421.092122 -259.366766)
			(xy 421.091624 -259.393415) (xy 424.480472 -259.393415) (xy 424.480472 -259.340117) (xy 424.488415 -259.287413)
			(xy 424.504125 -259.236483) (xy 424.527251 -259.188462) (xy 424.557275 -259.144425) (xy 424.593527 -259.105354)
			(xy 424.635198 -259.072123) (xy 424.681356 -259.045474) (xy 424.73097 -259.026002) (xy 424.782932 -259.014142)
			(xy 424.836082 -259.010159) (xy 424.889232 -259.014142) (xy 424.941194 -259.026002) (xy 424.990808 -259.045474)
			(xy 425.036966 -259.072123) (xy 425.078637 -259.105354) (xy 425.114889 -259.144425) (xy 425.144913 -259.188462)
			(xy 425.168039 -259.236483) (xy 425.183749 -259.287413) (xy 425.191692 -259.340117) (xy 425.19219 -259.366766)
			(xy 425.191692 -259.393415) (xy 432.024272 -259.393415) (xy 432.024272 -259.340117) (xy 432.032215 -259.287413)
			(xy 432.047925 -259.236483) (xy 432.071051 -259.188462) (xy 432.101075 -259.144425) (xy 432.137327 -259.105354)
			(xy 432.178998 -259.072123) (xy 432.225156 -259.045474) (xy 432.27477 -259.026002) (xy 432.326732 -259.014142)
			(xy 432.379882 -259.010159) (xy 432.433032 -259.014142) (xy 432.484994 -259.026002) (xy 432.534608 -259.045474)
			(xy 432.580766 -259.072123) (xy 432.622437 -259.105354) (xy 432.658689 -259.144425) (xy 432.688713 -259.188462)
			(xy 432.711839 -259.236483) (xy 432.727549 -259.287413) (xy 432.735492 -259.340117) (xy 432.73599 -259.366766)
			(xy 432.735492 -259.393415) (xy 435.468004 -259.393415) (xy 435.468004 -259.340117) (xy 435.475947 -259.287413)
			(xy 435.491657 -259.236483) (xy 435.514783 -259.188462) (xy 435.544807 -259.144425) (xy 435.581059 -259.105354)
			(xy 435.62273 -259.072123) (xy 435.668888 -259.045474) (xy 435.718502 -259.026002) (xy 435.770464 -259.014142)
			(xy 435.823614 -259.010159) (xy 435.876764 -259.014142) (xy 435.928726 -259.026002) (xy 435.97834 -259.045474)
			(xy 436.024498 -259.072123) (xy 436.066169 -259.105354) (xy 436.102421 -259.144425) (xy 436.132445 -259.188462)
			(xy 436.155571 -259.236483) (xy 436.171281 -259.287413) (xy 436.179224 -259.340117) (xy 436.179722 -259.366766)
			(xy 436.179224 -259.393415) (xy 439.568072 -259.393415) (xy 439.568072 -259.340117) (xy 439.576015 -259.287413)
			(xy 439.591725 -259.236483) (xy 439.614851 -259.188462) (xy 439.644875 -259.144425) (xy 439.681127 -259.105354)
			(xy 439.722798 -259.072123) (xy 439.768956 -259.045474) (xy 439.81857 -259.026002) (xy 439.870532 -259.014142)
			(xy 439.923682 -259.010159) (xy 439.976832 -259.014142) (xy 440.028794 -259.026002) (xy 440.078408 -259.045474)
			(xy 440.124566 -259.072123) (xy 440.166237 -259.105354) (xy 440.202489 -259.144425) (xy 440.232513 -259.188462)
			(xy 440.255639 -259.236483) (xy 440.271349 -259.287413) (xy 440.279292 -259.340117) (xy 440.27979 -259.366766)
			(xy 440.279292 -259.393415) (xy 447.111872 -259.393415) (xy 447.111872 -259.340117) (xy 447.119815 -259.287413)
			(xy 447.135525 -259.236483) (xy 447.158651 -259.188462) (xy 447.188675 -259.144425) (xy 447.224927 -259.105354)
			(xy 447.266598 -259.072123) (xy 447.312756 -259.045474) (xy 447.36237 -259.026002) (xy 447.414332 -259.014142)
			(xy 447.467482 -259.010159) (xy 447.520632 -259.014142) (xy 447.572594 -259.026002) (xy 447.622208 -259.045474)
			(xy 447.668366 -259.072123) (xy 447.710037 -259.105354) (xy 447.746289 -259.144425) (xy 447.776313 -259.188462)
			(xy 447.799439 -259.236483) (xy 447.815149 -259.287413) (xy 447.823092 -259.340117) (xy 447.82359 -259.366766)
			(xy 447.823092 -259.393415) (xy 447.815149 -259.446119) (xy 447.799439 -259.497049) (xy 447.776313 -259.54507)
			(xy 447.746289 -259.589107) (xy 447.710037 -259.628178) (xy 447.668366 -259.661409) (xy 447.622208 -259.688058)
			(xy 447.572594 -259.70753) (xy 447.520632 -259.71939) (xy 447.467482 -259.723374) (xy 447.414332 -259.71939)
			(xy 447.36237 -259.70753) (xy 447.312756 -259.688058) (xy 447.266598 -259.661409) (xy 447.224927 -259.628178)
			(xy 447.188675 -259.589107) (xy 447.158651 -259.54507) (xy 447.135525 -259.497049) (xy 447.119815 -259.446119)
			(xy 447.111872 -259.393415) (xy 440.279292 -259.393415) (xy 440.271349 -259.446119) (xy 440.255639 -259.497049)
			(xy 440.232513 -259.54507) (xy 440.202489 -259.589107) (xy 440.166237 -259.628178) (xy 440.124566 -259.661409)
			(xy 440.078408 -259.688058) (xy 440.028794 -259.70753) (xy 439.976832 -259.71939) (xy 439.923682 -259.723374)
			(xy 439.870532 -259.71939) (xy 439.81857 -259.70753) (xy 439.768956 -259.688058) (xy 439.722798 -259.661409)
			(xy 439.681127 -259.628178) (xy 439.644875 -259.589107) (xy 439.614851 -259.54507) (xy 439.591725 -259.497049)
			(xy 439.576015 -259.446119) (xy 439.568072 -259.393415) (xy 436.179224 -259.393415) (xy 436.171281 -259.446119)
			(xy 436.155571 -259.497049) (xy 436.132445 -259.54507) (xy 436.102421 -259.589107) (xy 436.066169 -259.628178)
			(xy 436.024498 -259.661409) (xy 435.97834 -259.688058) (xy 435.928726 -259.70753) (xy 435.876764 -259.71939)
			(xy 435.823614 -259.723374) (xy 435.770464 -259.71939) (xy 435.718502 -259.70753) (xy 435.668888 -259.688058)
			(xy 435.62273 -259.661409) (xy 435.581059 -259.628178) (xy 435.544807 -259.589107) (xy 435.514783 -259.54507)
			(xy 435.491657 -259.497049) (xy 435.475947 -259.446119) (xy 435.468004 -259.393415) (xy 432.735492 -259.393415)
			(xy 432.727549 -259.446119) (xy 432.711839 -259.497049) (xy 432.688713 -259.54507) (xy 432.658689 -259.589107)
			(xy 432.622437 -259.628178) (xy 432.580766 -259.661409) (xy 432.534608 -259.688058) (xy 432.484994 -259.70753)
			(xy 432.433032 -259.71939) (xy 432.379882 -259.723374) (xy 432.326732 -259.71939) (xy 432.27477 -259.70753)
			(xy 432.225156 -259.688058) (xy 432.178998 -259.661409) (xy 432.137327 -259.628178) (xy 432.101075 -259.589107)
			(xy 432.071051 -259.54507) (xy 432.047925 -259.497049) (xy 432.032215 -259.446119) (xy 432.024272 -259.393415)
			(xy 425.191692 -259.393415) (xy 425.183749 -259.446119) (xy 425.168039 -259.497049) (xy 425.144913 -259.54507)
			(xy 425.114889 -259.589107) (xy 425.078637 -259.628178) (xy 425.036966 -259.661409) (xy 424.990808 -259.688058)
			(xy 424.941194 -259.70753) (xy 424.889232 -259.71939) (xy 424.836082 -259.723374) (xy 424.782932 -259.71939)
			(xy 424.73097 -259.70753) (xy 424.681356 -259.688058) (xy 424.635198 -259.661409) (xy 424.593527 -259.628178)
			(xy 424.557275 -259.589107) (xy 424.527251 -259.54507) (xy 424.504125 -259.497049) (xy 424.488415 -259.446119)
			(xy 424.480472 -259.393415) (xy 421.091624 -259.393415) (xy 421.083681 -259.446119) (xy 421.067971 -259.497049)
			(xy 421.044845 -259.54507) (xy 421.014821 -259.589107) (xy 420.978569 -259.628178) (xy 420.936898 -259.661409)
			(xy 420.89074 -259.688058) (xy 420.841126 -259.70753) (xy 420.789164 -259.71939) (xy 420.736014 -259.723374)
			(xy 420.682864 -259.71939) (xy 420.630902 -259.70753) (xy 420.581288 -259.688058) (xy 420.53513 -259.661409)
			(xy 420.493459 -259.628178) (xy 420.457207 -259.589107) (xy 420.427183 -259.54507) (xy 420.404057 -259.497049)
			(xy 420.388347 -259.446119) (xy 420.380404 -259.393415) (xy 405.752901 -259.393415) (xy 405.7142 -259.892546)
			(xy 405.738794 -259.898023) (xy 405.786076 -259.915423) (xy 405.830173 -259.939794) (xy 405.870061 -259.970574)
			(xy 405.904818 -260.007048) (xy 405.93364 -260.048372) (xy 405.95586 -260.093591) (xy 405.970962 -260.141657)
			(xy 405.978598 -260.191458) (xy 405.979122 -260.21665) (xy 405.978643 -260.241888) (xy 405.978426 -260.243299)
			(xy 424.480472 -260.243299) (xy 424.480472 -260.190001) (xy 424.488415 -260.137297) (xy 424.504125 -260.086367)
			(xy 424.527251 -260.038346) (xy 424.557275 -259.994309) (xy 424.593527 -259.955238) (xy 424.635198 -259.922007)
			(xy 424.681356 -259.895358) (xy 424.73097 -259.875886) (xy 424.782932 -259.864026) (xy 424.836082 -259.860043)
			(xy 424.889232 -259.864026) (xy 424.941194 -259.875886) (xy 424.990808 -259.895358) (xy 425.036966 -259.922007)
			(xy 425.078637 -259.955238) (xy 425.114889 -259.994309) (xy 425.144913 -260.038346) (xy 425.168039 -260.086367)
			(xy 425.183749 -260.137297) (xy 425.191692 -260.190001) (xy 425.19219 -260.21665) (xy 425.191692 -260.243299)
			(xy 432.024272 -260.243299) (xy 432.024272 -260.190001) (xy 432.032215 -260.137297) (xy 432.047925 -260.086367)
			(xy 432.071051 -260.038346) (xy 432.101075 -259.994309) (xy 432.137327 -259.955238) (xy 432.178998 -259.922007)
			(xy 432.225156 -259.895358) (xy 432.27477 -259.875886) (xy 432.326732 -259.864026) (xy 432.379882 -259.860043)
			(xy 432.433032 -259.864026) (xy 432.484994 -259.875886) (xy 432.534608 -259.895358) (xy 432.580766 -259.922007)
			(xy 432.622437 -259.955238) (xy 432.658689 -259.994309) (xy 432.688713 -260.038346) (xy 432.711839 -260.086367)
			(xy 432.727549 -260.137297) (xy 432.735492 -260.190001) (xy 432.73599 -260.21665) (xy 432.735492 -260.243299)
			(xy 439.568072 -260.243299) (xy 439.568072 -260.190001) (xy 439.576015 -260.137297) (xy 439.591725 -260.086367)
			(xy 439.614851 -260.038346) (xy 439.644875 -259.994309) (xy 439.681127 -259.955238) (xy 439.722798 -259.922007)
			(xy 439.768956 -259.895358) (xy 439.81857 -259.875886) (xy 439.870532 -259.864026) (xy 439.923682 -259.860043)
			(xy 439.976832 -259.864026) (xy 440.028794 -259.875886) (xy 440.078408 -259.895358) (xy 440.124566 -259.922007)
			(xy 440.166237 -259.955238) (xy 440.202489 -259.994309) (xy 440.232513 -260.038346) (xy 440.255639 -260.086367)
			(xy 440.271349 -260.137297) (xy 440.279292 -260.190001) (xy 440.27979 -260.21665) (xy 440.279292 -260.243299)
			(xy 447.111872 -260.243299) (xy 447.111872 -260.190001) (xy 447.119815 -260.137297) (xy 447.135525 -260.086367)
			(xy 447.158651 -260.038346) (xy 447.188675 -259.994309) (xy 447.224927 -259.955238) (xy 447.266598 -259.922007)
			(xy 447.312756 -259.895358) (xy 447.36237 -259.875886) (xy 447.414332 -259.864026) (xy 447.467482 -259.860043)
			(xy 447.520632 -259.864026) (xy 447.572594 -259.875886) (xy 447.622208 -259.895358) (xy 447.668366 -259.922007)
			(xy 447.710037 -259.955238) (xy 447.746289 -259.994309) (xy 447.776313 -260.038346) (xy 447.799439 -260.086367)
			(xy 447.815149 -260.137297) (xy 447.823092 -260.190001) (xy 447.82359 -260.21665) (xy 447.823092 -260.243299)
			(xy 447.815149 -260.296003) (xy 447.799439 -260.346933) (xy 447.776313 -260.394954) (xy 447.746289 -260.438991)
			(xy 447.710037 -260.478062) (xy 447.668366 -260.511293) (xy 447.622208 -260.537942) (xy 447.572594 -260.557414)
			(xy 447.520632 -260.569274) (xy 447.467482 -260.573258) (xy 447.414332 -260.569274) (xy 447.36237 -260.557414)
			(xy 447.312756 -260.537942) (xy 447.266598 -260.511293) (xy 447.224927 -260.478062) (xy 447.188675 -260.438991)
			(xy 447.158651 -260.394954) (xy 447.135525 -260.346933) (xy 447.119815 -260.296003) (xy 447.111872 -260.243299)
			(xy 440.279292 -260.243299) (xy 440.271349 -260.296003) (xy 440.255639 -260.346933) (xy 440.232513 -260.394954)
			(xy 440.202489 -260.438991) (xy 440.166237 -260.478062) (xy 440.124566 -260.511293) (xy 440.078408 -260.537942)
			(xy 440.028794 -260.557414) (xy 439.976832 -260.569274) (xy 439.923682 -260.573258) (xy 439.870532 -260.569274)
			(xy 439.81857 -260.557414) (xy 439.768956 -260.537942) (xy 439.722798 -260.511293) (xy 439.681127 -260.478062)
			(xy 439.644875 -260.438991) (xy 439.614851 -260.394954) (xy 439.591725 -260.346933) (xy 439.576015 -260.296003)
			(xy 439.568072 -260.243299) (xy 432.735492 -260.243299) (xy 432.727549 -260.296003) (xy 432.711839 -260.346933)
			(xy 432.688713 -260.394954) (xy 432.658689 -260.438991) (xy 432.622437 -260.478062) (xy 432.580766 -260.511293)
			(xy 432.534608 -260.537942) (xy 432.484994 -260.557414) (xy 432.433032 -260.569274) (xy 432.379882 -260.573258)
			(xy 432.326732 -260.569274) (xy 432.27477 -260.557414) (xy 432.225156 -260.537942) (xy 432.178998 -260.511293)
			(xy 432.137327 -260.478062) (xy 432.101075 -260.438991) (xy 432.071051 -260.394954) (xy 432.047925 -260.346933)
			(xy 432.032215 -260.296003) (xy 432.024272 -260.243299) (xy 425.191692 -260.243299) (xy 425.183749 -260.296003)
			(xy 425.168039 -260.346933) (xy 425.144913 -260.394954) (xy 425.114889 -260.438991) (xy 425.078637 -260.478062)
			(xy 425.036966 -260.511293) (xy 424.990808 -260.537942) (xy 424.941194 -260.557414) (xy 424.889232 -260.569274)
			(xy 424.836082 -260.573258) (xy 424.782932 -260.569274) (xy 424.73097 -260.557414) (xy 424.681356 -260.537942)
			(xy 424.635198 -260.511293) (xy 424.593527 -260.478062) (xy 424.557275 -260.438991) (xy 424.527251 -260.394954)
			(xy 424.504125 -260.346933) (xy 424.488415 -260.296003) (xy 424.480472 -260.243299) (xy 405.978426 -260.243299)
			(xy 405.970967 -260.291776) (xy 405.955803 -260.339919) (xy 405.933501 -260.385201) (xy 405.904579 -260.426568)
			(xy 405.869709 -260.463063) (xy 405.8297 -260.493836) (xy 405.78548 -260.518175) (xy 405.738076 -260.535514)
			(xy 405.688588 -260.54545) (xy 405.6634 -260.547104) (xy 405.62102 -261.093437) (xy 420.304204 -261.093437)
			(xy 420.304204 -261.040139) (xy 420.312147 -260.987435) (xy 420.327857 -260.936505) (xy 420.350983 -260.888484)
			(xy 420.381007 -260.844447) (xy 420.417259 -260.805376) (xy 420.45893 -260.772145) (xy 420.505088 -260.745496)
			(xy 420.554702 -260.726024) (xy 420.606664 -260.714164) (xy 420.659814 -260.710181) (xy 420.712964 -260.714164)
			(xy 420.764926 -260.726024) (xy 420.81454 -260.745496) (xy 420.860698 -260.772145) (xy 420.902369 -260.805376)
			(xy 420.938621 -260.844447) (xy 420.968645 -260.888484) (xy 420.991771 -260.936505) (xy 421.007481 -260.987435)
			(xy 421.015424 -261.040139) (xy 421.015922 -261.066788) (xy 421.015424 -261.093437) (xy 435.468004 -261.093437)
			(xy 435.468004 -261.040139) (xy 435.475947 -260.987435) (xy 435.491657 -260.936505) (xy 435.514783 -260.888484)
			(xy 435.544807 -260.844447) (xy 435.581059 -260.805376) (xy 435.62273 -260.772145) (xy 435.668888 -260.745496)
			(xy 435.718502 -260.726024) (xy 435.770464 -260.714164) (xy 435.823614 -260.710181) (xy 435.876764 -260.714164)
			(xy 435.928726 -260.726024) (xy 435.97834 -260.745496) (xy 436.024498 -260.772145) (xy 436.066169 -260.805376)
			(xy 436.102421 -260.844447) (xy 436.132445 -260.888484) (xy 436.155571 -260.936505) (xy 436.171281 -260.987435)
			(xy 436.179224 -261.040139) (xy 436.179722 -261.066788) (xy 436.179224 -261.093437) (xy 436.171281 -261.146141)
			(xy 436.155571 -261.197071) (xy 436.132445 -261.245092) (xy 436.102421 -261.289129) (xy 436.066169 -261.3282)
			(xy 436.024498 -261.361431) (xy 435.97834 -261.38808) (xy 435.928726 -261.407552) (xy 435.876764 -261.419412)
			(xy 435.823614 -261.423396) (xy 435.770464 -261.419412) (xy 435.718502 -261.407552) (xy 435.668888 -261.38808)
			(xy 435.62273 -261.361431) (xy 435.581059 -261.3282) (xy 435.544807 -261.289129) (xy 435.514783 -261.245092)
			(xy 435.491657 -261.197071) (xy 435.475947 -261.146141) (xy 435.468004 -261.093437) (xy 421.015424 -261.093437)
			(xy 421.007481 -261.146141) (xy 420.991771 -261.197071) (xy 420.968645 -261.245092) (xy 420.938621 -261.289129)
			(xy 420.902369 -261.3282) (xy 420.860698 -261.361431) (xy 420.81454 -261.38808) (xy 420.764926 -261.407552)
			(xy 420.712964 -261.419412) (xy 420.659814 -261.423396) (xy 420.606664 -261.419412) (xy 420.554702 -261.407552)
			(xy 420.505088 -261.38808) (xy 420.45893 -261.361431) (xy 420.417259 -261.3282) (xy 420.381007 -261.289129)
			(xy 420.350983 -261.245092) (xy 420.327857 -261.197071) (xy 420.312147 -261.146141) (xy 420.304204 -261.093437)
			(xy 405.62102 -261.093437) (xy 405.555093 -261.943321) (xy 424.480472 -261.943321) (xy 424.480472 -261.890023)
			(xy 424.488415 -261.837319) (xy 424.504125 -261.786389) (xy 424.527251 -261.738368) (xy 424.557275 -261.694331)
			(xy 424.593527 -261.65526) (xy 424.635198 -261.622029) (xy 424.681356 -261.59538) (xy 424.73097 -261.575908)
			(xy 424.782932 -261.564048) (xy 424.836082 -261.560065) (xy 424.889232 -261.564048) (xy 424.941194 -261.575908)
			(xy 424.990808 -261.59538) (xy 425.036966 -261.622029) (xy 425.078637 -261.65526) (xy 425.114889 -261.694331)
			(xy 425.144913 -261.738368) (xy 425.168039 -261.786389) (xy 425.183749 -261.837319) (xy 425.191692 -261.890023)
			(xy 425.19219 -261.916672) (xy 425.191692 -261.943321) (xy 439.568072 -261.943321) (xy 439.568072 -261.890023)
			(xy 439.576015 -261.837319) (xy 439.591725 -261.786389) (xy 439.614851 -261.738368) (xy 439.644875 -261.694331)
			(xy 439.681127 -261.65526) (xy 439.722798 -261.622029) (xy 439.768956 -261.59538) (xy 439.81857 -261.575908)
			(xy 439.870532 -261.564048) (xy 439.923682 -261.560065) (xy 439.976832 -261.564048) (xy 440.028794 -261.575908)
			(xy 440.078408 -261.59538) (xy 440.124566 -261.622029) (xy 440.166237 -261.65526) (xy 440.202489 -261.694331)
			(xy 440.232513 -261.738368) (xy 440.255639 -261.786389) (xy 440.271349 -261.837319) (xy 440.279292 -261.890023)
			(xy 440.27979 -261.916672) (xy 440.279292 -261.943321) (xy 440.271349 -261.996025) (xy 440.255639 -262.046955)
			(xy 440.232513 -262.094976) (xy 440.202489 -262.139013) (xy 440.166237 -262.178084) (xy 440.124566 -262.211315)
			(xy 440.078408 -262.237964) (xy 440.028794 -262.257436) (xy 439.976832 -262.269296) (xy 439.923682 -262.27328)
			(xy 439.870532 -262.269296) (xy 439.81857 -262.257436) (xy 439.768956 -262.237964) (xy 439.722798 -262.211315)
			(xy 439.681127 -262.178084) (xy 439.644875 -262.139013) (xy 439.614851 -262.094976) (xy 439.591725 -262.046955)
			(xy 439.576015 -261.996025) (xy 439.568072 -261.943321) (xy 425.191692 -261.943321) (xy 425.183749 -261.996025)
			(xy 425.168039 -262.046955) (xy 425.144913 -262.094976) (xy 425.114889 -262.139013) (xy 425.078637 -262.178084)
			(xy 425.036966 -262.211315) (xy 424.990808 -262.237964) (xy 424.941194 -262.257436) (xy 424.889232 -262.269296)
			(xy 424.836082 -262.27328) (xy 424.782932 -262.269296) (xy 424.73097 -262.257436) (xy 424.681356 -262.237964)
			(xy 424.635198 -262.211315) (xy 424.593527 -262.178084) (xy 424.557275 -262.139013) (xy 424.527251 -262.094976)
			(xy 424.504125 -262.046955) (xy 424.488415 -261.996025) (xy 424.480472 -261.943321) (xy 405.555093 -261.943321)
			(xy 405.54656 -262.053324) (xy 405.54656 -262.793205) (xy 420.304204 -262.793205) (xy 420.304204 -262.739907)
			(xy 420.312147 -262.687203) (xy 420.327857 -262.636273) (xy 420.350983 -262.588252) (xy 420.381007 -262.544215)
			(xy 420.417259 -262.505144) (xy 420.45893 -262.471913) (xy 420.505088 -262.445264) (xy 420.554702 -262.425792)
			(xy 420.606664 -262.413932) (xy 420.659814 -262.409949) (xy 420.712964 -262.413932) (xy 420.764926 -262.425792)
			(xy 420.81454 -262.445264) (xy 420.860698 -262.471913) (xy 420.902369 -262.505144) (xy 420.938621 -262.544215)
			(xy 420.968645 -262.588252) (xy 420.991771 -262.636273) (xy 421.007481 -262.687203) (xy 421.015424 -262.739907)
			(xy 421.015922 -262.766556) (xy 421.015424 -262.793205) (xy 435.468004 -262.793205) (xy 435.468004 -262.739907)
			(xy 435.475947 -262.687203) (xy 435.491657 -262.636273) (xy 435.514783 -262.588252) (xy 435.544807 -262.544215)
			(xy 435.581059 -262.505144) (xy 435.62273 -262.471913) (xy 435.668888 -262.445264) (xy 435.718502 -262.425792)
			(xy 435.770464 -262.413932) (xy 435.823614 -262.409949) (xy 435.876764 -262.413932) (xy 435.928726 -262.425792)
			(xy 435.97834 -262.445264) (xy 436.024498 -262.471913) (xy 436.066169 -262.505144) (xy 436.102421 -262.544215)
			(xy 436.132445 -262.588252) (xy 436.155571 -262.636273) (xy 436.171281 -262.687203) (xy 436.179224 -262.739907)
			(xy 436.179722 -262.766556) (xy 436.179224 -262.793205) (xy 436.171281 -262.845909) (xy 436.155571 -262.896839)
			(xy 436.132445 -262.94486) (xy 436.102421 -262.988897) (xy 436.066169 -263.027968) (xy 436.024498 -263.061199)
			(xy 435.97834 -263.087848) (xy 435.928726 -263.10732) (xy 435.876764 -263.11918) (xy 435.823614 -263.123164)
			(xy 435.770464 -263.11918) (xy 435.718502 -263.10732) (xy 435.668888 -263.087848) (xy 435.62273 -263.061199)
			(xy 435.581059 -263.027968) (xy 435.544807 -262.988897) (xy 435.514783 -262.94486) (xy 435.491657 -262.896839)
			(xy 435.475947 -262.845909) (xy 435.468004 -262.793205) (xy 421.015424 -262.793205) (xy 421.007481 -262.845909)
			(xy 420.991771 -262.896839) (xy 420.968645 -262.94486) (xy 420.938621 -262.988897) (xy 420.902369 -263.027968)
			(xy 420.860698 -263.061199) (xy 420.81454 -263.087848) (xy 420.764926 -263.10732) (xy 420.712964 -263.11918)
			(xy 420.659814 -263.123164) (xy 420.606664 -263.11918) (xy 420.554702 -263.10732) (xy 420.505088 -263.087848)
			(xy 420.45893 -263.061199) (xy 420.417259 -263.027968) (xy 420.381007 -262.988897) (xy 420.350983 -262.94486)
			(xy 420.327857 -262.896839) (xy 420.312147 -262.845909) (xy 420.304204 -262.793205) (xy 405.54656 -262.793205)
			(xy 405.54656 -263.643343) (xy 424.404272 -263.643343) (xy 424.404272 -263.590045) (xy 424.412215 -263.537341)
			(xy 424.427925 -263.486411) (xy 424.451051 -263.43839) (xy 424.481075 -263.394353) (xy 424.517327 -263.355282)
			(xy 424.558998 -263.322051) (xy 424.605156 -263.295402) (xy 424.65477 -263.27593) (xy 424.706732 -263.26407)
			(xy 424.759882 -263.260087) (xy 424.813032 -263.26407) (xy 424.864994 -263.27593) (xy 424.914608 -263.295402)
			(xy 424.960766 -263.322051) (xy 425.002437 -263.355282) (xy 425.038689 -263.394353) (xy 425.068713 -263.43839)
			(xy 425.091839 -263.486411) (xy 425.107549 -263.537341) (xy 425.115492 -263.590045) (xy 425.11599 -263.616694)
			(xy 425.115492 -263.643343) (xy 439.491872 -263.643343) (xy 439.491872 -263.590045) (xy 439.499815 -263.537341)
			(xy 439.515525 -263.486411) (xy 439.538651 -263.43839) (xy 439.568675 -263.394353) (xy 439.604927 -263.355282)
			(xy 439.646598 -263.322051) (xy 439.692756 -263.295402) (xy 439.74237 -263.27593) (xy 439.794332 -263.26407)
			(xy 439.847482 -263.260087) (xy 439.900632 -263.26407) (xy 439.952594 -263.27593) (xy 440.002208 -263.295402)
			(xy 440.048366 -263.322051) (xy 440.090037 -263.355282) (xy 440.126289 -263.394353) (xy 440.156313 -263.43839)
			(xy 440.179439 -263.486411) (xy 440.195149 -263.537341) (xy 440.203092 -263.590045) (xy 440.20359 -263.616694)
			(xy 440.203092 -263.643343) (xy 440.195149 -263.696047) (xy 440.179439 -263.746977) (xy 440.156313 -263.794998)
			(xy 440.126289 -263.839035) (xy 440.090037 -263.878106) (xy 440.048366 -263.911337) (xy 440.002208 -263.937986)
			(xy 439.952594 -263.957458) (xy 439.900632 -263.969318) (xy 439.847482 -263.973302) (xy 439.794332 -263.969318)
			(xy 439.74237 -263.957458) (xy 439.692756 -263.937986) (xy 439.646598 -263.911337) (xy 439.604927 -263.878106)
			(xy 439.568675 -263.839035) (xy 439.538651 -263.794998) (xy 439.515525 -263.746977) (xy 439.499815 -263.696047)
			(xy 439.491872 -263.643343) (xy 425.115492 -263.643343) (xy 425.107549 -263.696047) (xy 425.091839 -263.746977)
			(xy 425.068713 -263.794998) (xy 425.038689 -263.839035) (xy 425.002437 -263.878106) (xy 424.960766 -263.911337)
			(xy 424.914608 -263.937986) (xy 424.864994 -263.957458) (xy 424.813032 -263.969318) (xy 424.759882 -263.973302)
			(xy 424.706732 -263.969318) (xy 424.65477 -263.957458) (xy 424.605156 -263.937986) (xy 424.558998 -263.911337)
			(xy 424.517327 -263.878106) (xy 424.481075 -263.839035) (xy 424.451051 -263.794998) (xy 424.427925 -263.746977)
			(xy 424.412215 -263.696047) (xy 424.404272 -263.643343) (xy 405.54656 -263.643343) (xy 405.54656 -264.493227)
			(xy 420.304204 -264.493227) (xy 420.304204 -264.439929) (xy 420.312147 -264.387225) (xy 420.327857 -264.336295)
			(xy 420.350983 -264.288274) (xy 420.381007 -264.244237) (xy 420.417259 -264.205166) (xy 420.45893 -264.171935)
			(xy 420.505088 -264.145286) (xy 420.554702 -264.125814) (xy 420.606664 -264.113954) (xy 420.659814 -264.109971)
			(xy 420.712964 -264.113954) (xy 420.764926 -264.125814) (xy 420.81454 -264.145286) (xy 420.860698 -264.171935)
			(xy 420.902369 -264.205166) (xy 420.938621 -264.244237) (xy 420.968645 -264.288274) (xy 420.991771 -264.336295)
			(xy 421.007481 -264.387225) (xy 421.015424 -264.439929) (xy 421.015922 -264.466578) (xy 421.015424 -264.493227)
			(xy 435.468004 -264.493227) (xy 435.468004 -264.439929) (xy 435.475947 -264.387225) (xy 435.491657 -264.336295)
			(xy 435.514783 -264.288274) (xy 435.544807 -264.244237) (xy 435.581059 -264.205166) (xy 435.62273 -264.171935)
			(xy 435.668888 -264.145286) (xy 435.718502 -264.125814) (xy 435.770464 -264.113954) (xy 435.823614 -264.109971)
			(xy 435.876764 -264.113954) (xy 435.928726 -264.125814) (xy 435.97834 -264.145286) (xy 436.024498 -264.171935)
			(xy 436.066169 -264.205166) (xy 436.102421 -264.244237) (xy 436.132445 -264.288274) (xy 436.155571 -264.336295)
			(xy 436.171281 -264.387225) (xy 436.179224 -264.439929) (xy 436.179722 -264.466578) (xy 436.179224 -264.493227)
			(xy 436.171281 -264.545931) (xy 436.155571 -264.596861) (xy 436.132445 -264.644882) (xy 436.102421 -264.688919)
			(xy 436.066169 -264.72799) (xy 436.024498 -264.761221) (xy 435.97834 -264.78787) (xy 435.928726 -264.807342)
			(xy 435.876764 -264.819202) (xy 435.823614 -264.823186) (xy 435.770464 -264.819202) (xy 435.718502 -264.807342)
			(xy 435.668888 -264.78787) (xy 435.62273 -264.761221) (xy 435.581059 -264.72799) (xy 435.544807 -264.688919)
			(xy 435.514783 -264.644882) (xy 435.491657 -264.596861) (xy 435.475947 -264.545931) (xy 435.468004 -264.493227)
			(xy 421.015424 -264.493227) (xy 421.007481 -264.545931) (xy 420.991771 -264.596861) (xy 420.968645 -264.644882)
			(xy 420.938621 -264.688919) (xy 420.902369 -264.72799) (xy 420.860698 -264.761221) (xy 420.81454 -264.78787)
			(xy 420.764926 -264.807342) (xy 420.712964 -264.819202) (xy 420.659814 -264.823186) (xy 420.606664 -264.819202)
			(xy 420.554702 -264.807342) (xy 420.505088 -264.78787) (xy 420.45893 -264.761221) (xy 420.417259 -264.72799)
			(xy 420.381007 -264.688919) (xy 420.350983 -264.644882) (xy 420.327857 -264.596861) (xy 420.312147 -264.545931)
			(xy 420.304204 -264.493227) (xy 405.54656 -264.493227) (xy 405.54656 -265.343365) (xy 424.404272 -265.343365)
			(xy 424.404272 -265.290067) (xy 424.412215 -265.237363) (xy 424.427925 -265.186433) (xy 424.451051 -265.138412)
			(xy 424.481075 -265.094375) (xy 424.517327 -265.055304) (xy 424.558998 -265.022073) (xy 424.605156 -264.995424)
			(xy 424.65477 -264.975952) (xy 424.706732 -264.964092) (xy 424.759882 -264.960109) (xy 424.813032 -264.964092)
			(xy 424.864994 -264.975952) (xy 424.914608 -264.995424) (xy 424.960766 -265.022073) (xy 425.002437 -265.055304)
			(xy 425.038689 -265.094375) (xy 425.068713 -265.138412) (xy 425.091839 -265.186433) (xy 425.107549 -265.237363)
			(xy 425.115492 -265.290067) (xy 425.11599 -265.316716) (xy 425.115492 -265.343365) (xy 439.491872 -265.343365)
			(xy 439.491872 -265.290067) (xy 439.499815 -265.237363) (xy 439.515525 -265.186433) (xy 439.538651 -265.138412)
			(xy 439.568675 -265.094375) (xy 439.604927 -265.055304) (xy 439.646598 -265.022073) (xy 439.692756 -264.995424)
			(xy 439.74237 -264.975952) (xy 439.794332 -264.964092) (xy 439.847482 -264.960109) (xy 439.900632 -264.964092)
			(xy 439.952594 -264.975952) (xy 440.002208 -264.995424) (xy 440.048366 -265.022073) (xy 440.090037 -265.055304)
			(xy 440.126289 -265.094375) (xy 440.156313 -265.138412) (xy 440.179439 -265.186433) (xy 440.195149 -265.237363)
			(xy 440.203092 -265.290067) (xy 440.20359 -265.316716) (xy 440.203092 -265.343365) (xy 440.195149 -265.396069)
			(xy 440.179439 -265.446999) (xy 440.156313 -265.49502) (xy 440.126289 -265.539057) (xy 440.090037 -265.578128)
			(xy 440.048366 -265.611359) (xy 440.002208 -265.638008) (xy 439.952594 -265.65748) (xy 439.900632 -265.66934)
			(xy 439.847482 -265.673324) (xy 439.794332 -265.66934) (xy 439.74237 -265.65748) (xy 439.692756 -265.638008)
			(xy 439.646598 -265.611359) (xy 439.604927 -265.578128) (xy 439.568675 -265.539057) (xy 439.538651 -265.49502)
			(xy 439.515525 -265.446999) (xy 439.499815 -265.396069) (xy 439.491872 -265.343365) (xy 425.115492 -265.343365)
			(xy 425.107549 -265.396069) (xy 425.091839 -265.446999) (xy 425.068713 -265.49502) (xy 425.038689 -265.539057)
			(xy 425.002437 -265.578128) (xy 424.960766 -265.611359) (xy 424.914608 -265.638008) (xy 424.864994 -265.65748)
			(xy 424.813032 -265.66934) (xy 424.759882 -265.673324) (xy 424.706732 -265.66934) (xy 424.65477 -265.65748)
			(xy 424.605156 -265.638008) (xy 424.558998 -265.611359) (xy 424.517327 -265.578128) (xy 424.481075 -265.539057)
			(xy 424.451051 -265.49502) (xy 424.427925 -265.446999) (xy 424.412215 -265.396069) (xy 424.404272 -265.343365)
			(xy 405.54656 -265.343365) (xy 405.54656 -266.193249) (xy 420.304204 -266.193249) (xy 420.304204 -266.139951)
			(xy 420.312147 -266.087247) (xy 420.327857 -266.036317) (xy 420.350983 -265.988296) (xy 420.381007 -265.944259)
			(xy 420.417259 -265.905188) (xy 420.45893 -265.871957) (xy 420.505088 -265.845308) (xy 420.554702 -265.825836)
			(xy 420.606664 -265.813976) (xy 420.659814 -265.809993) (xy 420.712964 -265.813976) (xy 420.764926 -265.825836)
			(xy 420.81454 -265.845308) (xy 420.860698 -265.871957) (xy 420.902369 -265.905188) (xy 420.938621 -265.944259)
			(xy 420.968645 -265.988296) (xy 420.991771 -266.036317) (xy 421.007481 -266.087247) (xy 421.015424 -266.139951)
			(xy 421.015922 -266.1666) (xy 421.015424 -266.193249) (xy 435.468004 -266.193249) (xy 435.468004 -266.139951)
			(xy 435.475947 -266.087247) (xy 435.491657 -266.036317) (xy 435.514783 -265.988296) (xy 435.544807 -265.944259)
			(xy 435.581059 -265.905188) (xy 435.62273 -265.871957) (xy 435.668888 -265.845308) (xy 435.718502 -265.825836)
			(xy 435.770464 -265.813976) (xy 435.823614 -265.809993) (xy 435.876764 -265.813976) (xy 435.928726 -265.825836)
			(xy 435.97834 -265.845308) (xy 436.024498 -265.871957) (xy 436.066169 -265.905188) (xy 436.102421 -265.944259)
			(xy 436.132445 -265.988296) (xy 436.155571 -266.036317) (xy 436.171281 -266.087247) (xy 436.179224 -266.139951)
			(xy 436.179722 -266.1666) (xy 436.179224 -266.193249) (xy 436.171281 -266.245953) (xy 436.155571 -266.296883)
			(xy 436.132445 -266.344904) (xy 436.102421 -266.388941) (xy 436.066169 -266.428012) (xy 436.024498 -266.461243)
			(xy 435.97834 -266.487892) (xy 435.928726 -266.507364) (xy 435.876764 -266.519224) (xy 435.823614 -266.523208)
			(xy 435.770464 -266.519224) (xy 435.718502 -266.507364) (xy 435.668888 -266.487892) (xy 435.62273 -266.461243)
			(xy 435.581059 -266.428012) (xy 435.544807 -266.388941) (xy 435.514783 -266.344904) (xy 435.491657 -266.296883)
			(xy 435.475947 -266.245953) (xy 435.468004 -266.193249) (xy 421.015424 -266.193249) (xy 421.007481 -266.245953)
			(xy 420.991771 -266.296883) (xy 420.968645 -266.344904) (xy 420.938621 -266.388941) (xy 420.902369 -266.428012)
			(xy 420.860698 -266.461243) (xy 420.81454 -266.487892) (xy 420.764926 -266.507364) (xy 420.712964 -266.519224)
			(xy 420.659814 -266.523208) (xy 420.606664 -266.519224) (xy 420.554702 -266.507364) (xy 420.505088 -266.487892)
			(xy 420.45893 -266.461243) (xy 420.417259 -266.428012) (xy 420.381007 -266.388941) (xy 420.350983 -266.344904)
			(xy 420.327857 -266.296883) (xy 420.312147 -266.245953) (xy 420.304204 -266.193249) (xy 405.54656 -266.193249)
			(xy 405.54656 -267.043387) (xy 424.480472 -267.043387) (xy 424.480472 -266.990089) (xy 424.488415 -266.937385)
			(xy 424.504125 -266.886455) (xy 424.527251 -266.838434) (xy 424.557275 -266.794397) (xy 424.593527 -266.755326)
			(xy 424.635198 -266.722095) (xy 424.681356 -266.695446) (xy 424.73097 -266.675974) (xy 424.782932 -266.664114)
			(xy 424.836082 -266.660131) (xy 424.889232 -266.664114) (xy 424.941194 -266.675974) (xy 424.990808 -266.695446)
			(xy 425.036966 -266.722095) (xy 425.078637 -266.755326) (xy 425.114889 -266.794397) (xy 425.144913 -266.838434)
			(xy 425.168039 -266.886455) (xy 425.183749 -266.937385) (xy 425.191692 -266.990089) (xy 425.19219 -267.016738)
			(xy 425.191692 -267.043387) (xy 432.024272 -267.043387) (xy 432.024272 -266.990089) (xy 432.032215 -266.937385)
			(xy 432.047925 -266.886455) (xy 432.071051 -266.838434) (xy 432.101075 -266.794397) (xy 432.137327 -266.755326)
			(xy 432.178998 -266.722095) (xy 432.225156 -266.695446) (xy 432.27477 -266.675974) (xy 432.326732 -266.664114)
			(xy 432.379882 -266.660131) (xy 432.433032 -266.664114) (xy 432.484994 -266.675974) (xy 432.534608 -266.695446)
			(xy 432.580766 -266.722095) (xy 432.622437 -266.755326) (xy 432.658689 -266.794397) (xy 432.688713 -266.838434)
			(xy 432.711839 -266.886455) (xy 432.727549 -266.937385) (xy 432.735492 -266.990089) (xy 432.73599 -267.016738)
			(xy 432.735492 -267.043387) (xy 439.568072 -267.043387) (xy 439.568072 -266.990089) (xy 439.576015 -266.937385)
			(xy 439.591725 -266.886455) (xy 439.614851 -266.838434) (xy 439.644875 -266.794397) (xy 439.681127 -266.755326)
			(xy 439.722798 -266.722095) (xy 439.768956 -266.695446) (xy 439.81857 -266.675974) (xy 439.870532 -266.664114)
			(xy 439.923682 -266.660131) (xy 439.976832 -266.664114) (xy 440.028794 -266.675974) (xy 440.078408 -266.695446)
			(xy 440.124566 -266.722095) (xy 440.166237 -266.755326) (xy 440.202489 -266.794397) (xy 440.232513 -266.838434)
			(xy 440.255639 -266.886455) (xy 440.271349 -266.937385) (xy 440.279292 -266.990089) (xy 440.27979 -267.016738)
			(xy 440.279292 -267.043387) (xy 447.111872 -267.043387) (xy 447.111872 -266.990089) (xy 447.119815 -266.937385)
			(xy 447.135525 -266.886455) (xy 447.158651 -266.838434) (xy 447.188675 -266.794397) (xy 447.224927 -266.755326)
			(xy 447.266598 -266.722095) (xy 447.312756 -266.695446) (xy 447.36237 -266.675974) (xy 447.414332 -266.664114)
			(xy 447.467482 -266.660131) (xy 447.520632 -266.664114) (xy 447.572594 -266.675974) (xy 447.622208 -266.695446)
			(xy 447.668366 -266.722095) (xy 447.710037 -266.755326) (xy 447.746289 -266.794397) (xy 447.776313 -266.838434)
			(xy 447.799439 -266.886455) (xy 447.815149 -266.937385) (xy 447.823092 -266.990089) (xy 447.82359 -267.016738)
			(xy 447.823092 -267.043387) (xy 447.815149 -267.096091) (xy 447.799439 -267.147021) (xy 447.776313 -267.195042)
			(xy 447.746289 -267.239079) (xy 447.710037 -267.27815) (xy 447.668366 -267.311381) (xy 447.622208 -267.33803)
			(xy 447.572594 -267.357502) (xy 447.520632 -267.369362) (xy 447.467482 -267.373346) (xy 447.414332 -267.369362)
			(xy 447.36237 -267.357502) (xy 447.312756 -267.33803) (xy 447.266598 -267.311381) (xy 447.224927 -267.27815)
			(xy 447.188675 -267.239079) (xy 447.158651 -267.195042) (xy 447.135525 -267.147021) (xy 447.119815 -267.096091)
			(xy 447.111872 -267.043387) (xy 440.279292 -267.043387) (xy 440.271349 -267.096091) (xy 440.255639 -267.147021)
			(xy 440.232513 -267.195042) (xy 440.202489 -267.239079) (xy 440.166237 -267.27815) (xy 440.124566 -267.311381)
			(xy 440.078408 -267.33803) (xy 440.028794 -267.357502) (xy 439.976832 -267.369362) (xy 439.923682 -267.373346)
			(xy 439.870532 -267.369362) (xy 439.81857 -267.357502) (xy 439.768956 -267.33803) (xy 439.722798 -267.311381)
			(xy 439.681127 -267.27815) (xy 439.644875 -267.239079) (xy 439.614851 -267.195042) (xy 439.591725 -267.147021)
			(xy 439.576015 -267.096091) (xy 439.568072 -267.043387) (xy 432.735492 -267.043387) (xy 432.727549 -267.096091)
			(xy 432.711839 -267.147021) (xy 432.688713 -267.195042) (xy 432.658689 -267.239079) (xy 432.622437 -267.27815)
			(xy 432.580766 -267.311381) (xy 432.534608 -267.33803) (xy 432.484994 -267.357502) (xy 432.433032 -267.369362)
			(xy 432.379882 -267.373346) (xy 432.326732 -267.369362) (xy 432.27477 -267.357502) (xy 432.225156 -267.33803)
			(xy 432.178998 -267.311381) (xy 432.137327 -267.27815) (xy 432.101075 -267.239079) (xy 432.071051 -267.195042)
			(xy 432.047925 -267.147021) (xy 432.032215 -267.096091) (xy 432.024272 -267.043387) (xy 425.191692 -267.043387)
			(xy 425.183749 -267.096091) (xy 425.168039 -267.147021) (xy 425.144913 -267.195042) (xy 425.114889 -267.239079)
			(xy 425.078637 -267.27815) (xy 425.036966 -267.311381) (xy 424.990808 -267.33803) (xy 424.941194 -267.357502)
			(xy 424.889232 -267.369362) (xy 424.836082 -267.373346) (xy 424.782932 -267.369362) (xy 424.73097 -267.357502)
			(xy 424.681356 -267.33803) (xy 424.635198 -267.311381) (xy 424.593527 -267.27815) (xy 424.557275 -267.239079)
			(xy 424.527251 -267.195042) (xy 424.504125 -267.147021) (xy 424.488415 -267.096091) (xy 424.480472 -267.043387)
			(xy 405.54656 -267.043387) (xy 405.54656 -267.893271) (xy 420.304204 -267.893271) (xy 420.304204 -267.839973)
			(xy 420.312147 -267.787269) (xy 420.327857 -267.736339) (xy 420.350983 -267.688318) (xy 420.381007 -267.644281)
			(xy 420.417259 -267.60521) (xy 420.45893 -267.571979) (xy 420.505088 -267.54533) (xy 420.554702 -267.525858)
			(xy 420.606664 -267.513998) (xy 420.659814 -267.510015) (xy 420.712964 -267.513998) (xy 420.764926 -267.525858)
			(xy 420.81454 -267.54533) (xy 420.860698 -267.571979) (xy 420.902369 -267.60521) (xy 420.938621 -267.644281)
			(xy 420.968645 -267.688318) (xy 420.991771 -267.736339) (xy 421.007481 -267.787269) (xy 421.015424 -267.839973)
			(xy 421.015922 -267.866622) (xy 421.015424 -267.893271) (xy 427.924204 -267.893271) (xy 427.924204 -267.839973)
			(xy 427.932147 -267.787269) (xy 427.947857 -267.736339) (xy 427.970983 -267.688318) (xy 428.001007 -267.644281)
			(xy 428.037259 -267.60521) (xy 428.07893 -267.571979) (xy 428.125088 -267.54533) (xy 428.174702 -267.525858)
			(xy 428.226664 -267.513998) (xy 428.279814 -267.510015) (xy 428.332964 -267.513998) (xy 428.384926 -267.525858)
			(xy 428.43454 -267.54533) (xy 428.480698 -267.571979) (xy 428.522369 -267.60521) (xy 428.558621 -267.644281)
			(xy 428.588645 -267.688318) (xy 428.611771 -267.736339) (xy 428.627481 -267.787269) (xy 428.635424 -267.839973)
			(xy 428.635922 -267.866622) (xy 428.635424 -267.893271) (xy 435.468004 -267.893271) (xy 435.468004 -267.839973)
			(xy 435.475947 -267.787269) (xy 435.491657 -267.736339) (xy 435.514783 -267.688318) (xy 435.544807 -267.644281)
			(xy 435.581059 -267.60521) (xy 435.62273 -267.571979) (xy 435.668888 -267.54533) (xy 435.718502 -267.525858)
			(xy 435.770464 -267.513998) (xy 435.823614 -267.510015) (xy 435.876764 -267.513998) (xy 435.928726 -267.525858)
			(xy 435.97834 -267.54533) (xy 436.024498 -267.571979) (xy 436.066169 -267.60521) (xy 436.102421 -267.644281)
			(xy 436.132445 -267.688318) (xy 436.155571 -267.736339) (xy 436.171281 -267.787269) (xy 436.179224 -267.839973)
			(xy 436.179722 -267.866622) (xy 436.179224 -267.893271) (xy 443.011804 -267.893271) (xy 443.011804 -267.839973)
			(xy 443.019747 -267.787269) (xy 443.035457 -267.736339) (xy 443.058583 -267.688318) (xy 443.088607 -267.644281)
			(xy 443.124859 -267.60521) (xy 443.16653 -267.571979) (xy 443.212688 -267.54533) (xy 443.262302 -267.525858)
			(xy 443.314264 -267.513998) (xy 443.367414 -267.510015) (xy 443.420564 -267.513998) (xy 443.472526 -267.525858)
			(xy 443.52214 -267.54533) (xy 443.568298 -267.571979) (xy 443.609969 -267.60521) (xy 443.646221 -267.644281)
			(xy 443.676245 -267.688318) (xy 443.699371 -267.736339) (xy 443.715081 -267.787269) (xy 443.723024 -267.839973)
			(xy 443.723522 -267.866622) (xy 443.723024 -267.893271) (xy 443.715081 -267.945975) (xy 443.699371 -267.996905)
			(xy 443.676245 -268.044926) (xy 443.646221 -268.088963) (xy 443.609969 -268.128034) (xy 443.568298 -268.161265)
			(xy 443.52214 -268.187914) (xy 443.472526 -268.207386) (xy 443.420564 -268.219246) (xy 443.367414 -268.22323)
			(xy 443.314264 -268.219246) (xy 443.262302 -268.207386) (xy 443.212688 -268.187914) (xy 443.16653 -268.161265)
			(xy 443.124859 -268.128034) (xy 443.088607 -268.088963) (xy 443.058583 -268.044926) (xy 443.035457 -267.996905)
			(xy 443.019747 -267.945975) (xy 443.011804 -267.893271) (xy 436.179224 -267.893271) (xy 436.171281 -267.945975)
			(xy 436.155571 -267.996905) (xy 436.132445 -268.044926) (xy 436.102421 -268.088963) (xy 436.066169 -268.128034)
			(xy 436.024498 -268.161265) (xy 435.97834 -268.187914) (xy 435.928726 -268.207386) (xy 435.876764 -268.219246)
			(xy 435.823614 -268.22323) (xy 435.770464 -268.219246) (xy 435.718502 -268.207386) (xy 435.668888 -268.187914)
			(xy 435.62273 -268.161265) (xy 435.581059 -268.128034) (xy 435.544807 -268.088963) (xy 435.514783 -268.044926)
			(xy 435.491657 -267.996905) (xy 435.475947 -267.945975) (xy 435.468004 -267.893271) (xy 428.635424 -267.893271)
			(xy 428.627481 -267.945975) (xy 428.611771 -267.996905) (xy 428.588645 -268.044926) (xy 428.558621 -268.088963)
			(xy 428.522369 -268.128034) (xy 428.480698 -268.161265) (xy 428.43454 -268.187914) (xy 428.384926 -268.207386)
			(xy 428.332964 -268.219246) (xy 428.279814 -268.22323) (xy 428.226664 -268.219246) (xy 428.174702 -268.207386)
			(xy 428.125088 -268.187914) (xy 428.07893 -268.161265) (xy 428.037259 -268.128034) (xy 428.001007 -268.088963)
			(xy 427.970983 -268.044926) (xy 427.947857 -267.996905) (xy 427.932147 -267.945975) (xy 427.924204 -267.893271)
			(xy 421.015424 -267.893271) (xy 421.007481 -267.945975) (xy 420.991771 -267.996905) (xy 420.968645 -268.044926)
			(xy 420.938621 -268.088963) (xy 420.902369 -268.128034) (xy 420.860698 -268.161265) (xy 420.81454 -268.187914)
			(xy 420.764926 -268.207386) (xy 420.712964 -268.219246) (xy 420.659814 -268.22323) (xy 420.606664 -268.219246)
			(xy 420.554702 -268.207386) (xy 420.505088 -268.187914) (xy 420.45893 -268.161265) (xy 420.417259 -268.128034)
			(xy 420.381007 -268.088963) (xy 420.350983 -268.044926) (xy 420.327857 -267.996905) (xy 420.312147 -267.945975)
			(xy 420.304204 -267.893271) (xy 405.54656 -267.893271) (xy 405.54656 -268.743409) (xy 432.024272 -268.743409)
			(xy 432.024272 -268.690111) (xy 432.032215 -268.637407) (xy 432.047925 -268.586477) (xy 432.071051 -268.538456)
			(xy 432.101075 -268.494419) (xy 432.137327 -268.455348) (xy 432.178998 -268.422117) (xy 432.225156 -268.395468)
			(xy 432.27477 -268.375996) (xy 432.326732 -268.364136) (xy 432.379882 -268.360153) (xy 432.433032 -268.364136)
			(xy 432.484994 -268.375996) (xy 432.534608 -268.395468) (xy 432.580766 -268.422117) (xy 432.622437 -268.455348)
			(xy 432.658689 -268.494419) (xy 432.688713 -268.538456) (xy 432.711839 -268.586477) (xy 432.727549 -268.637407)
			(xy 432.735492 -268.690111) (xy 432.73599 -268.71676) (xy 432.735492 -268.743409) (xy 439.491872 -268.743409)
			(xy 439.491872 -268.690111) (xy 439.499815 -268.637407) (xy 439.515525 -268.586477) (xy 439.538651 -268.538456)
			(xy 439.568675 -268.494419) (xy 439.604927 -268.455348) (xy 439.646598 -268.422117) (xy 439.692756 -268.395468)
			(xy 439.74237 -268.375996) (xy 439.794332 -268.364136) (xy 439.847482 -268.360153) (xy 439.900632 -268.364136)
			(xy 439.952594 -268.375996) (xy 440.002208 -268.395468) (xy 440.048366 -268.422117) (xy 440.090037 -268.455348)
			(xy 440.126289 -268.494419) (xy 440.156313 -268.538456) (xy 440.179439 -268.586477) (xy 440.195149 -268.637407)
			(xy 440.203092 -268.690111) (xy 440.20359 -268.71676) (xy 440.203092 -268.743409) (xy 440.195149 -268.796113)
			(xy 440.179439 -268.847043) (xy 440.156313 -268.895064) (xy 440.126289 -268.939101) (xy 440.090037 -268.978172)
			(xy 440.048366 -269.011403) (xy 440.002208 -269.038052) (xy 439.952594 -269.057524) (xy 439.900632 -269.069384)
			(xy 439.847482 -269.073368) (xy 439.794332 -269.069384) (xy 439.74237 -269.057524) (xy 439.692756 -269.038052)
			(xy 439.646598 -269.011403) (xy 439.604927 -268.978172) (xy 439.568675 -268.939101) (xy 439.538651 -268.895064)
			(xy 439.515525 -268.847043) (xy 439.499815 -268.796113) (xy 439.491872 -268.743409) (xy 432.735492 -268.743409)
			(xy 432.727549 -268.796113) (xy 432.711839 -268.847043) (xy 432.688713 -268.895064) (xy 432.658689 -268.939101)
			(xy 432.622437 -268.978172) (xy 432.580766 -269.011403) (xy 432.534608 -269.038052) (xy 432.484994 -269.057524)
			(xy 432.433032 -269.069384) (xy 432.379882 -269.073368) (xy 432.326732 -269.069384) (xy 432.27477 -269.057524)
			(xy 432.225156 -269.038052) (xy 432.178998 -269.011403) (xy 432.137327 -268.978172) (xy 432.101075 -268.939101)
			(xy 432.071051 -268.895064) (xy 432.047925 -268.847043) (xy 432.032215 -268.796113) (xy 432.024272 -268.743409)
			(xy 405.54656 -268.743409) (xy 405.54656 -269.108936) (xy 405.546999 -269.122253) (xy 405.553898 -269.14798)
			(xy 405.567218 -269.171045) (xy 405.586052 -269.189879) (xy 405.609117 -269.2032) (xy 405.634843 -269.210101)
			(xy 405.64816 -269.210536) (xy 405.648414 -269.210536) (xy 405.675059 -269.211035) (xy 405.727754 -269.218979)
			(xy 405.778677 -269.234689) (xy 405.82669 -269.257812) (xy 405.87072 -269.287833) (xy 405.909784 -269.32408)
			(xy 405.943009 -269.365745) (xy 405.969654 -269.411897) (xy 405.989123 -269.461504) (xy 406.000981 -269.513458)
			(xy 406.004963 -269.5666) (xy 406.002963 -269.593293) (xy 420.380404 -269.593293) (xy 420.380404 -269.539995)
			(xy 420.388347 -269.487291) (xy 420.404057 -269.436361) (xy 420.427183 -269.38834) (xy 420.457207 -269.344303)
			(xy 420.493459 -269.305232) (xy 420.53513 -269.272001) (xy 420.581288 -269.245352) (xy 420.630902 -269.22588)
			(xy 420.682864 -269.21402) (xy 420.736014 -269.210037) (xy 420.789164 -269.21402) (xy 420.841126 -269.22588)
			(xy 420.89074 -269.245352) (xy 420.936898 -269.272001) (xy 420.978569 -269.305232) (xy 421.014821 -269.344303)
			(xy 421.044845 -269.38834) (xy 421.067971 -269.436361) (xy 421.083681 -269.487291) (xy 421.091624 -269.539995)
			(xy 421.092122 -269.566644) (xy 421.091624 -269.593293) (xy 435.468004 -269.593293) (xy 435.468004 -269.539995)
			(xy 435.475947 -269.487291) (xy 435.491657 -269.436361) (xy 435.514783 -269.38834) (xy 435.544807 -269.344303)
			(xy 435.581059 -269.305232) (xy 435.62273 -269.272001) (xy 435.668888 -269.245352) (xy 435.718502 -269.22588)
			(xy 435.770464 -269.21402) (xy 435.823614 -269.210037) (xy 435.876764 -269.21402) (xy 435.928726 -269.22588)
			(xy 435.97834 -269.245352) (xy 436.024498 -269.272001) (xy 436.066169 -269.305232) (xy 436.102421 -269.344303)
			(xy 436.132445 -269.38834) (xy 436.155571 -269.436361) (xy 436.171281 -269.487291) (xy 436.179224 -269.539995)
			(xy 436.179722 -269.566644) (xy 436.179224 -269.593293) (xy 436.171281 -269.645997) (xy 436.155571 -269.696927)
			(xy 436.132445 -269.744948) (xy 436.102421 -269.788985) (xy 436.066169 -269.828056) (xy 436.024498 -269.861287)
			(xy 435.97834 -269.887936) (xy 435.928726 -269.907408) (xy 435.876764 -269.919268) (xy 435.823614 -269.923252)
			(xy 435.770464 -269.919268) (xy 435.718502 -269.907408) (xy 435.668888 -269.887936) (xy 435.62273 -269.861287)
			(xy 435.581059 -269.828056) (xy 435.544807 -269.788985) (xy 435.514783 -269.744948) (xy 435.491657 -269.696927)
			(xy 435.475947 -269.645997) (xy 435.468004 -269.593293) (xy 421.091624 -269.593293) (xy 421.083681 -269.645997)
			(xy 421.067971 -269.696927) (xy 421.044845 -269.744948) (xy 421.014821 -269.788985) (xy 420.978569 -269.828056)
			(xy 420.936898 -269.861287) (xy 420.89074 -269.887936) (xy 420.841126 -269.907408) (xy 420.789164 -269.919268)
			(xy 420.736014 -269.923252) (xy 420.682864 -269.919268) (xy 420.630902 -269.907408) (xy 420.581288 -269.887936)
			(xy 420.53513 -269.861287) (xy 420.493459 -269.828056) (xy 420.457207 -269.788985) (xy 420.427183 -269.744948)
			(xy 420.404057 -269.696927) (xy 420.388347 -269.645997) (xy 420.380404 -269.593293) (xy 406.002963 -269.593293)
			(xy 406.000981 -269.619742) (xy 405.989123 -269.671696) (xy 405.969654 -269.721303) (xy 405.943009 -269.767455)
			(xy 405.909784 -269.80912) (xy 405.87072 -269.845367) (xy 405.82669 -269.875388) (xy 405.778677 -269.898511)
			(xy 405.727754 -269.914221) (xy 405.675059 -269.922165) (xy 405.648414 -269.922752) (xy 405.64816 -269.922752)
			(xy 405.634843 -269.923191) (xy 405.609116 -269.930091) (xy 405.586051 -269.943411) (xy 405.567216 -269.962245)
			(xy 405.553894 -269.985309) (xy 405.546992 -270.011035) (xy 405.54656 -270.024352) (xy 405.54656 -270.443431)
			(xy 424.480472 -270.443431) (xy 424.480472 -270.390133) (xy 424.488415 -270.337429) (xy 424.504125 -270.286499)
			(xy 424.527251 -270.238478) (xy 424.557275 -270.194441) (xy 424.593527 -270.15537) (xy 424.635198 -270.122139)
			(xy 424.681356 -270.09549) (xy 424.73097 -270.076018) (xy 424.782932 -270.064158) (xy 424.836082 -270.060175)
			(xy 424.889232 -270.064158) (xy 424.941194 -270.076018) (xy 424.990808 -270.09549) (xy 425.036966 -270.122139)
			(xy 425.078637 -270.15537) (xy 425.114889 -270.194441) (xy 425.144913 -270.238478) (xy 425.168039 -270.286499)
			(xy 425.183749 -270.337429) (xy 425.191692 -270.390133) (xy 425.19219 -270.416782) (xy 425.191692 -270.443431)
			(xy 439.542672 -270.443431) (xy 439.542672 -270.390133) (xy 439.550615 -270.337429) (xy 439.566325 -270.286499)
			(xy 439.589451 -270.238478) (xy 439.619475 -270.194441) (xy 439.655727 -270.15537) (xy 439.697398 -270.122139)
			(xy 439.743556 -270.09549) (xy 439.79317 -270.076018) (xy 439.845132 -270.064158) (xy 439.898282 -270.060175)
			(xy 439.951432 -270.064158) (xy 440.003394 -270.076018) (xy 440.053008 -270.09549) (xy 440.099166 -270.122139)
			(xy 440.140837 -270.15537) (xy 440.177089 -270.194441) (xy 440.207113 -270.238478) (xy 440.230239 -270.286499)
			(xy 440.245949 -270.337429) (xy 440.253892 -270.390133) (xy 440.25439 -270.416782) (xy 440.253892 -270.443431)
			(xy 440.245949 -270.496135) (xy 440.230239 -270.547065) (xy 440.207113 -270.595086) (xy 440.177089 -270.639123)
			(xy 440.140837 -270.678194) (xy 440.099166 -270.711425) (xy 440.053008 -270.738074) (xy 440.003394 -270.757546)
			(xy 439.951432 -270.769406) (xy 439.898282 -270.77339) (xy 439.845132 -270.769406) (xy 439.79317 -270.757546)
			(xy 439.743556 -270.738074) (xy 439.697398 -270.711425) (xy 439.655727 -270.678194) (xy 439.619475 -270.639123)
			(xy 439.589451 -270.595086) (xy 439.566325 -270.547065) (xy 439.550615 -270.496135) (xy 439.542672 -270.443431)
			(xy 425.191692 -270.443431) (xy 425.183749 -270.496135) (xy 425.168039 -270.547065) (xy 425.144913 -270.595086)
			(xy 425.114889 -270.639123) (xy 425.078637 -270.678194) (xy 425.036966 -270.711425) (xy 424.990808 -270.738074)
			(xy 424.941194 -270.757546) (xy 424.889232 -270.769406) (xy 424.836082 -270.77339) (xy 424.782932 -270.769406)
			(xy 424.73097 -270.757546) (xy 424.681356 -270.738074) (xy 424.635198 -270.711425) (xy 424.593527 -270.678194)
			(xy 424.557275 -270.639123) (xy 424.527251 -270.595086) (xy 424.504125 -270.547065) (xy 424.488415 -270.496135)
			(xy 424.480472 -270.443431) (xy 405.54656 -270.443431) (xy 405.54656 -271.293315) (xy 420.380404 -271.293315)
			(xy 420.380404 -271.240017) (xy 420.388347 -271.187313) (xy 420.404057 -271.136383) (xy 420.427183 -271.088362)
			(xy 420.457207 -271.044325) (xy 420.493459 -271.005254) (xy 420.53513 -270.972023) (xy 420.581288 -270.945374)
			(xy 420.630902 -270.925902) (xy 420.682864 -270.914042) (xy 420.736014 -270.910059) (xy 420.789164 -270.914042)
			(xy 420.841126 -270.925902) (xy 420.89074 -270.945374) (xy 420.936898 -270.972023) (xy 420.978569 -271.005254)
			(xy 421.014821 -271.044325) (xy 421.044845 -271.088362) (xy 421.067971 -271.136383) (xy 421.083681 -271.187313)
			(xy 421.091624 -271.240017) (xy 421.092122 -271.266666) (xy 421.091624 -271.293315) (xy 435.468004 -271.293315)
			(xy 435.468004 -271.240017) (xy 435.475947 -271.187313) (xy 435.491657 -271.136383) (xy 435.514783 -271.088362)
			(xy 435.544807 -271.044325) (xy 435.581059 -271.005254) (xy 435.62273 -270.972023) (xy 435.668888 -270.945374)
			(xy 435.718502 -270.925902) (xy 435.770464 -270.914042) (xy 435.823614 -270.910059) (xy 435.876764 -270.914042)
			(xy 435.928726 -270.925902) (xy 435.97834 -270.945374) (xy 436.024498 -270.972023) (xy 436.066169 -271.005254)
			(xy 436.102421 -271.044325) (xy 436.132445 -271.088362) (xy 436.155571 -271.136383) (xy 436.171281 -271.187313)
			(xy 436.179224 -271.240017) (xy 436.179722 -271.266666) (xy 436.179224 -271.293315) (xy 436.171281 -271.346019)
			(xy 436.155571 -271.396949) (xy 436.132445 -271.44497) (xy 436.102421 -271.489007) (xy 436.066169 -271.528078)
			(xy 436.024498 -271.561309) (xy 435.97834 -271.587958) (xy 435.928726 -271.60743) (xy 435.876764 -271.61929)
			(xy 435.823614 -271.623274) (xy 435.770464 -271.61929) (xy 435.718502 -271.60743) (xy 435.668888 -271.587958)
			(xy 435.62273 -271.561309) (xy 435.581059 -271.528078) (xy 435.544807 -271.489007) (xy 435.514783 -271.44497)
			(xy 435.491657 -271.396949) (xy 435.475947 -271.346019) (xy 435.468004 -271.293315) (xy 421.091624 -271.293315)
			(xy 421.083681 -271.346019) (xy 421.067971 -271.396949) (xy 421.044845 -271.44497) (xy 421.014821 -271.489007)
			(xy 420.978569 -271.528078) (xy 420.936898 -271.561309) (xy 420.89074 -271.587958) (xy 420.841126 -271.60743)
			(xy 420.789164 -271.61929) (xy 420.736014 -271.623274) (xy 420.682864 -271.61929) (xy 420.630902 -271.60743)
			(xy 420.581288 -271.587958) (xy 420.53513 -271.561309) (xy 420.493459 -271.528078) (xy 420.457207 -271.489007)
			(xy 420.427183 -271.44497) (xy 420.404057 -271.396949) (xy 420.388347 -271.346019) (xy 420.380404 -271.293315)
			(xy 405.54656 -271.293315) (xy 405.54656 -271.809718) (xy 405.573738 -271.824196) (xy 405.596249 -271.836566)
			(xy 405.637482 -271.86719) (xy 405.67348 -271.903825) (xy 405.703378 -271.945589) (xy 405.726455 -271.991474)
			(xy 405.742155 -272.040378) (xy 405.750101 -272.091121) (xy 405.7501 -272.142483) (xy 405.749988 -272.143199)
			(xy 424.480472 -272.143199) (xy 424.480472 -272.089901) (xy 424.488415 -272.037197) (xy 424.504125 -271.986267)
			(xy 424.527251 -271.938246) (xy 424.557275 -271.894209) (xy 424.593527 -271.855138) (xy 424.635198 -271.821907)
			(xy 424.681356 -271.795258) (xy 424.73097 -271.775786) (xy 424.782932 -271.763926) (xy 424.836082 -271.759943)
			(xy 424.889232 -271.763926) (xy 424.941194 -271.775786) (xy 424.990808 -271.795258) (xy 425.036966 -271.821907)
			(xy 425.078637 -271.855138) (xy 425.114889 -271.894209) (xy 425.144913 -271.938246) (xy 425.168039 -271.986267)
			(xy 425.183749 -272.037197) (xy 425.191692 -272.089901) (xy 425.19219 -272.11655) (xy 425.191692 -272.143199)
			(xy 425.191654 -272.143453) (xy 439.526162 -272.143453) (xy 439.526162 -272.090155) (xy 439.534105 -272.037451)
			(xy 439.549815 -271.986521) (xy 439.572941 -271.9385) (xy 439.602965 -271.894463) (xy 439.639217 -271.855392)
			(xy 439.680888 -271.822161) (xy 439.727046 -271.795512) (xy 439.77666 -271.77604) (xy 439.828622 -271.76418)
			(xy 439.881772 -271.760197) (xy 439.934922 -271.76418) (xy 439.986884 -271.77604) (xy 440.036498 -271.795512)
			(xy 440.082656 -271.822161) (xy 440.124327 -271.855392) (xy 440.160579 -271.894463) (xy 440.190603 -271.9385)
			(xy 440.213729 -271.986521) (xy 440.229439 -272.037451) (xy 440.237382 -272.090155) (xy 440.23788 -272.116804)
			(xy 440.237382 -272.143453) (xy 440.229439 -272.196157) (xy 440.213729 -272.247087) (xy 440.190603 -272.295108)
			(xy 440.160579 -272.339145) (xy 440.124327 -272.378216) (xy 440.082656 -272.411447) (xy 440.036498 -272.438096)
			(xy 439.986884 -272.457568) (xy 439.934922 -272.469428) (xy 439.881772 -272.473412) (xy 439.828622 -272.469428)
			(xy 439.77666 -272.457568) (xy 439.727046 -272.438096) (xy 439.680888 -272.411447) (xy 439.639217 -272.378216)
			(xy 439.602965 -272.339145) (xy 439.572941 -272.295108) (xy 439.549815 -272.247087) (xy 439.534105 -272.196157)
			(xy 439.526162 -272.143453) (xy 425.191654 -272.143453) (xy 425.183749 -272.195903) (xy 425.168039 -272.246833)
			(xy 425.144913 -272.294854) (xy 425.114889 -272.338891) (xy 425.078637 -272.377962) (xy 425.036966 -272.411193)
			(xy 424.990808 -272.437842) (xy 424.941194 -272.457314) (xy 424.889232 -272.469174) (xy 424.836082 -272.473158)
			(xy 424.782932 -272.469174) (xy 424.73097 -272.457314) (xy 424.681356 -272.437842) (xy 424.635198 -272.411193)
			(xy 424.593527 -272.377962) (xy 424.557275 -272.338891) (xy 424.527251 -272.294854) (xy 424.504125 -272.246833)
			(xy 424.488415 -272.195903) (xy 424.480472 -272.143199) (xy 405.749988 -272.143199) (xy 405.742154 -272.193226)
			(xy 405.726453 -272.242129) (xy 405.703376 -272.288015) (xy 405.673478 -272.329777) (xy 405.637479 -272.366412)
			(xy 405.596246 -272.397036) (xy 405.573738 -272.409412) (xy 405.54656 -272.42389) (xy 405.54656 -272.993337)
			(xy 420.380404 -272.993337) (xy 420.380404 -272.940039) (xy 420.388347 -272.887335) (xy 420.404057 -272.836405)
			(xy 420.427183 -272.788384) (xy 420.457207 -272.744347) (xy 420.493459 -272.705276) (xy 420.53513 -272.672045)
			(xy 420.581288 -272.645396) (xy 420.630902 -272.625924) (xy 420.682864 -272.614064) (xy 420.736014 -272.610081)
			(xy 420.789164 -272.614064) (xy 420.841126 -272.625924) (xy 420.89074 -272.645396) (xy 420.936898 -272.672045)
			(xy 420.978569 -272.705276) (xy 421.014821 -272.744347) (xy 421.044845 -272.788384) (xy 421.067971 -272.836405)
			(xy 421.083681 -272.887335) (xy 421.091624 -272.940039) (xy 421.092122 -272.966688) (xy 421.091624 -272.993337)
			(xy 435.468004 -272.993337) (xy 435.468004 -272.940039) (xy 435.475947 -272.887335) (xy 435.491657 -272.836405)
			(xy 435.514783 -272.788384) (xy 435.544807 -272.744347) (xy 435.581059 -272.705276) (xy 435.62273 -272.672045)
			(xy 435.668888 -272.645396) (xy 435.718502 -272.625924) (xy 435.770464 -272.614064) (xy 435.823614 -272.610081)
			(xy 435.876764 -272.614064) (xy 435.928726 -272.625924) (xy 435.97834 -272.645396) (xy 436.024498 -272.672045)
			(xy 436.066169 -272.705276) (xy 436.102421 -272.744347) (xy 436.132445 -272.788384) (xy 436.155571 -272.836405)
			(xy 436.171281 -272.887335) (xy 436.179224 -272.940039) (xy 436.179722 -272.966688) (xy 436.179224 -272.993337)
			(xy 436.171281 -273.046041) (xy 436.155571 -273.096971) (xy 436.132445 -273.144992) (xy 436.102421 -273.189029)
			(xy 436.066169 -273.2281) (xy 436.024498 -273.261331) (xy 435.97834 -273.28798) (xy 435.928726 -273.307452)
			(xy 435.876764 -273.319312) (xy 435.823614 -273.323296) (xy 435.770464 -273.319312) (xy 435.718502 -273.307452)
			(xy 435.668888 -273.28798) (xy 435.62273 -273.261331) (xy 435.581059 -273.2281) (xy 435.544807 -273.189029)
			(xy 435.514783 -273.144992) (xy 435.491657 -273.096971) (xy 435.475947 -273.046041) (xy 435.468004 -272.993337)
			(xy 421.091624 -272.993337) (xy 421.083681 -273.046041) (xy 421.067971 -273.096971) (xy 421.044845 -273.144992)
			(xy 421.014821 -273.189029) (xy 420.978569 -273.2281) (xy 420.936898 -273.261331) (xy 420.89074 -273.28798)
			(xy 420.841126 -273.307452) (xy 420.789164 -273.319312) (xy 420.736014 -273.323296) (xy 420.682864 -273.319312)
			(xy 420.630902 -273.307452) (xy 420.581288 -273.28798) (xy 420.53513 -273.261331) (xy 420.493459 -273.2281)
			(xy 420.457207 -273.189029) (xy 420.427183 -273.144992) (xy 420.404057 -273.096971) (xy 420.388347 -273.046041)
			(xy 420.380404 -272.993337) (xy 405.54656 -272.993337) (xy 405.54656 -273.843221) (xy 424.480472 -273.843221)
			(xy 424.480472 -273.789923) (xy 424.488415 -273.737219) (xy 424.504125 -273.686289) (xy 424.527251 -273.638268)
			(xy 424.557275 -273.594231) (xy 424.593527 -273.55516) (xy 424.635198 -273.521929) (xy 424.681356 -273.49528)
			(xy 424.73097 -273.475808) (xy 424.782932 -273.463948) (xy 424.836082 -273.459965) (xy 424.889232 -273.463948)
			(xy 424.941194 -273.475808) (xy 424.990808 -273.49528) (xy 425.036966 -273.521929) (xy 425.078637 -273.55516)
			(xy 425.114889 -273.594231) (xy 425.144913 -273.638268) (xy 425.168039 -273.686289) (xy 425.183749 -273.737219)
			(xy 425.191692 -273.789923) (xy 425.19219 -273.816572) (xy 425.191692 -273.843221) (xy 439.568072 -273.843221)
			(xy 439.568072 -273.789923) (xy 439.576015 -273.737219) (xy 439.591725 -273.686289) (xy 439.614851 -273.638268)
			(xy 439.644875 -273.594231) (xy 439.681127 -273.55516) (xy 439.722798 -273.521929) (xy 439.768956 -273.49528)
			(xy 439.81857 -273.475808) (xy 439.870532 -273.463948) (xy 439.923682 -273.459965) (xy 439.976832 -273.463948)
			(xy 440.028794 -273.475808) (xy 440.078408 -273.49528) (xy 440.124566 -273.521929) (xy 440.166237 -273.55516)
			(xy 440.202489 -273.594231) (xy 440.232513 -273.638268) (xy 440.255639 -273.686289) (xy 440.271349 -273.737219)
			(xy 440.279292 -273.789923) (xy 440.27979 -273.816572) (xy 440.279292 -273.843221) (xy 440.271349 -273.895925)
			(xy 440.255639 -273.946855) (xy 440.232513 -273.994876) (xy 440.202489 -274.038913) (xy 440.166237 -274.077984)
			(xy 440.124566 -274.111215) (xy 440.078408 -274.137864) (xy 440.028794 -274.157336) (xy 439.976832 -274.169196)
			(xy 439.923682 -274.17318) (xy 439.870532 -274.169196) (xy 439.81857 -274.157336) (xy 439.768956 -274.137864)
			(xy 439.722798 -274.111215) (xy 439.681127 -274.077984) (xy 439.644875 -274.038913) (xy 439.614851 -273.994876)
			(xy 439.591725 -273.946855) (xy 439.576015 -273.895925) (xy 439.568072 -273.843221) (xy 425.191692 -273.843221)
			(xy 425.183749 -273.895925) (xy 425.168039 -273.946855) (xy 425.144913 -273.994876) (xy 425.114889 -274.038913)
			(xy 425.078637 -274.077984) (xy 425.036966 -274.111215) (xy 424.990808 -274.137864) (xy 424.941194 -274.157336)
			(xy 424.889232 -274.169196) (xy 424.836082 -274.17318) (xy 424.782932 -274.169196) (xy 424.73097 -274.157336)
			(xy 424.681356 -274.137864) (xy 424.635198 -274.111215) (xy 424.593527 -274.077984) (xy 424.557275 -274.038913)
			(xy 424.527251 -273.994876) (xy 424.504125 -273.946855) (xy 424.488415 -273.895925) (xy 424.480472 -273.843221)
			(xy 405.54656 -273.843221) (xy 405.54656 -274.693359) (xy 420.380404 -274.693359) (xy 420.380404 -274.640061)
			(xy 420.388347 -274.587357) (xy 420.404057 -274.536427) (xy 420.427183 -274.488406) (xy 420.457207 -274.444369)
			(xy 420.493459 -274.405298) (xy 420.53513 -274.372067) (xy 420.581288 -274.345418) (xy 420.630902 -274.325946)
			(xy 420.682864 -274.314086) (xy 420.736014 -274.310103) (xy 420.789164 -274.314086) (xy 420.841126 -274.325946)
			(xy 420.89074 -274.345418) (xy 420.936898 -274.372067) (xy 420.978569 -274.405298) (xy 421.014821 -274.444369)
			(xy 421.044845 -274.488406) (xy 421.067971 -274.536427) (xy 421.083681 -274.587357) (xy 421.091624 -274.640061)
			(xy 421.092122 -274.66671) (xy 421.091624 -274.693359) (xy 424.480472 -274.693359) (xy 424.480472 -274.640061)
			(xy 424.488415 -274.587357) (xy 424.504125 -274.536427) (xy 424.527251 -274.488406) (xy 424.557275 -274.444369)
			(xy 424.593527 -274.405298) (xy 424.635198 -274.372067) (xy 424.681356 -274.345418) (xy 424.73097 -274.325946)
			(xy 424.782932 -274.314086) (xy 424.836082 -274.310103) (xy 424.889232 -274.314086) (xy 424.941194 -274.325946)
			(xy 424.990808 -274.345418) (xy 425.036966 -274.372067) (xy 425.078637 -274.405298) (xy 425.114889 -274.444369)
			(xy 425.144913 -274.488406) (xy 425.168039 -274.536427) (xy 425.183749 -274.587357) (xy 425.191692 -274.640061)
			(xy 425.19219 -274.66671) (xy 425.191692 -274.693359) (xy 435.468004 -274.693359) (xy 435.468004 -274.640061)
			(xy 435.475947 -274.587357) (xy 435.491657 -274.536427) (xy 435.514783 -274.488406) (xy 435.544807 -274.444369)
			(xy 435.581059 -274.405298) (xy 435.62273 -274.372067) (xy 435.668888 -274.345418) (xy 435.718502 -274.325946)
			(xy 435.770464 -274.314086) (xy 435.823614 -274.310103) (xy 435.876764 -274.314086) (xy 435.928726 -274.325946)
			(xy 435.97834 -274.345418) (xy 436.024498 -274.372067) (xy 436.066169 -274.405298) (xy 436.102421 -274.444369)
			(xy 436.132445 -274.488406) (xy 436.155571 -274.536427) (xy 436.171281 -274.587357) (xy 436.179224 -274.640061)
			(xy 436.179722 -274.66671) (xy 436.179224 -274.693359) (xy 439.568072 -274.693359) (xy 439.568072 -274.640061)
			(xy 439.576015 -274.587357) (xy 439.591725 -274.536427) (xy 439.614851 -274.488406) (xy 439.644875 -274.444369)
			(xy 439.681127 -274.405298) (xy 439.722798 -274.372067) (xy 439.768956 -274.345418) (xy 439.81857 -274.325946)
			(xy 439.870532 -274.314086) (xy 439.923682 -274.310103) (xy 439.976832 -274.314086) (xy 440.028794 -274.325946)
			(xy 440.078408 -274.345418) (xy 440.124566 -274.372067) (xy 440.166237 -274.405298) (xy 440.202489 -274.444369)
			(xy 440.232513 -274.488406) (xy 440.255639 -274.536427) (xy 440.271349 -274.587357) (xy 440.279292 -274.640061)
			(xy 440.27979 -274.66671) (xy 440.279292 -274.693359) (xy 440.271349 -274.746063) (xy 440.255639 -274.796993)
			(xy 440.232513 -274.845014) (xy 440.202489 -274.889051) (xy 440.166237 -274.928122) (xy 440.124566 -274.961353)
			(xy 440.078408 -274.988002) (xy 440.028794 -275.007474) (xy 439.976832 -275.019334) (xy 439.923682 -275.023318)
			(xy 439.870532 -275.019334) (xy 439.81857 -275.007474) (xy 439.768956 -274.988002) (xy 439.722798 -274.961353)
			(xy 439.681127 -274.928122) (xy 439.644875 -274.889051) (xy 439.614851 -274.845014) (xy 439.591725 -274.796993)
			(xy 439.576015 -274.746063) (xy 439.568072 -274.693359) (xy 436.179224 -274.693359) (xy 436.171281 -274.746063)
			(xy 436.155571 -274.796993) (xy 436.132445 -274.845014) (xy 436.102421 -274.889051) (xy 436.066169 -274.928122)
			(xy 436.024498 -274.961353) (xy 435.97834 -274.988002) (xy 435.928726 -275.007474) (xy 435.876764 -275.019334)
			(xy 435.823614 -275.023318) (xy 435.770464 -275.019334) (xy 435.718502 -275.007474) (xy 435.668888 -274.988002)
			(xy 435.62273 -274.961353) (xy 435.581059 -274.928122) (xy 435.544807 -274.889051) (xy 435.514783 -274.845014)
			(xy 435.491657 -274.796993) (xy 435.475947 -274.746063) (xy 435.468004 -274.693359) (xy 425.191692 -274.693359)
			(xy 425.183749 -274.746063) (xy 425.168039 -274.796993) (xy 425.144913 -274.845014) (xy 425.114889 -274.889051)
			(xy 425.078637 -274.928122) (xy 425.036966 -274.961353) (xy 424.990808 -274.988002) (xy 424.941194 -275.007474)
			(xy 424.889232 -275.019334) (xy 424.836082 -275.023318) (xy 424.782932 -275.019334) (xy 424.73097 -275.007474)
			(xy 424.681356 -274.988002) (xy 424.635198 -274.961353) (xy 424.593527 -274.928122) (xy 424.557275 -274.889051)
			(xy 424.527251 -274.845014) (xy 424.504125 -274.796993) (xy 424.488415 -274.746063) (xy 424.480472 -274.693359)
			(xy 421.091624 -274.693359) (xy 421.083681 -274.746063) (xy 421.067971 -274.796993) (xy 421.044845 -274.845014)
			(xy 421.014821 -274.889051) (xy 420.978569 -274.928122) (xy 420.936898 -274.961353) (xy 420.89074 -274.988002)
			(xy 420.841126 -275.007474) (xy 420.789164 -275.019334) (xy 420.736014 -275.023318) (xy 420.682864 -275.019334)
			(xy 420.630902 -275.007474) (xy 420.581288 -274.988002) (xy 420.53513 -274.961353) (xy 420.493459 -274.928122)
			(xy 420.457207 -274.889051) (xy 420.427183 -274.845014) (xy 420.404057 -274.796993) (xy 420.388347 -274.746063)
			(xy 420.380404 -274.693359) (xy 405.54656 -274.693359) (xy 405.54656 -275.543243) (xy 420.380404 -275.543243)
			(xy 420.380404 -275.489945) (xy 420.388347 -275.437241) (xy 420.404057 -275.386311) (xy 420.427183 -275.33829)
			(xy 420.457207 -275.294253) (xy 420.493459 -275.255182) (xy 420.53513 -275.221951) (xy 420.581288 -275.195302)
			(xy 420.630902 -275.17583) (xy 420.682864 -275.16397) (xy 420.736014 -275.159987) (xy 420.789164 -275.16397)
			(xy 420.841126 -275.17583) (xy 420.89074 -275.195302) (xy 420.936898 -275.221951) (xy 420.978569 -275.255182)
			(xy 421.014821 -275.294253) (xy 421.044845 -275.33829) (xy 421.067971 -275.386311) (xy 421.083681 -275.437241)
			(xy 421.091624 -275.489945) (xy 421.092122 -275.516594) (xy 421.091624 -275.543243) (xy 435.468004 -275.543243)
			(xy 435.468004 -275.489945) (xy 435.475947 -275.437241) (xy 435.491657 -275.386311) (xy 435.514783 -275.33829)
			(xy 435.544807 -275.294253) (xy 435.581059 -275.255182) (xy 435.62273 -275.221951) (xy 435.668888 -275.195302)
			(xy 435.718502 -275.17583) (xy 435.770464 -275.16397) (xy 435.823614 -275.159987) (xy 435.876764 -275.16397)
			(xy 435.928726 -275.17583) (xy 435.97834 -275.195302) (xy 436.024498 -275.221951) (xy 436.066169 -275.255182)
			(xy 436.102421 -275.294253) (xy 436.132445 -275.33829) (xy 436.155571 -275.386311) (xy 436.171281 -275.437241)
			(xy 436.179224 -275.489945) (xy 436.179722 -275.516594) (xy 436.179224 -275.543243) (xy 436.171281 -275.595947)
			(xy 436.155571 -275.646877) (xy 436.132445 -275.694898) (xy 436.102421 -275.738935) (xy 436.066169 -275.778006)
			(xy 436.024498 -275.811237) (xy 435.97834 -275.837886) (xy 435.928726 -275.857358) (xy 435.876764 -275.869218)
			(xy 435.823614 -275.873202) (xy 435.770464 -275.869218) (xy 435.718502 -275.857358) (xy 435.668888 -275.837886)
			(xy 435.62273 -275.811237) (xy 435.581059 -275.778006) (xy 435.544807 -275.738935) (xy 435.514783 -275.694898)
			(xy 435.491657 -275.646877) (xy 435.475947 -275.595947) (xy 435.468004 -275.543243) (xy 421.091624 -275.543243)
			(xy 421.083681 -275.595947) (xy 421.067971 -275.646877) (xy 421.044845 -275.694898) (xy 421.014821 -275.738935)
			(xy 420.978569 -275.778006) (xy 420.936898 -275.811237) (xy 420.89074 -275.837886) (xy 420.841126 -275.857358)
			(xy 420.789164 -275.869218) (xy 420.736014 -275.873202) (xy 420.682864 -275.869218) (xy 420.630902 -275.857358)
			(xy 420.581288 -275.837886) (xy 420.53513 -275.811237) (xy 420.493459 -275.778006) (xy 420.457207 -275.738935)
			(xy 420.427183 -275.694898) (xy 420.404057 -275.646877) (xy 420.388347 -275.595947) (xy 420.380404 -275.543243)
			(xy 405.54656 -275.543243) (xy 405.54656 -276.393381) (xy 424.480472 -276.393381) (xy 424.480472 -276.340083)
			(xy 424.488415 -276.287379) (xy 424.504125 -276.236449) (xy 424.527251 -276.188428) (xy 424.557275 -276.144391)
			(xy 424.593527 -276.10532) (xy 424.635198 -276.072089) (xy 424.681356 -276.04544) (xy 424.73097 -276.025968)
			(xy 424.782932 -276.014108) (xy 424.836082 -276.010125) (xy 424.889232 -276.014108) (xy 424.941194 -276.025968)
			(xy 424.990808 -276.04544) (xy 425.036966 -276.072089) (xy 425.078637 -276.10532) (xy 425.114889 -276.144391)
			(xy 425.144913 -276.188428) (xy 425.168039 -276.236449) (xy 425.183749 -276.287379) (xy 425.191692 -276.340083)
			(xy 425.19219 -276.366732) (xy 425.191692 -276.393381) (xy 439.568072 -276.393381) (xy 439.568072 -276.340083)
			(xy 439.576015 -276.287379) (xy 439.591725 -276.236449) (xy 439.614851 -276.188428) (xy 439.644875 -276.144391)
			(xy 439.681127 -276.10532) (xy 439.722798 -276.072089) (xy 439.768956 -276.04544) (xy 439.81857 -276.025968)
			(xy 439.870532 -276.014108) (xy 439.923682 -276.010125) (xy 439.976832 -276.014108) (xy 440.028794 -276.025968)
			(xy 440.078408 -276.04544) (xy 440.124566 -276.072089) (xy 440.166237 -276.10532) (xy 440.202489 -276.144391)
			(xy 440.232513 -276.188428) (xy 440.255639 -276.236449) (xy 440.271349 -276.287379) (xy 440.279292 -276.340083)
			(xy 440.27979 -276.366732) (xy 440.279292 -276.393381) (xy 440.271349 -276.446085) (xy 440.255639 -276.497015)
			(xy 440.232513 -276.545036) (xy 440.202489 -276.589073) (xy 440.166237 -276.628144) (xy 440.124566 -276.661375)
			(xy 440.078408 -276.688024) (xy 440.028794 -276.707496) (xy 439.976832 -276.719356) (xy 439.923682 -276.72334)
			(xy 439.870532 -276.719356) (xy 439.81857 -276.707496) (xy 439.768956 -276.688024) (xy 439.722798 -276.661375)
			(xy 439.681127 -276.628144) (xy 439.644875 -276.589073) (xy 439.614851 -276.545036) (xy 439.591725 -276.497015)
			(xy 439.576015 -276.446085) (xy 439.568072 -276.393381) (xy 425.191692 -276.393381) (xy 425.183749 -276.446085)
			(xy 425.168039 -276.497015) (xy 425.144913 -276.545036) (xy 425.114889 -276.589073) (xy 425.078637 -276.628144)
			(xy 425.036966 -276.661375) (xy 424.990808 -276.688024) (xy 424.941194 -276.707496) (xy 424.889232 -276.719356)
			(xy 424.836082 -276.72334) (xy 424.782932 -276.719356) (xy 424.73097 -276.707496) (xy 424.681356 -276.688024)
			(xy 424.635198 -276.661375) (xy 424.593527 -276.628144) (xy 424.557275 -276.589073) (xy 424.527251 -276.545036)
			(xy 424.504125 -276.497015) (xy 424.488415 -276.446085) (xy 424.480472 -276.393381) (xy 405.54656 -276.393381)
			(xy 405.54656 -277.243265) (xy 420.380404 -277.243265) (xy 420.380404 -277.189967) (xy 420.388347 -277.137263)
			(xy 420.404057 -277.086333) (xy 420.427183 -277.038312) (xy 420.457207 -276.994275) (xy 420.493459 -276.955204)
			(xy 420.53513 -276.921973) (xy 420.581288 -276.895324) (xy 420.630902 -276.875852) (xy 420.682864 -276.863992)
			(xy 420.736014 -276.860009) (xy 420.789164 -276.863992) (xy 420.841126 -276.875852) (xy 420.89074 -276.895324)
			(xy 420.936898 -276.921973) (xy 420.978569 -276.955204) (xy 421.014821 -276.994275) (xy 421.044845 -277.038312)
			(xy 421.067971 -277.086333) (xy 421.083681 -277.137263) (xy 421.091624 -277.189967) (xy 421.092122 -277.216616)
			(xy 421.091624 -277.243265) (xy 435.468004 -277.243265) (xy 435.468004 -277.189967) (xy 435.475947 -277.137263)
			(xy 435.491657 -277.086333) (xy 435.514783 -277.038312) (xy 435.544807 -276.994275) (xy 435.581059 -276.955204)
			(xy 435.62273 -276.921973) (xy 435.668888 -276.895324) (xy 435.718502 -276.875852) (xy 435.770464 -276.863992)
			(xy 435.823614 -276.860009) (xy 435.876764 -276.863992) (xy 435.928726 -276.875852) (xy 435.97834 -276.895324)
			(xy 436.024498 -276.921973) (xy 436.066169 -276.955204) (xy 436.102421 -276.994275) (xy 436.132445 -277.038312)
			(xy 436.155571 -277.086333) (xy 436.171281 -277.137263) (xy 436.179224 -277.189967) (xy 436.179722 -277.216616)
			(xy 436.179224 -277.243265) (xy 436.171281 -277.295969) (xy 436.155571 -277.346899) (xy 436.132445 -277.39492)
			(xy 436.102421 -277.438957) (xy 436.066169 -277.478028) (xy 436.024498 -277.511259) (xy 435.97834 -277.537908)
			(xy 435.928726 -277.55738) (xy 435.876764 -277.56924) (xy 435.823614 -277.573224) (xy 435.770464 -277.56924)
			(xy 435.718502 -277.55738) (xy 435.668888 -277.537908) (xy 435.62273 -277.511259) (xy 435.581059 -277.478028)
			(xy 435.544807 -277.438957) (xy 435.514783 -277.39492) (xy 435.491657 -277.346899) (xy 435.475947 -277.295969)
			(xy 435.468004 -277.243265) (xy 421.091624 -277.243265) (xy 421.083681 -277.295969) (xy 421.067971 -277.346899)
			(xy 421.044845 -277.39492) (xy 421.014821 -277.438957) (xy 420.978569 -277.478028) (xy 420.936898 -277.511259)
			(xy 420.89074 -277.537908) (xy 420.841126 -277.55738) (xy 420.789164 -277.56924) (xy 420.736014 -277.573224)
			(xy 420.682864 -277.56924) (xy 420.630902 -277.55738) (xy 420.581288 -277.537908) (xy 420.53513 -277.511259)
			(xy 420.493459 -277.478028) (xy 420.457207 -277.438957) (xy 420.427183 -277.39492) (xy 420.404057 -277.346899)
			(xy 420.388347 -277.295969) (xy 420.380404 -277.243265) (xy 405.54656 -277.243265) (xy 405.54656 -278.093403)
			(xy 424.480472 -278.093403) (xy 424.480472 -278.040105) (xy 424.488415 -277.987401) (xy 424.504125 -277.936471)
			(xy 424.527251 -277.88845) (xy 424.557275 -277.844413) (xy 424.593527 -277.805342) (xy 424.635198 -277.772111)
			(xy 424.681356 -277.745462) (xy 424.73097 -277.72599) (xy 424.782932 -277.71413) (xy 424.836082 -277.710147)
			(xy 424.889232 -277.71413) (xy 424.941194 -277.72599) (xy 424.990808 -277.745462) (xy 425.036966 -277.772111)
			(xy 425.078637 -277.805342) (xy 425.114889 -277.844413) (xy 425.144913 -277.88845) (xy 425.168039 -277.936471)
			(xy 425.183749 -277.987401) (xy 425.191692 -278.040105) (xy 425.19219 -278.066754) (xy 425.191692 -278.093403)
			(xy 439.568072 -278.093403) (xy 439.568072 -278.040105) (xy 439.576015 -277.987401) (xy 439.591725 -277.936471)
			(xy 439.614851 -277.88845) (xy 439.644875 -277.844413) (xy 439.681127 -277.805342) (xy 439.722798 -277.772111)
			(xy 439.768956 -277.745462) (xy 439.81857 -277.72599) (xy 439.870532 -277.71413) (xy 439.923682 -277.710147)
			(xy 439.976832 -277.71413) (xy 440.028794 -277.72599) (xy 440.078408 -277.745462) (xy 440.124566 -277.772111)
			(xy 440.166237 -277.805342) (xy 440.202489 -277.844413) (xy 440.232513 -277.88845) (xy 440.255639 -277.936471)
			(xy 440.271349 -277.987401) (xy 440.279292 -278.040105) (xy 440.27979 -278.066754) (xy 440.279292 -278.093403)
			(xy 440.271349 -278.146107) (xy 440.255639 -278.197037) (xy 440.232513 -278.245058) (xy 440.202489 -278.289095)
			(xy 440.166237 -278.328166) (xy 440.124566 -278.361397) (xy 440.078408 -278.388046) (xy 440.028794 -278.407518)
			(xy 439.976832 -278.419378) (xy 439.923682 -278.423362) (xy 439.870532 -278.419378) (xy 439.81857 -278.407518)
			(xy 439.768956 -278.388046) (xy 439.722798 -278.361397) (xy 439.681127 -278.328166) (xy 439.644875 -278.289095)
			(xy 439.614851 -278.245058) (xy 439.591725 -278.197037) (xy 439.576015 -278.146107) (xy 439.568072 -278.093403)
			(xy 425.191692 -278.093403) (xy 425.183749 -278.146107) (xy 425.168039 -278.197037) (xy 425.144913 -278.245058)
			(xy 425.114889 -278.289095) (xy 425.078637 -278.328166) (xy 425.036966 -278.361397) (xy 424.990808 -278.388046)
			(xy 424.941194 -278.407518) (xy 424.889232 -278.419378) (xy 424.836082 -278.423362) (xy 424.782932 -278.419378)
			(xy 424.73097 -278.407518) (xy 424.681356 -278.388046) (xy 424.635198 -278.361397) (xy 424.593527 -278.328166)
			(xy 424.557275 -278.289095) (xy 424.527251 -278.245058) (xy 424.504125 -278.197037) (xy 424.488415 -278.146107)
			(xy 424.480472 -278.093403) (xy 405.54656 -278.093403) (xy 405.54656 -278.943287) (xy 420.380404 -278.943287)
			(xy 420.380404 -278.889989) (xy 420.388347 -278.837285) (xy 420.404057 -278.786355) (xy 420.427183 -278.738334)
			(xy 420.457207 -278.694297) (xy 420.493459 -278.655226) (xy 420.53513 -278.621995) (xy 420.581288 -278.595346)
			(xy 420.630902 -278.575874) (xy 420.682864 -278.564014) (xy 420.736014 -278.560031) (xy 420.789164 -278.564014)
			(xy 420.841126 -278.575874) (xy 420.89074 -278.595346) (xy 420.936898 -278.621995) (xy 420.978569 -278.655226)
			(xy 421.014821 -278.694297) (xy 421.044845 -278.738334) (xy 421.067971 -278.786355) (xy 421.083681 -278.837285)
			(xy 421.091624 -278.889989) (xy 421.092122 -278.916638) (xy 421.091624 -278.943287) (xy 435.468004 -278.943287)
			(xy 435.468004 -278.889989) (xy 435.475947 -278.837285) (xy 435.491657 -278.786355) (xy 435.514783 -278.738334)
			(xy 435.544807 -278.694297) (xy 435.581059 -278.655226) (xy 435.62273 -278.621995) (xy 435.668888 -278.595346)
			(xy 435.718502 -278.575874) (xy 435.770464 -278.564014) (xy 435.823614 -278.560031) (xy 435.876764 -278.564014)
			(xy 435.928726 -278.575874) (xy 435.97834 -278.595346) (xy 436.024498 -278.621995) (xy 436.066169 -278.655226)
			(xy 436.102421 -278.694297) (xy 436.132445 -278.738334) (xy 436.155571 -278.786355) (xy 436.171281 -278.837285)
			(xy 436.179224 -278.889989) (xy 436.179722 -278.916638) (xy 436.179224 -278.943287) (xy 436.171281 -278.995991)
			(xy 436.155571 -279.046921) (xy 436.132445 -279.094942) (xy 436.102421 -279.138979) (xy 436.066169 -279.17805)
			(xy 436.024498 -279.211281) (xy 435.97834 -279.23793) (xy 435.928726 -279.257402) (xy 435.876764 -279.269262)
			(xy 435.823614 -279.273246) (xy 435.770464 -279.269262) (xy 435.718502 -279.257402) (xy 435.668888 -279.23793)
			(xy 435.62273 -279.211281) (xy 435.581059 -279.17805) (xy 435.544807 -279.138979) (xy 435.514783 -279.094942)
			(xy 435.491657 -279.046921) (xy 435.475947 -278.995991) (xy 435.468004 -278.943287) (xy 421.091624 -278.943287)
			(xy 421.083681 -278.995991) (xy 421.067971 -279.046921) (xy 421.044845 -279.094942) (xy 421.014821 -279.138979)
			(xy 420.978569 -279.17805) (xy 420.936898 -279.211281) (xy 420.89074 -279.23793) (xy 420.841126 -279.257402)
			(xy 420.789164 -279.269262) (xy 420.736014 -279.273246) (xy 420.682864 -279.269262) (xy 420.630902 -279.257402)
			(xy 420.581288 -279.23793) (xy 420.53513 -279.211281) (xy 420.493459 -279.17805) (xy 420.457207 -279.138979)
			(xy 420.427183 -279.094942) (xy 420.404057 -279.046921) (xy 420.388347 -278.995991) (xy 420.380404 -278.943287)
			(xy 405.54656 -278.943287) (xy 405.54656 -279.793425) (xy 424.480472 -279.793425) (xy 424.480472 -279.740127)
			(xy 424.488415 -279.687423) (xy 424.504125 -279.636493) (xy 424.527251 -279.588472) (xy 424.557275 -279.544435)
			(xy 424.593527 -279.505364) (xy 424.635198 -279.472133) (xy 424.681356 -279.445484) (xy 424.73097 -279.426012)
			(xy 424.782932 -279.414152) (xy 424.836082 -279.410169) (xy 424.889232 -279.414152) (xy 424.941194 -279.426012)
			(xy 424.990808 -279.445484) (xy 425.036966 -279.472133) (xy 425.078637 -279.505364) (xy 425.114889 -279.544435)
			(xy 425.144913 -279.588472) (xy 425.168039 -279.636493) (xy 425.183749 -279.687423) (xy 425.191692 -279.740127)
			(xy 425.19219 -279.766776) (xy 425.191692 -279.793425) (xy 439.568072 -279.793425) (xy 439.568072 -279.740127)
			(xy 439.576015 -279.687423) (xy 439.591725 -279.636493) (xy 439.614851 -279.588472) (xy 439.644875 -279.544435)
			(xy 439.681127 -279.505364) (xy 439.722798 -279.472133) (xy 439.768956 -279.445484) (xy 439.81857 -279.426012)
			(xy 439.870532 -279.414152) (xy 439.923682 -279.410169) (xy 439.976832 -279.414152) (xy 440.028794 -279.426012)
			(xy 440.078408 -279.445484) (xy 440.124566 -279.472133) (xy 440.166237 -279.505364) (xy 440.202489 -279.544435)
			(xy 440.232513 -279.588472) (xy 440.255639 -279.636493) (xy 440.271349 -279.687423) (xy 440.279292 -279.740127)
			(xy 440.27979 -279.766776) (xy 440.279292 -279.793425) (xy 440.271349 -279.846129) (xy 440.255639 -279.897059)
			(xy 440.232513 -279.94508) (xy 440.202489 -279.989117) (xy 440.166237 -280.028188) (xy 440.124566 -280.061419)
			(xy 440.078408 -280.088068) (xy 440.028794 -280.10754) (xy 439.976832 -280.1194) (xy 439.923682 -280.123384)
			(xy 439.870532 -280.1194) (xy 439.81857 -280.10754) (xy 439.768956 -280.088068) (xy 439.722798 -280.061419)
			(xy 439.681127 -280.028188) (xy 439.644875 -279.989117) (xy 439.614851 -279.94508) (xy 439.591725 -279.897059)
			(xy 439.576015 -279.846129) (xy 439.568072 -279.793425) (xy 425.191692 -279.793425) (xy 425.183749 -279.846129)
			(xy 425.168039 -279.897059) (xy 425.144913 -279.94508) (xy 425.114889 -279.989117) (xy 425.078637 -280.028188)
			(xy 425.036966 -280.061419) (xy 424.990808 -280.088068) (xy 424.941194 -280.10754) (xy 424.889232 -280.1194)
			(xy 424.836082 -280.123384) (xy 424.782932 -280.1194) (xy 424.73097 -280.10754) (xy 424.681356 -280.088068)
			(xy 424.635198 -280.061419) (xy 424.593527 -280.028188) (xy 424.557275 -279.989117) (xy 424.527251 -279.94508)
			(xy 424.504125 -279.897059) (xy 424.488415 -279.846129) (xy 424.480472 -279.793425) (xy 405.54656 -279.793425)
			(xy 405.54656 -280.643309) (xy 420.380404 -280.643309) (xy 420.380404 -280.590011) (xy 420.388347 -280.537307)
			(xy 420.404057 -280.486377) (xy 420.427183 -280.438356) (xy 420.457207 -280.394319) (xy 420.493459 -280.355248)
			(xy 420.53513 -280.322017) (xy 420.581288 -280.295368) (xy 420.630902 -280.275896) (xy 420.682864 -280.264036)
			(xy 420.736014 -280.260053) (xy 420.789164 -280.264036) (xy 420.841126 -280.275896) (xy 420.89074 -280.295368)
			(xy 420.936898 -280.322017) (xy 420.978569 -280.355248) (xy 421.014821 -280.394319) (xy 421.044845 -280.438356)
			(xy 421.067971 -280.486377) (xy 421.083681 -280.537307) (xy 421.091624 -280.590011) (xy 421.092122 -280.61666)
			(xy 421.091624 -280.643309) (xy 435.468004 -280.643309) (xy 435.468004 -280.590011) (xy 435.475947 -280.537307)
			(xy 435.491657 -280.486377) (xy 435.514783 -280.438356) (xy 435.544807 -280.394319) (xy 435.581059 -280.355248)
			(xy 435.62273 -280.322017) (xy 435.668888 -280.295368) (xy 435.718502 -280.275896) (xy 435.770464 -280.264036)
			(xy 435.823614 -280.260053) (xy 435.876764 -280.264036) (xy 435.928726 -280.275896) (xy 435.97834 -280.295368)
			(xy 436.024498 -280.322017) (xy 436.066169 -280.355248) (xy 436.102421 -280.394319) (xy 436.132445 -280.438356)
			(xy 436.155571 -280.486377) (xy 436.171281 -280.537307) (xy 436.179224 -280.590011) (xy 436.179722 -280.61666)
			(xy 436.179224 -280.643309) (xy 436.171281 -280.696013) (xy 436.155571 -280.746943) (xy 436.132445 -280.794964)
			(xy 436.102421 -280.839001) (xy 436.066169 -280.878072) (xy 436.024498 -280.911303) (xy 435.97834 -280.937952)
			(xy 435.928726 -280.957424) (xy 435.876764 -280.969284) (xy 435.823614 -280.973268) (xy 435.770464 -280.969284)
			(xy 435.718502 -280.957424) (xy 435.668888 -280.937952) (xy 435.62273 -280.911303) (xy 435.581059 -280.878072)
			(xy 435.544807 -280.839001) (xy 435.514783 -280.794964) (xy 435.491657 -280.746943) (xy 435.475947 -280.696013)
			(xy 435.468004 -280.643309) (xy 421.091624 -280.643309) (xy 421.083681 -280.696013) (xy 421.067971 -280.746943)
			(xy 421.044845 -280.794964) (xy 421.014821 -280.839001) (xy 420.978569 -280.878072) (xy 420.936898 -280.911303)
			(xy 420.89074 -280.937952) (xy 420.841126 -280.957424) (xy 420.789164 -280.969284) (xy 420.736014 -280.973268)
			(xy 420.682864 -280.969284) (xy 420.630902 -280.957424) (xy 420.581288 -280.937952) (xy 420.53513 -280.911303)
			(xy 420.493459 -280.878072) (xy 420.457207 -280.839001) (xy 420.427183 -280.794964) (xy 420.404057 -280.746943)
			(xy 420.388347 -280.696013) (xy 420.380404 -280.643309) (xy 405.54656 -280.643309) (xy 405.54656 -281.493193)
			(xy 424.480472 -281.493193) (xy 424.480472 -281.439895) (xy 424.488415 -281.387191) (xy 424.504125 -281.336261)
			(xy 424.527251 -281.28824) (xy 424.557275 -281.244203) (xy 424.593527 -281.205132) (xy 424.635198 -281.171901)
			(xy 424.681356 -281.145252) (xy 424.73097 -281.12578) (xy 424.782932 -281.11392) (xy 424.836082 -281.109937)
			(xy 424.889232 -281.11392) (xy 424.941194 -281.12578) (xy 424.990808 -281.145252) (xy 425.036966 -281.171901)
			(xy 425.078637 -281.205132) (xy 425.114889 -281.244203) (xy 425.144913 -281.28824) (xy 425.168039 -281.336261)
			(xy 425.183749 -281.387191) (xy 425.191692 -281.439895) (xy 425.19219 -281.466544) (xy 425.191692 -281.493193)
			(xy 425.191654 -281.493447) (xy 439.526162 -281.493447) (xy 439.526162 -281.440149) (xy 439.534105 -281.387445)
			(xy 439.549815 -281.336515) (xy 439.572941 -281.288494) (xy 439.602965 -281.244457) (xy 439.639217 -281.205386)
			(xy 439.680888 -281.172155) (xy 439.727046 -281.145506) (xy 439.77666 -281.126034) (xy 439.828622 -281.114174)
			(xy 439.881772 -281.110191) (xy 439.934922 -281.114174) (xy 439.986884 -281.126034) (xy 440.036498 -281.145506)
			(xy 440.082656 -281.172155) (xy 440.124327 -281.205386) (xy 440.160579 -281.244457) (xy 440.190603 -281.288494)
			(xy 440.213729 -281.336515) (xy 440.229439 -281.387445) (xy 440.237382 -281.440149) (xy 440.23788 -281.466798)
			(xy 440.237382 -281.493447) (xy 440.229439 -281.546151) (xy 440.213729 -281.597081) (xy 440.190603 -281.645102)
			(xy 440.160579 -281.689139) (xy 440.124327 -281.72821) (xy 440.082656 -281.761441) (xy 440.036498 -281.78809)
			(xy 439.986884 -281.807562) (xy 439.934922 -281.819422) (xy 439.881772 -281.823406) (xy 439.828622 -281.819422)
			(xy 439.77666 -281.807562) (xy 439.727046 -281.78809) (xy 439.680888 -281.761441) (xy 439.639217 -281.72821)
			(xy 439.602965 -281.689139) (xy 439.572941 -281.645102) (xy 439.549815 -281.597081) (xy 439.534105 -281.546151)
			(xy 439.526162 -281.493447) (xy 425.191654 -281.493447) (xy 425.183749 -281.545897) (xy 425.168039 -281.596827)
			(xy 425.144913 -281.644848) (xy 425.114889 -281.688885) (xy 425.078637 -281.727956) (xy 425.036966 -281.761187)
			(xy 424.990808 -281.787836) (xy 424.941194 -281.807308) (xy 424.889232 -281.819168) (xy 424.836082 -281.823152)
			(xy 424.782932 -281.819168) (xy 424.73097 -281.807308) (xy 424.681356 -281.787836) (xy 424.635198 -281.761187)
			(xy 424.593527 -281.727956) (xy 424.557275 -281.688885) (xy 424.527251 -281.644848) (xy 424.504125 -281.596827)
			(xy 424.488415 -281.545897) (xy 424.480472 -281.493193) (xy 405.54656 -281.493193) (xy 405.54656 -282.343331)
			(xy 420.380404 -282.343331) (xy 420.380404 -282.290033) (xy 420.388347 -282.237329) (xy 420.404057 -282.186399)
			(xy 420.427183 -282.138378) (xy 420.457207 -282.094341) (xy 420.493459 -282.05527) (xy 420.53513 -282.022039)
			(xy 420.581288 -281.99539) (xy 420.630902 -281.975918) (xy 420.682864 -281.964058) (xy 420.736014 -281.960075)
			(xy 420.789164 -281.964058) (xy 420.841126 -281.975918) (xy 420.89074 -281.99539) (xy 420.936898 -282.022039)
			(xy 420.978569 -282.05527) (xy 421.014821 -282.094341) (xy 421.044845 -282.138378) (xy 421.067971 -282.186399)
			(xy 421.083681 -282.237329) (xy 421.091624 -282.290033) (xy 421.092122 -282.316682) (xy 421.091624 -282.343331)
			(xy 435.468004 -282.343331) (xy 435.468004 -282.290033) (xy 435.475947 -282.237329) (xy 435.491657 -282.186399)
			(xy 435.514783 -282.138378) (xy 435.544807 -282.094341) (xy 435.581059 -282.05527) (xy 435.62273 -282.022039)
			(xy 435.668888 -281.99539) (xy 435.718502 -281.975918) (xy 435.770464 -281.964058) (xy 435.823614 -281.960075)
			(xy 435.876764 -281.964058) (xy 435.928726 -281.975918) (xy 435.97834 -281.99539) (xy 436.024498 -282.022039)
			(xy 436.066169 -282.05527) (xy 436.102421 -282.094341) (xy 436.132445 -282.138378) (xy 436.155571 -282.186399)
			(xy 436.171281 -282.237329) (xy 436.179224 -282.290033) (xy 436.179722 -282.316682) (xy 436.179224 -282.343331)
			(xy 436.171281 -282.396035) (xy 436.155571 -282.446965) (xy 436.132445 -282.494986) (xy 436.102421 -282.539023)
			(xy 436.066169 -282.578094) (xy 436.024498 -282.611325) (xy 435.97834 -282.637974) (xy 435.928726 -282.657446)
			(xy 435.876764 -282.669306) (xy 435.823614 -282.67329) (xy 435.770464 -282.669306) (xy 435.718502 -282.657446)
			(xy 435.668888 -282.637974) (xy 435.62273 -282.611325) (xy 435.581059 -282.578094) (xy 435.544807 -282.539023)
			(xy 435.514783 -282.494986) (xy 435.491657 -282.446965) (xy 435.475947 -282.396035) (xy 435.468004 -282.343331)
			(xy 421.091624 -282.343331) (xy 421.083681 -282.396035) (xy 421.067971 -282.446965) (xy 421.044845 -282.494986)
			(xy 421.014821 -282.539023) (xy 420.978569 -282.578094) (xy 420.936898 -282.611325) (xy 420.89074 -282.637974)
			(xy 420.841126 -282.657446) (xy 420.789164 -282.669306) (xy 420.736014 -282.67329) (xy 420.682864 -282.669306)
			(xy 420.630902 -282.657446) (xy 420.581288 -282.637974) (xy 420.53513 -282.611325) (xy 420.493459 -282.578094)
			(xy 420.457207 -282.539023) (xy 420.427183 -282.494986) (xy 420.404057 -282.446965) (xy 420.388347 -282.396035)
			(xy 420.380404 -282.343331) (xy 405.54656 -282.343331) (xy 405.54656 -282.850082) (xy 405.57704 -282.86329)
			(xy 405.600332 -282.873938) (xy 405.643591 -282.901348) (xy 405.682107 -282.9351) (xy 405.71496 -282.974385)
			(xy 405.741365 -283.018265) (xy 405.760691 -283.06569) (xy 405.772475 -283.115528) (xy 405.776436 -283.166586)
			(xy 405.774372 -283.193215) (xy 424.480472 -283.193215) (xy 424.480472 -283.139917) (xy 424.488415 -283.087213)
			(xy 424.504125 -283.036283) (xy 424.527251 -282.988262) (xy 424.557275 -282.944225) (xy 424.593527 -282.905154)
			(xy 424.635198 -282.871923) (xy 424.681356 -282.845274) (xy 424.73097 -282.825802) (xy 424.782932 -282.813942)
			(xy 424.836082 -282.809959) (xy 424.889232 -282.813942) (xy 424.941194 -282.825802) (xy 424.990808 -282.845274)
			(xy 425.036966 -282.871923) (xy 425.078637 -282.905154) (xy 425.114889 -282.944225) (xy 425.144913 -282.988262)
			(xy 425.168039 -283.036283) (xy 425.183749 -283.087213) (xy 425.191692 -283.139917) (xy 425.19219 -283.166566)
			(xy 425.191692 -283.193215) (xy 439.568072 -283.193215) (xy 439.568072 -283.139917) (xy 439.576015 -283.087213)
			(xy 439.591725 -283.036283) (xy 439.614851 -282.988262) (xy 439.644875 -282.944225) (xy 439.681127 -282.905154)
			(xy 439.722798 -282.871923) (xy 439.768956 -282.845274) (xy 439.81857 -282.825802) (xy 439.870532 -282.813942)
			(xy 439.923682 -282.809959) (xy 439.976832 -282.813942) (xy 440.028794 -282.825802) (xy 440.078408 -282.845274)
			(xy 440.124566 -282.871923) (xy 440.166237 -282.905154) (xy 440.202489 -282.944225) (xy 440.232513 -282.988262)
			(xy 440.255639 -283.036283) (xy 440.271349 -283.087213) (xy 440.279292 -283.139917) (xy 440.27979 -283.166566)
			(xy 440.279292 -283.193215) (xy 440.271349 -283.245919) (xy 440.255639 -283.296849) (xy 440.232513 -283.34487)
			(xy 440.202489 -283.388907) (xy 440.166237 -283.427978) (xy 440.124566 -283.461209) (xy 440.078408 -283.487858)
			(xy 440.028794 -283.50733) (xy 439.976832 -283.51919) (xy 439.923682 -283.523174) (xy 439.870532 -283.51919)
			(xy 439.81857 -283.50733) (xy 439.768956 -283.487858) (xy 439.722798 -283.461209) (xy 439.681127 -283.427978)
			(xy 439.644875 -283.388907) (xy 439.614851 -283.34487) (xy 439.591725 -283.296849) (xy 439.576015 -283.245919)
			(xy 439.568072 -283.193215) (xy 425.191692 -283.193215) (xy 425.183749 -283.245919) (xy 425.168039 -283.296849)
			(xy 425.144913 -283.34487) (xy 425.114889 -283.388907) (xy 425.078637 -283.427978) (xy 425.036966 -283.461209)
			(xy 424.990808 -283.487858) (xy 424.941194 -283.50733) (xy 424.889232 -283.51919) (xy 424.836082 -283.523174)
			(xy 424.782932 -283.51919) (xy 424.73097 -283.50733) (xy 424.681356 -283.487858) (xy 424.635198 -283.461209)
			(xy 424.593527 -283.427978) (xy 424.557275 -283.388907) (xy 424.527251 -283.34487) (xy 424.504125 -283.296849)
			(xy 424.488415 -283.245919) (xy 424.480472 -283.193215) (xy 405.774372 -283.193215) (xy 405.772479 -283.217645)
			(xy 405.760699 -283.267484) (xy 405.741378 -283.314911) (xy 405.714976 -283.358793) (xy 405.682126 -283.398081)
			(xy 405.643613 -283.431835) (xy 405.600356 -283.45925) (xy 405.57704 -283.469842) (xy 405.54656 -283.48305)
			(xy 405.54656 -284.043353) (xy 420.380404 -284.043353) (xy 420.380404 -283.990055) (xy 420.388347 -283.937351)
			(xy 420.404057 -283.886421) (xy 420.427183 -283.8384) (xy 420.457207 -283.794363) (xy 420.493459 -283.755292)
			(xy 420.53513 -283.722061) (xy 420.581288 -283.695412) (xy 420.630902 -283.67594) (xy 420.682864 -283.66408)
			(xy 420.736014 -283.660097) (xy 420.789164 -283.66408) (xy 420.841126 -283.67594) (xy 420.89074 -283.695412)
			(xy 420.936898 -283.722061) (xy 420.978569 -283.755292) (xy 421.014821 -283.794363) (xy 421.044845 -283.8384)
			(xy 421.067971 -283.886421) (xy 421.083681 -283.937351) (xy 421.091624 -283.990055) (xy 421.092122 -284.016704)
			(xy 421.091624 -284.043353) (xy 424.480472 -284.043353) (xy 424.480472 -283.990055) (xy 424.488415 -283.937351)
			(xy 424.504125 -283.886421) (xy 424.527251 -283.8384) (xy 424.557275 -283.794363) (xy 424.593527 -283.755292)
			(xy 424.635198 -283.722061) (xy 424.681356 -283.695412) (xy 424.73097 -283.67594) (xy 424.782932 -283.66408)
			(xy 424.836082 -283.660097) (xy 424.889232 -283.66408) (xy 424.941194 -283.67594) (xy 424.990808 -283.695412)
			(xy 425.036966 -283.722061) (xy 425.078637 -283.755292) (xy 425.114889 -283.794363) (xy 425.144913 -283.8384)
			(xy 425.168039 -283.886421) (xy 425.183749 -283.937351) (xy 425.191692 -283.990055) (xy 425.19219 -284.016704)
			(xy 425.191692 -284.043353) (xy 435.468004 -284.043353) (xy 435.468004 -283.990055) (xy 435.475947 -283.937351)
			(xy 435.491657 -283.886421) (xy 435.514783 -283.8384) (xy 435.544807 -283.794363) (xy 435.581059 -283.755292)
			(xy 435.62273 -283.722061) (xy 435.668888 -283.695412) (xy 435.718502 -283.67594) (xy 435.770464 -283.66408)
			(xy 435.823614 -283.660097) (xy 435.876764 -283.66408) (xy 435.928726 -283.67594) (xy 435.97834 -283.695412)
			(xy 436.024498 -283.722061) (xy 436.066169 -283.755292) (xy 436.102421 -283.794363) (xy 436.132445 -283.8384)
			(xy 436.155571 -283.886421) (xy 436.171281 -283.937351) (xy 436.179224 -283.990055) (xy 436.179722 -284.016704)
			(xy 436.179224 -284.043353) (xy 439.568072 -284.043353) (xy 439.568072 -283.990055) (xy 439.576015 -283.937351)
			(xy 439.591725 -283.886421) (xy 439.614851 -283.8384) (xy 439.644875 -283.794363) (xy 439.681127 -283.755292)
			(xy 439.722798 -283.722061) (xy 439.768956 -283.695412) (xy 439.81857 -283.67594) (xy 439.870532 -283.66408)
			(xy 439.923682 -283.660097) (xy 439.976832 -283.66408) (xy 440.028794 -283.67594) (xy 440.078408 -283.695412)
			(xy 440.124566 -283.722061) (xy 440.166237 -283.755292) (xy 440.202489 -283.794363) (xy 440.232513 -283.8384)
			(xy 440.255639 -283.886421) (xy 440.271349 -283.937351) (xy 440.279292 -283.990055) (xy 440.27979 -284.016704)
			(xy 440.279292 -284.043353) (xy 440.271349 -284.096057) (xy 440.255639 -284.146987) (xy 440.232513 -284.195008)
			(xy 440.202489 -284.239045) (xy 440.166237 -284.278116) (xy 440.124566 -284.311347) (xy 440.078408 -284.337996)
			(xy 440.028794 -284.357468) (xy 439.976832 -284.369328) (xy 439.923682 -284.373312) (xy 439.870532 -284.369328)
			(xy 439.81857 -284.357468) (xy 439.768956 -284.337996) (xy 439.722798 -284.311347) (xy 439.681127 -284.278116)
			(xy 439.644875 -284.239045) (xy 439.614851 -284.195008) (xy 439.591725 -284.146987) (xy 439.576015 -284.096057)
			(xy 439.568072 -284.043353) (xy 436.179224 -284.043353) (xy 436.171281 -284.096057) (xy 436.155571 -284.146987)
			(xy 436.132445 -284.195008) (xy 436.102421 -284.239045) (xy 436.066169 -284.278116) (xy 436.024498 -284.311347)
			(xy 435.97834 -284.337996) (xy 435.928726 -284.357468) (xy 435.876764 -284.369328) (xy 435.823614 -284.373312)
			(xy 435.770464 -284.369328) (xy 435.718502 -284.357468) (xy 435.668888 -284.337996) (xy 435.62273 -284.311347)
			(xy 435.581059 -284.278116) (xy 435.544807 -284.239045) (xy 435.514783 -284.195008) (xy 435.491657 -284.146987)
			(xy 435.475947 -284.096057) (xy 435.468004 -284.043353) (xy 425.191692 -284.043353) (xy 425.183749 -284.096057)
			(xy 425.168039 -284.146987) (xy 425.144913 -284.195008) (xy 425.114889 -284.239045) (xy 425.078637 -284.278116)
			(xy 425.036966 -284.311347) (xy 424.990808 -284.337996) (xy 424.941194 -284.357468) (xy 424.889232 -284.369328)
			(xy 424.836082 -284.373312) (xy 424.782932 -284.369328) (xy 424.73097 -284.357468) (xy 424.681356 -284.337996)
			(xy 424.635198 -284.311347) (xy 424.593527 -284.278116) (xy 424.557275 -284.239045) (xy 424.527251 -284.195008)
			(xy 424.504125 -284.146987) (xy 424.488415 -284.096057) (xy 424.480472 -284.043353) (xy 421.091624 -284.043353)
			(xy 421.083681 -284.096057) (xy 421.067971 -284.146987) (xy 421.044845 -284.195008) (xy 421.014821 -284.239045)
			(xy 420.978569 -284.278116) (xy 420.936898 -284.311347) (xy 420.89074 -284.337996) (xy 420.841126 -284.357468)
			(xy 420.789164 -284.369328) (xy 420.736014 -284.373312) (xy 420.682864 -284.369328) (xy 420.630902 -284.357468)
			(xy 420.581288 -284.337996) (xy 420.53513 -284.311347) (xy 420.493459 -284.278116) (xy 420.457207 -284.239045)
			(xy 420.427183 -284.195008) (xy 420.404057 -284.146987) (xy 420.388347 -284.096057) (xy 420.380404 -284.043353)
			(xy 405.54656 -284.043353) (xy 405.54656 -284.893237) (xy 420.380404 -284.893237) (xy 420.380404 -284.839939)
			(xy 420.388347 -284.787235) (xy 420.404057 -284.736305) (xy 420.427183 -284.688284) (xy 420.457207 -284.644247)
			(xy 420.493459 -284.605176) (xy 420.53513 -284.571945) (xy 420.581288 -284.545296) (xy 420.630902 -284.525824)
			(xy 420.682864 -284.513964) (xy 420.736014 -284.509981) (xy 420.789164 -284.513964) (xy 420.841126 -284.525824)
			(xy 420.89074 -284.545296) (xy 420.936898 -284.571945) (xy 420.978569 -284.605176) (xy 421.014821 -284.644247)
			(xy 421.044845 -284.688284) (xy 421.067971 -284.736305) (xy 421.083681 -284.787235) (xy 421.091624 -284.839939)
			(xy 421.092122 -284.866588) (xy 421.091624 -284.893237) (xy 435.468004 -284.893237) (xy 435.468004 -284.839939)
			(xy 435.475947 -284.787235) (xy 435.491657 -284.736305) (xy 435.514783 -284.688284) (xy 435.544807 -284.644247)
			(xy 435.581059 -284.605176) (xy 435.62273 -284.571945) (xy 435.668888 -284.545296) (xy 435.718502 -284.525824)
			(xy 435.770464 -284.513964) (xy 435.823614 -284.509981) (xy 435.876764 -284.513964) (xy 435.928726 -284.525824)
			(xy 435.97834 -284.545296) (xy 436.024498 -284.571945) (xy 436.066169 -284.605176) (xy 436.102421 -284.644247)
			(xy 436.132445 -284.688284) (xy 436.155571 -284.736305) (xy 436.171281 -284.787235) (xy 436.179224 -284.839939)
			(xy 436.179722 -284.866588) (xy 436.179224 -284.893237) (xy 436.171281 -284.945941) (xy 436.155571 -284.996871)
			(xy 436.132445 -285.044892) (xy 436.102421 -285.088929) (xy 436.066169 -285.128) (xy 436.024498 -285.161231)
			(xy 435.97834 -285.18788) (xy 435.928726 -285.207352) (xy 435.876764 -285.219212) (xy 435.823614 -285.223196)
			(xy 435.770464 -285.219212) (xy 435.718502 -285.207352) (xy 435.668888 -285.18788) (xy 435.62273 -285.161231)
			(xy 435.581059 -285.128) (xy 435.544807 -285.088929) (xy 435.514783 -285.044892) (xy 435.491657 -284.996871)
			(xy 435.475947 -284.945941) (xy 435.468004 -284.893237) (xy 421.091624 -284.893237) (xy 421.083681 -284.945941)
			(xy 421.067971 -284.996871) (xy 421.044845 -285.044892) (xy 421.014821 -285.088929) (xy 420.978569 -285.128)
			(xy 420.936898 -285.161231) (xy 420.89074 -285.18788) (xy 420.841126 -285.207352) (xy 420.789164 -285.219212)
			(xy 420.736014 -285.223196) (xy 420.682864 -285.219212) (xy 420.630902 -285.207352) (xy 420.581288 -285.18788)
			(xy 420.53513 -285.161231) (xy 420.493459 -285.128) (xy 420.457207 -285.088929) (xy 420.427183 -285.044892)
			(xy 420.404057 -284.996871) (xy 420.388347 -284.945941) (xy 420.380404 -284.893237) (xy 405.54656 -284.893237)
			(xy 405.54656 -285.410656) (xy 405.586184 -285.419546) (xy 405.611715 -285.425779) (xy 405.660536 -285.445226)
			(xy 405.705665 -285.472152) (xy 405.745965 -285.505881) (xy 405.78042 -285.545561) (xy 405.808163 -285.590194)
			(xy 405.828493 -285.638653) (xy 405.8409 -285.68972) (xy 405.84507 -285.742106) (xy 405.844969 -285.743375)
			(xy 424.480472 -285.743375) (xy 424.480472 -285.690077) (xy 424.488415 -285.637373) (xy 424.504125 -285.586443)
			(xy 424.527251 -285.538422) (xy 424.557275 -285.494385) (xy 424.593527 -285.455314) (xy 424.635198 -285.422083)
			(xy 424.681356 -285.395434) (xy 424.73097 -285.375962) (xy 424.782932 -285.364102) (xy 424.836082 -285.360119)
			(xy 424.889232 -285.364102) (xy 424.941194 -285.375962) (xy 424.990808 -285.395434) (xy 425.036966 -285.422083)
			(xy 425.078637 -285.455314) (xy 425.114889 -285.494385) (xy 425.144913 -285.538422) (xy 425.168039 -285.586443)
			(xy 425.183749 -285.637373) (xy 425.191692 -285.690077) (xy 425.19219 -285.716726) (xy 425.191692 -285.743375)
			(xy 439.568072 -285.743375) (xy 439.568072 -285.690077) (xy 439.576015 -285.637373) (xy 439.591725 -285.586443)
			(xy 439.614851 -285.538422) (xy 439.644875 -285.494385) (xy 439.681127 -285.455314) (xy 439.722798 -285.422083)
			(xy 439.768956 -285.395434) (xy 439.81857 -285.375962) (xy 439.870532 -285.364102) (xy 439.923682 -285.360119)
			(xy 439.976832 -285.364102) (xy 440.028794 -285.375962) (xy 440.078408 -285.395434) (xy 440.124566 -285.422083)
			(xy 440.166237 -285.455314) (xy 440.202489 -285.494385) (xy 440.232513 -285.538422) (xy 440.255639 -285.586443)
			(xy 440.271349 -285.637373) (xy 440.279292 -285.690077) (xy 440.27979 -285.716726) (xy 440.279292 -285.743375)
			(xy 440.271349 -285.796079) (xy 440.255639 -285.847009) (xy 440.232513 -285.89503) (xy 440.202489 -285.939067)
			(xy 440.166237 -285.978138) (xy 440.124566 -286.011369) (xy 440.078408 -286.038018) (xy 440.028794 -286.05749)
			(xy 439.976832 -286.06935) (xy 439.923682 -286.073334) (xy 439.870532 -286.06935) (xy 439.81857 -286.05749)
			(xy 439.768956 -286.038018) (xy 439.722798 -286.011369) (xy 439.681127 -285.978138) (xy 439.644875 -285.939067)
			(xy 439.614851 -285.89503) (xy 439.591725 -285.847009) (xy 439.576015 -285.796079) (xy 439.568072 -285.743375)
			(xy 425.191692 -285.743375) (xy 425.183749 -285.796079) (xy 425.168039 -285.847009) (xy 425.144913 -285.89503)
			(xy 425.114889 -285.939067) (xy 425.078637 -285.978138) (xy 425.036966 -286.011369) (xy 424.990808 -286.038018)
			(xy 424.941194 -286.05749) (xy 424.889232 -286.06935) (xy 424.836082 -286.073334) (xy 424.782932 -286.06935)
			(xy 424.73097 -286.05749) (xy 424.681356 -286.038018) (xy 424.635198 -286.011369) (xy 424.593527 -285.978138)
			(xy 424.557275 -285.939067) (xy 424.527251 -285.89503) (xy 424.504125 -285.847009) (xy 424.488415 -285.796079)
			(xy 424.480472 -285.743375) (xy 405.844969 -285.743375) (xy 405.840898 -285.794492) (xy 405.82849 -285.845557)
			(xy 405.808157 -285.894017) (xy 405.780413 -285.938648) (xy 405.745957 -285.978327) (xy 405.705656 -286.012054)
			(xy 405.660526 -286.038979) (xy 405.611704 -286.058424) (xy 405.586184 -286.064706) (xy 405.54656 -286.073596)
			(xy 405.54656 -286.593259) (xy 420.380404 -286.593259) (xy 420.380404 -286.539961) (xy 420.388347 -286.487257)
			(xy 420.404057 -286.436327) (xy 420.427183 -286.388306) (xy 420.457207 -286.344269) (xy 420.493459 -286.305198)
			(xy 420.53513 -286.271967) (xy 420.581288 -286.245318) (xy 420.630902 -286.225846) (xy 420.682864 -286.213986)
			(xy 420.736014 -286.210003) (xy 420.789164 -286.213986) (xy 420.841126 -286.225846) (xy 420.89074 -286.245318)
			(xy 420.936898 -286.271967) (xy 420.978569 -286.305198) (xy 421.014821 -286.344269) (xy 421.044845 -286.388306)
			(xy 421.067971 -286.436327) (xy 421.083681 -286.487257) (xy 421.091624 -286.539961) (xy 421.092122 -286.56661)
			(xy 421.091624 -286.593259) (xy 435.468004 -286.593259) (xy 435.468004 -286.539961) (xy 435.475947 -286.487257)
			(xy 435.491657 -286.436327) (xy 435.514783 -286.388306) (xy 435.544807 -286.344269) (xy 435.581059 -286.305198)
			(xy 435.62273 -286.271967) (xy 435.668888 -286.245318) (xy 435.718502 -286.225846) (xy 435.770464 -286.213986)
			(xy 435.823614 -286.210003) (xy 435.876764 -286.213986) (xy 435.928726 -286.225846) (xy 435.97834 -286.245318)
			(xy 436.024498 -286.271967) (xy 436.066169 -286.305198) (xy 436.102421 -286.344269) (xy 436.132445 -286.388306)
			(xy 436.155571 -286.436327) (xy 436.171281 -286.487257) (xy 436.179224 -286.539961) (xy 436.179722 -286.56661)
			(xy 436.179224 -286.593259) (xy 436.171281 -286.645963) (xy 436.155571 -286.696893) (xy 436.132445 -286.744914)
			(xy 436.102421 -286.788951) (xy 436.066169 -286.828022) (xy 436.024498 -286.861253) (xy 435.97834 -286.887902)
			(xy 435.928726 -286.907374) (xy 435.876764 -286.919234) (xy 435.823614 -286.923218) (xy 435.770464 -286.919234)
			(xy 435.718502 -286.907374) (xy 435.668888 -286.887902) (xy 435.62273 -286.861253) (xy 435.581059 -286.828022)
			(xy 435.544807 -286.788951) (xy 435.514783 -286.744914) (xy 435.491657 -286.696893) (xy 435.475947 -286.645963)
			(xy 435.468004 -286.593259) (xy 421.091624 -286.593259) (xy 421.083681 -286.645963) (xy 421.067971 -286.696893)
			(xy 421.044845 -286.744914) (xy 421.014821 -286.788951) (xy 420.978569 -286.828022) (xy 420.936898 -286.861253)
			(xy 420.89074 -286.887902) (xy 420.841126 -286.907374) (xy 420.789164 -286.919234) (xy 420.736014 -286.923218)
			(xy 420.682864 -286.919234) (xy 420.630902 -286.907374) (xy 420.581288 -286.887902) (xy 420.53513 -286.861253)
			(xy 420.493459 -286.828022) (xy 420.457207 -286.788951) (xy 420.427183 -286.744914) (xy 420.404057 -286.696893)
			(xy 420.388347 -286.645963) (xy 420.380404 -286.593259) (xy 405.54656 -286.593259) (xy 405.54656 -287.443397)
			(xy 424.480472 -287.443397) (xy 424.480472 -287.390099) (xy 424.488415 -287.337395) (xy 424.504125 -287.286465)
			(xy 424.527251 -287.238444) (xy 424.557275 -287.194407) (xy 424.593527 -287.155336) (xy 424.635198 -287.122105)
			(xy 424.681356 -287.095456) (xy 424.73097 -287.075984) (xy 424.782932 -287.064124) (xy 424.836082 -287.060141)
			(xy 424.889232 -287.064124) (xy 424.941194 -287.075984) (xy 424.990808 -287.095456) (xy 425.036966 -287.122105)
			(xy 425.078637 -287.155336) (xy 425.114889 -287.194407) (xy 425.144913 -287.238444) (xy 425.168039 -287.286465)
			(xy 425.183749 -287.337395) (xy 425.191692 -287.390099) (xy 425.19219 -287.416748) (xy 425.191692 -287.443397)
			(xy 439.568072 -287.443397) (xy 439.568072 -287.390099) (xy 439.576015 -287.337395) (xy 439.591725 -287.286465)
			(xy 439.614851 -287.238444) (xy 439.644875 -287.194407) (xy 439.681127 -287.155336) (xy 439.722798 -287.122105)
			(xy 439.768956 -287.095456) (xy 439.81857 -287.075984) (xy 439.870532 -287.064124) (xy 439.923682 -287.060141)
			(xy 439.976832 -287.064124) (xy 440.028794 -287.075984) (xy 440.078408 -287.095456) (xy 440.124566 -287.122105)
			(xy 440.166237 -287.155336) (xy 440.202489 -287.194407) (xy 440.232513 -287.238444) (xy 440.255639 -287.286465)
			(xy 440.271349 -287.337395) (xy 440.279292 -287.390099) (xy 440.27979 -287.416748) (xy 440.279292 -287.443397)
			(xy 440.271349 -287.496101) (xy 440.255639 -287.547031) (xy 440.232513 -287.595052) (xy 440.202489 -287.639089)
			(xy 440.166237 -287.67816) (xy 440.124566 -287.711391) (xy 440.078408 -287.73804) (xy 440.028794 -287.757512)
			(xy 439.976832 -287.769372) (xy 439.923682 -287.773356) (xy 439.870532 -287.769372) (xy 439.81857 -287.757512)
			(xy 439.768956 -287.73804) (xy 439.722798 -287.711391) (xy 439.681127 -287.67816) (xy 439.644875 -287.639089)
			(xy 439.614851 -287.595052) (xy 439.591725 -287.547031) (xy 439.576015 -287.496101) (xy 439.568072 -287.443397)
			(xy 425.191692 -287.443397) (xy 425.183749 -287.496101) (xy 425.168039 -287.547031) (xy 425.144913 -287.595052)
			(xy 425.114889 -287.639089) (xy 425.078637 -287.67816) (xy 425.036966 -287.711391) (xy 424.990808 -287.73804)
			(xy 424.941194 -287.757512) (xy 424.889232 -287.769372) (xy 424.836082 -287.773356) (xy 424.782932 -287.769372)
			(xy 424.73097 -287.757512) (xy 424.681356 -287.73804) (xy 424.635198 -287.711391) (xy 424.593527 -287.67816)
			(xy 424.557275 -287.639089) (xy 424.527251 -287.595052) (xy 424.504125 -287.547031) (xy 424.488415 -287.496101)
			(xy 424.480472 -287.443397) (xy 405.54656 -287.443397) (xy 405.54656 -288.293281) (xy 420.380404 -288.293281)
			(xy 420.380404 -288.239983) (xy 420.388347 -288.187279) (xy 420.404057 -288.136349) (xy 420.427183 -288.088328)
			(xy 420.457207 -288.044291) (xy 420.493459 -288.00522) (xy 420.53513 -287.971989) (xy 420.581288 -287.94534)
			(xy 420.630902 -287.925868) (xy 420.682864 -287.914008) (xy 420.736014 -287.910025) (xy 420.789164 -287.914008)
			(xy 420.841126 -287.925868) (xy 420.89074 -287.94534) (xy 420.936898 -287.971989) (xy 420.978569 -288.00522)
			(xy 421.014821 -288.044291) (xy 421.044845 -288.088328) (xy 421.067971 -288.136349) (xy 421.083681 -288.187279)
			(xy 421.091624 -288.239983) (xy 421.092122 -288.266632) (xy 421.091624 -288.293281) (xy 435.468004 -288.293281)
			(xy 435.468004 -288.239983) (xy 435.475947 -288.187279) (xy 435.491657 -288.136349) (xy 435.514783 -288.088328)
			(xy 435.544807 -288.044291) (xy 435.581059 -288.00522) (xy 435.62273 -287.971989) (xy 435.668888 -287.94534)
			(xy 435.718502 -287.925868) (xy 435.770464 -287.914008) (xy 435.823614 -287.910025) (xy 435.876764 -287.914008)
			(xy 435.928726 -287.925868) (xy 435.97834 -287.94534) (xy 436.024498 -287.971989) (xy 436.066169 -288.00522)
			(xy 436.102421 -288.044291) (xy 436.132445 -288.088328) (xy 436.155571 -288.136349) (xy 436.171281 -288.187279)
			(xy 436.179224 -288.239983) (xy 436.179722 -288.266632) (xy 436.179224 -288.293281) (xy 436.171281 -288.345985)
			(xy 436.155571 -288.396915) (xy 436.132445 -288.444936) (xy 436.102421 -288.488973) (xy 436.066169 -288.528044)
			(xy 436.024498 -288.561275) (xy 435.97834 -288.587924) (xy 435.928726 -288.607396) (xy 435.876764 -288.619256)
			(xy 435.823614 -288.62324) (xy 435.770464 -288.619256) (xy 435.718502 -288.607396) (xy 435.668888 -288.587924)
			(xy 435.62273 -288.561275) (xy 435.581059 -288.528044) (xy 435.544807 -288.488973) (xy 435.514783 -288.444936)
			(xy 435.491657 -288.396915) (xy 435.475947 -288.345985) (xy 435.468004 -288.293281) (xy 421.091624 -288.293281)
			(xy 421.083681 -288.345985) (xy 421.067971 -288.396915) (xy 421.044845 -288.444936) (xy 421.014821 -288.488973)
			(xy 420.978569 -288.528044) (xy 420.936898 -288.561275) (xy 420.89074 -288.587924) (xy 420.841126 -288.607396)
			(xy 420.789164 -288.619256) (xy 420.736014 -288.62324) (xy 420.682864 -288.619256) (xy 420.630902 -288.607396)
			(xy 420.581288 -288.587924) (xy 420.53513 -288.561275) (xy 420.493459 -288.528044) (xy 420.457207 -288.488973)
			(xy 420.427183 -288.444936) (xy 420.404057 -288.396915) (xy 420.388347 -288.345985) (xy 420.380404 -288.293281)
			(xy 405.54656 -288.293281) (xy 405.54656 -289.143419) (xy 424.480472 -289.143419) (xy 424.480472 -289.090121)
			(xy 424.488415 -289.037417) (xy 424.504125 -288.986487) (xy 424.527251 -288.938466) (xy 424.557275 -288.894429)
			(xy 424.593527 -288.855358) (xy 424.635198 -288.822127) (xy 424.681356 -288.795478) (xy 424.73097 -288.776006)
			(xy 424.782932 -288.764146) (xy 424.836082 -288.760163) (xy 424.889232 -288.764146) (xy 424.941194 -288.776006)
			(xy 424.990808 -288.795478) (xy 425.036966 -288.822127) (xy 425.078637 -288.855358) (xy 425.114889 -288.894429)
			(xy 425.144913 -288.938466) (xy 425.168039 -288.986487) (xy 425.183749 -289.037417) (xy 425.191692 -289.090121)
			(xy 425.19219 -289.11677) (xy 425.191692 -289.143419) (xy 439.568072 -289.143419) (xy 439.568072 -289.090121)
			(xy 439.576015 -289.037417) (xy 439.591725 -288.986487) (xy 439.614851 -288.938466) (xy 439.644875 -288.894429)
			(xy 439.681127 -288.855358) (xy 439.722798 -288.822127) (xy 439.768956 -288.795478) (xy 439.81857 -288.776006)
			(xy 439.870532 -288.764146) (xy 439.923682 -288.760163) (xy 439.976832 -288.764146) (xy 440.028794 -288.776006)
			(xy 440.078408 -288.795478) (xy 440.124566 -288.822127) (xy 440.166237 -288.855358) (xy 440.202489 -288.894429)
			(xy 440.232513 -288.938466) (xy 440.255639 -288.986487) (xy 440.271349 -289.037417) (xy 440.279292 -289.090121)
			(xy 440.27979 -289.11677) (xy 440.279292 -289.143419) (xy 440.271349 -289.196123) (xy 440.255639 -289.247053)
			(xy 440.232513 -289.295074) (xy 440.202489 -289.339111) (xy 440.166237 -289.378182) (xy 440.124566 -289.411413)
			(xy 440.078408 -289.438062) (xy 440.028794 -289.457534) (xy 439.976832 -289.469394) (xy 439.923682 -289.473378)
			(xy 439.870532 -289.469394) (xy 439.81857 -289.457534) (xy 439.768956 -289.438062) (xy 439.722798 -289.411413)
			(xy 439.681127 -289.378182) (xy 439.644875 -289.339111) (xy 439.614851 -289.295074) (xy 439.591725 -289.247053)
			(xy 439.576015 -289.196123) (xy 439.568072 -289.143419) (xy 425.191692 -289.143419) (xy 425.183749 -289.196123)
			(xy 425.168039 -289.247053) (xy 425.144913 -289.295074) (xy 425.114889 -289.339111) (xy 425.078637 -289.378182)
			(xy 425.036966 -289.411413) (xy 424.990808 -289.438062) (xy 424.941194 -289.457534) (xy 424.889232 -289.469394)
			(xy 424.836082 -289.473378) (xy 424.782932 -289.469394) (xy 424.73097 -289.457534) (xy 424.681356 -289.438062)
			(xy 424.635198 -289.411413) (xy 424.593527 -289.378182) (xy 424.557275 -289.339111) (xy 424.527251 -289.295074)
			(xy 424.504125 -289.247053) (xy 424.488415 -289.196123) (xy 424.480472 -289.143419) (xy 405.54656 -289.143419)
			(xy 405.54656 -289.993303) (xy 420.380404 -289.993303) (xy 420.380404 -289.940005) (xy 420.388347 -289.887301)
			(xy 420.404057 -289.836371) (xy 420.427183 -289.78835) (xy 420.457207 -289.744313) (xy 420.493459 -289.705242)
			(xy 420.53513 -289.672011) (xy 420.581288 -289.645362) (xy 420.630902 -289.62589) (xy 420.682864 -289.61403)
			(xy 420.736014 -289.610047) (xy 420.789164 -289.61403) (xy 420.841126 -289.62589) (xy 420.89074 -289.645362)
			(xy 420.936898 -289.672011) (xy 420.978569 -289.705242) (xy 421.014821 -289.744313) (xy 421.044845 -289.78835)
			(xy 421.067971 -289.836371) (xy 421.083681 -289.887301) (xy 421.091624 -289.940005) (xy 421.092122 -289.966654)
			(xy 421.091624 -289.993303) (xy 435.468004 -289.993303) (xy 435.468004 -289.940005) (xy 435.475947 -289.887301)
			(xy 435.491657 -289.836371) (xy 435.514783 -289.78835) (xy 435.544807 -289.744313) (xy 435.581059 -289.705242)
			(xy 435.62273 -289.672011) (xy 435.668888 -289.645362) (xy 435.718502 -289.62589) (xy 435.770464 -289.61403)
			(xy 435.823614 -289.610047) (xy 435.876764 -289.61403) (xy 435.928726 -289.62589) (xy 435.97834 -289.645362)
			(xy 436.024498 -289.672011) (xy 436.066169 -289.705242) (xy 436.102421 -289.744313) (xy 436.132445 -289.78835)
			(xy 436.155571 -289.836371) (xy 436.171281 -289.887301) (xy 436.179224 -289.940005) (xy 436.179722 -289.966654)
			(xy 436.179224 -289.993303) (xy 436.171281 -290.046007) (xy 436.155571 -290.096937) (xy 436.132445 -290.144958)
			(xy 436.102421 -290.188995) (xy 436.066169 -290.228066) (xy 436.024498 -290.261297) (xy 435.97834 -290.287946)
			(xy 435.928726 -290.307418) (xy 435.876764 -290.319278) (xy 435.823614 -290.323262) (xy 435.770464 -290.319278)
			(xy 435.718502 -290.307418) (xy 435.668888 -290.287946) (xy 435.62273 -290.261297) (xy 435.581059 -290.228066)
			(xy 435.544807 -290.188995) (xy 435.514783 -290.144958) (xy 435.491657 -290.096937) (xy 435.475947 -290.046007)
			(xy 435.468004 -289.993303) (xy 421.091624 -289.993303) (xy 421.083681 -290.046007) (xy 421.067971 -290.096937)
			(xy 421.044845 -290.144958) (xy 421.014821 -290.188995) (xy 420.978569 -290.228066) (xy 420.936898 -290.261297)
			(xy 420.89074 -290.287946) (xy 420.841126 -290.307418) (xy 420.789164 -290.319278) (xy 420.736014 -290.323262)
			(xy 420.682864 -290.319278) (xy 420.630902 -290.307418) (xy 420.581288 -290.287946) (xy 420.53513 -290.261297)
			(xy 420.493459 -290.228066) (xy 420.457207 -290.188995) (xy 420.427183 -290.144958) (xy 420.404057 -290.096937)
			(xy 420.388347 -290.046007) (xy 420.380404 -289.993303) (xy 405.54656 -289.993303) (xy 405.54656 -290.843187)
			(xy 424.480472 -290.843187) (xy 424.480472 -290.789889) (xy 424.488415 -290.737185) (xy 424.504125 -290.686255)
			(xy 424.527251 -290.638234) (xy 424.557275 -290.594197) (xy 424.593527 -290.555126) (xy 424.635198 -290.521895)
			(xy 424.681356 -290.495246) (xy 424.73097 -290.475774) (xy 424.782932 -290.463914) (xy 424.836082 -290.459931)
			(xy 424.889232 -290.463914) (xy 424.941194 -290.475774) (xy 424.990808 -290.495246) (xy 425.036966 -290.521895)
			(xy 425.078637 -290.555126) (xy 425.114889 -290.594197) (xy 425.144913 -290.638234) (xy 425.168039 -290.686255)
			(xy 425.183749 -290.737185) (xy 425.191692 -290.789889) (xy 425.19219 -290.816538) (xy 425.191692 -290.843187)
			(xy 439.568072 -290.843187) (xy 439.568072 -290.789889) (xy 439.576015 -290.737185) (xy 439.591725 -290.686255)
			(xy 439.614851 -290.638234) (xy 439.644875 -290.594197) (xy 439.681127 -290.555126) (xy 439.722798 -290.521895)
			(xy 439.768956 -290.495246) (xy 439.81857 -290.475774) (xy 439.870532 -290.463914) (xy 439.923682 -290.459931)
			(xy 439.976832 -290.463914) (xy 440.028794 -290.475774) (xy 440.078408 -290.495246) (xy 440.124566 -290.521895)
			(xy 440.166237 -290.555126) (xy 440.202489 -290.594197) (xy 440.232513 -290.638234) (xy 440.255639 -290.686255)
			(xy 440.271349 -290.737185) (xy 440.279292 -290.789889) (xy 440.27979 -290.816538) (xy 440.279292 -290.843187)
			(xy 440.271349 -290.895891) (xy 440.255639 -290.946821) (xy 440.232513 -290.994842) (xy 440.202489 -291.038879)
			(xy 440.166237 -291.07795) (xy 440.124566 -291.111181) (xy 440.078408 -291.13783) (xy 440.028794 -291.157302)
			(xy 439.976832 -291.169162) (xy 439.923682 -291.173146) (xy 439.870532 -291.169162) (xy 439.81857 -291.157302)
			(xy 439.768956 -291.13783) (xy 439.722798 -291.111181) (xy 439.681127 -291.07795) (xy 439.644875 -291.038879)
			(xy 439.614851 -290.994842) (xy 439.591725 -290.946821) (xy 439.576015 -290.895891) (xy 439.568072 -290.843187)
			(xy 425.191692 -290.843187) (xy 425.183749 -290.895891) (xy 425.168039 -290.946821) (xy 425.144913 -290.994842)
			(xy 425.114889 -291.038879) (xy 425.078637 -291.07795) (xy 425.036966 -291.111181) (xy 424.990808 -291.13783)
			(xy 424.941194 -291.157302) (xy 424.889232 -291.169162) (xy 424.836082 -291.173146) (xy 424.782932 -291.169162)
			(xy 424.73097 -291.157302) (xy 424.681356 -291.13783) (xy 424.635198 -291.111181) (xy 424.593527 -291.07795)
			(xy 424.557275 -291.038879) (xy 424.527251 -290.994842) (xy 424.504125 -290.946821) (xy 424.488415 -290.895891)
			(xy 424.480472 -290.843187) (xy 405.54656 -290.843187) (xy 405.54656 -291.693325) (xy 420.380404 -291.693325)
			(xy 420.380404 -291.640027) (xy 420.388347 -291.587323) (xy 420.404057 -291.536393) (xy 420.427183 -291.488372)
			(xy 420.457207 -291.444335) (xy 420.493459 -291.405264) (xy 420.53513 -291.372033) (xy 420.581288 -291.345384)
			(xy 420.630902 -291.325912) (xy 420.682864 -291.314052) (xy 420.736014 -291.310069) (xy 420.789164 -291.314052)
			(xy 420.841126 -291.325912) (xy 420.89074 -291.345384) (xy 420.936898 -291.372033) (xy 420.978569 -291.405264)
			(xy 421.014821 -291.444335) (xy 421.044845 -291.488372) (xy 421.067971 -291.536393) (xy 421.083681 -291.587323)
			(xy 421.091624 -291.640027) (xy 421.092122 -291.666676) (xy 421.091624 -291.693325) (xy 435.468004 -291.693325)
			(xy 435.468004 -291.640027) (xy 435.475947 -291.587323) (xy 435.491657 -291.536393) (xy 435.514783 -291.488372)
			(xy 435.544807 -291.444335) (xy 435.581059 -291.405264) (xy 435.62273 -291.372033) (xy 435.668888 -291.345384)
			(xy 435.718502 -291.325912) (xy 435.770464 -291.314052) (xy 435.823614 -291.310069) (xy 435.876764 -291.314052)
			(xy 435.928726 -291.325912) (xy 435.97834 -291.345384) (xy 436.024498 -291.372033) (xy 436.066169 -291.405264)
			(xy 436.102421 -291.444335) (xy 436.132445 -291.488372) (xy 436.155571 -291.536393) (xy 436.171281 -291.587323)
			(xy 436.179224 -291.640027) (xy 436.179722 -291.666676) (xy 436.179224 -291.693325) (xy 436.171281 -291.746029)
			(xy 436.155571 -291.796959) (xy 436.132445 -291.84498) (xy 436.102421 -291.889017) (xy 436.066169 -291.928088)
			(xy 436.024498 -291.961319) (xy 435.97834 -291.987968) (xy 435.928726 -292.00744) (xy 435.876764 -292.0193)
			(xy 435.823614 -292.023284) (xy 435.770464 -292.0193) (xy 435.718502 -292.00744) (xy 435.668888 -291.987968)
			(xy 435.62273 -291.961319) (xy 435.581059 -291.928088) (xy 435.544807 -291.889017) (xy 435.514783 -291.84498)
			(xy 435.491657 -291.796959) (xy 435.475947 -291.746029) (xy 435.468004 -291.693325) (xy 421.091624 -291.693325)
			(xy 421.083681 -291.746029) (xy 421.067971 -291.796959) (xy 421.044845 -291.84498) (xy 421.014821 -291.889017)
			(xy 420.978569 -291.928088) (xy 420.936898 -291.961319) (xy 420.89074 -291.987968) (xy 420.841126 -292.00744)
			(xy 420.789164 -292.0193) (xy 420.736014 -292.023284) (xy 420.682864 -292.0193) (xy 420.630902 -292.00744)
			(xy 420.581288 -291.987968) (xy 420.53513 -291.961319) (xy 420.493459 -291.928088) (xy 420.457207 -291.889017)
			(xy 420.427183 -291.84498) (xy 420.404057 -291.796959) (xy 420.388347 -291.746029) (xy 420.380404 -291.693325)
			(xy 405.54656 -291.693325) (xy 405.54656 -292.543209) (xy 424.480472 -292.543209) (xy 424.480472 -292.489911)
			(xy 424.488415 -292.437207) (xy 424.504125 -292.386277) (xy 424.527251 -292.338256) (xy 424.557275 -292.294219)
			(xy 424.593527 -292.255148) (xy 424.635198 -292.221917) (xy 424.681356 -292.195268) (xy 424.73097 -292.175796)
			(xy 424.782932 -292.163936) (xy 424.836082 -292.159953) (xy 424.889232 -292.163936) (xy 424.941194 -292.175796)
			(xy 424.990808 -292.195268) (xy 425.036966 -292.221917) (xy 425.078637 -292.255148) (xy 425.114889 -292.294219)
			(xy 425.144913 -292.338256) (xy 425.168039 -292.386277) (xy 425.183749 -292.437207) (xy 425.191692 -292.489911)
			(xy 425.19219 -292.51656) (xy 425.191692 -292.543209) (xy 439.568072 -292.543209) (xy 439.568072 -292.489911)
			(xy 439.576015 -292.437207) (xy 439.591725 -292.386277) (xy 439.614851 -292.338256) (xy 439.644875 -292.294219)
			(xy 439.681127 -292.255148) (xy 439.722798 -292.221917) (xy 439.768956 -292.195268) (xy 439.81857 -292.175796)
			(xy 439.870532 -292.163936) (xy 439.923682 -292.159953) (xy 439.976832 -292.163936) (xy 440.028794 -292.175796)
			(xy 440.078408 -292.195268) (xy 440.124566 -292.221917) (xy 440.166237 -292.255148) (xy 440.202489 -292.294219)
			(xy 440.232513 -292.338256) (xy 440.255639 -292.386277) (xy 440.271349 -292.437207) (xy 440.279292 -292.489911)
			(xy 440.27979 -292.51656) (xy 440.279292 -292.543209) (xy 440.271349 -292.595913) (xy 440.255639 -292.646843)
			(xy 440.232513 -292.694864) (xy 440.202489 -292.738901) (xy 440.166237 -292.777972) (xy 440.124566 -292.811203)
			(xy 440.078408 -292.837852) (xy 440.028794 -292.857324) (xy 439.976832 -292.869184) (xy 439.923682 -292.873168)
			(xy 439.870532 -292.869184) (xy 439.81857 -292.857324) (xy 439.768956 -292.837852) (xy 439.722798 -292.811203)
			(xy 439.681127 -292.777972) (xy 439.644875 -292.738901) (xy 439.614851 -292.694864) (xy 439.591725 -292.646843)
			(xy 439.576015 -292.595913) (xy 439.568072 -292.543209) (xy 425.191692 -292.543209) (xy 425.183749 -292.595913)
			(xy 425.168039 -292.646843) (xy 425.144913 -292.694864) (xy 425.114889 -292.738901) (xy 425.078637 -292.777972)
			(xy 425.036966 -292.811203) (xy 424.990808 -292.837852) (xy 424.941194 -292.857324) (xy 424.889232 -292.869184)
			(xy 424.836082 -292.873168) (xy 424.782932 -292.869184) (xy 424.73097 -292.857324) (xy 424.681356 -292.837852)
			(xy 424.635198 -292.811203) (xy 424.593527 -292.777972) (xy 424.557275 -292.738901) (xy 424.527251 -292.694864)
			(xy 424.504125 -292.646843) (xy 424.488415 -292.595913) (xy 424.480472 -292.543209) (xy 405.54656 -292.543209)
			(xy 405.54656 -293.393347) (xy 420.380404 -293.393347) (xy 420.380404 -293.340049) (xy 420.388347 -293.287345)
			(xy 420.404057 -293.236415) (xy 420.427183 -293.188394) (xy 420.457207 -293.144357) (xy 420.493459 -293.105286)
			(xy 420.53513 -293.072055) (xy 420.581288 -293.045406) (xy 420.630902 -293.025934) (xy 420.682864 -293.014074)
			(xy 420.736014 -293.010091) (xy 420.789164 -293.014074) (xy 420.841126 -293.025934) (xy 420.89074 -293.045406)
			(xy 420.936898 -293.072055) (xy 420.978569 -293.105286) (xy 421.014821 -293.144357) (xy 421.044845 -293.188394)
			(xy 421.067971 -293.236415) (xy 421.083681 -293.287345) (xy 421.091624 -293.340049) (xy 421.092122 -293.366698)
			(xy 421.091624 -293.393347) (xy 424.480472 -293.393347) (xy 424.480472 -293.340049) (xy 424.488415 -293.287345)
			(xy 424.504125 -293.236415) (xy 424.527251 -293.188394) (xy 424.557275 -293.144357) (xy 424.593527 -293.105286)
			(xy 424.635198 -293.072055) (xy 424.681356 -293.045406) (xy 424.73097 -293.025934) (xy 424.782932 -293.014074)
			(xy 424.836082 -293.010091) (xy 424.889232 -293.014074) (xy 424.941194 -293.025934) (xy 424.990808 -293.045406)
			(xy 425.036966 -293.072055) (xy 425.078637 -293.105286) (xy 425.114889 -293.144357) (xy 425.144913 -293.188394)
			(xy 425.168039 -293.236415) (xy 425.183749 -293.287345) (xy 425.191692 -293.340049) (xy 425.19219 -293.366698)
			(xy 425.191692 -293.393347) (xy 435.468004 -293.393347) (xy 435.468004 -293.340049) (xy 435.475947 -293.287345)
			(xy 435.491657 -293.236415) (xy 435.514783 -293.188394) (xy 435.544807 -293.144357) (xy 435.581059 -293.105286)
			(xy 435.62273 -293.072055) (xy 435.668888 -293.045406) (xy 435.718502 -293.025934) (xy 435.770464 -293.014074)
			(xy 435.823614 -293.010091) (xy 435.876764 -293.014074) (xy 435.928726 -293.025934) (xy 435.97834 -293.045406)
			(xy 436.024498 -293.072055) (xy 436.066169 -293.105286) (xy 436.102421 -293.144357) (xy 436.132445 -293.188394)
			(xy 436.155571 -293.236415) (xy 436.171281 -293.287345) (xy 436.179224 -293.340049) (xy 436.179722 -293.366698)
			(xy 436.179224 -293.393347) (xy 439.568072 -293.393347) (xy 439.568072 -293.340049) (xy 439.576015 -293.287345)
			(xy 439.591725 -293.236415) (xy 439.614851 -293.188394) (xy 439.644875 -293.144357) (xy 439.681127 -293.105286)
			(xy 439.722798 -293.072055) (xy 439.768956 -293.045406) (xy 439.81857 -293.025934) (xy 439.870532 -293.014074)
			(xy 439.923682 -293.010091) (xy 439.976832 -293.014074) (xy 440.028794 -293.025934) (xy 440.078408 -293.045406)
			(xy 440.124566 -293.072055) (xy 440.166237 -293.105286) (xy 440.202489 -293.144357) (xy 440.232513 -293.188394)
			(xy 440.255639 -293.236415) (xy 440.271349 -293.287345) (xy 440.279292 -293.340049) (xy 440.27979 -293.366698)
			(xy 440.279292 -293.393347) (xy 440.271349 -293.446051) (xy 440.255639 -293.496981) (xy 440.232513 -293.545002)
			(xy 440.202489 -293.589039) (xy 440.166237 -293.62811) (xy 440.124566 -293.661341) (xy 440.078408 -293.68799)
			(xy 440.028794 -293.707462) (xy 439.976832 -293.719322) (xy 439.923682 -293.723306) (xy 439.870532 -293.719322)
			(xy 439.81857 -293.707462) (xy 439.768956 -293.68799) (xy 439.722798 -293.661341) (xy 439.681127 -293.62811)
			(xy 439.644875 -293.589039) (xy 439.614851 -293.545002) (xy 439.591725 -293.496981) (xy 439.576015 -293.446051)
			(xy 439.568072 -293.393347) (xy 436.179224 -293.393347) (xy 436.171281 -293.446051) (xy 436.155571 -293.496981)
			(xy 436.132445 -293.545002) (xy 436.102421 -293.589039) (xy 436.066169 -293.62811) (xy 436.024498 -293.661341)
			(xy 435.97834 -293.68799) (xy 435.928726 -293.707462) (xy 435.876764 -293.719322) (xy 435.823614 -293.723306)
			(xy 435.770464 -293.719322) (xy 435.718502 -293.707462) (xy 435.668888 -293.68799) (xy 435.62273 -293.661341)
			(xy 435.581059 -293.62811) (xy 435.544807 -293.589039) (xy 435.514783 -293.545002) (xy 435.491657 -293.496981)
			(xy 435.475947 -293.446051) (xy 435.468004 -293.393347) (xy 425.191692 -293.393347) (xy 425.183749 -293.446051)
			(xy 425.168039 -293.496981) (xy 425.144913 -293.545002) (xy 425.114889 -293.589039) (xy 425.078637 -293.62811)
			(xy 425.036966 -293.661341) (xy 424.990808 -293.68799) (xy 424.941194 -293.707462) (xy 424.889232 -293.719322)
			(xy 424.836082 -293.723306) (xy 424.782932 -293.719322) (xy 424.73097 -293.707462) (xy 424.681356 -293.68799)
			(xy 424.635198 -293.661341) (xy 424.593527 -293.62811) (xy 424.557275 -293.589039) (xy 424.527251 -293.545002)
			(xy 424.504125 -293.496981) (xy 424.488415 -293.446051) (xy 424.480472 -293.393347) (xy 421.091624 -293.393347)
			(xy 421.083681 -293.446051) (xy 421.067971 -293.496981) (xy 421.044845 -293.545002) (xy 421.014821 -293.589039)
			(xy 420.978569 -293.62811) (xy 420.936898 -293.661341) (xy 420.89074 -293.68799) (xy 420.841126 -293.707462)
			(xy 420.789164 -293.719322) (xy 420.736014 -293.723306) (xy 420.682864 -293.719322) (xy 420.630902 -293.707462)
			(xy 420.581288 -293.68799) (xy 420.53513 -293.661341) (xy 420.493459 -293.62811) (xy 420.457207 -293.589039)
			(xy 420.427183 -293.545002) (xy 420.404057 -293.496981) (xy 420.388347 -293.446051) (xy 420.380404 -293.393347)
			(xy 405.54656 -293.393347) (xy 405.54656 -294.243231) (xy 420.380404 -294.243231) (xy 420.380404 -294.189933)
			(xy 420.388347 -294.137229) (xy 420.404057 -294.086299) (xy 420.427183 -294.038278) (xy 420.457207 -293.994241)
			(xy 420.493459 -293.95517) (xy 420.53513 -293.921939) (xy 420.581288 -293.89529) (xy 420.630902 -293.875818)
			(xy 420.682864 -293.863958) (xy 420.736014 -293.859975) (xy 420.789164 -293.863958) (xy 420.841126 -293.875818)
			(xy 420.89074 -293.89529) (xy 420.936898 -293.921939) (xy 420.978569 -293.95517) (xy 421.014821 -293.994241)
			(xy 421.044845 -294.038278) (xy 421.067971 -294.086299) (xy 421.083681 -294.137229) (xy 421.091624 -294.189933)
			(xy 421.092122 -294.216582) (xy 421.091624 -294.243231) (xy 435.468004 -294.243231) (xy 435.468004 -294.189933)
			(xy 435.475947 -294.137229) (xy 435.491657 -294.086299) (xy 435.514783 -294.038278) (xy 435.544807 -293.994241)
			(xy 435.581059 -293.95517) (xy 435.62273 -293.921939) (xy 435.668888 -293.89529) (xy 435.718502 -293.875818)
			(xy 435.770464 -293.863958) (xy 435.823614 -293.859975) (xy 435.876764 -293.863958) (xy 435.928726 -293.875818)
			(xy 435.97834 -293.89529) (xy 436.024498 -293.921939) (xy 436.066169 -293.95517) (xy 436.102421 -293.994241)
			(xy 436.132445 -294.038278) (xy 436.155571 -294.086299) (xy 436.171281 -294.137229) (xy 436.179224 -294.189933)
			(xy 436.179722 -294.216582) (xy 436.179224 -294.243231) (xy 436.171281 -294.295935) (xy 436.155571 -294.346865)
			(xy 436.132445 -294.394886) (xy 436.102421 -294.438923) (xy 436.066169 -294.477994) (xy 436.024498 -294.511225)
			(xy 435.97834 -294.537874) (xy 435.928726 -294.557346) (xy 435.876764 -294.569206) (xy 435.823614 -294.57319)
			(xy 435.770464 -294.569206) (xy 435.718502 -294.557346) (xy 435.668888 -294.537874) (xy 435.62273 -294.511225)
			(xy 435.581059 -294.477994) (xy 435.544807 -294.438923) (xy 435.514783 -294.394886) (xy 435.491657 -294.346865)
			(xy 435.475947 -294.295935) (xy 435.468004 -294.243231) (xy 421.091624 -294.243231) (xy 421.083681 -294.295935)
			(xy 421.067971 -294.346865) (xy 421.044845 -294.394886) (xy 421.014821 -294.438923) (xy 420.978569 -294.477994)
			(xy 420.936898 -294.511225) (xy 420.89074 -294.537874) (xy 420.841126 -294.557346) (xy 420.789164 -294.569206)
			(xy 420.736014 -294.57319) (xy 420.682864 -294.569206) (xy 420.630902 -294.557346) (xy 420.581288 -294.537874)
			(xy 420.53513 -294.511225) (xy 420.493459 -294.477994) (xy 420.457207 -294.438923) (xy 420.427183 -294.394886)
			(xy 420.404057 -294.346865) (xy 420.388347 -294.295935) (xy 420.380404 -294.243231) (xy 405.54656 -294.243231)
			(xy 405.54656 -295.093369) (xy 424.480472 -295.093369) (xy 424.480472 -295.040071) (xy 424.488415 -294.987367)
			(xy 424.504125 -294.936437) (xy 424.527251 -294.888416) (xy 424.557275 -294.844379) (xy 424.593527 -294.805308)
			(xy 424.635198 -294.772077) (xy 424.681356 -294.745428) (xy 424.73097 -294.725956) (xy 424.782932 -294.714096)
			(xy 424.836082 -294.710113) (xy 424.889232 -294.714096) (xy 424.941194 -294.725956) (xy 424.990808 -294.745428)
			(xy 425.036966 -294.772077) (xy 425.078637 -294.805308) (xy 425.114889 -294.844379) (xy 425.144913 -294.888416)
			(xy 425.168039 -294.936437) (xy 425.183749 -294.987367) (xy 425.191692 -295.040071) (xy 425.19219 -295.06672)
			(xy 425.191692 -295.093369) (xy 439.568072 -295.093369) (xy 439.568072 -295.040071) (xy 439.576015 -294.987367)
			(xy 439.591725 -294.936437) (xy 439.614851 -294.888416) (xy 439.644875 -294.844379) (xy 439.681127 -294.805308)
			(xy 439.722798 -294.772077) (xy 439.768956 -294.745428) (xy 439.81857 -294.725956) (xy 439.870532 -294.714096)
			(xy 439.923682 -294.710113) (xy 439.976832 -294.714096) (xy 440.028794 -294.725956) (xy 440.078408 -294.745428)
			(xy 440.124566 -294.772077) (xy 440.166237 -294.805308) (xy 440.202489 -294.844379) (xy 440.232513 -294.888416)
			(xy 440.255639 -294.936437) (xy 440.271349 -294.987367) (xy 440.279292 -295.040071) (xy 440.27979 -295.06672)
			(xy 440.279292 -295.093369) (xy 440.271349 -295.146073) (xy 440.255639 -295.197003) (xy 440.232513 -295.245024)
			(xy 440.202489 -295.289061) (xy 440.166237 -295.328132) (xy 440.124566 -295.361363) (xy 440.078408 -295.388012)
			(xy 440.028794 -295.407484) (xy 439.976832 -295.419344) (xy 439.923682 -295.423328) (xy 439.870532 -295.419344)
			(xy 439.81857 -295.407484) (xy 439.768956 -295.388012) (xy 439.722798 -295.361363) (xy 439.681127 -295.328132)
			(xy 439.644875 -295.289061) (xy 439.614851 -295.245024) (xy 439.591725 -295.197003) (xy 439.576015 -295.146073)
			(xy 439.568072 -295.093369) (xy 425.191692 -295.093369) (xy 425.183749 -295.146073) (xy 425.168039 -295.197003)
			(xy 425.144913 -295.245024) (xy 425.114889 -295.289061) (xy 425.078637 -295.328132) (xy 425.036966 -295.361363)
			(xy 424.990808 -295.388012) (xy 424.941194 -295.407484) (xy 424.889232 -295.419344) (xy 424.836082 -295.423328)
			(xy 424.782932 -295.419344) (xy 424.73097 -295.407484) (xy 424.681356 -295.388012) (xy 424.635198 -295.361363)
			(xy 424.593527 -295.328132) (xy 424.557275 -295.289061) (xy 424.527251 -295.245024) (xy 424.504125 -295.197003)
			(xy 424.488415 -295.146073) (xy 424.480472 -295.093369) (xy 405.54656 -295.093369) (xy 405.54656 -295.943253)
			(xy 420.380404 -295.943253) (xy 420.380404 -295.889955) (xy 420.388347 -295.837251) (xy 420.404057 -295.786321)
			(xy 420.427183 -295.7383) (xy 420.457207 -295.694263) (xy 420.493459 -295.655192) (xy 420.53513 -295.621961)
			(xy 420.581288 -295.595312) (xy 420.630902 -295.57584) (xy 420.682864 -295.56398) (xy 420.736014 -295.559997)
			(xy 420.789164 -295.56398) (xy 420.841126 -295.57584) (xy 420.89074 -295.595312) (xy 420.936898 -295.621961)
			(xy 420.978569 -295.655192) (xy 421.014821 -295.694263) (xy 421.044845 -295.7383) (xy 421.067971 -295.786321)
			(xy 421.083681 -295.837251) (xy 421.091624 -295.889955) (xy 421.092122 -295.916604) (xy 421.091624 -295.943253)
			(xy 435.468004 -295.943253) (xy 435.468004 -295.889955) (xy 435.475947 -295.837251) (xy 435.491657 -295.786321)
			(xy 435.514783 -295.7383) (xy 435.544807 -295.694263) (xy 435.581059 -295.655192) (xy 435.62273 -295.621961)
			(xy 435.668888 -295.595312) (xy 435.718502 -295.57584) (xy 435.770464 -295.56398) (xy 435.823614 -295.559997)
			(xy 435.876764 -295.56398) (xy 435.928726 -295.57584) (xy 435.97834 -295.595312) (xy 436.024498 -295.621961)
			(xy 436.066169 -295.655192) (xy 436.102421 -295.694263) (xy 436.132445 -295.7383) (xy 436.155571 -295.786321)
			(xy 436.171281 -295.837251) (xy 436.179224 -295.889955) (xy 436.179722 -295.916604) (xy 436.179224 -295.943253)
			(xy 436.171281 -295.995957) (xy 436.155571 -296.046887) (xy 436.132445 -296.094908) (xy 436.102421 -296.138945)
			(xy 436.066169 -296.178016) (xy 436.024498 -296.211247) (xy 435.97834 -296.237896) (xy 435.928726 -296.257368)
			(xy 435.876764 -296.269228) (xy 435.823614 -296.273212) (xy 435.770464 -296.269228) (xy 435.718502 -296.257368)
			(xy 435.668888 -296.237896) (xy 435.62273 -296.211247) (xy 435.581059 -296.178016) (xy 435.544807 -296.138945)
			(xy 435.514783 -296.094908) (xy 435.491657 -296.046887) (xy 435.475947 -295.995957) (xy 435.468004 -295.943253)
			(xy 421.091624 -295.943253) (xy 421.083681 -295.995957) (xy 421.067971 -296.046887) (xy 421.044845 -296.094908)
			(xy 421.014821 -296.138945) (xy 420.978569 -296.178016) (xy 420.936898 -296.211247) (xy 420.89074 -296.237896)
			(xy 420.841126 -296.257368) (xy 420.789164 -296.269228) (xy 420.736014 -296.273212) (xy 420.682864 -296.269228)
			(xy 420.630902 -296.257368) (xy 420.581288 -296.237896) (xy 420.53513 -296.211247) (xy 420.493459 -296.178016)
			(xy 420.457207 -296.138945) (xy 420.427183 -296.094908) (xy 420.404057 -296.046887) (xy 420.388347 -295.995957)
			(xy 420.380404 -295.943253) (xy 405.54656 -295.943253) (xy 405.54656 -296.793391) (xy 424.480472 -296.793391)
			(xy 424.480472 -296.740093) (xy 424.488415 -296.687389) (xy 424.504125 -296.636459) (xy 424.527251 -296.588438)
			(xy 424.557275 -296.544401) (xy 424.593527 -296.50533) (xy 424.635198 -296.472099) (xy 424.681356 -296.44545)
			(xy 424.73097 -296.425978) (xy 424.782932 -296.414118) (xy 424.836082 -296.410135) (xy 424.889232 -296.414118)
			(xy 424.941194 -296.425978) (xy 424.990808 -296.44545) (xy 425.036966 -296.472099) (xy 425.078637 -296.50533)
			(xy 425.114889 -296.544401) (xy 425.144913 -296.588438) (xy 425.168039 -296.636459) (xy 425.183749 -296.687389)
			(xy 425.191692 -296.740093) (xy 425.19219 -296.766742) (xy 425.191692 -296.793391) (xy 439.568072 -296.793391)
			(xy 439.568072 -296.740093) (xy 439.576015 -296.687389) (xy 439.591725 -296.636459) (xy 439.614851 -296.588438)
			(xy 439.644875 -296.544401) (xy 439.681127 -296.50533) (xy 439.722798 -296.472099) (xy 439.768956 -296.44545)
			(xy 439.81857 -296.425978) (xy 439.870532 -296.414118) (xy 439.923682 -296.410135) (xy 439.976832 -296.414118)
			(xy 440.028794 -296.425978) (xy 440.078408 -296.44545) (xy 440.124566 -296.472099) (xy 440.166237 -296.50533)
			(xy 440.202489 -296.544401) (xy 440.232513 -296.588438) (xy 440.255639 -296.636459) (xy 440.271349 -296.687389)
			(xy 440.279292 -296.740093) (xy 440.27979 -296.766742) (xy 440.279292 -296.793391) (xy 440.271349 -296.846095)
			(xy 440.255639 -296.897025) (xy 440.232513 -296.945046) (xy 440.202489 -296.989083) (xy 440.166237 -297.028154)
			(xy 440.124566 -297.061385) (xy 440.078408 -297.088034) (xy 440.028794 -297.107506) (xy 439.976832 -297.119366)
			(xy 439.923682 -297.12335) (xy 439.870532 -297.119366) (xy 439.81857 -297.107506) (xy 439.768956 -297.088034)
			(xy 439.722798 -297.061385) (xy 439.681127 -297.028154) (xy 439.644875 -296.989083) (xy 439.614851 -296.945046)
			(xy 439.591725 -296.897025) (xy 439.576015 -296.846095) (xy 439.568072 -296.793391) (xy 425.191692 -296.793391)
			(xy 425.183749 -296.846095) (xy 425.168039 -296.897025) (xy 425.144913 -296.945046) (xy 425.114889 -296.989083)
			(xy 425.078637 -297.028154) (xy 425.036966 -297.061385) (xy 424.990808 -297.088034) (xy 424.941194 -297.107506)
			(xy 424.889232 -297.119366) (xy 424.836082 -297.12335) (xy 424.782932 -297.119366) (xy 424.73097 -297.107506)
			(xy 424.681356 -297.088034) (xy 424.635198 -297.061385) (xy 424.593527 -297.028154) (xy 424.557275 -296.989083)
			(xy 424.527251 -296.945046) (xy 424.504125 -296.897025) (xy 424.488415 -296.846095) (xy 424.480472 -296.793391)
			(xy 405.54656 -296.793391) (xy 405.54656 -297.643275) (xy 420.380404 -297.643275) (xy 420.380404 -297.589977)
			(xy 420.388347 -297.537273) (xy 420.404057 -297.486343) (xy 420.427183 -297.438322) (xy 420.457207 -297.394285)
			(xy 420.493459 -297.355214) (xy 420.53513 -297.321983) (xy 420.581288 -297.295334) (xy 420.630902 -297.275862)
			(xy 420.682864 -297.264002) (xy 420.736014 -297.260019) (xy 420.789164 -297.264002) (xy 420.841126 -297.275862)
			(xy 420.89074 -297.295334) (xy 420.936898 -297.321983) (xy 420.978569 -297.355214) (xy 421.014821 -297.394285)
			(xy 421.044845 -297.438322) (xy 421.067971 -297.486343) (xy 421.083681 -297.537273) (xy 421.091624 -297.589977)
			(xy 421.092122 -297.616626) (xy 421.091624 -297.643275) (xy 435.468004 -297.643275) (xy 435.468004 -297.589977)
			(xy 435.475947 -297.537273) (xy 435.491657 -297.486343) (xy 435.514783 -297.438322) (xy 435.544807 -297.394285)
			(xy 435.581059 -297.355214) (xy 435.62273 -297.321983) (xy 435.668888 -297.295334) (xy 435.718502 -297.275862)
			(xy 435.770464 -297.264002) (xy 435.823614 -297.260019) (xy 435.876764 -297.264002) (xy 435.928726 -297.275862)
			(xy 435.97834 -297.295334) (xy 436.024498 -297.321983) (xy 436.066169 -297.355214) (xy 436.102421 -297.394285)
			(xy 436.132445 -297.438322) (xy 436.155571 -297.486343) (xy 436.171281 -297.537273) (xy 436.179224 -297.589977)
			(xy 436.179722 -297.616626) (xy 436.179224 -297.643275) (xy 436.171281 -297.695979) (xy 436.155571 -297.746909)
			(xy 436.132445 -297.79493) (xy 436.102421 -297.838967) (xy 436.066169 -297.878038) (xy 436.024498 -297.911269)
			(xy 435.97834 -297.937918) (xy 435.928726 -297.95739) (xy 435.876764 -297.96925) (xy 435.823614 -297.973234)
			(xy 435.770464 -297.96925) (xy 435.718502 -297.95739) (xy 435.668888 -297.937918) (xy 435.62273 -297.911269)
			(xy 435.581059 -297.878038) (xy 435.544807 -297.838967) (xy 435.514783 -297.79493) (xy 435.491657 -297.746909)
			(xy 435.475947 -297.695979) (xy 435.468004 -297.643275) (xy 421.091624 -297.643275) (xy 421.083681 -297.695979)
			(xy 421.067971 -297.746909) (xy 421.044845 -297.79493) (xy 421.014821 -297.838967) (xy 420.978569 -297.878038)
			(xy 420.936898 -297.911269) (xy 420.89074 -297.937918) (xy 420.841126 -297.95739) (xy 420.789164 -297.96925)
			(xy 420.736014 -297.973234) (xy 420.682864 -297.96925) (xy 420.630902 -297.95739) (xy 420.581288 -297.937918)
			(xy 420.53513 -297.911269) (xy 420.493459 -297.878038) (xy 420.457207 -297.838967) (xy 420.427183 -297.79493)
			(xy 420.404057 -297.746909) (xy 420.388347 -297.695979) (xy 420.380404 -297.643275) (xy 405.54656 -297.643275)
			(xy 405.54656 -298.493413) (xy 409.367472 -298.493413) (xy 409.367472 -298.440115) (xy 409.375415 -298.387411)
			(xy 409.391125 -298.336481) (xy 409.414251 -298.28846) (xy 409.444275 -298.244423) (xy 409.480527 -298.205352)
			(xy 409.522198 -298.172121) (xy 409.568356 -298.145472) (xy 409.61797 -298.126) (xy 409.669932 -298.11414)
			(xy 409.723082 -298.110157) (xy 409.776232 -298.11414) (xy 409.828194 -298.126) (xy 409.877808 -298.145472)
			(xy 409.923966 -298.172121) (xy 409.965637 -298.205352) (xy 410.001889 -298.244423) (xy 410.031913 -298.28846)
			(xy 410.055039 -298.336481) (xy 410.070749 -298.387411) (xy 410.078692 -298.440115) (xy 410.07919 -298.466764)
			(xy 410.078692 -298.493413) (xy 424.480472 -298.493413) (xy 424.480472 -298.440115) (xy 424.488415 -298.387411)
			(xy 424.504125 -298.336481) (xy 424.527251 -298.28846) (xy 424.557275 -298.244423) (xy 424.593527 -298.205352)
			(xy 424.635198 -298.172121) (xy 424.681356 -298.145472) (xy 424.73097 -298.126) (xy 424.782932 -298.11414)
			(xy 424.836082 -298.110157) (xy 424.889232 -298.11414) (xy 424.941194 -298.126) (xy 424.990808 -298.145472)
			(xy 425.036966 -298.172121) (xy 425.078637 -298.205352) (xy 425.114889 -298.244423) (xy 425.144913 -298.28846)
			(xy 425.168039 -298.336481) (xy 425.183749 -298.387411) (xy 425.191692 -298.440115) (xy 425.19219 -298.466764)
			(xy 425.191692 -298.493413) (xy 439.568072 -298.493413) (xy 439.568072 -298.440115) (xy 439.576015 -298.387411)
			(xy 439.591725 -298.336481) (xy 439.614851 -298.28846) (xy 439.644875 -298.244423) (xy 439.681127 -298.205352)
			(xy 439.722798 -298.172121) (xy 439.768956 -298.145472) (xy 439.81857 -298.126) (xy 439.870532 -298.11414)
			(xy 439.923682 -298.110157) (xy 439.976832 -298.11414) (xy 440.028794 -298.126) (xy 440.078408 -298.145472)
			(xy 440.124566 -298.172121) (xy 440.166237 -298.205352) (xy 440.202489 -298.244423) (xy 440.232513 -298.28846)
			(xy 440.255639 -298.336481) (xy 440.271349 -298.387411) (xy 440.279292 -298.440115) (xy 440.27979 -298.466764)
			(xy 440.279292 -298.493413) (xy 440.271349 -298.546117) (xy 440.255639 -298.597047) (xy 440.232513 -298.645068)
			(xy 440.202489 -298.689105) (xy 440.166237 -298.728176) (xy 440.124566 -298.761407) (xy 440.078408 -298.788056)
			(xy 440.028794 -298.807528) (xy 439.976832 -298.819388) (xy 439.923682 -298.823372) (xy 439.870532 -298.819388)
			(xy 439.81857 -298.807528) (xy 439.768956 -298.788056) (xy 439.722798 -298.761407) (xy 439.681127 -298.728176)
			(xy 439.644875 -298.689105) (xy 439.614851 -298.645068) (xy 439.591725 -298.597047) (xy 439.576015 -298.546117)
			(xy 439.568072 -298.493413) (xy 425.191692 -298.493413) (xy 425.183749 -298.546117) (xy 425.168039 -298.597047)
			(xy 425.144913 -298.645068) (xy 425.114889 -298.689105) (xy 425.078637 -298.728176) (xy 425.036966 -298.761407)
			(xy 424.990808 -298.788056) (xy 424.941194 -298.807528) (xy 424.889232 -298.819388) (xy 424.836082 -298.823372)
			(xy 424.782932 -298.819388) (xy 424.73097 -298.807528) (xy 424.681356 -298.788056) (xy 424.635198 -298.761407)
			(xy 424.593527 -298.728176) (xy 424.557275 -298.689105) (xy 424.527251 -298.645068) (xy 424.504125 -298.597047)
			(xy 424.488415 -298.546117) (xy 424.480472 -298.493413) (xy 410.078692 -298.493413) (xy 410.070749 -298.546117)
			(xy 410.055039 -298.597047) (xy 410.031913 -298.645068) (xy 410.001889 -298.689105) (xy 409.965637 -298.728176)
			(xy 409.923966 -298.761407) (xy 409.877808 -298.788056) (xy 409.828194 -298.807528) (xy 409.776232 -298.819388)
			(xy 409.723082 -298.823372) (xy 409.669932 -298.819388) (xy 409.61797 -298.807528) (xy 409.568356 -298.788056)
			(xy 409.522198 -298.761407) (xy 409.480527 -298.728176) (xy 409.444275 -298.689105) (xy 409.414251 -298.645068)
			(xy 409.391125 -298.597047) (xy 409.375415 -298.546117) (xy 409.367472 -298.493413) (xy 405.54656 -298.493413)
			(xy 405.54656 -298.859702) (xy 405.547087 -298.87514) (xy 405.55629 -298.90461) (xy 405.573884 -298.929982)
			(xy 405.598258 -298.948932) (xy 405.627184 -298.959727) (xy 405.642572 -298.961048) (xy 405.669506 -298.963031)
			(xy 405.722362 -298.974108) (xy 405.77294 -298.993039) (xy 405.820078 -299.01939) (xy 405.862698 -299.052557)
			(xy 405.89982 -299.091779) (xy 405.930594 -299.136157) (xy 405.954314 -299.184674) (xy 405.970436 -299.236215)
			(xy 405.978591 -299.2896) (xy 405.97859 -299.343297) (xy 420.380404 -299.343297) (xy 420.380404 -299.289999)
			(xy 420.388347 -299.237295) (xy 420.404057 -299.186365) (xy 420.427183 -299.138344) (xy 420.457207 -299.094307)
			(xy 420.493459 -299.055236) (xy 420.53513 -299.022005) (xy 420.581288 -298.995356) (xy 420.630902 -298.975884)
			(xy 420.682864 -298.964024) (xy 420.736014 -298.960041) (xy 420.789164 -298.964024) (xy 420.841126 -298.975884)
			(xy 420.89074 -298.995356) (xy 420.936898 -299.022005) (xy 420.978569 -299.055236) (xy 421.014821 -299.094307)
			(xy 421.044845 -299.138344) (xy 421.067971 -299.186365) (xy 421.083681 -299.237295) (xy 421.091624 -299.289999)
			(xy 421.092122 -299.316648) (xy 421.091624 -299.343297) (xy 435.468004 -299.343297) (xy 435.468004 -299.289999)
			(xy 435.475947 -299.237295) (xy 435.491657 -299.186365) (xy 435.514783 -299.138344) (xy 435.544807 -299.094307)
			(xy 435.581059 -299.055236) (xy 435.62273 -299.022005) (xy 435.668888 -298.995356) (xy 435.718502 -298.975884)
			(xy 435.770464 -298.964024) (xy 435.823614 -298.960041) (xy 435.876764 -298.964024) (xy 435.928726 -298.975884)
			(xy 435.97834 -298.995356) (xy 436.024498 -299.022005) (xy 436.066169 -299.055236) (xy 436.102421 -299.094307)
			(xy 436.132445 -299.138344) (xy 436.155571 -299.186365) (xy 436.171281 -299.237295) (xy 436.179224 -299.289999)
			(xy 436.179722 -299.316648) (xy 436.179224 -299.343297) (xy 436.171281 -299.396001) (xy 436.155571 -299.446931)
			(xy 436.132445 -299.494952) (xy 436.102421 -299.538989) (xy 436.066169 -299.57806) (xy 436.024498 -299.611291)
			(xy 435.97834 -299.63794) (xy 435.928726 -299.657412) (xy 435.876764 -299.669272) (xy 435.823614 -299.673256)
			(xy 435.770464 -299.669272) (xy 435.718502 -299.657412) (xy 435.668888 -299.63794) (xy 435.62273 -299.611291)
			(xy 435.581059 -299.57806) (xy 435.544807 -299.538989) (xy 435.514783 -299.494952) (xy 435.491657 -299.446931)
			(xy 435.475947 -299.396001) (xy 435.468004 -299.343297) (xy 421.091624 -299.343297) (xy 421.083681 -299.396001)
			(xy 421.067971 -299.446931) (xy 421.044845 -299.494952) (xy 421.014821 -299.538989) (xy 420.978569 -299.57806)
			(xy 420.936898 -299.611291) (xy 420.89074 -299.63794) (xy 420.841126 -299.657412) (xy 420.789164 -299.669272)
			(xy 420.736014 -299.673256) (xy 420.682864 -299.669272) (xy 420.630902 -299.657412) (xy 420.581288 -299.63794)
			(xy 420.53513 -299.611291) (xy 420.493459 -299.57806) (xy 420.457207 -299.538989) (xy 420.427183 -299.494952)
			(xy 420.404057 -299.446931) (xy 420.388347 -299.396001) (xy 420.380404 -299.343297) (xy 405.97859 -299.343297)
			(xy 405.97859 -299.343605) (xy 405.970435 -299.39699) (xy 405.954312 -299.448531) (xy 405.930592 -299.497047)
			(xy 405.899817 -299.541425) (xy 405.862694 -299.580647) (xy 405.820074 -299.613813) (xy 405.772935 -299.640163)
			(xy 405.722357 -299.659094) (xy 405.669501 -299.67017) (xy 405.642572 -299.672248) (xy 405.627196 -299.673637)
			(xy 405.598294 -299.684451) (xy 405.573929 -299.703389) (xy 405.556318 -299.728728) (xy 405.547059 -299.758166)
			(xy 405.54656 -299.773594) (xy 405.54656 -300.193435) (xy 409.367472 -300.193435) (xy 409.367472 -300.140137)
			(xy 409.375415 -300.087433) (xy 409.391125 -300.036503) (xy 409.414251 -299.988482) (xy 409.444275 -299.944445)
			(xy 409.480527 -299.905374) (xy 409.522198 -299.872143) (xy 409.568356 -299.845494) (xy 409.61797 -299.826022)
			(xy 409.669932 -299.814162) (xy 409.723082 -299.810179) (xy 409.776232 -299.814162) (xy 409.828194 -299.826022)
			(xy 409.877808 -299.845494) (xy 409.923966 -299.872143) (xy 409.965637 -299.905374) (xy 410.001889 -299.944445)
			(xy 410.031913 -299.988482) (xy 410.055039 -300.036503) (xy 410.070749 -300.087433) (xy 410.078692 -300.140137)
			(xy 410.07919 -300.166786) (xy 410.078697 -300.193181) (xy 424.480472 -300.193181) (xy 424.480472 -300.139883)
			(xy 424.488415 -300.087179) (xy 424.504125 -300.036249) (xy 424.527251 -299.988228) (xy 424.557275 -299.944191)
			(xy 424.593527 -299.90512) (xy 424.635198 -299.871889) (xy 424.681356 -299.84524) (xy 424.73097 -299.825768)
			(xy 424.782932 -299.813908) (xy 424.836082 -299.809925) (xy 424.889232 -299.813908) (xy 424.941194 -299.825768)
			(xy 424.990808 -299.84524) (xy 425.036966 -299.871889) (xy 425.078637 -299.90512) (xy 425.114889 -299.944191)
			(xy 425.144913 -299.988228) (xy 425.168039 -300.036249) (xy 425.183749 -300.087179) (xy 425.191692 -300.139883)
			(xy 425.19219 -300.166532) (xy 425.191692 -300.193181) (xy 425.191654 -300.193435) (xy 439.526162 -300.193435)
			(xy 439.526162 -300.140137) (xy 439.534105 -300.087433) (xy 439.549815 -300.036503) (xy 439.572941 -299.988482)
			(xy 439.602965 -299.944445) (xy 439.639217 -299.905374) (xy 439.680888 -299.872143) (xy 439.727046 -299.845494)
			(xy 439.77666 -299.826022) (xy 439.828622 -299.814162) (xy 439.881772 -299.810179) (xy 439.934922 -299.814162)
			(xy 439.986884 -299.826022) (xy 440.036498 -299.845494) (xy 440.082656 -299.872143) (xy 440.124327 -299.905374)
			(xy 440.160579 -299.944445) (xy 440.190603 -299.988482) (xy 440.213729 -300.036503) (xy 440.229439 -300.087433)
			(xy 440.237382 -300.140137) (xy 440.23788 -300.166786) (xy 440.237382 -300.193435) (xy 440.229439 -300.246139)
			(xy 440.213729 -300.297069) (xy 440.190603 -300.34509) (xy 440.160579 -300.389127) (xy 440.124327 -300.428198)
			(xy 440.082656 -300.461429) (xy 440.036498 -300.488078) (xy 439.986884 -300.50755) (xy 439.934922 -300.51941)
			(xy 439.881772 -300.523394) (xy 439.828622 -300.51941) (xy 439.77666 -300.50755) (xy 439.727046 -300.488078)
			(xy 439.680888 -300.461429) (xy 439.639217 -300.428198) (xy 439.602965 -300.389127) (xy 439.572941 -300.34509)
			(xy 439.549815 -300.297069) (xy 439.534105 -300.246139) (xy 439.526162 -300.193435) (xy 425.191654 -300.193435)
			(xy 425.183749 -300.245885) (xy 425.168039 -300.296815) (xy 425.144913 -300.344836) (xy 425.114889 -300.388873)
			(xy 425.078637 -300.427944) (xy 425.036966 -300.461175) (xy 424.990808 -300.487824) (xy 424.941194 -300.507296)
			(xy 424.889232 -300.519156) (xy 424.836082 -300.52314) (xy 424.782932 -300.519156) (xy 424.73097 -300.507296)
			(xy 424.681356 -300.487824) (xy 424.635198 -300.461175) (xy 424.593527 -300.427944) (xy 424.557275 -300.388873)
			(xy 424.527251 -300.344836) (xy 424.504125 -300.296815) (xy 424.488415 -300.245885) (xy 424.480472 -300.193181)
			(xy 410.078697 -300.193181) (xy 410.078692 -300.193435) (xy 410.070749 -300.246139) (xy 410.055039 -300.297069)
			(xy 410.031913 -300.34509) (xy 410.001889 -300.389127) (xy 409.965637 -300.428198) (xy 409.923966 -300.461429)
			(xy 409.877808 -300.488078) (xy 409.828194 -300.50755) (xy 409.776232 -300.51941) (xy 409.723082 -300.523394)
			(xy 409.669932 -300.51941) (xy 409.61797 -300.50755) (xy 409.568356 -300.488078) (xy 409.522198 -300.461429)
			(xy 409.480527 -300.428198) (xy 409.444275 -300.389127) (xy 409.414251 -300.34509) (xy 409.391125 -300.297069)
			(xy 409.375415 -300.246139) (xy 409.367472 -300.193435) (xy 405.54656 -300.193435) (xy 405.54656 -300.559724)
			(xy 405.54709 -300.575159) (xy 405.556297 -300.604625) (xy 405.573892 -300.62999) (xy 405.598265 -300.648935)
			(xy 405.627187 -300.659728) (xy 405.642572 -300.66107) (xy 405.669512 -300.663053) (xy 405.72238 -300.674132)
			(xy 405.772968 -300.693066) (xy 405.820118 -300.719423) (xy 405.862747 -300.752596) (xy 405.899878 -300.791827)
			(xy 405.930659 -300.836214) (xy 405.954385 -300.884741) (xy 405.970511 -300.936294) (xy 405.978668 -300.98969)
			(xy 405.978668 -301.043319) (xy 420.380404 -301.043319) (xy 420.380404 -300.990021) (xy 420.388347 -300.937317)
			(xy 420.404057 -300.886387) (xy 420.427183 -300.838366) (xy 420.457207 -300.794329) (xy 420.493459 -300.755258)
			(xy 420.53513 -300.722027) (xy 420.581288 -300.695378) (xy 420.630902 -300.675906) (xy 420.682864 -300.664046)
			(xy 420.736014 -300.660063) (xy 420.789164 -300.664046) (xy 420.841126 -300.675906) (xy 420.89074 -300.695378)
			(xy 420.936898 -300.722027) (xy 420.978569 -300.755258) (xy 421.014821 -300.794329) (xy 421.044845 -300.838366)
			(xy 421.067971 -300.886387) (xy 421.083681 -300.937317) (xy 421.091624 -300.990021) (xy 421.092122 -301.01667)
			(xy 421.091624 -301.043319) (xy 435.468004 -301.043319) (xy 435.468004 -300.990021) (xy 435.475947 -300.937317)
			(xy 435.491657 -300.886387) (xy 435.514783 -300.838366) (xy 435.544807 -300.794329) (xy 435.581059 -300.755258)
			(xy 435.62273 -300.722027) (xy 435.668888 -300.695378) (xy 435.718502 -300.675906) (xy 435.770464 -300.664046)
			(xy 435.823614 -300.660063) (xy 435.876764 -300.664046) (xy 435.928726 -300.675906) (xy 435.97834 -300.695378)
			(xy 436.024498 -300.722027) (xy 436.066169 -300.755258) (xy 436.102421 -300.794329) (xy 436.132445 -300.838366)
			(xy 436.155571 -300.886387) (xy 436.171281 -300.937317) (xy 436.179224 -300.990021) (xy 436.179722 -301.01667)
			(xy 436.179224 -301.043319) (xy 436.171281 -301.096023) (xy 436.155571 -301.146953) (xy 436.132445 -301.194974)
			(xy 436.102421 -301.239011) (xy 436.066169 -301.278082) (xy 436.024498 -301.311313) (xy 435.97834 -301.337962)
			(xy 435.928726 -301.357434) (xy 435.876764 -301.369294) (xy 435.823614 -301.373278) (xy 435.770464 -301.369294)
			(xy 435.718502 -301.357434) (xy 435.668888 -301.337962) (xy 435.62273 -301.311313) (xy 435.581059 -301.278082)
			(xy 435.544807 -301.239011) (xy 435.514783 -301.194974) (xy 435.491657 -301.146953) (xy 435.475947 -301.096023)
			(xy 435.468004 -301.043319) (xy 421.091624 -301.043319) (xy 421.083681 -301.096023) (xy 421.067971 -301.146953)
			(xy 421.044845 -301.194974) (xy 421.014821 -301.239011) (xy 420.978569 -301.278082) (xy 420.936898 -301.311313)
			(xy 420.89074 -301.337962) (xy 420.841126 -301.357434) (xy 420.789164 -301.369294) (xy 420.736014 -301.373278)
			(xy 420.682864 -301.369294) (xy 420.630902 -301.357434) (xy 420.581288 -301.337962) (xy 420.53513 -301.311313)
			(xy 420.493459 -301.278082) (xy 420.457207 -301.239011) (xy 420.427183 -301.194974) (xy 420.404057 -301.146953)
			(xy 420.388347 -301.096023) (xy 420.380404 -301.043319) (xy 405.978668 -301.043319) (xy 405.978668 -301.043706)
			(xy 405.970512 -301.097103) (xy 405.954386 -301.148656) (xy 405.930661 -301.197183) (xy 405.89988 -301.241571)
			(xy 405.862749 -301.280801) (xy 405.820121 -301.313976) (xy 405.772971 -301.340332) (xy 405.722383 -301.359267)
			(xy 405.669515 -301.370346) (xy 405.642572 -301.37227) (xy 405.627197 -301.373659) (xy 405.598298 -301.384474)
			(xy 405.573937 -301.403412) (xy 405.55633 -301.428752) (xy 405.547078 -301.458189) (xy 405.54656 -301.473616)
			(xy 405.54656 -301.893203) (xy 409.367472 -301.893203) (xy 409.367472 -301.839905) (xy 409.375415 -301.787201)
			(xy 409.391125 -301.736271) (xy 409.414251 -301.68825) (xy 409.444275 -301.644213) (xy 409.480527 -301.605142)
			(xy 409.522198 -301.571911) (xy 409.568356 -301.545262) (xy 409.61797 -301.52579) (xy 409.669932 -301.51393)
			(xy 409.723082 -301.509947) (xy 409.776232 -301.51393) (xy 409.828194 -301.52579) (xy 409.877808 -301.545262)
			(xy 409.923966 -301.571911) (xy 409.965637 -301.605142) (xy 410.001889 -301.644213) (xy 410.031913 -301.68825)
			(xy 410.055039 -301.736271) (xy 410.070749 -301.787201) (xy 410.078692 -301.839905) (xy 410.07919 -301.866554)
			(xy 410.078692 -301.893203) (xy 424.480472 -301.893203) (xy 424.480472 -301.839905) (xy 424.488415 -301.787201)
			(xy 424.504125 -301.736271) (xy 424.527251 -301.68825) (xy 424.557275 -301.644213) (xy 424.593527 -301.605142)
			(xy 424.635198 -301.571911) (xy 424.681356 -301.545262) (xy 424.73097 -301.52579) (xy 424.782932 -301.51393)
			(xy 424.836082 -301.509947) (xy 424.889232 -301.51393) (xy 424.941194 -301.52579) (xy 424.990808 -301.545262)
			(xy 425.036966 -301.571911) (xy 425.078637 -301.605142) (xy 425.114889 -301.644213) (xy 425.144913 -301.68825)
			(xy 425.168039 -301.736271) (xy 425.183749 -301.787201) (xy 425.191692 -301.839905) (xy 425.19219 -301.866554)
			(xy 425.191692 -301.893203) (xy 425.191654 -301.893457) (xy 439.526162 -301.893457) (xy 439.526162 -301.840159)
			(xy 439.534105 -301.787455) (xy 439.549815 -301.736525) (xy 439.572941 -301.688504) (xy 439.602965 -301.644467)
			(xy 439.639217 -301.605396) (xy 439.680888 -301.572165) (xy 439.727046 -301.545516) (xy 439.77666 -301.526044)
			(xy 439.828622 -301.514184) (xy 439.881772 -301.510201) (xy 439.934922 -301.514184) (xy 439.986884 -301.526044)
			(xy 440.036498 -301.545516) (xy 440.082656 -301.572165) (xy 440.124327 -301.605396) (xy 440.160579 -301.644467)
			(xy 440.190603 -301.688504) (xy 440.213729 -301.736525) (xy 440.229439 -301.787455) (xy 440.237382 -301.840159)
			(xy 440.23788 -301.866808) (xy 440.237382 -301.893457) (xy 440.229439 -301.946161) (xy 440.213729 -301.997091)
			(xy 440.190603 -302.045112) (xy 440.160579 -302.089149) (xy 440.124327 -302.12822) (xy 440.082656 -302.161451)
			(xy 440.036498 -302.1881) (xy 439.986884 -302.207572) (xy 439.934922 -302.219432) (xy 439.881772 -302.223416)
			(xy 439.828622 -302.219432) (xy 439.77666 -302.207572) (xy 439.727046 -302.1881) (xy 439.680888 -302.161451)
			(xy 439.639217 -302.12822) (xy 439.602965 -302.089149) (xy 439.572941 -302.045112) (xy 439.549815 -301.997091)
			(xy 439.534105 -301.946161) (xy 439.526162 -301.893457) (xy 425.191654 -301.893457) (xy 425.183749 -301.945907)
			(xy 425.168039 -301.996837) (xy 425.144913 -302.044858) (xy 425.114889 -302.088895) (xy 425.078637 -302.127966)
			(xy 425.036966 -302.161197) (xy 424.990808 -302.187846) (xy 424.941194 -302.207318) (xy 424.889232 -302.219178)
			(xy 424.836082 -302.223162) (xy 424.782932 -302.219178) (xy 424.73097 -302.207318) (xy 424.681356 -302.187846)
			(xy 424.635198 -302.161197) (xy 424.593527 -302.127966) (xy 424.557275 -302.088895) (xy 424.527251 -302.044858)
			(xy 424.504125 -301.996837) (xy 424.488415 -301.945907) (xy 424.480472 -301.893203) (xy 410.078692 -301.893203)
			(xy 410.070749 -301.945907) (xy 410.055039 -301.996837) (xy 410.031913 -302.044858) (xy 410.001889 -302.088895)
			(xy 409.965637 -302.127966) (xy 409.923966 -302.161197) (xy 409.877808 -302.187846) (xy 409.828194 -302.207318)
			(xy 409.776232 -302.219178) (xy 409.723082 -302.223162) (xy 409.669932 -302.219178) (xy 409.61797 -302.207318)
			(xy 409.568356 -302.187846) (xy 409.522198 -302.161197) (xy 409.480527 -302.127966) (xy 409.444275 -302.088895)
			(xy 409.414251 -302.044858) (xy 409.391125 -301.996837) (xy 409.375415 -301.945907) (xy 409.367472 -301.893203)
			(xy 405.54656 -301.893203) (xy 405.54656 -302.259746) (xy 405.547093 -302.275179) (xy 405.556304 -302.304639)
			(xy 405.5739 -302.329998) (xy 405.598271 -302.348939) (xy 405.62719 -302.359728) (xy 405.642572 -302.361092)
			(xy 405.669507 -302.363076) (xy 405.722365 -302.374154) (xy 405.772943 -302.393089) (xy 405.820082 -302.419445)
			(xy 405.862699 -302.452617) (xy 405.899818 -302.491846) (xy 405.930586 -302.536231) (xy 405.954299 -302.584753)
			(xy 405.970411 -302.6363) (xy 405.978553 -302.689689) (xy 405.979122 -302.716692) (xy 405.9786 -302.743341)
			(xy 409.367472 -302.743341) (xy 409.367472 -302.690043) (xy 409.375415 -302.637339) (xy 409.391125 -302.586409)
			(xy 409.414251 -302.538388) (xy 409.444275 -302.494351) (xy 409.480527 -302.45528) (xy 409.522198 -302.422049)
			(xy 409.568356 -302.3954) (xy 409.61797 -302.375928) (xy 409.669932 -302.364068) (xy 409.723082 -302.360085)
			(xy 409.776232 -302.364068) (xy 409.828194 -302.375928) (xy 409.877808 -302.3954) (xy 409.923966 -302.422049)
			(xy 409.965637 -302.45528) (xy 410.001889 -302.494351) (xy 410.031913 -302.538388) (xy 410.055039 -302.586409)
			(xy 410.070749 -302.637339) (xy 410.078692 -302.690043) (xy 410.07919 -302.716692) (xy 410.078692 -302.743341)
			(xy 420.380404 -302.743341) (xy 420.380404 -302.690043) (xy 420.388347 -302.637339) (xy 420.404057 -302.586409)
			(xy 420.427183 -302.538388) (xy 420.457207 -302.494351) (xy 420.493459 -302.45528) (xy 420.53513 -302.422049)
			(xy 420.581288 -302.3954) (xy 420.630902 -302.375928) (xy 420.682864 -302.364068) (xy 420.736014 -302.360085)
			(xy 420.789164 -302.364068) (xy 420.841126 -302.375928) (xy 420.89074 -302.3954) (xy 420.936898 -302.422049)
			(xy 420.978569 -302.45528) (xy 421.014821 -302.494351) (xy 421.044845 -302.538388) (xy 421.067971 -302.586409)
			(xy 421.083681 -302.637339) (xy 421.091624 -302.690043) (xy 421.092122 -302.716692) (xy 421.091624 -302.743341)
			(xy 424.480472 -302.743341) (xy 424.480472 -302.690043) (xy 424.488415 -302.637339) (xy 424.504125 -302.586409)
			(xy 424.527251 -302.538388) (xy 424.557275 -302.494351) (xy 424.593527 -302.45528) (xy 424.635198 -302.422049)
			(xy 424.681356 -302.3954) (xy 424.73097 -302.375928) (xy 424.782932 -302.364068) (xy 424.836082 -302.360085)
			(xy 424.889232 -302.364068) (xy 424.941194 -302.375928) (xy 424.990808 -302.3954) (xy 425.036966 -302.422049)
			(xy 425.078637 -302.45528) (xy 425.114889 -302.494351) (xy 425.144913 -302.538388) (xy 425.168039 -302.586409)
			(xy 425.183749 -302.637339) (xy 425.191692 -302.690043) (xy 425.19219 -302.716692) (xy 425.191692 -302.743341)
			(xy 435.468004 -302.743341) (xy 435.468004 -302.690043) (xy 435.475947 -302.637339) (xy 435.491657 -302.586409)
			(xy 435.514783 -302.538388) (xy 435.544807 -302.494351) (xy 435.581059 -302.45528) (xy 435.62273 -302.422049)
			(xy 435.668888 -302.3954) (xy 435.718502 -302.375928) (xy 435.770464 -302.364068) (xy 435.823614 -302.360085)
			(xy 435.876764 -302.364068) (xy 435.928726 -302.375928) (xy 435.97834 -302.3954) (xy 436.024498 -302.422049)
			(xy 436.066169 -302.45528) (xy 436.102421 -302.494351) (xy 436.132445 -302.538388) (xy 436.155571 -302.586409)
			(xy 436.171281 -302.637339) (xy 436.179224 -302.690043) (xy 436.179722 -302.716692) (xy 436.179224 -302.743341)
			(xy 439.568072 -302.743341) (xy 439.568072 -302.690043) (xy 439.576015 -302.637339) (xy 439.591725 -302.586409)
			(xy 439.614851 -302.538388) (xy 439.644875 -302.494351) (xy 439.681127 -302.45528) (xy 439.722798 -302.422049)
			(xy 439.768956 -302.3954) (xy 439.81857 -302.375928) (xy 439.870532 -302.364068) (xy 439.923682 -302.360085)
			(xy 439.976832 -302.364068) (xy 440.028794 -302.375928) (xy 440.078408 -302.3954) (xy 440.124566 -302.422049)
			(xy 440.166237 -302.45528) (xy 440.202489 -302.494351) (xy 440.232513 -302.538388) (xy 440.255639 -302.586409)
			(xy 440.271349 -302.637339) (xy 440.279292 -302.690043) (xy 440.27979 -302.716692) (xy 440.279292 -302.743341)
			(xy 440.271349 -302.796045) (xy 440.255639 -302.846975) (xy 440.232513 -302.894996) (xy 440.202489 -302.939033)
			(xy 440.166237 -302.978104) (xy 440.124566 -303.011335) (xy 440.078408 -303.037984) (xy 440.028794 -303.057456)
			(xy 439.976832 -303.069316) (xy 439.923682 -303.0733) (xy 439.870532 -303.069316) (xy 439.81857 -303.057456)
			(xy 439.768956 -303.037984) (xy 439.722798 -303.011335) (xy 439.681127 -302.978104) (xy 439.644875 -302.939033)
			(xy 439.614851 -302.894996) (xy 439.591725 -302.846975) (xy 439.576015 -302.796045) (xy 439.568072 -302.743341)
			(xy 436.179224 -302.743341) (xy 436.171281 -302.796045) (xy 436.155571 -302.846975) (xy 436.132445 -302.894996)
			(xy 436.102421 -302.939033) (xy 436.066169 -302.978104) (xy 436.024498 -303.011335) (xy 435.97834 -303.037984)
			(xy 435.928726 -303.057456) (xy 435.876764 -303.069316) (xy 435.823614 -303.0733) (xy 435.770464 -303.069316)
			(xy 435.718502 -303.057456) (xy 435.668888 -303.037984) (xy 435.62273 -303.011335) (xy 435.581059 -302.978104)
			(xy 435.544807 -302.939033) (xy 435.514783 -302.894996) (xy 435.491657 -302.846975) (xy 435.475947 -302.796045)
			(xy 435.468004 -302.743341) (xy 425.191692 -302.743341) (xy 425.183749 -302.796045) (xy 425.168039 -302.846975)
			(xy 425.144913 -302.894996) (xy 425.114889 -302.939033) (xy 425.078637 -302.978104) (xy 425.036966 -303.011335)
			(xy 424.990808 -303.037984) (xy 424.941194 -303.057456) (xy 424.889232 -303.069316) (xy 424.836082 -303.0733)
			(xy 424.782932 -303.069316) (xy 424.73097 -303.057456) (xy 424.681356 -303.037984) (xy 424.635198 -303.011335)
			(xy 424.593527 -302.978104) (xy 424.557275 -302.939033) (xy 424.527251 -302.894996) (xy 424.504125 -302.846975)
			(xy 424.488415 -302.796045) (xy 424.480472 -302.743341) (xy 421.091624 -302.743341) (xy 421.083681 -302.796045)
			(xy 421.067971 -302.846975) (xy 421.044845 -302.894996) (xy 421.014821 -302.939033) (xy 420.978569 -302.978104)
			(xy 420.936898 -303.011335) (xy 420.89074 -303.037984) (xy 420.841126 -303.057456) (xy 420.789164 -303.069316)
			(xy 420.736014 -303.0733) (xy 420.682864 -303.069316) (xy 420.630902 -303.057456) (xy 420.581288 -303.037984)
			(xy 420.53513 -303.011335) (xy 420.493459 -302.978104) (xy 420.457207 -302.939033) (xy 420.427183 -302.894996)
			(xy 420.404057 -302.846975) (xy 420.388347 -302.796045) (xy 420.380404 -302.743341) (xy 410.078692 -302.743341)
			(xy 410.070749 -302.796045) (xy 410.055039 -302.846975) (xy 410.031913 -302.894996) (xy 410.001889 -302.939033)
			(xy 409.965637 -302.978104) (xy 409.923966 -303.011335) (xy 409.877808 -303.037984) (xy 409.828194 -303.057456)
			(xy 409.776232 -303.069316) (xy 409.723082 -303.0733) (xy 409.669932 -303.069316) (xy 409.61797 -303.057456)
			(xy 409.568356 -303.037984) (xy 409.522198 -303.011335) (xy 409.480527 -302.978104) (xy 409.444275 -302.939033)
			(xy 409.414251 -302.894996) (xy 409.391125 -302.846975) (xy 409.375415 -302.796045) (xy 409.367472 -302.743341)
			(xy 405.9786 -302.743341) (xy 405.978574 -302.744676) (xy 405.96982 -302.799955) (xy 405.952526 -302.853184)
			(xy 405.927119 -302.903052) (xy 405.894223 -302.948332) (xy 405.854649 -302.987909) (xy 405.809371 -303.020807)
			(xy 405.759504 -303.046218) (xy 405.706276 -303.063515) (xy 405.650998 -303.072272) (xy 405.623014 -303.0728)
			(xy 405.600662 -303.072038) (xy 405.590233 -303.071848) (xy 405.570606 -303.078845) (xy 405.555376 -303.093065)
			(xy 405.547052 -303.112167) (xy 405.54656 -303.122584) (xy 405.54656 -303.160684) (xy 405.547111 -303.171087)
			(xy 405.555453 -303.190154) (xy 405.570659 -303.204364) (xy 405.590246 -303.211396) (xy 405.600662 -303.21123)
			(xy 405.623014 -303.210468) (xy 405.650997 -303.211018) (xy 405.706274 -303.219775) (xy 405.759501 -303.23707)
			(xy 405.809367 -303.262479) (xy 405.854644 -303.295374) (xy 405.894219 -303.334948) (xy 405.927116 -303.380225)
			(xy 405.952526 -303.43009) (xy 405.969823 -303.483316) (xy 405.978581 -303.538593) (xy 405.979122 -303.566576)
			(xy 405.978631 -303.593225) (xy 420.380404 -303.593225) (xy 420.380404 -303.539927) (xy 420.388347 -303.487223)
			(xy 420.404057 -303.436293) (xy 420.427183 -303.388272) (xy 420.457207 -303.344235) (xy 420.493459 -303.305164)
			(xy 420.53513 -303.271933) (xy 420.581288 -303.245284) (xy 420.630902 -303.225812) (xy 420.682864 -303.213952)
			(xy 420.736014 -303.209969) (xy 420.789164 -303.213952) (xy 420.841126 -303.225812) (xy 420.89074 -303.245284)
			(xy 420.936898 -303.271933) (xy 420.978569 -303.305164) (xy 421.014821 -303.344235) (xy 421.044845 -303.388272)
			(xy 421.067971 -303.436293) (xy 421.083681 -303.487223) (xy 421.091624 -303.539927) (xy 421.092122 -303.566576)
			(xy 421.091624 -303.593225) (xy 435.468004 -303.593225) (xy 435.468004 -303.539927) (xy 435.475947 -303.487223)
			(xy 435.491657 -303.436293) (xy 435.514783 -303.388272) (xy 435.544807 -303.344235) (xy 435.581059 -303.305164)
			(xy 435.62273 -303.271933) (xy 435.668888 -303.245284) (xy 435.718502 -303.225812) (xy 435.770464 -303.213952)
			(xy 435.823614 -303.209969) (xy 435.876764 -303.213952) (xy 435.928726 -303.225812) (xy 435.97834 -303.245284)
			(xy 436.024498 -303.271933) (xy 436.066169 -303.305164) (xy 436.102421 -303.344235) (xy 436.132445 -303.388272)
			(xy 436.155571 -303.436293) (xy 436.171281 -303.487223) (xy 436.179224 -303.539927) (xy 436.179722 -303.566576)
			(xy 436.179224 -303.593225) (xy 436.171281 -303.645929) (xy 436.155571 -303.696859) (xy 436.132445 -303.74488)
			(xy 436.102421 -303.788917) (xy 436.066169 -303.827988) (xy 436.024498 -303.861219) (xy 435.97834 -303.887868)
			(xy 435.928726 -303.90734) (xy 435.876764 -303.9192) (xy 435.823614 -303.923184) (xy 435.770464 -303.9192)
			(xy 435.718502 -303.90734) (xy 435.668888 -303.887868) (xy 435.62273 -303.861219) (xy 435.581059 -303.827988)
			(xy 435.544807 -303.788917) (xy 435.514783 -303.74488) (xy 435.491657 -303.696859) (xy 435.475947 -303.645929)
			(xy 435.468004 -303.593225) (xy 421.091624 -303.593225) (xy 421.083681 -303.645929) (xy 421.067971 -303.696859)
			(xy 421.044845 -303.74488) (xy 421.014821 -303.788917) (xy 420.978569 -303.827988) (xy 420.936898 -303.861219)
			(xy 420.89074 -303.887868) (xy 420.841126 -303.90734) (xy 420.789164 -303.9192) (xy 420.736014 -303.923184)
			(xy 420.682864 -303.9192) (xy 420.630902 -303.90734) (xy 420.581288 -303.887868) (xy 420.53513 -303.861219)
			(xy 420.493459 -303.827988) (xy 420.457207 -303.788917) (xy 420.427183 -303.74488) (xy 420.404057 -303.696859)
			(xy 420.388347 -303.645929) (xy 420.380404 -303.593225) (xy 405.978631 -303.593225) (xy 405.978624 -303.593582)
			(xy 405.970471 -303.646974) (xy 405.95435 -303.698523) (xy 405.930628 -303.747047) (xy 405.899852 -303.791432)
			(xy 405.862726 -303.830661) (xy 405.820101 -303.863833) (xy 405.772957 -303.890188) (xy 405.722373 -303.909122)
			(xy 405.66951 -303.9202) (xy 405.642572 -303.922176) (xy 405.627198 -303.923565) (xy 405.5983 -303.934381)
			(xy 405.57394 -303.953319) (xy 405.556334 -303.978659) (xy 405.547084 -304.008095) (xy 405.54656 -304.023522)
			(xy 405.54656 -304.443363) (xy 409.367472 -304.443363) (xy 409.367472 -304.390065) (xy 409.375415 -304.337361)
			(xy 409.391125 -304.286431) (xy 409.414251 -304.23841) (xy 409.444275 -304.194373) (xy 409.480527 -304.155302)
			(xy 409.522198 -304.122071) (xy 409.568356 -304.095422) (xy 409.61797 -304.07595) (xy 409.669932 -304.06409)
			(xy 409.723082 -304.060107) (xy 409.776232 -304.06409) (xy 409.828194 -304.07595) (xy 409.877808 -304.095422)
			(xy 409.923966 -304.122071) (xy 409.965637 -304.155302) (xy 410.001889 -304.194373) (xy 410.031913 -304.23841)
			(xy 410.055039 -304.286431) (xy 410.070749 -304.337361) (xy 410.078692 -304.390065) (xy 410.07919 -304.416714)
			(xy 410.078692 -304.443363) (xy 424.480472 -304.443363) (xy 424.480472 -304.390065) (xy 424.488415 -304.337361)
			(xy 424.504125 -304.286431) (xy 424.527251 -304.23841) (xy 424.557275 -304.194373) (xy 424.593527 -304.155302)
			(xy 424.635198 -304.122071) (xy 424.681356 -304.095422) (xy 424.73097 -304.07595) (xy 424.782932 -304.06409)
			(xy 424.836082 -304.060107) (xy 424.889232 -304.06409) (xy 424.941194 -304.07595) (xy 424.990808 -304.095422)
			(xy 425.036966 -304.122071) (xy 425.078637 -304.155302) (xy 425.114889 -304.194373) (xy 425.144913 -304.23841)
			(xy 425.168039 -304.286431) (xy 425.183749 -304.337361) (xy 425.191692 -304.390065) (xy 425.19219 -304.416714)
			(xy 425.191692 -304.443363) (xy 439.568072 -304.443363) (xy 439.568072 -304.390065) (xy 439.576015 -304.337361)
			(xy 439.591725 -304.286431) (xy 439.614851 -304.23841) (xy 439.644875 -304.194373) (xy 439.681127 -304.155302)
			(xy 439.722798 -304.122071) (xy 439.768956 -304.095422) (xy 439.81857 -304.07595) (xy 439.870532 -304.06409)
			(xy 439.923682 -304.060107) (xy 439.976832 -304.06409) (xy 440.028794 -304.07595) (xy 440.078408 -304.095422)
			(xy 440.124566 -304.122071) (xy 440.166237 -304.155302) (xy 440.202489 -304.194373) (xy 440.232513 -304.23841)
			(xy 440.255639 -304.286431) (xy 440.271349 -304.337361) (xy 440.279292 -304.390065) (xy 440.27979 -304.416714)
			(xy 440.279292 -304.443363) (xy 440.271349 -304.496067) (xy 440.255639 -304.546997) (xy 440.232513 -304.595018)
			(xy 440.202489 -304.639055) (xy 440.166237 -304.678126) (xy 440.124566 -304.711357) (xy 440.078408 -304.738006)
			(xy 440.028794 -304.757478) (xy 439.976832 -304.769338) (xy 439.923682 -304.773322) (xy 439.870532 -304.769338)
			(xy 439.81857 -304.757478) (xy 439.768956 -304.738006) (xy 439.722798 -304.711357) (xy 439.681127 -304.678126)
			(xy 439.644875 -304.639055) (xy 439.614851 -304.595018) (xy 439.591725 -304.546997) (xy 439.576015 -304.496067)
			(xy 439.568072 -304.443363) (xy 425.191692 -304.443363) (xy 425.183749 -304.496067) (xy 425.168039 -304.546997)
			(xy 425.144913 -304.595018) (xy 425.114889 -304.639055) (xy 425.078637 -304.678126) (xy 425.036966 -304.711357)
			(xy 424.990808 -304.738006) (xy 424.941194 -304.757478) (xy 424.889232 -304.769338) (xy 424.836082 -304.773322)
			(xy 424.782932 -304.769338) (xy 424.73097 -304.757478) (xy 424.681356 -304.738006) (xy 424.635198 -304.711357)
			(xy 424.593527 -304.678126) (xy 424.557275 -304.639055) (xy 424.527251 -304.595018) (xy 424.504125 -304.546997)
			(xy 424.488415 -304.496067) (xy 424.480472 -304.443363) (xy 410.078692 -304.443363) (xy 410.070749 -304.496067)
			(xy 410.055039 -304.546997) (xy 410.031913 -304.595018) (xy 410.001889 -304.639055) (xy 409.965637 -304.678126)
			(xy 409.923966 -304.711357) (xy 409.877808 -304.738006) (xy 409.828194 -304.757478) (xy 409.776232 -304.769338)
			(xy 409.723082 -304.773322) (xy 409.669932 -304.769338) (xy 409.61797 -304.757478) (xy 409.568356 -304.738006)
			(xy 409.522198 -304.711357) (xy 409.480527 -304.678126) (xy 409.444275 -304.639055) (xy 409.414251 -304.595018)
			(xy 409.391125 -304.546997) (xy 409.375415 -304.496067) (xy 409.367472 -304.443363) (xy 405.54656 -304.443363)
			(xy 405.54656 -304.809652) (xy 405.547094 -304.825085) (xy 405.556306 -304.854543) (xy 405.573902 -304.879901)
			(xy 405.598273 -304.89884) (xy 405.627191 -304.909628) (xy 405.642572 -304.910998) (xy 405.66951 -304.912981)
			(xy 405.722373 -304.924059) (xy 405.772958 -304.942992) (xy 405.820104 -304.969347) (xy 405.862729 -305.002518)
			(xy 405.899857 -305.041746) (xy 405.930636 -305.08613) (xy 405.95436 -305.134653) (xy 405.970484 -305.186201)
			(xy 405.97864 -305.239594) (xy 405.97864 -305.293247) (xy 420.380404 -305.293247) (xy 420.380404 -305.239949)
			(xy 420.388347 -305.187245) (xy 420.404057 -305.136315) (xy 420.427183 -305.088294) (xy 420.457207 -305.044257)
			(xy 420.493459 -305.005186) (xy 420.53513 -304.971955) (xy 420.581288 -304.945306) (xy 420.630902 -304.925834)
			(xy 420.682864 -304.913974) (xy 420.736014 -304.909991) (xy 420.789164 -304.913974) (xy 420.841126 -304.925834)
			(xy 420.89074 -304.945306) (xy 420.936898 -304.971955) (xy 420.978569 -305.005186) (xy 421.014821 -305.044257)
			(xy 421.044845 -305.088294) (xy 421.067971 -305.136315) (xy 421.083681 -305.187245) (xy 421.091624 -305.239949)
			(xy 421.092122 -305.266598) (xy 421.091624 -305.293247) (xy 435.468004 -305.293247) (xy 435.468004 -305.239949)
			(xy 435.475947 -305.187245) (xy 435.491657 -305.136315) (xy 435.514783 -305.088294) (xy 435.544807 -305.044257)
			(xy 435.581059 -305.005186) (xy 435.62273 -304.971955) (xy 435.668888 -304.945306) (xy 435.718502 -304.925834)
			(xy 435.770464 -304.913974) (xy 435.823614 -304.909991) (xy 435.876764 -304.913974) (xy 435.928726 -304.925834)
			(xy 435.97834 -304.945306) (xy 436.024498 -304.971955) (xy 436.066169 -305.005186) (xy 436.102421 -305.044257)
			(xy 436.132445 -305.088294) (xy 436.155571 -305.136315) (xy 436.171281 -305.187245) (xy 436.179224 -305.239949)
			(xy 436.179722 -305.266598) (xy 436.179224 -305.293247) (xy 436.171281 -305.345951) (xy 436.155571 -305.396881)
			(xy 436.132445 -305.444902) (xy 436.102421 -305.488939) (xy 436.066169 -305.52801) (xy 436.024498 -305.561241)
			(xy 435.97834 -305.58789) (xy 435.928726 -305.607362) (xy 435.876764 -305.619222) (xy 435.823614 -305.623206)
			(xy 435.770464 -305.619222) (xy 435.718502 -305.607362) (xy 435.668888 -305.58789) (xy 435.62273 -305.561241)
			(xy 435.581059 -305.52801) (xy 435.544807 -305.488939) (xy 435.514783 -305.444902) (xy 435.491657 -305.396881)
			(xy 435.475947 -305.345951) (xy 435.468004 -305.293247) (xy 421.091624 -305.293247) (xy 421.083681 -305.345951)
			(xy 421.067971 -305.396881) (xy 421.044845 -305.444902) (xy 421.014821 -305.488939) (xy 420.978569 -305.52801)
			(xy 420.936898 -305.561241) (xy 420.89074 -305.58789) (xy 420.841126 -305.607362) (xy 420.789164 -305.619222)
			(xy 420.736014 -305.623206) (xy 420.682864 -305.619222) (xy 420.630902 -305.607362) (xy 420.581288 -305.58789)
			(xy 420.53513 -305.561241) (xy 420.493459 -305.52801) (xy 420.457207 -305.488939) (xy 420.427183 -305.444902)
			(xy 420.404057 -305.396881) (xy 420.388347 -305.345951) (xy 420.380404 -305.293247) (xy 405.97864 -305.293247)
			(xy 405.97864 -305.293606) (xy 405.970484 -305.346998) (xy 405.95436 -305.398547) (xy 405.930636 -305.44707)
			(xy 405.899857 -305.491454) (xy 405.862729 -305.530682) (xy 405.820104 -305.563853) (xy 405.772958 -305.590208)
			(xy 405.722373 -305.609141) (xy 405.66951 -305.620219) (xy 405.642572 -305.622198) (xy 405.627199 -305.623588)
			(xy 405.598304 -305.634403) (xy 405.573948 -305.653343) (xy 405.556347 -305.678683) (xy 405.547102 -305.708118)
			(xy 405.54656 -305.723544) (xy 405.54656 -306.143385) (xy 409.367472 -306.143385) (xy 409.367472 -306.090087)
			(xy 409.375415 -306.037383) (xy 409.391125 -305.986453) (xy 409.414251 -305.938432) (xy 409.444275 -305.894395)
			(xy 409.480527 -305.855324) (xy 409.522198 -305.822093) (xy 409.568356 -305.795444) (xy 409.61797 -305.775972)
			(xy 409.669932 -305.764112) (xy 409.723082 -305.760129) (xy 409.776232 -305.764112) (xy 409.828194 -305.775972)
			(xy 409.877808 -305.795444) (xy 409.923966 -305.822093) (xy 409.965637 -305.855324) (xy 410.001889 -305.894395)
			(xy 410.031913 -305.938432) (xy 410.055039 -305.986453) (xy 410.070749 -306.037383) (xy 410.078692 -306.090087)
			(xy 410.07919 -306.116736) (xy 410.078692 -306.143385) (xy 424.480472 -306.143385) (xy 424.480472 -306.090087)
			(xy 424.488415 -306.037383) (xy 424.504125 -305.986453) (xy 424.527251 -305.938432) (xy 424.557275 -305.894395)
			(xy 424.593527 -305.855324) (xy 424.635198 -305.822093) (xy 424.681356 -305.795444) (xy 424.73097 -305.775972)
			(xy 424.782932 -305.764112) (xy 424.836082 -305.760129) (xy 424.889232 -305.764112) (xy 424.941194 -305.775972)
			(xy 424.990808 -305.795444) (xy 425.036966 -305.822093) (xy 425.078637 -305.855324) (xy 425.114889 -305.894395)
			(xy 425.144913 -305.938432) (xy 425.168039 -305.986453) (xy 425.183749 -306.037383) (xy 425.191692 -306.090087)
			(xy 425.19219 -306.116736) (xy 425.191692 -306.143385) (xy 439.568072 -306.143385) (xy 439.568072 -306.090087)
			(xy 439.576015 -306.037383) (xy 439.591725 -305.986453) (xy 439.614851 -305.938432) (xy 439.644875 -305.894395)
			(xy 439.681127 -305.855324) (xy 439.722798 -305.822093) (xy 439.768956 -305.795444) (xy 439.81857 -305.775972)
			(xy 439.870532 -305.764112) (xy 439.923682 -305.760129) (xy 439.976832 -305.764112) (xy 440.028794 -305.775972)
			(xy 440.078408 -305.795444) (xy 440.124566 -305.822093) (xy 440.166237 -305.855324) (xy 440.202489 -305.894395)
			(xy 440.232513 -305.938432) (xy 440.255639 -305.986453) (xy 440.271349 -306.037383) (xy 440.279292 -306.090087)
			(xy 440.27979 -306.116736) (xy 440.279292 -306.143385) (xy 440.271349 -306.196089) (xy 440.255639 -306.247019)
			(xy 440.232513 -306.29504) (xy 440.202489 -306.339077) (xy 440.166237 -306.378148) (xy 440.124566 -306.411379)
			(xy 440.078408 -306.438028) (xy 440.028794 -306.4575) (xy 439.976832 -306.46936) (xy 439.923682 -306.473344)
			(xy 439.870532 -306.46936) (xy 439.81857 -306.4575) (xy 439.768956 -306.438028) (xy 439.722798 -306.411379)
			(xy 439.681127 -306.378148) (xy 439.644875 -306.339077) (xy 439.614851 -306.29504) (xy 439.591725 -306.247019)
			(xy 439.576015 -306.196089) (xy 439.568072 -306.143385) (xy 425.191692 -306.143385) (xy 425.183749 -306.196089)
			(xy 425.168039 -306.247019) (xy 425.144913 -306.29504) (xy 425.114889 -306.339077) (xy 425.078637 -306.378148)
			(xy 425.036966 -306.411379) (xy 424.990808 -306.438028) (xy 424.941194 -306.4575) (xy 424.889232 -306.46936)
			(xy 424.836082 -306.473344) (xy 424.782932 -306.46936) (xy 424.73097 -306.4575) (xy 424.681356 -306.438028)
			(xy 424.635198 -306.411379) (xy 424.593527 -306.378148) (xy 424.557275 -306.339077) (xy 424.527251 -306.29504)
			(xy 424.504125 -306.247019) (xy 424.488415 -306.196089) (xy 424.480472 -306.143385) (xy 410.078692 -306.143385)
			(xy 410.070749 -306.196089) (xy 410.055039 -306.247019) (xy 410.031913 -306.29504) (xy 410.001889 -306.339077)
			(xy 409.965637 -306.378148) (xy 409.923966 -306.411379) (xy 409.877808 -306.438028) (xy 409.828194 -306.4575)
			(xy 409.776232 -306.46936) (xy 409.723082 -306.473344) (xy 409.669932 -306.46936) (xy 409.61797 -306.4575)
			(xy 409.568356 -306.438028) (xy 409.522198 -306.411379) (xy 409.480527 -306.378148) (xy 409.444275 -306.339077)
			(xy 409.414251 -306.29504) (xy 409.391125 -306.247019) (xy 409.375415 -306.196089) (xy 409.367472 -306.143385)
			(xy 405.54656 -306.143385) (xy 405.54656 -306.509674) (xy 405.547097 -306.525104) (xy 405.556313 -306.554557)
			(xy 405.57391 -306.579909) (xy 405.598279 -306.598843) (xy 405.627194 -306.609629) (xy 405.642572 -306.61102)
			(xy 405.669508 -306.613003) (xy 405.722368 -306.62408) (xy 405.77295 -306.643013) (xy 405.820093 -306.669366)
			(xy 405.862715 -306.702535) (xy 405.899841 -306.741761) (xy 405.930618 -306.786142) (xy 405.95434 -306.834662)
			(xy 405.970463 -306.886208) (xy 405.978618 -306.939597) (xy 405.978618 -306.993269) (xy 420.380404 -306.993269)
			(xy 420.380404 -306.939971) (xy 420.388347 -306.887267) (xy 420.404057 -306.836337) (xy 420.427183 -306.788316)
			(xy 420.457207 -306.744279) (xy 420.493459 -306.705208) (xy 420.53513 -306.671977) (xy 420.581288 -306.645328)
			(xy 420.630902 -306.625856) (xy 420.682864 -306.613996) (xy 420.736014 -306.610013) (xy 420.789164 -306.613996)
			(xy 420.841126 -306.625856) (xy 420.89074 -306.645328) (xy 420.936898 -306.671977) (xy 420.978569 -306.705208)
			(xy 421.014821 -306.744279) (xy 421.044845 -306.788316) (xy 421.067971 -306.836337) (xy 421.083681 -306.887267)
			(xy 421.091624 -306.939971) (xy 421.092122 -306.96662) (xy 421.091624 -306.993269) (xy 435.468004 -306.993269)
			(xy 435.468004 -306.939971) (xy 435.475947 -306.887267) (xy 435.491657 -306.836337) (xy 435.514783 -306.788316)
			(xy 435.544807 -306.744279) (xy 435.581059 -306.705208) (xy 435.62273 -306.671977) (xy 435.668888 -306.645328)
			(xy 435.718502 -306.625856) (xy 435.770464 -306.613996) (xy 435.823614 -306.610013) (xy 435.876764 -306.613996)
			(xy 435.928726 -306.625856) (xy 435.97834 -306.645328) (xy 436.024498 -306.671977) (xy 436.066169 -306.705208)
			(xy 436.102421 -306.744279) (xy 436.132445 -306.788316) (xy 436.155571 -306.836337) (xy 436.171281 -306.887267)
			(xy 436.179224 -306.939971) (xy 436.179722 -306.96662) (xy 436.179224 -306.993269) (xy 436.171281 -307.045973)
			(xy 436.155571 -307.096903) (xy 436.132445 -307.144924) (xy 436.102421 -307.188961) (xy 436.066169 -307.228032)
			(xy 436.024498 -307.261263) (xy 435.97834 -307.287912) (xy 435.928726 -307.307384) (xy 435.876764 -307.319244)
			(xy 435.823614 -307.323228) (xy 435.770464 -307.319244) (xy 435.718502 -307.307384) (xy 435.668888 -307.287912)
			(xy 435.62273 -307.261263) (xy 435.581059 -307.228032) (xy 435.544807 -307.188961) (xy 435.514783 -307.144924)
			(xy 435.491657 -307.096903) (xy 435.475947 -307.045973) (xy 435.468004 -306.993269) (xy 421.091624 -306.993269)
			(xy 421.083681 -307.045973) (xy 421.067971 -307.096903) (xy 421.044845 -307.144924) (xy 421.014821 -307.188961)
			(xy 420.978569 -307.228032) (xy 420.936898 -307.261263) (xy 420.89074 -307.287912) (xy 420.841126 -307.307384)
			(xy 420.789164 -307.319244) (xy 420.736014 -307.323228) (xy 420.682864 -307.319244) (xy 420.630902 -307.307384)
			(xy 420.581288 -307.287912) (xy 420.53513 -307.261263) (xy 420.493459 -307.228032) (xy 420.457207 -307.188961)
			(xy 420.427183 -307.144924) (xy 420.404057 -307.096903) (xy 420.388347 -307.045973) (xy 420.380404 -306.993269)
			(xy 405.978618 -306.993269) (xy 405.978618 -306.993605) (xy 405.970463 -307.046995) (xy 405.954339 -307.09854)
			(xy 405.930617 -307.14706) (xy 405.89984 -307.191441) (xy 405.862714 -307.230666) (xy 405.820091 -307.263835)
			(xy 405.772948 -307.290188) (xy 405.722366 -307.30912) (xy 405.669506 -307.320197) (xy 405.642572 -307.32222)
			(xy 405.6272 -307.32361) (xy 405.598308 -307.334426) (xy 405.573956 -307.353366) (xy 405.55636 -307.378707)
			(xy 405.547121 -307.408141) (xy 405.54656 -307.423566) (xy 405.54656 -307.843407) (xy 424.480472 -307.843407)
			(xy 424.480472 -307.790109) (xy 424.488415 -307.737405) (xy 424.504125 -307.686475) (xy 424.527251 -307.638454)
			(xy 424.557275 -307.594417) (xy 424.593527 -307.555346) (xy 424.635198 -307.522115) (xy 424.681356 -307.495466)
			(xy 424.73097 -307.475994) (xy 424.782932 -307.464134) (xy 424.836082 -307.460151) (xy 424.889232 -307.464134)
			(xy 424.941194 -307.475994) (xy 424.990808 -307.495466) (xy 425.036966 -307.522115) (xy 425.078637 -307.555346)
			(xy 425.114889 -307.594417) (xy 425.144913 -307.638454) (xy 425.168039 -307.686475) (xy 425.183749 -307.737405)
			(xy 425.191692 -307.790109) (xy 425.19219 -307.816758) (xy 425.191692 -307.843407) (xy 439.568072 -307.843407)
			(xy 439.568072 -307.790109) (xy 439.576015 -307.737405) (xy 439.591725 -307.686475) (xy 439.614851 -307.638454)
			(xy 439.644875 -307.594417) (xy 439.681127 -307.555346) (xy 439.722798 -307.522115) (xy 439.768956 -307.495466)
			(xy 439.81857 -307.475994) (xy 439.870532 -307.464134) (xy 439.923682 -307.460151) (xy 439.976832 -307.464134)
			(xy 440.028794 -307.475994) (xy 440.078408 -307.495466) (xy 440.124566 -307.522115) (xy 440.166237 -307.555346)
			(xy 440.202489 -307.594417) (xy 440.232513 -307.638454) (xy 440.255639 -307.686475) (xy 440.271349 -307.737405)
			(xy 440.279292 -307.790109) (xy 440.27979 -307.816758) (xy 440.279292 -307.843407) (xy 440.271349 -307.896111)
			(xy 440.255639 -307.947041) (xy 440.232513 -307.995062) (xy 440.202489 -308.039099) (xy 440.166237 -308.07817)
			(xy 440.124566 -308.111401) (xy 440.078408 -308.13805) (xy 440.028794 -308.157522) (xy 439.976832 -308.169382)
			(xy 439.923682 -308.173366) (xy 439.870532 -308.169382) (xy 439.81857 -308.157522) (xy 439.768956 -308.13805)
			(xy 439.722798 -308.111401) (xy 439.681127 -308.07817) (xy 439.644875 -308.039099) (xy 439.614851 -307.995062)
			(xy 439.591725 -307.947041) (xy 439.576015 -307.896111) (xy 439.568072 -307.843407) (xy 425.191692 -307.843407)
			(xy 425.183749 -307.896111) (xy 425.168039 -307.947041) (xy 425.144913 -307.995062) (xy 425.114889 -308.039099)
			(xy 425.078637 -308.07817) (xy 425.036966 -308.111401) (xy 424.990808 -308.13805) (xy 424.941194 -308.157522)
			(xy 424.889232 -308.169382) (xy 424.836082 -308.173366) (xy 424.782932 -308.169382) (xy 424.73097 -308.157522)
			(xy 424.681356 -308.13805) (xy 424.635198 -308.111401) (xy 424.593527 -308.07817) (xy 424.557275 -308.039099)
			(xy 424.527251 -307.995062) (xy 424.504125 -307.947041) (xy 424.488415 -307.896111) (xy 424.480472 -307.843407)
			(xy 405.54656 -307.843407) (xy 405.54656 -308.693291) (xy 420.380404 -308.693291) (xy 420.380404 -308.639993)
			(xy 420.388347 -308.587289) (xy 420.404057 -308.536359) (xy 420.427183 -308.488338) (xy 420.457207 -308.444301)
			(xy 420.493459 -308.40523) (xy 420.53513 -308.371999) (xy 420.581288 -308.34535) (xy 420.630902 -308.325878)
			(xy 420.682864 -308.314018) (xy 420.736014 -308.310035) (xy 420.789164 -308.314018) (xy 420.841126 -308.325878)
			(xy 420.89074 -308.34535) (xy 420.936898 -308.371999) (xy 420.978569 -308.40523) (xy 421.014821 -308.444301)
			(xy 421.044845 -308.488338) (xy 421.067971 -308.536359) (xy 421.083681 -308.587289) (xy 421.091624 -308.639993)
			(xy 421.092122 -308.666642) (xy 421.091624 -308.693291) (xy 435.468004 -308.693291) (xy 435.468004 -308.639993)
			(xy 435.475947 -308.587289) (xy 435.491657 -308.536359) (xy 435.514783 -308.488338) (xy 435.544807 -308.444301)
			(xy 435.581059 -308.40523) (xy 435.62273 -308.371999) (xy 435.668888 -308.34535) (xy 435.718502 -308.325878)
			(xy 435.770464 -308.314018) (xy 435.823614 -308.310035) (xy 435.876764 -308.314018) (xy 435.928726 -308.325878)
			(xy 435.97834 -308.34535) (xy 436.024498 -308.371999) (xy 436.066169 -308.40523) (xy 436.102421 -308.444301)
			(xy 436.132445 -308.488338) (xy 436.155571 -308.536359) (xy 436.171281 -308.587289) (xy 436.179224 -308.639993)
			(xy 436.179722 -308.666642) (xy 436.179224 -308.693291) (xy 436.171281 -308.745995) (xy 436.155571 -308.796925)
			(xy 436.132445 -308.844946) (xy 436.102421 -308.888983) (xy 436.066169 -308.928054) (xy 436.024498 -308.961285)
			(xy 435.97834 -308.987934) (xy 435.928726 -309.007406) (xy 435.876764 -309.019266) (xy 435.823614 -309.02325)
			(xy 435.770464 -309.019266) (xy 435.718502 -309.007406) (xy 435.668888 -308.987934) (xy 435.62273 -308.961285)
			(xy 435.581059 -308.928054) (xy 435.544807 -308.888983) (xy 435.514783 -308.844946) (xy 435.491657 -308.796925)
			(xy 435.475947 -308.745995) (xy 435.468004 -308.693291) (xy 421.091624 -308.693291) (xy 421.083681 -308.745995)
			(xy 421.067971 -308.796925) (xy 421.044845 -308.844946) (xy 421.014821 -308.888983) (xy 420.978569 -308.928054)
			(xy 420.936898 -308.961285) (xy 420.89074 -308.987934) (xy 420.841126 -309.007406) (xy 420.789164 -309.019266)
			(xy 420.736014 -309.02325) (xy 420.682864 -309.019266) (xy 420.630902 -309.007406) (xy 420.581288 -308.987934)
			(xy 420.53513 -308.961285) (xy 420.493459 -308.928054) (xy 420.457207 -308.888983) (xy 420.427183 -308.844946)
			(xy 420.404057 -308.796925) (xy 420.388347 -308.745995) (xy 420.380404 -308.693291) (xy 405.54656 -308.693291)
			(xy 405.54656 -309.543175) (xy 424.480472 -309.543175) (xy 424.480472 -309.489877) (xy 424.488415 -309.437173)
			(xy 424.504125 -309.386243) (xy 424.527251 -309.338222) (xy 424.557275 -309.294185) (xy 424.593527 -309.255114)
			(xy 424.635198 -309.221883) (xy 424.681356 -309.195234) (xy 424.73097 -309.175762) (xy 424.782932 -309.163902)
			(xy 424.836082 -309.159919) (xy 424.889232 -309.163902) (xy 424.941194 -309.175762) (xy 424.990808 -309.195234)
			(xy 425.036966 -309.221883) (xy 425.078637 -309.255114) (xy 425.114889 -309.294185) (xy 425.144913 -309.338222)
			(xy 425.168039 -309.386243) (xy 425.183749 -309.437173) (xy 425.191692 -309.489877) (xy 425.19219 -309.516526)
			(xy 425.191692 -309.543175) (xy 439.568072 -309.543175) (xy 439.568072 -309.489877) (xy 439.576015 -309.437173)
			(xy 439.591725 -309.386243) (xy 439.614851 -309.338222) (xy 439.644875 -309.294185) (xy 439.681127 -309.255114)
			(xy 439.722798 -309.221883) (xy 439.768956 -309.195234) (xy 439.81857 -309.175762) (xy 439.870532 -309.163902)
			(xy 439.923682 -309.159919) (xy 439.976832 -309.163902) (xy 440.028794 -309.175762) (xy 440.078408 -309.195234)
			(xy 440.124566 -309.221883) (xy 440.166237 -309.255114) (xy 440.202489 -309.294185) (xy 440.232513 -309.338222)
			(xy 440.255639 -309.386243) (xy 440.271349 -309.437173) (xy 440.279292 -309.489877) (xy 440.27979 -309.516526)
			(xy 440.279292 -309.543175) (xy 440.271349 -309.595879) (xy 440.255639 -309.646809) (xy 440.232513 -309.69483)
			(xy 440.202489 -309.738867) (xy 440.166237 -309.777938) (xy 440.124566 -309.811169) (xy 440.078408 -309.837818)
			(xy 440.028794 -309.85729) (xy 439.976832 -309.86915) (xy 439.923682 -309.873134) (xy 439.870532 -309.86915)
			(xy 439.81857 -309.85729) (xy 439.768956 -309.837818) (xy 439.722798 -309.811169) (xy 439.681127 -309.777938)
			(xy 439.644875 -309.738867) (xy 439.614851 -309.69483) (xy 439.591725 -309.646809) (xy 439.576015 -309.595879)
			(xy 439.568072 -309.543175) (xy 425.191692 -309.543175) (xy 425.183749 -309.595879) (xy 425.168039 -309.646809)
			(xy 425.144913 -309.69483) (xy 425.114889 -309.738867) (xy 425.078637 -309.777938) (xy 425.036966 -309.811169)
			(xy 424.990808 -309.837818) (xy 424.941194 -309.85729) (xy 424.889232 -309.86915) (xy 424.836082 -309.873134)
			(xy 424.782932 -309.86915) (xy 424.73097 -309.85729) (xy 424.681356 -309.837818) (xy 424.635198 -309.811169)
			(xy 424.593527 -309.777938) (xy 424.557275 -309.738867) (xy 424.527251 -309.69483) (xy 424.504125 -309.646809)
			(xy 424.488415 -309.595879) (xy 424.480472 -309.543175) (xy 405.54656 -309.543175) (xy 405.54656 -310.393313)
			(xy 420.380404 -310.393313) (xy 420.380404 -310.340015) (xy 420.388347 -310.287311) (xy 420.404057 -310.236381)
			(xy 420.427183 -310.18836) (xy 420.457207 -310.144323) (xy 420.493459 -310.105252) (xy 420.53513 -310.072021)
			(xy 420.581288 -310.045372) (xy 420.630902 -310.0259) (xy 420.682864 -310.01404) (xy 420.736014 -310.010057)
			(xy 420.789164 -310.01404) (xy 420.841126 -310.0259) (xy 420.89074 -310.045372) (xy 420.936898 -310.072021)
			(xy 420.978569 -310.105252) (xy 421.014821 -310.144323) (xy 421.044845 -310.18836) (xy 421.067971 -310.236381)
			(xy 421.083681 -310.287311) (xy 421.091624 -310.340015) (xy 421.092122 -310.366664) (xy 421.091624 -310.393313)
			(xy 435.468004 -310.393313) (xy 435.468004 -310.340015) (xy 435.475947 -310.287311) (xy 435.491657 -310.236381)
			(xy 435.514783 -310.18836) (xy 435.544807 -310.144323) (xy 435.581059 -310.105252) (xy 435.62273 -310.072021)
			(xy 435.668888 -310.045372) (xy 435.718502 -310.0259) (xy 435.770464 -310.01404) (xy 435.823614 -310.010057)
			(xy 435.876764 -310.01404) (xy 435.928726 -310.0259) (xy 435.97834 -310.045372) (xy 436.024498 -310.072021)
			(xy 436.066169 -310.105252) (xy 436.102421 -310.144323) (xy 436.132445 -310.18836) (xy 436.155571 -310.236381)
			(xy 436.171281 -310.287311) (xy 436.179224 -310.340015) (xy 436.179722 -310.366664) (xy 436.179224 -310.393313)
			(xy 436.171281 -310.446017) (xy 436.155571 -310.496947) (xy 436.132445 -310.544968) (xy 436.102421 -310.589005)
			(xy 436.066169 -310.628076) (xy 436.024498 -310.661307) (xy 435.97834 -310.687956) (xy 435.928726 -310.707428)
			(xy 435.876764 -310.719288) (xy 435.823614 -310.723272) (xy 435.770464 -310.719288) (xy 435.718502 -310.707428)
			(xy 435.668888 -310.687956) (xy 435.62273 -310.661307) (xy 435.581059 -310.628076) (xy 435.544807 -310.589005)
			(xy 435.514783 -310.544968) (xy 435.491657 -310.496947) (xy 435.475947 -310.446017) (xy 435.468004 -310.393313)
			(xy 421.091624 -310.393313) (xy 421.083681 -310.446017) (xy 421.067971 -310.496947) (xy 421.044845 -310.544968)
			(xy 421.014821 -310.589005) (xy 420.978569 -310.628076) (xy 420.936898 -310.661307) (xy 420.89074 -310.687956)
			(xy 420.841126 -310.707428) (xy 420.789164 -310.719288) (xy 420.736014 -310.723272) (xy 420.682864 -310.719288)
			(xy 420.630902 -310.707428) (xy 420.581288 -310.687956) (xy 420.53513 -310.661307) (xy 420.493459 -310.628076)
			(xy 420.457207 -310.589005) (xy 420.427183 -310.544968) (xy 420.404057 -310.496947) (xy 420.388347 -310.446017)
			(xy 420.380404 -310.393313) (xy 405.54656 -310.393313) (xy 405.54656 -311.243197) (xy 424.480472 -311.243197)
			(xy 424.480472 -311.189899) (xy 424.488415 -311.137195) (xy 424.504125 -311.086265) (xy 424.527251 -311.038244)
			(xy 424.557275 -310.994207) (xy 424.593527 -310.955136) (xy 424.635198 -310.921905) (xy 424.681356 -310.895256)
			(xy 424.73097 -310.875784) (xy 424.782932 -310.863924) (xy 424.836082 -310.859941) (xy 424.889232 -310.863924)
			(xy 424.941194 -310.875784) (xy 424.990808 -310.895256) (xy 425.036966 -310.921905) (xy 425.078637 -310.955136)
			(xy 425.114889 -310.994207) (xy 425.144913 -311.038244) (xy 425.168039 -311.086265) (xy 425.183749 -311.137195)
			(xy 425.191692 -311.189899) (xy 425.19219 -311.216548) (xy 425.191692 -311.243197) (xy 439.568072 -311.243197)
			(xy 439.568072 -311.189899) (xy 439.576015 -311.137195) (xy 439.591725 -311.086265) (xy 439.614851 -311.038244)
			(xy 439.644875 -310.994207) (xy 439.681127 -310.955136) (xy 439.722798 -310.921905) (xy 439.768956 -310.895256)
			(xy 439.81857 -310.875784) (xy 439.870532 -310.863924) (xy 439.923682 -310.859941) (xy 439.976832 -310.863924)
			(xy 440.028794 -310.875784) (xy 440.078408 -310.895256) (xy 440.124566 -310.921905) (xy 440.166237 -310.955136)
			(xy 440.202489 -310.994207) (xy 440.232513 -311.038244) (xy 440.255639 -311.086265) (xy 440.271349 -311.137195)
			(xy 440.279292 -311.189899) (xy 440.27979 -311.216548) (xy 440.279292 -311.243197) (xy 440.271349 -311.295901)
			(xy 440.255639 -311.346831) (xy 440.232513 -311.394852) (xy 440.202489 -311.438889) (xy 440.166237 -311.47796)
			(xy 440.124566 -311.511191) (xy 440.078408 -311.53784) (xy 440.028794 -311.557312) (xy 439.976832 -311.569172)
			(xy 439.923682 -311.573156) (xy 439.870532 -311.569172) (xy 439.81857 -311.557312) (xy 439.768956 -311.53784)
			(xy 439.722798 -311.511191) (xy 439.681127 -311.47796) (xy 439.644875 -311.438889) (xy 439.614851 -311.394852)
			(xy 439.591725 -311.346831) (xy 439.576015 -311.295901) (xy 439.568072 -311.243197) (xy 425.191692 -311.243197)
			(xy 425.183749 -311.295901) (xy 425.168039 -311.346831) (xy 425.144913 -311.394852) (xy 425.114889 -311.438889)
			(xy 425.078637 -311.47796) (xy 425.036966 -311.511191) (xy 424.990808 -311.53784) (xy 424.941194 -311.557312)
			(xy 424.889232 -311.569172) (xy 424.836082 -311.573156) (xy 424.782932 -311.569172) (xy 424.73097 -311.557312)
			(xy 424.681356 -311.53784) (xy 424.635198 -311.511191) (xy 424.593527 -311.47796) (xy 424.557275 -311.438889)
			(xy 424.527251 -311.394852) (xy 424.504125 -311.346831) (xy 424.488415 -311.295901) (xy 424.480472 -311.243197)
			(xy 405.54656 -311.243197) (xy 405.54656 -312.093335) (xy 420.380404 -312.093335) (xy 420.380404 -312.040037)
			(xy 420.388347 -311.987333) (xy 420.404057 -311.936403) (xy 420.427183 -311.888382) (xy 420.457207 -311.844345)
			(xy 420.493459 -311.805274) (xy 420.53513 -311.772043) (xy 420.581288 -311.745394) (xy 420.630902 -311.725922)
			(xy 420.682864 -311.714062) (xy 420.736014 -311.710079) (xy 420.789164 -311.714062) (xy 420.841126 -311.725922)
			(xy 420.89074 -311.745394) (xy 420.936898 -311.772043) (xy 420.978569 -311.805274) (xy 421.014821 -311.844345)
			(xy 421.044845 -311.888382) (xy 421.067971 -311.936403) (xy 421.083681 -311.987333) (xy 421.091624 -312.040037)
			(xy 421.092122 -312.066686) (xy 421.091624 -312.093335) (xy 424.480472 -312.093335) (xy 424.480472 -312.040037)
			(xy 424.488415 -311.987333) (xy 424.504125 -311.936403) (xy 424.527251 -311.888382) (xy 424.557275 -311.844345)
			(xy 424.593527 -311.805274) (xy 424.635198 -311.772043) (xy 424.681356 -311.745394) (xy 424.73097 -311.725922)
			(xy 424.782932 -311.714062) (xy 424.836082 -311.710079) (xy 424.889232 -311.714062) (xy 424.941194 -311.725922)
			(xy 424.990808 -311.745394) (xy 425.036966 -311.772043) (xy 425.078637 -311.805274) (xy 425.114889 -311.844345)
			(xy 425.144913 -311.888382) (xy 425.168039 -311.936403) (xy 425.183749 -311.987333) (xy 425.191692 -312.040037)
			(xy 425.19219 -312.066686) (xy 425.191692 -312.093335) (xy 435.468004 -312.093335) (xy 435.468004 -312.040037)
			(xy 435.475947 -311.987333) (xy 435.491657 -311.936403) (xy 435.514783 -311.888382) (xy 435.544807 -311.844345)
			(xy 435.581059 -311.805274) (xy 435.62273 -311.772043) (xy 435.668888 -311.745394) (xy 435.718502 -311.725922)
			(xy 435.770464 -311.714062) (xy 435.823614 -311.710079) (xy 435.876764 -311.714062) (xy 435.928726 -311.725922)
			(xy 435.97834 -311.745394) (xy 436.024498 -311.772043) (xy 436.066169 -311.805274) (xy 436.102421 -311.844345)
			(xy 436.132445 -311.888382) (xy 436.155571 -311.936403) (xy 436.171281 -311.987333) (xy 436.179224 -312.040037)
			(xy 436.179722 -312.066686) (xy 436.179224 -312.093335) (xy 439.568072 -312.093335) (xy 439.568072 -312.040037)
			(xy 439.576015 -311.987333) (xy 439.591725 -311.936403) (xy 439.614851 -311.888382) (xy 439.644875 -311.844345)
			(xy 439.681127 -311.805274) (xy 439.722798 -311.772043) (xy 439.768956 -311.745394) (xy 439.81857 -311.725922)
			(xy 439.870532 -311.714062) (xy 439.923682 -311.710079) (xy 439.976832 -311.714062) (xy 440.028794 -311.725922)
			(xy 440.078408 -311.745394) (xy 440.124566 -311.772043) (xy 440.166237 -311.805274) (xy 440.202489 -311.844345)
			(xy 440.232513 -311.888382) (xy 440.255639 -311.936403) (xy 440.271349 -311.987333) (xy 440.279292 -312.040037)
			(xy 440.27979 -312.066686) (xy 440.279292 -312.093335) (xy 440.271349 -312.146039) (xy 440.255639 -312.196969)
			(xy 440.232513 -312.24499) (xy 440.202489 -312.289027) (xy 440.166237 -312.328098) (xy 440.124566 -312.361329)
			(xy 440.078408 -312.387978) (xy 440.028794 -312.40745) (xy 439.976832 -312.41931) (xy 439.923682 -312.423294)
			(xy 439.870532 -312.41931) (xy 439.81857 -312.40745) (xy 439.768956 -312.387978) (xy 439.722798 -312.361329)
			(xy 439.681127 -312.328098) (xy 439.644875 -312.289027) (xy 439.614851 -312.24499) (xy 439.591725 -312.196969)
			(xy 439.576015 -312.146039) (xy 439.568072 -312.093335) (xy 436.179224 -312.093335) (xy 436.171281 -312.146039)
			(xy 436.155571 -312.196969) (xy 436.132445 -312.24499) (xy 436.102421 -312.289027) (xy 436.066169 -312.328098)
			(xy 436.024498 -312.361329) (xy 435.97834 -312.387978) (xy 435.928726 -312.40745) (xy 435.876764 -312.41931)
			(xy 435.823614 -312.423294) (xy 435.770464 -312.41931) (xy 435.718502 -312.40745) (xy 435.668888 -312.387978)
			(xy 435.62273 -312.361329) (xy 435.581059 -312.328098) (xy 435.544807 -312.289027) (xy 435.514783 -312.24499)
			(xy 435.491657 -312.196969) (xy 435.475947 -312.146039) (xy 435.468004 -312.093335) (xy 425.191692 -312.093335)
			(xy 425.183749 -312.146039) (xy 425.168039 -312.196969) (xy 425.144913 -312.24499) (xy 425.114889 -312.289027)
			(xy 425.078637 -312.328098) (xy 425.036966 -312.361329) (xy 424.990808 -312.387978) (xy 424.941194 -312.40745)
			(xy 424.889232 -312.41931) (xy 424.836082 -312.423294) (xy 424.782932 -312.41931) (xy 424.73097 -312.40745)
			(xy 424.681356 -312.387978) (xy 424.635198 -312.361329) (xy 424.593527 -312.328098) (xy 424.557275 -312.289027)
			(xy 424.527251 -312.24499) (xy 424.504125 -312.196969) (xy 424.488415 -312.146039) (xy 424.480472 -312.093335)
			(xy 421.091624 -312.093335) (xy 421.083681 -312.146039) (xy 421.067971 -312.196969) (xy 421.044845 -312.24499)
			(xy 421.014821 -312.289027) (xy 420.978569 -312.328098) (xy 420.936898 -312.361329) (xy 420.89074 -312.387978)
			(xy 420.841126 -312.40745) (xy 420.789164 -312.41931) (xy 420.736014 -312.423294) (xy 420.682864 -312.41931)
			(xy 420.630902 -312.40745) (xy 420.581288 -312.387978) (xy 420.53513 -312.361329) (xy 420.493459 -312.328098)
			(xy 420.457207 -312.289027) (xy 420.427183 -312.24499) (xy 420.404057 -312.196969) (xy 420.388347 -312.146039)
			(xy 420.380404 -312.093335) (xy 405.54656 -312.093335) (xy 405.54656 -312.943219) (xy 420.380404 -312.943219)
			(xy 420.380404 -312.889921) (xy 420.388347 -312.837217) (xy 420.404057 -312.786287) (xy 420.427183 -312.738266)
			(xy 420.457207 -312.694229) (xy 420.493459 -312.655158) (xy 420.53513 -312.621927) (xy 420.581288 -312.595278)
			(xy 420.630902 -312.575806) (xy 420.682864 -312.563946) (xy 420.736014 -312.559963) (xy 420.789164 -312.563946)
			(xy 420.841126 -312.575806) (xy 420.89074 -312.595278) (xy 420.936898 -312.621927) (xy 420.978569 -312.655158)
			(xy 421.014821 -312.694229) (xy 421.044845 -312.738266) (xy 421.067971 -312.786287) (xy 421.083681 -312.837217)
			(xy 421.091624 -312.889921) (xy 421.092122 -312.91657) (xy 421.091624 -312.943219) (xy 435.468004 -312.943219)
			(xy 435.468004 -312.889921) (xy 435.475947 -312.837217) (xy 435.491657 -312.786287) (xy 435.514783 -312.738266)
			(xy 435.544807 -312.694229) (xy 435.581059 -312.655158) (xy 435.62273 -312.621927) (xy 435.668888 -312.595278)
			(xy 435.718502 -312.575806) (xy 435.770464 -312.563946) (xy 435.823614 -312.559963) (xy 435.876764 -312.563946)
			(xy 435.928726 -312.575806) (xy 435.97834 -312.595278) (xy 436.024498 -312.621927) (xy 436.066169 -312.655158)
			(xy 436.102421 -312.694229) (xy 436.132445 -312.738266) (xy 436.155571 -312.786287) (xy 436.171281 -312.837217)
			(xy 436.179224 -312.889921) (xy 436.179722 -312.91657) (xy 436.179224 -312.943219) (xy 436.171281 -312.995923)
			(xy 436.155571 -313.046853) (xy 436.132445 -313.094874) (xy 436.102421 -313.138911) (xy 436.066169 -313.177982)
			(xy 436.024498 -313.211213) (xy 435.97834 -313.237862) (xy 435.928726 -313.257334) (xy 435.876764 -313.269194)
			(xy 435.823614 -313.273178) (xy 435.770464 -313.269194) (xy 435.718502 -313.257334) (xy 435.668888 -313.237862)
			(xy 435.62273 -313.211213) (xy 435.581059 -313.177982) (xy 435.544807 -313.138911) (xy 435.514783 -313.094874)
			(xy 435.491657 -313.046853) (xy 435.475947 -312.995923) (xy 435.468004 -312.943219) (xy 421.091624 -312.943219)
			(xy 421.083681 -312.995923) (xy 421.067971 -313.046853) (xy 421.044845 -313.094874) (xy 421.014821 -313.138911)
			(xy 420.978569 -313.177982) (xy 420.936898 -313.211213) (xy 420.89074 -313.237862) (xy 420.841126 -313.257334)
			(xy 420.789164 -313.269194) (xy 420.736014 -313.273178) (xy 420.682864 -313.269194) (xy 420.630902 -313.257334)
			(xy 420.581288 -313.237862) (xy 420.53513 -313.211213) (xy 420.493459 -313.177982) (xy 420.457207 -313.138911)
			(xy 420.427183 -313.094874) (xy 420.404057 -313.046853) (xy 420.388347 -312.995923) (xy 420.380404 -312.943219)
			(xy 405.54656 -312.943219) (xy 405.54656 -313.068208) (xy 406.271709 -313.793357) (xy 424.480472 -313.793357)
			(xy 424.480472 -313.740059) (xy 424.488415 -313.687355) (xy 424.504125 -313.636425) (xy 424.527251 -313.588404)
			(xy 424.557275 -313.544367) (xy 424.593527 -313.505296) (xy 424.635198 -313.472065) (xy 424.681356 -313.445416)
			(xy 424.73097 -313.425944) (xy 424.782932 -313.414084) (xy 424.836082 -313.410101) (xy 424.889232 -313.414084)
			(xy 424.941194 -313.425944) (xy 424.990808 -313.445416) (xy 425.036966 -313.472065) (xy 425.078637 -313.505296)
			(xy 425.114889 -313.544367) (xy 425.144913 -313.588404) (xy 425.168039 -313.636425) (xy 425.183749 -313.687355)
			(xy 425.191692 -313.740059) (xy 425.19219 -313.766708) (xy 425.191692 -313.793357) (xy 439.568072 -313.793357)
			(xy 439.568072 -313.740059) (xy 439.576015 -313.687355) (xy 439.591725 -313.636425) (xy 439.614851 -313.588404)
			(xy 439.644875 -313.544367) (xy 439.681127 -313.505296) (xy 439.722798 -313.472065) (xy 439.768956 -313.445416)
			(xy 439.81857 -313.425944) (xy 439.870532 -313.414084) (xy 439.923682 -313.410101) (xy 439.976832 -313.414084)
			(xy 440.028794 -313.425944) (xy 440.078408 -313.445416) (xy 440.124566 -313.472065) (xy 440.166237 -313.505296)
			(xy 440.202489 -313.544367) (xy 440.232513 -313.588404) (xy 440.255639 -313.636425) (xy 440.271349 -313.687355)
			(xy 440.279292 -313.740059) (xy 440.27979 -313.766708) (xy 440.279292 -313.793357) (xy 440.271349 -313.846061)
			(xy 440.255639 -313.896991) (xy 440.232513 -313.945012) (xy 440.202489 -313.989049) (xy 440.166237 -314.02812)
			(xy 440.124566 -314.061351) (xy 440.078408 -314.088) (xy 440.028794 -314.107472) (xy 439.976832 -314.119332)
			(xy 439.923682 -314.123316) (xy 439.870532 -314.119332) (xy 439.81857 -314.107472) (xy 439.768956 -314.088)
			(xy 439.722798 -314.061351) (xy 439.681127 -314.02812) (xy 439.644875 -313.989049) (xy 439.614851 -313.945012)
			(xy 439.591725 -313.896991) (xy 439.576015 -313.846061) (xy 439.568072 -313.793357) (xy 425.191692 -313.793357)
			(xy 425.183749 -313.846061) (xy 425.168039 -313.896991) (xy 425.144913 -313.945012) (xy 425.114889 -313.989049)
			(xy 425.078637 -314.02812) (xy 425.036966 -314.061351) (xy 424.990808 -314.088) (xy 424.941194 -314.107472)
			(xy 424.889232 -314.119332) (xy 424.836082 -314.123316) (xy 424.782932 -314.119332) (xy 424.73097 -314.107472)
			(xy 424.681356 -314.088) (xy 424.635198 -314.061351) (xy 424.593527 -314.02812) (xy 424.557275 -313.989049)
			(xy 424.527251 -313.945012) (xy 424.504125 -313.896991) (xy 424.488415 -313.846061) (xy 424.480472 -313.793357)
			(xy 406.271709 -313.793357) (xy 407.05786 -314.579508) (xy 409.41752 -314.579508)
		)
		(stroke
			(width 0)
			(type solid)
		)
		(fill yes)
		(layer "In15.Cu")
		(net "GND")
	)
	(gr_poly
		(pts
			(xy 161.699956 -316.004194) (xy 161.726253 -315.995655) (xy 161.780771 -315.986461) (xy 161.836057 -315.986461)
			(xy 161.890575 -315.995655) (xy 161.916872 -316.004194) (xy 161.925 -316.006988) (xy 163.901628 -316.006988)
			(xy 163.909756 -316.004194) (xy 163.936053 -315.995655) (xy 163.990571 -315.986461) (xy 164.045857 -315.986461)
			(xy 164.100375 -315.995655) (xy 164.126672 -316.004194) (xy 164.1348 -316.006988) (xy 169.235628 -316.006988)
			(xy 169.243756 -316.004194) (xy 169.270053 -315.995655) (xy 169.324571 -315.986461) (xy 169.379857 -315.986461)
			(xy 169.434375 -315.995655) (xy 169.460672 -316.004194) (xy 169.4688 -316.006988) (xy 171.445428 -316.006988)
			(xy 171.453556 -316.004194) (xy 171.479853 -315.995655) (xy 171.534371 -315.986461) (xy 171.589657 -315.986461)
			(xy 171.644175 -315.995655) (xy 171.670472 -316.004194) (xy 171.6786 -316.006988) (xy 172.61967 -316.006988)
			(xy 172.630592 -316.001146) (xy 172.656263 -315.988364) (xy 172.710671 -315.970254) (xy 172.767275 -315.961077)
			(xy 172.795946 -315.960506) (xy 172.824623 -315.961026) (xy 172.881239 -315.970181) (xy 172.93565 -315.988312)
			(xy 172.9613 -316.001146) (xy 172.972222 -316.006988) (xy 176.779428 -316.006988) (xy 176.787556 -316.004194)
			(xy 176.813853 -315.995655) (xy 176.868371 -315.986461) (xy 176.923657 -315.986461) (xy 176.978175 -315.995655)
			(xy 177.004472 -316.004194) (xy 177.0126 -316.006988) (xy 178.989228 -316.006988) (xy 178.997356 -316.004194)
			(xy 179.023653 -315.995655) (xy 179.078171 -315.986461) (xy 179.133457 -315.986461) (xy 179.187975 -315.995655)
			(xy 179.214272 -316.004194) (xy 179.2224 -316.006988) (xy 184.323228 -316.006988) (xy 184.331356 -316.004194)
			(xy 184.357653 -315.995655) (xy 184.412171 -315.986461) (xy 184.467457 -315.986461) (xy 184.521975 -315.995655)
			(xy 184.548272 -316.004194) (xy 184.5564 -316.006988) (xy 186.533028 -316.006988) (xy 186.541156 -316.004194)
			(xy 186.567453 -315.995655) (xy 186.621971 -315.986461) (xy 186.677257 -315.986461) (xy 186.731775 -315.995655)
			(xy 186.758072 -316.004194) (xy 186.7662 -316.006988) (xy 187.70727 -316.006988) (xy 187.718192 -316.001146)
			(xy 187.743863 -315.988364) (xy 187.798271 -315.970254) (xy 187.854875 -315.961077) (xy 187.883546 -315.960506)
			(xy 187.912223 -315.961026) (xy 187.968839 -315.970181) (xy 188.02325 -315.988312) (xy 188.0489 -316.001146)
			(xy 188.059822 -316.006988) (xy 191.867028 -316.006988) (xy 191.875156 -316.004194) (xy 191.901453 -315.995655)
			(xy 191.955971 -315.986461) (xy 192.011257 -315.986461) (xy 192.065775 -315.995655) (xy 192.092072 -316.004194)
			(xy 192.1002 -316.006988) (xy 194.076828 -316.006988) (xy 194.084956 -316.004194) (xy 194.111253 -315.995655)
			(xy 194.165771 -315.986461) (xy 194.221057 -315.986461) (xy 194.275575 -315.995655) (xy 194.301872 -316.004194)
			(xy 194.31 -316.006988) (xy 199.410828 -316.006988) (xy 199.418956 -316.004194) (xy 199.445253 -315.995655)
			(xy 199.499771 -315.986461) (xy 199.555057 -315.986461) (xy 199.609575 -315.995655) (xy 199.635872 -316.004194)
			(xy 199.644 -316.006988) (xy 201.620628 -316.006988) (xy 201.628756 -316.004194) (xy 201.655053 -315.995655)
			(xy 201.709571 -315.986461) (xy 201.764857 -315.986461) (xy 201.819375 -315.995655) (xy 201.845672 -316.004194)
			(xy 201.8538 -316.006988) (xy 202.79487 -316.006988) (xy 202.805792 -316.001146) (xy 202.831463 -315.988364)
			(xy 202.885871 -315.970254) (xy 202.942475 -315.961077) (xy 202.971146 -315.960506) (xy 202.999823 -315.961026)
			(xy 203.056439 -315.970181) (xy 203.11085 -315.988312) (xy 203.1365 -316.001146) (xy 203.147422 -316.006988)
			(xy 206.954628 -316.006988) (xy 206.962756 -316.004194) (xy 206.989053 -315.995655) (xy 207.043571 -315.986461)
			(xy 207.098857 -315.986461) (xy 207.153375 -315.995655) (xy 207.179672 -316.004194) (xy 207.1878 -316.006988)
			(xy 209.164428 -316.006988) (xy 209.172556 -316.004194) (xy 209.198853 -315.995655) (xy 209.253371 -315.986461)
			(xy 209.308657 -315.986461) (xy 209.363175 -315.995655) (xy 209.389472 -316.004194) (xy 209.3976 -316.006988)
			(xy 213.96452 -316.006988) (xy 217.35796 -312.613548) (xy 217.35796 -200.807828) (xy 213.73338 -197.183248)
			(xy 207.527906 -197.183248) (xy 207.513988 -197.183679) (xy 207.487185 -197.191198) (xy 207.463411 -197.205678)
			(xy 207.444433 -197.226043) (xy 207.431663 -197.250778) (xy 207.42605 -197.278043) (xy 207.42656 -197.29196)
			(xy 207.427322 -197.316598) (xy 207.426824 -197.343247) (xy 207.418881 -197.395951) (xy 207.403171 -197.446881)
			(xy 207.380045 -197.494902) (xy 207.350021 -197.538939) (xy 207.313769 -197.57801) (xy 207.272098 -197.611241)
			(xy 207.22594 -197.63789) (xy 207.176326 -197.657362) (xy 207.124364 -197.669222) (xy 207.071214 -197.673206)
			(xy 207.018064 -197.669222) (xy 206.966102 -197.657362) (xy 206.916488 -197.63789) (xy 206.87033 -197.611241)
			(xy 206.828659 -197.57801) (xy 206.792407 -197.538939) (xy 206.762383 -197.494902) (xy 206.739257 -197.446881)
			(xy 206.723547 -197.395951) (xy 206.715604 -197.343247) (xy 206.715106 -197.316598) (xy 206.715868 -197.29196)
			(xy 206.716419 -197.278039) (xy 206.710804 -197.25076) (xy 206.698029 -197.226012) (xy 206.679045 -197.205634)
			(xy 206.655261 -197.191142) (xy 206.628447 -197.183614) (xy 206.614522 -197.183248) (xy 205.37678 -197.183248)
			(xy 203.071222 -194.87769) (xy 203.060704 -194.86791) (xy 203.035526 -194.85412) (xy 203.007502 -194.847892)
			(xy 202.978853 -194.849717) (xy 202.951847 -194.859452) (xy 202.928622 -194.876326) (xy 202.911018 -194.899002)
			(xy 202.900428 -194.925685) (xy 202.898502 -194.93992) (xy 202.895486 -194.966017) (xy 202.882766 -195.016988)
			(xy 202.862703 -195.06554) (xy 202.835732 -195.110621) (xy 202.802437 -195.151257) (xy 202.763539 -195.186566)
			(xy 202.71988 -195.215784) (xy 202.672406 -195.238278) (xy 202.622145 -195.253562) (xy 202.570185 -195.261303)
			(xy 202.543918 -195.261738) (xy 202.515933 -195.26119) (xy 202.460652 -195.252438) (xy 202.407421 -195.235145)
			(xy 202.35755 -195.209739) (xy 202.312267 -195.176843) (xy 202.272688 -195.137269) (xy 202.239787 -195.091991)
			(xy 202.214373 -195.042124) (xy 202.197073 -194.988895) (xy 202.188313 -194.933615) (xy 202.18781 -194.90563)
			(xy 202.188363 -194.877211) (xy 202.197392 -194.821095) (xy 202.215225 -194.767128) (xy 202.241409 -194.716681)
			(xy 202.257914 -194.69354) (xy 202.265911 -194.681973) (xy 202.275835 -194.655671) (xy 202.278215 -194.627661)
			(xy 202.27287 -194.600062) (xy 202.260206 -194.574965) (xy 202.24118 -194.55427) (xy 202.217235 -194.539544)
			(xy 202.190182 -194.531901) (xy 202.176126 -194.531488) (xy 199.229472 -194.531488) (xy 199.21421 -194.532003)
			(xy 199.185046 -194.541013) (xy 199.159835 -194.558223) (xy 199.140822 -194.582103) (xy 199.129697 -194.610527)
			(xy 199.127449 -194.640969) (xy 199.130412 -194.655948) (xy 199.135044 -194.677237) (xy 199.140016 -194.720523)
			(xy 199.140318 -194.742308) (xy 199.139832 -194.769559) (xy 199.132076 -194.823507) (xy 199.116721 -194.875802)
			(xy 199.094079 -194.925379) (xy 199.064613 -194.971229) (xy 199.028922 -195.01242) (xy 198.987731 -195.048111)
			(xy 198.941881 -195.077577) (xy 198.892304 -195.100219) (xy 198.840009 -195.115574) (xy 198.786061 -195.12333)
			(xy 198.731559 -195.12333) (xy 198.677611 -195.115574) (xy 198.625316 -195.100219) (xy 198.575739 -195.077577)
			(xy 198.529889 -195.048111) (xy 198.488698 -195.01242) (xy 198.453007 -194.971229) (xy 198.423541 -194.925379)
			(xy 198.400899 -194.875802) (xy 198.385544 -194.823507) (xy 198.377788 -194.769559) (xy 198.377302 -194.742308)
			(xy 198.377612 -194.720523) (xy 198.382578 -194.677237) (xy 198.387208 -194.655948) (xy 198.390141 -194.640961)
			(xy 198.387918 -194.610515) (xy 198.376806 -194.582083) (xy 198.357796 -194.558199) (xy 198.332582 -194.540991)
			(xy 198.303411 -194.531994) (xy 198.288148 -194.531488) (xy 195.864988 -194.531488) (xy 195.851412 -194.531908)
			(xy 195.825219 -194.539056) (xy 195.801844 -194.552868) (xy 195.782946 -194.572362) (xy 195.769868 -194.596156)
			(xy 195.763538 -194.622559) (xy 195.764405 -194.649696) (xy 195.76796 -194.662806) (xy 195.775192 -194.688166)
			(xy 195.782965 -194.740325) (xy 195.783454 -194.766692) (xy 195.782956 -194.793341) (xy 195.775013 -194.846045)
			(xy 195.759303 -194.896975) (xy 195.736177 -194.944996) (xy 195.706153 -194.989033) (xy 195.669901 -195.028104)
			(xy 195.62823 -195.061335) (xy 195.582072 -195.087984) (xy 195.532458 -195.107456) (xy 195.480496 -195.119316)
			(xy 195.427346 -195.1233) (xy 195.374196 -195.119316) (xy 195.322234 -195.107456) (xy 195.27262 -195.087984)
			(xy 195.226462 -195.061335) (xy 195.184791 -195.028104) (xy 195.148539 -194.989033) (xy 195.118515 -194.944996)
			(xy 195.095389 -194.896975) (xy 195.079679 -194.846045) (xy 195.071736 -194.793341) (xy 195.071238 -194.766692)
			(xy 195.071716 -194.740324) (xy 195.079498 -194.688166) (xy 195.086732 -194.662806) (xy 195.090288 -194.649704)
			(xy 195.091103 -194.622578) (xy 195.084746 -194.596194) (xy 195.071666 -194.572415) (xy 195.052786 -194.55292)
			(xy 195.029439 -194.539085) (xy 195.003273 -194.531886) (xy 194.989704 -194.531488) (xy 188.321188 -194.531488)
			(xy 188.307612 -194.531908) (xy 188.281419 -194.539056) (xy 188.258044 -194.552868) (xy 188.239146 -194.572362)
			(xy 188.226068 -194.596156) (xy 188.219738 -194.622559) (xy 188.220605 -194.649696) (xy 188.22416 -194.662806)
			(xy 188.231392 -194.688166) (xy 188.239165 -194.740325) (xy 188.239654 -194.766692) (xy 188.239156 -194.793341)
			(xy 188.231213 -194.846045) (xy 188.215503 -194.896975) (xy 188.192377 -194.944996) (xy 188.162353 -194.989033)
			(xy 188.126101 -195.028104) (xy 188.08443 -195.061335) (xy 188.038272 -195.087984) (xy 187.988658 -195.107456)
			(xy 187.936696 -195.119316) (xy 187.883546 -195.1233) (xy 187.830396 -195.119316) (xy 187.778434 -195.107456)
			(xy 187.72882 -195.087984) (xy 187.682662 -195.061335) (xy 187.640991 -195.028104) (xy 187.604739 -194.989033)
			(xy 187.574715 -194.944996) (xy 187.551589 -194.896975) (xy 187.535879 -194.846045) (xy 187.527936 -194.793341)
			(xy 187.527438 -194.766692) (xy 187.527916 -194.740324) (xy 187.535698 -194.688166) (xy 187.542932 -194.662806)
			(xy 187.546488 -194.649704) (xy 187.547303 -194.622578) (xy 187.540946 -194.596194) (xy 187.527866 -194.572415)
			(xy 187.508986 -194.55292) (xy 187.485639 -194.539085) (xy 187.459473 -194.531886) (xy 187.445904 -194.531488)
			(xy 183.441086 -194.531488) (xy 183.435752 -194.575938) (xy 183.431864 -194.603297) (xy 183.417221 -194.656581)
			(xy 183.395047 -194.707196) (xy 183.365804 -194.754083) (xy 183.330104 -194.796262) (xy 183.288694 -194.832852)
			(xy 183.24244 -194.863086) (xy 183.192309 -194.886333) (xy 183.139349 -194.902106) (xy 183.084668 -194.910076)
			(xy 183.029408 -194.910076) (xy 182.974727 -194.902106) (xy 182.921767 -194.886333) (xy 182.871636 -194.863086)
			(xy 182.825382 -194.832852) (xy 182.783972 -194.796262) (xy 182.748272 -194.754083) (xy 182.719029 -194.707196)
			(xy 182.696855 -194.656581) (xy 182.682212 -194.603297) (xy 182.678324 -194.575938) (xy 182.67299 -194.531488)
			(xy 180.751988 -194.531488) (xy 180.738412 -194.531908) (xy 180.712219 -194.539056) (xy 180.688844 -194.552868)
			(xy 180.669946 -194.572362) (xy 180.656868 -194.596156) (xy 180.650538 -194.622559) (xy 180.651405 -194.649696)
			(xy 180.65496 -194.662806) (xy 180.662192 -194.688166) (xy 180.669965 -194.740325) (xy 180.670454 -194.766692)
			(xy 180.669956 -194.793341) (xy 180.662013 -194.846045) (xy 180.646303 -194.896975) (xy 180.623177 -194.944996)
			(xy 180.593153 -194.989033) (xy 180.556901 -195.028104) (xy 180.51523 -195.061335) (xy 180.469072 -195.087984)
			(xy 180.419458 -195.107456) (xy 180.367496 -195.119316) (xy 180.314346 -195.1233) (xy 180.261196 -195.119316)
			(xy 180.209234 -195.107456) (xy 180.15962 -195.087984) (xy 180.113462 -195.061335) (xy 180.071791 -195.028104)
			(xy 180.035539 -194.989033) (xy 180.005515 -194.944996) (xy 179.982389 -194.896975) (xy 179.966679 -194.846045)
			(xy 179.958736 -194.793341) (xy 179.958238 -194.766692) (xy 179.958716 -194.740324) (xy 179.966498 -194.688166)
			(xy 179.973732 -194.662806) (xy 179.977288 -194.649704) (xy 179.978103 -194.622578) (xy 179.971746 -194.596194)
			(xy 179.958666 -194.572415) (xy 179.939786 -194.55292) (xy 179.916439 -194.539085) (xy 179.890273 -194.531886)
			(xy 179.876704 -194.531488) (xy 173.233588 -194.531488) (xy 173.220012 -194.531908) (xy 173.193819 -194.539056)
			(xy 173.170444 -194.552868) (xy 173.151546 -194.572362) (xy 173.138468 -194.596156) (xy 173.132138 -194.622559)
			(xy 173.133005 -194.649696) (xy 173.13656 -194.662806) (xy 173.143792 -194.688166) (xy 173.151565 -194.740325)
			(xy 173.152054 -194.766692) (xy 173.151556 -194.793341) (xy 173.143613 -194.846045) (xy 173.127903 -194.896975)
			(xy 173.104777 -194.944996) (xy 173.074753 -194.989033) (xy 173.038501 -195.028104) (xy 172.99683 -195.061335)
			(xy 172.950672 -195.087984) (xy 172.901058 -195.107456) (xy 172.849096 -195.119316) (xy 172.795946 -195.1233)
			(xy 172.742796 -195.119316) (xy 172.690834 -195.107456) (xy 172.64122 -195.087984) (xy 172.595062 -195.061335)
			(xy 172.553391 -195.028104) (xy 172.517139 -194.989033) (xy 172.487115 -194.944996) (xy 172.463989 -194.896975)
			(xy 172.448279 -194.846045) (xy 172.440336 -194.793341) (xy 172.439838 -194.766692) (xy 172.440316 -194.740324)
			(xy 172.448098 -194.688166) (xy 172.455332 -194.662806) (xy 172.458888 -194.649704) (xy 172.459703 -194.622578)
			(xy 172.453346 -194.596194) (xy 172.440266 -194.572415) (xy 172.421386 -194.55292) (xy 172.398039 -194.539085)
			(xy 172.371873 -194.531886) (xy 172.358304 -194.531488) (xy 165.689788 -194.531488) (xy 165.676212 -194.531908)
			(xy 165.650019 -194.539056) (xy 165.626644 -194.552868) (xy 165.607746 -194.572362) (xy 165.594668 -194.596156)
			(xy 165.588338 -194.622559) (xy 165.589205 -194.649696) (xy 165.59276 -194.662806) (xy 165.599992 -194.688166)
			(xy 165.607765 -194.740325) (xy 165.608254 -194.766692) (xy 165.607756 -194.793341) (xy 165.599813 -194.846045)
			(xy 165.584103 -194.896975) (xy 165.560977 -194.944996) (xy 165.530953 -194.989033) (xy 165.494701 -195.028104)
			(xy 165.45303 -195.061335) (xy 165.406872 -195.087984) (xy 165.357258 -195.107456) (xy 165.305296 -195.119316)
			(xy 165.252146 -195.1233) (xy 165.198996 -195.119316) (xy 165.147034 -195.107456) (xy 165.09742 -195.087984)
			(xy 165.051262 -195.061335) (xy 165.009591 -195.028104) (xy 164.973339 -194.989033) (xy 164.943315 -194.944996)
			(xy 164.920189 -194.896975) (xy 164.904479 -194.846045) (xy 164.896536 -194.793341) (xy 164.896038 -194.766692)
			(xy 164.896516 -194.740324) (xy 164.904298 -194.688166) (xy 164.911532 -194.662806) (xy 164.915088 -194.649704)
			(xy 164.915903 -194.622578) (xy 164.909546 -194.596194) (xy 164.896466 -194.572415) (xy 164.877586 -194.55292)
			(xy 164.854239 -194.539085) (xy 164.828073 -194.531886) (xy 164.814504 -194.531488) (xy 160.387792 -194.531488)
			(xy 160.373486 -194.531961) (xy 160.345992 -194.53988) (xy 160.321778 -194.55512) (xy 160.302747 -194.576485)
			(xy 160.290396 -194.602293) (xy 160.285696 -194.630516) (xy 160.286954 -194.644772) (xy 160.288041 -194.654897)
			(xy 160.289187 -194.675229) (xy 160.28924 -194.685412) (xy 160.28869 -194.713395) (xy 160.279934 -194.768673)
			(xy 160.262639 -194.8219) (xy 160.23723 -194.871767) (xy 160.204335 -194.917046) (xy 160.164761 -194.956622)
			(xy 160.119484 -194.98952) (xy 160.069619 -195.014931) (xy 160.016392 -195.032229) (xy 159.961115 -195.040989)
			(xy 159.933132 -195.04152) (xy 159.905531 -195.041003) (xy 159.85099 -195.032488) (xy 159.798418 -195.015656)
			(xy 159.749073 -194.990912) (xy 159.704138 -194.958848) (xy 159.664691 -194.920232) (xy 159.631677 -194.875991)
			(xy 159.605888 -194.827185) (xy 159.58794 -194.774982) (xy 159.582612 -194.747896) (xy 159.579721 -194.734317)
			(xy 159.567689 -194.709312) (xy 159.549372 -194.688466) (xy 159.52612 -194.67332) (xy 159.49965 -194.664989)
			(xy 159.471915 -194.664089) (xy 159.44496 -194.670686) (xy 159.420776 -194.684294) (xy 159.410654 -194.693794)
			(xy 159.11576 -194.988688) (xy 159.11576 -195.643225) (xy 176.540404 -195.643225) (xy 176.540404 -195.589927)
			(xy 176.548347 -195.537223) (xy 176.564057 -195.486293) (xy 176.587183 -195.438272) (xy 176.617207 -195.394235)
			(xy 176.653459 -195.355164) (xy 176.69513 -195.321933) (xy 176.741288 -195.295284) (xy 176.790902 -195.275812)
			(xy 176.842864 -195.263952) (xy 176.896014 -195.259969) (xy 176.949164 -195.263952) (xy 177.001126 -195.275812)
			(xy 177.05074 -195.295284) (xy 177.096898 -195.321933) (xy 177.138569 -195.355164) (xy 177.174821 -195.394235)
			(xy 177.204845 -195.438272) (xy 177.227971 -195.486293) (xy 177.243681 -195.537223) (xy 177.251624 -195.589927)
			(xy 177.252122 -195.616576) (xy 177.251624 -195.643225) (xy 191.628004 -195.643225) (xy 191.628004 -195.589927)
			(xy 191.635947 -195.537223) (xy 191.651657 -195.486293) (xy 191.674783 -195.438272) (xy 191.704807 -195.394235)
			(xy 191.741059 -195.355164) (xy 191.78273 -195.321933) (xy 191.828888 -195.295284) (xy 191.878502 -195.275812)
			(xy 191.930464 -195.263952) (xy 191.983614 -195.259969) (xy 192.036764 -195.263952) (xy 192.088726 -195.275812)
			(xy 192.13834 -195.295284) (xy 192.184498 -195.321933) (xy 192.226169 -195.355164) (xy 192.262421 -195.394235)
			(xy 192.292445 -195.438272) (xy 192.315571 -195.486293) (xy 192.331281 -195.537223) (xy 192.339224 -195.589927)
			(xy 192.339722 -195.616576) (xy 192.339224 -195.643225) (xy 192.331281 -195.695929) (xy 192.315571 -195.746859)
			(xy 192.292445 -195.79488) (xy 192.262421 -195.838917) (xy 192.226169 -195.877988) (xy 192.184498 -195.911219)
			(xy 192.13834 -195.937868) (xy 192.088726 -195.95734) (xy 192.036764 -195.9692) (xy 191.983614 -195.973184)
			(xy 191.930464 -195.9692) (xy 191.878502 -195.95734) (xy 191.828888 -195.937868) (xy 191.78273 -195.911219)
			(xy 191.741059 -195.877988) (xy 191.704807 -195.838917) (xy 191.674783 -195.79488) (xy 191.651657 -195.746859)
			(xy 191.635947 -195.695929) (xy 191.628004 -195.643225) (xy 177.251624 -195.643225) (xy 177.243681 -195.695929)
			(xy 177.227971 -195.746859) (xy 177.204845 -195.79488) (xy 177.174821 -195.838917) (xy 177.138569 -195.877988)
			(xy 177.096898 -195.911219) (xy 177.05074 -195.937868) (xy 177.001126 -195.95734) (xy 176.949164 -195.9692)
			(xy 176.896014 -195.973184) (xy 176.842864 -195.9692) (xy 176.790902 -195.95734) (xy 176.741288 -195.937868)
			(xy 176.69513 -195.911219) (xy 176.653459 -195.877988) (xy 176.617207 -195.838917) (xy 176.587183 -195.79488)
			(xy 176.564057 -195.746859) (xy 176.548347 -195.695929) (xy 176.540404 -195.643225) (xy 159.11576 -195.643225)
			(xy 159.11576 -196.493363) (xy 172.440336 -196.493363) (xy 172.440336 -196.440065) (xy 172.448279 -196.387361)
			(xy 172.463989 -196.336431) (xy 172.487115 -196.28841) (xy 172.517139 -196.244373) (xy 172.553391 -196.205302)
			(xy 172.595062 -196.172071) (xy 172.64122 -196.145422) (xy 172.690834 -196.12595) (xy 172.742796 -196.11409)
			(xy 172.795946 -196.110107) (xy 172.849096 -196.11409) (xy 172.901058 -196.12595) (xy 172.950672 -196.145422)
			(xy 172.99683 -196.172071) (xy 173.038501 -196.205302) (xy 173.074753 -196.244373) (xy 173.104777 -196.28841)
			(xy 173.127903 -196.336431) (xy 173.143613 -196.387361) (xy 173.151556 -196.440065) (xy 173.152054 -196.466714)
			(xy 173.151556 -196.493363) (xy 187.527936 -196.493363) (xy 187.527936 -196.440065) (xy 187.535879 -196.387361)
			(xy 187.551589 -196.336431) (xy 187.574715 -196.28841) (xy 187.604739 -196.244373) (xy 187.640991 -196.205302)
			(xy 187.682662 -196.172071) (xy 187.72882 -196.145422) (xy 187.778434 -196.12595) (xy 187.830396 -196.11409)
			(xy 187.883546 -196.110107) (xy 187.936696 -196.11409) (xy 187.988658 -196.12595) (xy 188.038272 -196.145422)
			(xy 188.08443 -196.172071) (xy 188.126101 -196.205302) (xy 188.162353 -196.244373) (xy 188.192377 -196.28841)
			(xy 188.215503 -196.336431) (xy 188.231213 -196.387361) (xy 188.239156 -196.440065) (xy 188.239654 -196.466714)
			(xy 188.239156 -196.493363) (xy 202.615536 -196.493363) (xy 202.615536 -196.440065) (xy 202.623479 -196.387361)
			(xy 202.639189 -196.336431) (xy 202.662315 -196.28841) (xy 202.692339 -196.244373) (xy 202.728591 -196.205302)
			(xy 202.770262 -196.172071) (xy 202.81642 -196.145422) (xy 202.866034 -196.12595) (xy 202.917996 -196.11409)
			(xy 202.971146 -196.110107) (xy 203.024296 -196.11409) (xy 203.076258 -196.12595) (xy 203.125872 -196.145422)
			(xy 203.17203 -196.172071) (xy 203.213701 -196.205302) (xy 203.249953 -196.244373) (xy 203.279977 -196.28841)
			(xy 203.303103 -196.336431) (xy 203.318813 -196.387361) (xy 203.326756 -196.440065) (xy 203.327254 -196.466714)
			(xy 203.326756 -196.493363) (xy 203.318813 -196.546067) (xy 203.303103 -196.596997) (xy 203.279977 -196.645018)
			(xy 203.249953 -196.689055) (xy 203.213701 -196.728126) (xy 203.17203 -196.761357) (xy 203.125872 -196.788006)
			(xy 203.076258 -196.807478) (xy 203.024296 -196.819338) (xy 202.971146 -196.823322) (xy 202.917996 -196.819338)
			(xy 202.866034 -196.807478) (xy 202.81642 -196.788006) (xy 202.770262 -196.761357) (xy 202.728591 -196.728126)
			(xy 202.692339 -196.689055) (xy 202.662315 -196.645018) (xy 202.639189 -196.596997) (xy 202.623479 -196.546067)
			(xy 202.615536 -196.493363) (xy 188.239156 -196.493363) (xy 188.231213 -196.546067) (xy 188.215503 -196.596997)
			(xy 188.192377 -196.645018) (xy 188.162353 -196.689055) (xy 188.126101 -196.728126) (xy 188.08443 -196.761357)
			(xy 188.038272 -196.788006) (xy 187.988658 -196.807478) (xy 187.936696 -196.819338) (xy 187.883546 -196.823322)
			(xy 187.830396 -196.819338) (xy 187.778434 -196.807478) (xy 187.72882 -196.788006) (xy 187.682662 -196.761357)
			(xy 187.640991 -196.728126) (xy 187.604739 -196.689055) (xy 187.574715 -196.645018) (xy 187.551589 -196.596997)
			(xy 187.535879 -196.546067) (xy 187.527936 -196.493363) (xy 173.151556 -196.493363) (xy 173.143613 -196.546067)
			(xy 173.127903 -196.596997) (xy 173.104777 -196.645018) (xy 173.074753 -196.689055) (xy 173.038501 -196.728126)
			(xy 172.99683 -196.761357) (xy 172.950672 -196.788006) (xy 172.901058 -196.807478) (xy 172.849096 -196.819338)
			(xy 172.795946 -196.823322) (xy 172.742796 -196.819338) (xy 172.690834 -196.807478) (xy 172.64122 -196.788006)
			(xy 172.595062 -196.761357) (xy 172.553391 -196.728126) (xy 172.517139 -196.689055) (xy 172.487115 -196.645018)
			(xy 172.463989 -196.596997) (xy 172.448279 -196.546067) (xy 172.440336 -196.493363) (xy 159.11576 -196.493363)
			(xy 159.11576 -197.343247) (xy 176.540404 -197.343247) (xy 176.540404 -197.289949) (xy 176.548347 -197.237245)
			(xy 176.564057 -197.186315) (xy 176.587183 -197.138294) (xy 176.617207 -197.094257) (xy 176.653459 -197.055186)
			(xy 176.69513 -197.021955) (xy 176.741288 -196.995306) (xy 176.790902 -196.975834) (xy 176.842864 -196.963974)
			(xy 176.896014 -196.959991) (xy 176.949164 -196.963974) (xy 177.001126 -196.975834) (xy 177.05074 -196.995306)
			(xy 177.096898 -197.021955) (xy 177.138569 -197.055186) (xy 177.174821 -197.094257) (xy 177.204845 -197.138294)
			(xy 177.227971 -197.186315) (xy 177.243681 -197.237245) (xy 177.251624 -197.289949) (xy 177.252122 -197.316598)
			(xy 177.251624 -197.343247) (xy 191.628004 -197.343247) (xy 191.628004 -197.289949) (xy 191.635947 -197.237245)
			(xy 191.651657 -197.186315) (xy 191.674783 -197.138294) (xy 191.704807 -197.094257) (xy 191.741059 -197.055186)
			(xy 191.78273 -197.021955) (xy 191.828888 -196.995306) (xy 191.878502 -196.975834) (xy 191.930464 -196.963974)
			(xy 191.983614 -196.959991) (xy 192.036764 -196.963974) (xy 192.088726 -196.975834) (xy 192.13834 -196.995306)
			(xy 192.184498 -197.021955) (xy 192.226169 -197.055186) (xy 192.262421 -197.094257) (xy 192.292445 -197.138294)
			(xy 192.315571 -197.186315) (xy 192.331281 -197.237245) (xy 192.339224 -197.289949) (xy 192.339722 -197.316598)
			(xy 192.339224 -197.343247) (xy 192.331281 -197.395951) (xy 192.315571 -197.446881) (xy 192.292445 -197.494902)
			(xy 192.262421 -197.538939) (xy 192.226169 -197.57801) (xy 192.184498 -197.611241) (xy 192.13834 -197.63789)
			(xy 192.088726 -197.657362) (xy 192.036764 -197.669222) (xy 191.983614 -197.673206) (xy 191.930464 -197.669222)
			(xy 191.878502 -197.657362) (xy 191.828888 -197.63789) (xy 191.78273 -197.611241) (xy 191.741059 -197.57801)
			(xy 191.704807 -197.538939) (xy 191.674783 -197.494902) (xy 191.651657 -197.446881) (xy 191.635947 -197.395951)
			(xy 191.628004 -197.343247) (xy 177.251624 -197.343247) (xy 177.243681 -197.395951) (xy 177.227971 -197.446881)
			(xy 177.204845 -197.494902) (xy 177.174821 -197.538939) (xy 177.138569 -197.57801) (xy 177.096898 -197.611241)
			(xy 177.05074 -197.63789) (xy 177.001126 -197.657362) (xy 176.949164 -197.669222) (xy 176.896014 -197.673206)
			(xy 176.842864 -197.669222) (xy 176.790902 -197.657362) (xy 176.741288 -197.63789) (xy 176.69513 -197.611241)
			(xy 176.653459 -197.57801) (xy 176.617207 -197.538939) (xy 176.587183 -197.494902) (xy 176.564057 -197.446881)
			(xy 176.548347 -197.395951) (xy 176.540404 -197.343247) (xy 159.11576 -197.343247) (xy 159.11576 -198.193385)
			(xy 172.440336 -198.193385) (xy 172.440336 -198.140087) (xy 172.448279 -198.087383) (xy 172.463989 -198.036453)
			(xy 172.487115 -197.988432) (xy 172.517139 -197.944395) (xy 172.553391 -197.905324) (xy 172.595062 -197.872093)
			(xy 172.64122 -197.845444) (xy 172.690834 -197.825972) (xy 172.742796 -197.814112) (xy 172.795946 -197.810129)
			(xy 172.849096 -197.814112) (xy 172.901058 -197.825972) (xy 172.950672 -197.845444) (xy 172.99683 -197.872093)
			(xy 173.038501 -197.905324) (xy 173.074753 -197.944395) (xy 173.104777 -197.988432) (xy 173.127903 -198.036453)
			(xy 173.143613 -198.087383) (xy 173.151556 -198.140087) (xy 173.152054 -198.166736) (xy 173.151556 -198.193385)
			(xy 187.527936 -198.193385) (xy 187.527936 -198.140087) (xy 187.535879 -198.087383) (xy 187.551589 -198.036453)
			(xy 187.574715 -197.988432) (xy 187.604739 -197.944395) (xy 187.640991 -197.905324) (xy 187.682662 -197.872093)
			(xy 187.72882 -197.845444) (xy 187.778434 -197.825972) (xy 187.830396 -197.814112) (xy 187.883546 -197.810129)
			(xy 187.936696 -197.814112) (xy 187.988658 -197.825972) (xy 188.038272 -197.845444) (xy 188.08443 -197.872093)
			(xy 188.126101 -197.905324) (xy 188.162353 -197.944395) (xy 188.192377 -197.988432) (xy 188.215503 -198.036453)
			(xy 188.231213 -198.087383) (xy 188.239156 -198.140087) (xy 188.239654 -198.166736) (xy 188.239156 -198.193385)
			(xy 202.615536 -198.193385) (xy 202.615536 -198.140087) (xy 202.623479 -198.087383) (xy 202.639189 -198.036453)
			(xy 202.662315 -197.988432) (xy 202.692339 -197.944395) (xy 202.728591 -197.905324) (xy 202.770262 -197.872093)
			(xy 202.81642 -197.845444) (xy 202.866034 -197.825972) (xy 202.917996 -197.814112) (xy 202.971146 -197.810129)
			(xy 203.024296 -197.814112) (xy 203.076258 -197.825972) (xy 203.125872 -197.845444) (xy 203.17203 -197.872093)
			(xy 203.213701 -197.905324) (xy 203.249953 -197.944395) (xy 203.279977 -197.988432) (xy 203.303103 -198.036453)
			(xy 203.318813 -198.087383) (xy 203.326756 -198.140087) (xy 203.327254 -198.166736) (xy 203.326756 -198.193385)
			(xy 203.318813 -198.246089) (xy 203.303103 -198.297019) (xy 203.279977 -198.34504) (xy 203.249953 -198.389077)
			(xy 203.213701 -198.428148) (xy 203.17203 -198.461379) (xy 203.125872 -198.488028) (xy 203.076258 -198.5075)
			(xy 203.024296 -198.51936) (xy 202.971146 -198.523344) (xy 202.917996 -198.51936) (xy 202.866034 -198.5075)
			(xy 202.81642 -198.488028) (xy 202.770262 -198.461379) (xy 202.728591 -198.428148) (xy 202.692339 -198.389077)
			(xy 202.662315 -198.34504) (xy 202.639189 -198.297019) (xy 202.623479 -198.246089) (xy 202.615536 -198.193385)
			(xy 188.239156 -198.193385) (xy 188.231213 -198.246089) (xy 188.215503 -198.297019) (xy 188.192377 -198.34504)
			(xy 188.162353 -198.389077) (xy 188.126101 -198.428148) (xy 188.08443 -198.461379) (xy 188.038272 -198.488028)
			(xy 187.988658 -198.5075) (xy 187.936696 -198.51936) (xy 187.883546 -198.523344) (xy 187.830396 -198.51936)
			(xy 187.778434 -198.5075) (xy 187.72882 -198.488028) (xy 187.682662 -198.461379) (xy 187.640991 -198.428148)
			(xy 187.604739 -198.389077) (xy 187.574715 -198.34504) (xy 187.551589 -198.297019) (xy 187.535879 -198.246089)
			(xy 187.527936 -198.193385) (xy 173.151556 -198.193385) (xy 173.143613 -198.246089) (xy 173.127903 -198.297019)
			(xy 173.104777 -198.34504) (xy 173.074753 -198.389077) (xy 173.038501 -198.428148) (xy 172.99683 -198.461379)
			(xy 172.950672 -198.488028) (xy 172.901058 -198.5075) (xy 172.849096 -198.51936) (xy 172.795946 -198.523344)
			(xy 172.742796 -198.51936) (xy 172.690834 -198.5075) (xy 172.64122 -198.488028) (xy 172.595062 -198.461379)
			(xy 172.553391 -198.428148) (xy 172.517139 -198.389077) (xy 172.487115 -198.34504) (xy 172.463989 -198.297019)
			(xy 172.448279 -198.246089) (xy 172.440336 -198.193385) (xy 159.11576 -198.193385) (xy 159.11576 -199.043269)
			(xy 176.540404 -199.043269) (xy 176.540404 -198.989971) (xy 176.548347 -198.937267) (xy 176.564057 -198.886337)
			(xy 176.587183 -198.838316) (xy 176.617207 -198.794279) (xy 176.653459 -198.755208) (xy 176.69513 -198.721977)
			(xy 176.741288 -198.695328) (xy 176.790902 -198.675856) (xy 176.842864 -198.663996) (xy 176.896014 -198.660013)
			(xy 176.949164 -198.663996) (xy 177.001126 -198.675856) (xy 177.05074 -198.695328) (xy 177.096898 -198.721977)
			(xy 177.138569 -198.755208) (xy 177.174821 -198.794279) (xy 177.204845 -198.838316) (xy 177.227971 -198.886337)
			(xy 177.243681 -198.937267) (xy 177.251624 -198.989971) (xy 177.252122 -199.01662) (xy 177.251624 -199.043269)
			(xy 191.628004 -199.043269) (xy 191.628004 -198.989971) (xy 191.635947 -198.937267) (xy 191.651657 -198.886337)
			(xy 191.674783 -198.838316) (xy 191.704807 -198.794279) (xy 191.741059 -198.755208) (xy 191.78273 -198.721977)
			(xy 191.828888 -198.695328) (xy 191.878502 -198.675856) (xy 191.930464 -198.663996) (xy 191.983614 -198.660013)
			(xy 192.036764 -198.663996) (xy 192.088726 -198.675856) (xy 192.13834 -198.695328) (xy 192.184498 -198.721977)
			(xy 192.226169 -198.755208) (xy 192.262421 -198.794279) (xy 192.292445 -198.838316) (xy 192.315571 -198.886337)
			(xy 192.331281 -198.937267) (xy 192.339224 -198.989971) (xy 192.339722 -199.01662) (xy 192.339224 -199.043269)
			(xy 206.715604 -199.043269) (xy 206.715604 -198.989971) (xy 206.723547 -198.937267) (xy 206.739257 -198.886337)
			(xy 206.762383 -198.838316) (xy 206.792407 -198.794279) (xy 206.828659 -198.755208) (xy 206.87033 -198.721977)
			(xy 206.916488 -198.695328) (xy 206.966102 -198.675856) (xy 207.018064 -198.663996) (xy 207.071214 -198.660013)
			(xy 207.124364 -198.663996) (xy 207.176326 -198.675856) (xy 207.22594 -198.695328) (xy 207.272098 -198.721977)
			(xy 207.313769 -198.755208) (xy 207.350021 -198.794279) (xy 207.380045 -198.838316) (xy 207.403171 -198.886337)
			(xy 207.418881 -198.937267) (xy 207.426824 -198.989971) (xy 207.427322 -199.01662) (xy 207.426824 -199.043269)
			(xy 207.418881 -199.095973) (xy 207.403171 -199.146903) (xy 207.380045 -199.194924) (xy 207.350021 -199.238961)
			(xy 207.313769 -199.278032) (xy 207.272098 -199.311263) (xy 207.22594 -199.337912) (xy 207.176326 -199.357384)
			(xy 207.124364 -199.369244) (xy 207.071214 -199.373228) (xy 207.018064 -199.369244) (xy 206.966102 -199.357384)
			(xy 206.916488 -199.337912) (xy 206.87033 -199.311263) (xy 206.828659 -199.278032) (xy 206.792407 -199.238961)
			(xy 206.762383 -199.194924) (xy 206.739257 -199.146903) (xy 206.723547 -199.095973) (xy 206.715604 -199.043269)
			(xy 192.339224 -199.043269) (xy 192.331281 -199.095973) (xy 192.315571 -199.146903) (xy 192.292445 -199.194924)
			(xy 192.262421 -199.238961) (xy 192.226169 -199.278032) (xy 192.184498 -199.311263) (xy 192.13834 -199.337912)
			(xy 192.088726 -199.357384) (xy 192.036764 -199.369244) (xy 191.983614 -199.373228) (xy 191.930464 -199.369244)
			(xy 191.878502 -199.357384) (xy 191.828888 -199.337912) (xy 191.78273 -199.311263) (xy 191.741059 -199.278032)
			(xy 191.704807 -199.238961) (xy 191.674783 -199.194924) (xy 191.651657 -199.146903) (xy 191.635947 -199.095973)
			(xy 191.628004 -199.043269) (xy 177.251624 -199.043269) (xy 177.243681 -199.095973) (xy 177.227971 -199.146903)
			(xy 177.204845 -199.194924) (xy 177.174821 -199.238961) (xy 177.138569 -199.278032) (xy 177.096898 -199.311263)
			(xy 177.05074 -199.337912) (xy 177.001126 -199.357384) (xy 176.949164 -199.369244) (xy 176.896014 -199.373228)
			(xy 176.842864 -199.369244) (xy 176.790902 -199.357384) (xy 176.741288 -199.337912) (xy 176.69513 -199.311263)
			(xy 176.653459 -199.278032) (xy 176.617207 -199.238961) (xy 176.587183 -199.194924) (xy 176.564057 -199.146903)
			(xy 176.548347 -199.095973) (xy 176.540404 -199.043269) (xy 159.11576 -199.043269) (xy 159.11576 -199.893407)
			(xy 172.440336 -199.893407) (xy 172.440336 -199.840109) (xy 172.448279 -199.787405) (xy 172.463989 -199.736475)
			(xy 172.487115 -199.688454) (xy 172.517139 -199.644417) (xy 172.553391 -199.605346) (xy 172.595062 -199.572115)
			(xy 172.64122 -199.545466) (xy 172.690834 -199.525994) (xy 172.742796 -199.514134) (xy 172.795946 -199.510151)
			(xy 172.849096 -199.514134) (xy 172.901058 -199.525994) (xy 172.950672 -199.545466) (xy 172.99683 -199.572115)
			(xy 173.038501 -199.605346) (xy 173.074753 -199.644417) (xy 173.104777 -199.688454) (xy 173.127903 -199.736475)
			(xy 173.143613 -199.787405) (xy 173.151556 -199.840109) (xy 173.152054 -199.866758) (xy 173.151556 -199.893407)
			(xy 176.540404 -199.893407) (xy 176.540404 -199.840109) (xy 176.548347 -199.787405) (xy 176.564057 -199.736475)
			(xy 176.587183 -199.688454) (xy 176.617207 -199.644417) (xy 176.653459 -199.605346) (xy 176.69513 -199.572115)
			(xy 176.741288 -199.545466) (xy 176.790902 -199.525994) (xy 176.842864 -199.514134) (xy 176.896014 -199.510151)
			(xy 176.949164 -199.514134) (xy 177.001126 -199.525994) (xy 177.05074 -199.545466) (xy 177.096898 -199.572115)
			(xy 177.138569 -199.605346) (xy 177.174821 -199.644417) (xy 177.204845 -199.688454) (xy 177.227971 -199.736475)
			(xy 177.243681 -199.787405) (xy 177.251624 -199.840109) (xy 177.252122 -199.866758) (xy 177.251624 -199.893407)
			(xy 187.527936 -199.893407) (xy 187.527936 -199.840109) (xy 187.535879 -199.787405) (xy 187.551589 -199.736475)
			(xy 187.574715 -199.688454) (xy 187.604739 -199.644417) (xy 187.640991 -199.605346) (xy 187.682662 -199.572115)
			(xy 187.72882 -199.545466) (xy 187.778434 -199.525994) (xy 187.830396 -199.514134) (xy 187.883546 -199.510151)
			(xy 187.936696 -199.514134) (xy 187.988658 -199.525994) (xy 188.038272 -199.545466) (xy 188.08443 -199.572115)
			(xy 188.126101 -199.605346) (xy 188.162353 -199.644417) (xy 188.192377 -199.688454) (xy 188.215503 -199.736475)
			(xy 188.231213 -199.787405) (xy 188.239156 -199.840109) (xy 188.239654 -199.866758) (xy 188.239156 -199.893407)
			(xy 191.628004 -199.893407) (xy 191.628004 -199.840109) (xy 191.635947 -199.787405) (xy 191.651657 -199.736475)
			(xy 191.674783 -199.688454) (xy 191.704807 -199.644417) (xy 191.741059 -199.605346) (xy 191.78273 -199.572115)
			(xy 191.828888 -199.545466) (xy 191.878502 -199.525994) (xy 191.930464 -199.514134) (xy 191.983614 -199.510151)
			(xy 192.036764 -199.514134) (xy 192.088726 -199.525994) (xy 192.13834 -199.545466) (xy 192.184498 -199.572115)
			(xy 192.226169 -199.605346) (xy 192.262421 -199.644417) (xy 192.292445 -199.688454) (xy 192.315571 -199.736475)
			(xy 192.331281 -199.787405) (xy 192.339224 -199.840109) (xy 192.339722 -199.866758) (xy 192.339224 -199.893407)
			(xy 202.615536 -199.893407) (xy 202.615536 -199.840109) (xy 202.623479 -199.787405) (xy 202.639189 -199.736475)
			(xy 202.662315 -199.688454) (xy 202.692339 -199.644417) (xy 202.728591 -199.605346) (xy 202.770262 -199.572115)
			(xy 202.81642 -199.545466) (xy 202.866034 -199.525994) (xy 202.917996 -199.514134) (xy 202.971146 -199.510151)
			(xy 203.024296 -199.514134) (xy 203.076258 -199.525994) (xy 203.125872 -199.545466) (xy 203.17203 -199.572115)
			(xy 203.213701 -199.605346) (xy 203.249953 -199.644417) (xy 203.279977 -199.688454) (xy 203.303103 -199.736475)
			(xy 203.318813 -199.787405) (xy 203.326756 -199.840109) (xy 203.327254 -199.866758) (xy 203.326756 -199.893407)
			(xy 206.715604 -199.893407) (xy 206.715604 -199.840109) (xy 206.723547 -199.787405) (xy 206.739257 -199.736475)
			(xy 206.762383 -199.688454) (xy 206.792407 -199.644417) (xy 206.828659 -199.605346) (xy 206.87033 -199.572115)
			(xy 206.916488 -199.545466) (xy 206.966102 -199.525994) (xy 207.018064 -199.514134) (xy 207.071214 -199.510151)
			(xy 207.124364 -199.514134) (xy 207.176326 -199.525994) (xy 207.22594 -199.545466) (xy 207.272098 -199.572115)
			(xy 207.313769 -199.605346) (xy 207.350021 -199.644417) (xy 207.380045 -199.688454) (xy 207.403171 -199.736475)
			(xy 207.418881 -199.787405) (xy 207.426824 -199.840109) (xy 207.427322 -199.866758) (xy 207.426824 -199.893407)
			(xy 207.418881 -199.946111) (xy 207.403171 -199.997041) (xy 207.380045 -200.045062) (xy 207.350021 -200.089099)
			(xy 207.313769 -200.12817) (xy 207.272098 -200.161401) (xy 207.22594 -200.18805) (xy 207.176326 -200.207522)
			(xy 207.124364 -200.219382) (xy 207.071214 -200.223366) (xy 207.018064 -200.219382) (xy 206.966102 -200.207522)
			(xy 206.916488 -200.18805) (xy 206.87033 -200.161401) (xy 206.828659 -200.12817) (xy 206.792407 -200.089099)
			(xy 206.762383 -200.045062) (xy 206.739257 -199.997041) (xy 206.723547 -199.946111) (xy 206.715604 -199.893407)
			(xy 203.326756 -199.893407) (xy 203.318813 -199.946111) (xy 203.303103 -199.997041) (xy 203.279977 -200.045062)
			(xy 203.249953 -200.089099) (xy 203.213701 -200.12817) (xy 203.17203 -200.161401) (xy 203.125872 -200.18805)
			(xy 203.076258 -200.207522) (xy 203.024296 -200.219382) (xy 202.971146 -200.223366) (xy 202.917996 -200.219382)
			(xy 202.866034 -200.207522) (xy 202.81642 -200.18805) (xy 202.770262 -200.161401) (xy 202.728591 -200.12817)
			(xy 202.692339 -200.089099) (xy 202.662315 -200.045062) (xy 202.639189 -199.997041) (xy 202.623479 -199.946111)
			(xy 202.615536 -199.893407) (xy 192.339224 -199.893407) (xy 192.331281 -199.946111) (xy 192.315571 -199.997041)
			(xy 192.292445 -200.045062) (xy 192.262421 -200.089099) (xy 192.226169 -200.12817) (xy 192.184498 -200.161401)
			(xy 192.13834 -200.18805) (xy 192.088726 -200.207522) (xy 192.036764 -200.219382) (xy 191.983614 -200.223366)
			(xy 191.930464 -200.219382) (xy 191.878502 -200.207522) (xy 191.828888 -200.18805) (xy 191.78273 -200.161401)
			(xy 191.741059 -200.12817) (xy 191.704807 -200.089099) (xy 191.674783 -200.045062) (xy 191.651657 -199.997041)
			(xy 191.635947 -199.946111) (xy 191.628004 -199.893407) (xy 188.239156 -199.893407) (xy 188.231213 -199.946111)
			(xy 188.215503 -199.997041) (xy 188.192377 -200.045062) (xy 188.162353 -200.089099) (xy 188.126101 -200.12817)
			(xy 188.08443 -200.161401) (xy 188.038272 -200.18805) (xy 187.988658 -200.207522) (xy 187.936696 -200.219382)
			(xy 187.883546 -200.223366) (xy 187.830396 -200.219382) (xy 187.778434 -200.207522) (xy 187.72882 -200.18805)
			(xy 187.682662 -200.161401) (xy 187.640991 -200.12817) (xy 187.604739 -200.089099) (xy 187.574715 -200.045062)
			(xy 187.551589 -199.997041) (xy 187.535879 -199.946111) (xy 187.527936 -199.893407) (xy 177.251624 -199.893407)
			(xy 177.243681 -199.946111) (xy 177.227971 -199.997041) (xy 177.204845 -200.045062) (xy 177.174821 -200.089099)
			(xy 177.138569 -200.12817) (xy 177.096898 -200.161401) (xy 177.05074 -200.18805) (xy 177.001126 -200.207522)
			(xy 176.949164 -200.219382) (xy 176.896014 -200.223366) (xy 176.842864 -200.219382) (xy 176.790902 -200.207522)
			(xy 176.741288 -200.18805) (xy 176.69513 -200.161401) (xy 176.653459 -200.12817) (xy 176.617207 -200.089099)
			(xy 176.587183 -200.045062) (xy 176.564057 -199.997041) (xy 176.548347 -199.946111) (xy 176.540404 -199.893407)
			(xy 173.151556 -199.893407) (xy 173.143613 -199.946111) (xy 173.127903 -199.997041) (xy 173.104777 -200.045062)
			(xy 173.074753 -200.089099) (xy 173.038501 -200.12817) (xy 172.99683 -200.161401) (xy 172.950672 -200.18805)
			(xy 172.901058 -200.207522) (xy 172.849096 -200.219382) (xy 172.795946 -200.223366) (xy 172.742796 -200.219382)
			(xy 172.690834 -200.207522) (xy 172.64122 -200.18805) (xy 172.595062 -200.161401) (xy 172.553391 -200.12817)
			(xy 172.517139 -200.089099) (xy 172.487115 -200.045062) (xy 172.463989 -199.997041) (xy 172.448279 -199.946111)
			(xy 172.440336 -199.893407) (xy 159.11576 -199.893407) (xy 159.11576 -200.743291) (xy 172.440336 -200.743291)
			(xy 172.440336 -200.689993) (xy 172.448279 -200.637289) (xy 172.463989 -200.586359) (xy 172.487115 -200.538338)
			(xy 172.517139 -200.494301) (xy 172.553391 -200.45523) (xy 172.595062 -200.421999) (xy 172.64122 -200.39535)
			(xy 172.690834 -200.375878) (xy 172.742796 -200.364018) (xy 172.795946 -200.360035) (xy 172.849096 -200.364018)
			(xy 172.901058 -200.375878) (xy 172.950672 -200.39535) (xy 172.99683 -200.421999) (xy 173.038501 -200.45523)
			(xy 173.074753 -200.494301) (xy 173.104777 -200.538338) (xy 173.127903 -200.586359) (xy 173.143613 -200.637289)
			(xy 173.151556 -200.689993) (xy 173.152054 -200.716642) (xy 173.151556 -200.743291) (xy 187.527936 -200.743291)
			(xy 187.527936 -200.689993) (xy 187.535879 -200.637289) (xy 187.551589 -200.586359) (xy 187.574715 -200.538338)
			(xy 187.604739 -200.494301) (xy 187.640991 -200.45523) (xy 187.682662 -200.421999) (xy 187.72882 -200.39535)
			(xy 187.778434 -200.375878) (xy 187.830396 -200.364018) (xy 187.883546 -200.360035) (xy 187.936696 -200.364018)
			(xy 187.988658 -200.375878) (xy 188.038272 -200.39535) (xy 188.08443 -200.421999) (xy 188.126101 -200.45523)
			(xy 188.162353 -200.494301) (xy 188.192377 -200.538338) (xy 188.215503 -200.586359) (xy 188.231213 -200.637289)
			(xy 188.239156 -200.689993) (xy 188.239654 -200.716642) (xy 188.239156 -200.743291) (xy 202.615536 -200.743291)
			(xy 202.615536 -200.689993) (xy 202.623479 -200.637289) (xy 202.639189 -200.586359) (xy 202.662315 -200.538338)
			(xy 202.692339 -200.494301) (xy 202.728591 -200.45523) (xy 202.770262 -200.421999) (xy 202.81642 -200.39535)
			(xy 202.866034 -200.375878) (xy 202.917996 -200.364018) (xy 202.971146 -200.360035) (xy 203.024296 -200.364018)
			(xy 203.076258 -200.375878) (xy 203.125872 -200.39535) (xy 203.17203 -200.421999) (xy 203.213701 -200.45523)
			(xy 203.249953 -200.494301) (xy 203.279977 -200.538338) (xy 203.303103 -200.586359) (xy 203.318813 -200.637289)
			(xy 203.326756 -200.689993) (xy 203.327254 -200.716642) (xy 203.326756 -200.743291) (xy 203.318813 -200.795995)
			(xy 203.303103 -200.846925) (xy 203.279977 -200.894946) (xy 203.249953 -200.938983) (xy 203.213701 -200.978054)
			(xy 203.17203 -201.011285) (xy 203.125872 -201.037934) (xy 203.076258 -201.057406) (xy 203.024296 -201.069266)
			(xy 202.971146 -201.07325) (xy 202.917996 -201.069266) (xy 202.866034 -201.057406) (xy 202.81642 -201.037934)
			(xy 202.770262 -201.011285) (xy 202.728591 -200.978054) (xy 202.692339 -200.938983) (xy 202.662315 -200.894946)
			(xy 202.639189 -200.846925) (xy 202.623479 -200.795995) (xy 202.615536 -200.743291) (xy 188.239156 -200.743291)
			(xy 188.231213 -200.795995) (xy 188.215503 -200.846925) (xy 188.192377 -200.894946) (xy 188.162353 -200.938983)
			(xy 188.126101 -200.978054) (xy 188.08443 -201.011285) (xy 188.038272 -201.037934) (xy 187.988658 -201.057406)
			(xy 187.936696 -201.069266) (xy 187.883546 -201.07325) (xy 187.830396 -201.069266) (xy 187.778434 -201.057406)
			(xy 187.72882 -201.037934) (xy 187.682662 -201.011285) (xy 187.640991 -200.978054) (xy 187.604739 -200.938983)
			(xy 187.574715 -200.894946) (xy 187.551589 -200.846925) (xy 187.535879 -200.795995) (xy 187.527936 -200.743291)
			(xy 173.151556 -200.743291) (xy 173.143613 -200.795995) (xy 173.127903 -200.846925) (xy 173.104777 -200.894946)
			(xy 173.074753 -200.938983) (xy 173.038501 -200.978054) (xy 172.99683 -201.011285) (xy 172.950672 -201.037934)
			(xy 172.901058 -201.057406) (xy 172.849096 -201.069266) (xy 172.795946 -201.07325) (xy 172.742796 -201.069266)
			(xy 172.690834 -201.057406) (xy 172.64122 -201.037934) (xy 172.595062 -201.011285) (xy 172.553391 -200.978054)
			(xy 172.517139 -200.938983) (xy 172.487115 -200.894946) (xy 172.463989 -200.846925) (xy 172.448279 -200.795995)
			(xy 172.440336 -200.743291) (xy 159.11576 -200.743291) (xy 159.11576 -201.593429) (xy 176.540404 -201.593429)
			(xy 176.540404 -201.540131) (xy 176.548347 -201.487427) (xy 176.564057 -201.436497) (xy 176.587183 -201.388476)
			(xy 176.617207 -201.344439) (xy 176.653459 -201.305368) (xy 176.69513 -201.272137) (xy 176.741288 -201.245488)
			(xy 176.790902 -201.226016) (xy 176.842864 -201.214156) (xy 176.896014 -201.210173) (xy 176.949164 -201.214156)
			(xy 177.001126 -201.226016) (xy 177.05074 -201.245488) (xy 177.096898 -201.272137) (xy 177.138569 -201.305368)
			(xy 177.174821 -201.344439) (xy 177.204845 -201.388476) (xy 177.227971 -201.436497) (xy 177.243681 -201.487427)
			(xy 177.251624 -201.540131) (xy 177.252122 -201.56678) (xy 177.251624 -201.593429) (xy 191.628004 -201.593429)
			(xy 191.628004 -201.540131) (xy 191.635947 -201.487427) (xy 191.651657 -201.436497) (xy 191.674783 -201.388476)
			(xy 191.704807 -201.344439) (xy 191.741059 -201.305368) (xy 191.78273 -201.272137) (xy 191.828888 -201.245488)
			(xy 191.878502 -201.226016) (xy 191.930464 -201.214156) (xy 191.983614 -201.210173) (xy 192.036764 -201.214156)
			(xy 192.088726 -201.226016) (xy 192.13834 -201.245488) (xy 192.184498 -201.272137) (xy 192.226169 -201.305368)
			(xy 192.262421 -201.344439) (xy 192.292445 -201.388476) (xy 192.315571 -201.436497) (xy 192.331281 -201.487427)
			(xy 192.339224 -201.540131) (xy 192.339722 -201.56678) (xy 192.339224 -201.593429) (xy 206.715604 -201.593429)
			(xy 206.715604 -201.540131) (xy 206.723547 -201.487427) (xy 206.739257 -201.436497) (xy 206.762383 -201.388476)
			(xy 206.792407 -201.344439) (xy 206.828659 -201.305368) (xy 206.87033 -201.272137) (xy 206.916488 -201.245488)
			(xy 206.966102 -201.226016) (xy 207.018064 -201.214156) (xy 207.071214 -201.210173) (xy 207.124364 -201.214156)
			(xy 207.176326 -201.226016) (xy 207.22594 -201.245488) (xy 207.272098 -201.272137) (xy 207.313769 -201.305368)
			(xy 207.350021 -201.344439) (xy 207.380045 -201.388476) (xy 207.403171 -201.436497) (xy 207.418881 -201.487427)
			(xy 207.426824 -201.540131) (xy 207.427322 -201.56678) (xy 207.426824 -201.593429) (xy 207.418881 -201.646133)
			(xy 207.403171 -201.697063) (xy 207.380045 -201.745084) (xy 207.350021 -201.789121) (xy 207.313769 -201.828192)
			(xy 207.272098 -201.861423) (xy 207.22594 -201.888072) (xy 207.176326 -201.907544) (xy 207.124364 -201.919404)
			(xy 207.071214 -201.923388) (xy 207.018064 -201.919404) (xy 206.966102 -201.907544) (xy 206.916488 -201.888072)
			(xy 206.87033 -201.861423) (xy 206.828659 -201.828192) (xy 206.792407 -201.789121) (xy 206.762383 -201.745084)
			(xy 206.739257 -201.697063) (xy 206.723547 -201.646133) (xy 206.715604 -201.593429) (xy 192.339224 -201.593429)
			(xy 192.331281 -201.646133) (xy 192.315571 -201.697063) (xy 192.292445 -201.745084) (xy 192.262421 -201.789121)
			(xy 192.226169 -201.828192) (xy 192.184498 -201.861423) (xy 192.13834 -201.888072) (xy 192.088726 -201.907544)
			(xy 192.036764 -201.919404) (xy 191.983614 -201.923388) (xy 191.930464 -201.919404) (xy 191.878502 -201.907544)
			(xy 191.828888 -201.888072) (xy 191.78273 -201.861423) (xy 191.741059 -201.828192) (xy 191.704807 -201.789121)
			(xy 191.674783 -201.745084) (xy 191.651657 -201.697063) (xy 191.635947 -201.646133) (xy 191.628004 -201.593429)
			(xy 177.251624 -201.593429) (xy 177.243681 -201.646133) (xy 177.227971 -201.697063) (xy 177.204845 -201.745084)
			(xy 177.174821 -201.789121) (xy 177.138569 -201.828192) (xy 177.096898 -201.861423) (xy 177.05074 -201.888072)
			(xy 177.001126 -201.907544) (xy 176.949164 -201.919404) (xy 176.896014 -201.923388) (xy 176.842864 -201.919404)
			(xy 176.790902 -201.907544) (xy 176.741288 -201.888072) (xy 176.69513 -201.861423) (xy 176.653459 -201.828192)
			(xy 176.617207 -201.789121) (xy 176.587183 -201.745084) (xy 176.564057 -201.697063) (xy 176.548347 -201.646133)
			(xy 176.540404 -201.593429) (xy 159.11576 -201.593429) (xy 159.11576 -202.443313) (xy 172.440336 -202.443313)
			(xy 172.440336 -202.390015) (xy 172.448279 -202.337311) (xy 172.463989 -202.286381) (xy 172.487115 -202.23836)
			(xy 172.517139 -202.194323) (xy 172.553391 -202.155252) (xy 172.595062 -202.122021) (xy 172.64122 -202.095372)
			(xy 172.690834 -202.0759) (xy 172.742796 -202.06404) (xy 172.795946 -202.060057) (xy 172.849096 -202.06404)
			(xy 172.901058 -202.0759) (xy 172.950672 -202.095372) (xy 172.99683 -202.122021) (xy 173.038501 -202.155252)
			(xy 173.074753 -202.194323) (xy 173.104777 -202.23836) (xy 173.127903 -202.286381) (xy 173.143613 -202.337311)
			(xy 173.151556 -202.390015) (xy 173.152054 -202.416664) (xy 173.151556 -202.443313) (xy 187.527936 -202.443313)
			(xy 187.527936 -202.390015) (xy 187.535879 -202.337311) (xy 187.551589 -202.286381) (xy 187.574715 -202.23836)
			(xy 187.604739 -202.194323) (xy 187.640991 -202.155252) (xy 187.682662 -202.122021) (xy 187.72882 -202.095372)
			(xy 187.778434 -202.0759) (xy 187.830396 -202.06404) (xy 187.883546 -202.060057) (xy 187.936696 -202.06404)
			(xy 187.988658 -202.0759) (xy 188.038272 -202.095372) (xy 188.08443 -202.122021) (xy 188.126101 -202.155252)
			(xy 188.162353 -202.194323) (xy 188.192377 -202.23836) (xy 188.215503 -202.286381) (xy 188.231213 -202.337311)
			(xy 188.239156 -202.390015) (xy 188.239654 -202.416664) (xy 188.239156 -202.443313) (xy 202.615536 -202.443313)
			(xy 202.615536 -202.390015) (xy 202.623479 -202.337311) (xy 202.639189 -202.286381) (xy 202.662315 -202.23836)
			(xy 202.692339 -202.194323) (xy 202.728591 -202.155252) (xy 202.770262 -202.122021) (xy 202.81642 -202.095372)
			(xy 202.866034 -202.0759) (xy 202.917996 -202.06404) (xy 202.971146 -202.060057) (xy 203.024296 -202.06404)
			(xy 203.076258 -202.0759) (xy 203.125872 -202.095372) (xy 203.17203 -202.122021) (xy 203.213701 -202.155252)
			(xy 203.249953 -202.194323) (xy 203.279977 -202.23836) (xy 203.303103 -202.286381) (xy 203.318813 -202.337311)
			(xy 203.326756 -202.390015) (xy 203.327254 -202.416664) (xy 203.326756 -202.443313) (xy 203.318813 -202.496017)
			(xy 203.303103 -202.546947) (xy 203.279977 -202.594968) (xy 203.249953 -202.639005) (xy 203.213701 -202.678076)
			(xy 203.17203 -202.711307) (xy 203.125872 -202.737956) (xy 203.076258 -202.757428) (xy 203.024296 -202.769288)
			(xy 202.971146 -202.773272) (xy 202.917996 -202.769288) (xy 202.866034 -202.757428) (xy 202.81642 -202.737956)
			(xy 202.770262 -202.711307) (xy 202.728591 -202.678076) (xy 202.692339 -202.639005) (xy 202.662315 -202.594968)
			(xy 202.639189 -202.546947) (xy 202.623479 -202.496017) (xy 202.615536 -202.443313) (xy 188.239156 -202.443313)
			(xy 188.231213 -202.496017) (xy 188.215503 -202.546947) (xy 188.192377 -202.594968) (xy 188.162353 -202.639005)
			(xy 188.126101 -202.678076) (xy 188.08443 -202.711307) (xy 188.038272 -202.737956) (xy 187.988658 -202.757428)
			(xy 187.936696 -202.769288) (xy 187.883546 -202.773272) (xy 187.830396 -202.769288) (xy 187.778434 -202.757428)
			(xy 187.72882 -202.737956) (xy 187.682662 -202.711307) (xy 187.640991 -202.678076) (xy 187.604739 -202.639005)
			(xy 187.574715 -202.594968) (xy 187.551589 -202.546947) (xy 187.535879 -202.496017) (xy 187.527936 -202.443313)
			(xy 173.151556 -202.443313) (xy 173.143613 -202.496017) (xy 173.127903 -202.546947) (xy 173.104777 -202.594968)
			(xy 173.074753 -202.639005) (xy 173.038501 -202.678076) (xy 172.99683 -202.711307) (xy 172.950672 -202.737956)
			(xy 172.901058 -202.757428) (xy 172.849096 -202.769288) (xy 172.795946 -202.773272) (xy 172.742796 -202.769288)
			(xy 172.690834 -202.757428) (xy 172.64122 -202.737956) (xy 172.595062 -202.711307) (xy 172.553391 -202.678076)
			(xy 172.517139 -202.639005) (xy 172.487115 -202.594968) (xy 172.463989 -202.546947) (xy 172.448279 -202.496017)
			(xy 172.440336 -202.443313) (xy 159.11576 -202.443313) (xy 159.11576 -203.293451) (xy 176.540404 -203.293451)
			(xy 176.540404 -203.240153) (xy 176.548347 -203.187449) (xy 176.564057 -203.136519) (xy 176.587183 -203.088498)
			(xy 176.617207 -203.044461) (xy 176.653459 -203.00539) (xy 176.69513 -202.972159) (xy 176.741288 -202.94551)
			(xy 176.790902 -202.926038) (xy 176.842864 -202.914178) (xy 176.896014 -202.910195) (xy 176.949164 -202.914178)
			(xy 177.001126 -202.926038) (xy 177.05074 -202.94551) (xy 177.096898 -202.972159) (xy 177.138569 -203.00539)
			(xy 177.174821 -203.044461) (xy 177.204845 -203.088498) (xy 177.227971 -203.136519) (xy 177.243681 -203.187449)
			(xy 177.251624 -203.240153) (xy 177.252122 -203.266802) (xy 177.251624 -203.293451) (xy 191.628004 -203.293451)
			(xy 191.628004 -203.240153) (xy 191.635947 -203.187449) (xy 191.651657 -203.136519) (xy 191.674783 -203.088498)
			(xy 191.704807 -203.044461) (xy 191.741059 -203.00539) (xy 191.78273 -202.972159) (xy 191.828888 -202.94551)
			(xy 191.878502 -202.926038) (xy 191.930464 -202.914178) (xy 191.983614 -202.910195) (xy 192.036764 -202.914178)
			(xy 192.088726 -202.926038) (xy 192.13834 -202.94551) (xy 192.184498 -202.972159) (xy 192.226169 -203.00539)
			(xy 192.262421 -203.044461) (xy 192.292445 -203.088498) (xy 192.315571 -203.136519) (xy 192.331281 -203.187449)
			(xy 192.339224 -203.240153) (xy 192.339722 -203.266802) (xy 192.339224 -203.293451) (xy 206.715604 -203.293451)
			(xy 206.715604 -203.240153) (xy 206.723547 -203.187449) (xy 206.739257 -203.136519) (xy 206.762383 -203.088498)
			(xy 206.792407 -203.044461) (xy 206.828659 -203.00539) (xy 206.87033 -202.972159) (xy 206.916488 -202.94551)
			(xy 206.966102 -202.926038) (xy 207.018064 -202.914178) (xy 207.071214 -202.910195) (xy 207.124364 -202.914178)
			(xy 207.176326 -202.926038) (xy 207.22594 -202.94551) (xy 207.272098 -202.972159) (xy 207.313769 -203.00539)
			(xy 207.350021 -203.044461) (xy 207.380045 -203.088498) (xy 207.403171 -203.136519) (xy 207.418881 -203.187449)
			(xy 207.426824 -203.240153) (xy 207.427322 -203.266802) (xy 207.426824 -203.293451) (xy 207.418881 -203.346155)
			(xy 207.403171 -203.397085) (xy 207.380045 -203.445106) (xy 207.350021 -203.489143) (xy 207.313769 -203.528214)
			(xy 207.272098 -203.561445) (xy 207.22594 -203.588094) (xy 207.176326 -203.607566) (xy 207.124364 -203.619426)
			(xy 207.071214 -203.62341) (xy 207.018064 -203.619426) (xy 206.966102 -203.607566) (xy 206.916488 -203.588094)
			(xy 206.87033 -203.561445) (xy 206.828659 -203.528214) (xy 206.792407 -203.489143) (xy 206.762383 -203.445106)
			(xy 206.739257 -203.397085) (xy 206.723547 -203.346155) (xy 206.715604 -203.293451) (xy 192.339224 -203.293451)
			(xy 192.331281 -203.346155) (xy 192.315571 -203.397085) (xy 192.292445 -203.445106) (xy 192.262421 -203.489143)
			(xy 192.226169 -203.528214) (xy 192.184498 -203.561445) (xy 192.13834 -203.588094) (xy 192.088726 -203.607566)
			(xy 192.036764 -203.619426) (xy 191.983614 -203.62341) (xy 191.930464 -203.619426) (xy 191.878502 -203.607566)
			(xy 191.828888 -203.588094) (xy 191.78273 -203.561445) (xy 191.741059 -203.528214) (xy 191.704807 -203.489143)
			(xy 191.674783 -203.445106) (xy 191.651657 -203.397085) (xy 191.635947 -203.346155) (xy 191.628004 -203.293451)
			(xy 177.251624 -203.293451) (xy 177.243681 -203.346155) (xy 177.227971 -203.397085) (xy 177.204845 -203.445106)
			(xy 177.174821 -203.489143) (xy 177.138569 -203.528214) (xy 177.096898 -203.561445) (xy 177.05074 -203.588094)
			(xy 177.001126 -203.607566) (xy 176.949164 -203.619426) (xy 176.896014 -203.62341) (xy 176.842864 -203.619426)
			(xy 176.790902 -203.607566) (xy 176.741288 -203.588094) (xy 176.69513 -203.561445) (xy 176.653459 -203.528214)
			(xy 176.617207 -203.489143) (xy 176.587183 -203.445106) (xy 176.564057 -203.397085) (xy 176.548347 -203.346155)
			(xy 176.540404 -203.293451) (xy 159.11576 -203.293451) (xy 159.11576 -204.143335) (xy 172.440336 -204.143335)
			(xy 172.440336 -204.090037) (xy 172.448279 -204.037333) (xy 172.463989 -203.986403) (xy 172.487115 -203.938382)
			(xy 172.517139 -203.894345) (xy 172.553391 -203.855274) (xy 172.595062 -203.822043) (xy 172.64122 -203.795394)
			(xy 172.690834 -203.775922) (xy 172.742796 -203.764062) (xy 172.795946 -203.760079) (xy 172.849096 -203.764062)
			(xy 172.901058 -203.775922) (xy 172.950672 -203.795394) (xy 172.99683 -203.822043) (xy 173.038501 -203.855274)
			(xy 173.074753 -203.894345) (xy 173.104777 -203.938382) (xy 173.127903 -203.986403) (xy 173.143613 -204.037333)
			(xy 173.151556 -204.090037) (xy 173.152054 -204.116686) (xy 173.151556 -204.143335) (xy 187.527936 -204.143335)
			(xy 187.527936 -204.090037) (xy 187.535879 -204.037333) (xy 187.551589 -203.986403) (xy 187.574715 -203.938382)
			(xy 187.604739 -203.894345) (xy 187.640991 -203.855274) (xy 187.682662 -203.822043) (xy 187.72882 -203.795394)
			(xy 187.778434 -203.775922) (xy 187.830396 -203.764062) (xy 187.883546 -203.760079) (xy 187.936696 -203.764062)
			(xy 187.988658 -203.775922) (xy 188.038272 -203.795394) (xy 188.08443 -203.822043) (xy 188.126101 -203.855274)
			(xy 188.162353 -203.894345) (xy 188.192377 -203.938382) (xy 188.215503 -203.986403) (xy 188.231213 -204.037333)
			(xy 188.239156 -204.090037) (xy 188.239654 -204.116686) (xy 188.239156 -204.143335) (xy 202.615536 -204.143335)
			(xy 202.615536 -204.090037) (xy 202.623479 -204.037333) (xy 202.639189 -203.986403) (xy 202.662315 -203.938382)
			(xy 202.692339 -203.894345) (xy 202.728591 -203.855274) (xy 202.770262 -203.822043) (xy 202.81642 -203.795394)
			(xy 202.866034 -203.775922) (xy 202.917996 -203.764062) (xy 202.971146 -203.760079) (xy 203.024296 -203.764062)
			(xy 203.076258 -203.775922) (xy 203.125872 -203.795394) (xy 203.17203 -203.822043) (xy 203.213701 -203.855274)
			(xy 203.249953 -203.894345) (xy 203.279977 -203.938382) (xy 203.303103 -203.986403) (xy 203.318813 -204.037333)
			(xy 203.326756 -204.090037) (xy 203.327254 -204.116686) (xy 203.326756 -204.143335) (xy 203.318813 -204.196039)
			(xy 203.303103 -204.246969) (xy 203.279977 -204.29499) (xy 203.249953 -204.339027) (xy 203.213701 -204.378098)
			(xy 203.17203 -204.411329) (xy 203.125872 -204.437978) (xy 203.076258 -204.45745) (xy 203.024296 -204.46931)
			(xy 202.971146 -204.473294) (xy 202.917996 -204.46931) (xy 202.866034 -204.45745) (xy 202.81642 -204.437978)
			(xy 202.770262 -204.411329) (xy 202.728591 -204.378098) (xy 202.692339 -204.339027) (xy 202.662315 -204.29499)
			(xy 202.639189 -204.246969) (xy 202.623479 -204.196039) (xy 202.615536 -204.143335) (xy 188.239156 -204.143335)
			(xy 188.231213 -204.196039) (xy 188.215503 -204.246969) (xy 188.192377 -204.29499) (xy 188.162353 -204.339027)
			(xy 188.126101 -204.378098) (xy 188.08443 -204.411329) (xy 188.038272 -204.437978) (xy 187.988658 -204.45745)
			(xy 187.936696 -204.46931) (xy 187.883546 -204.473294) (xy 187.830396 -204.46931) (xy 187.778434 -204.45745)
			(xy 187.72882 -204.437978) (xy 187.682662 -204.411329) (xy 187.640991 -204.378098) (xy 187.604739 -204.339027)
			(xy 187.574715 -204.29499) (xy 187.551589 -204.246969) (xy 187.535879 -204.196039) (xy 187.527936 -204.143335)
			(xy 173.151556 -204.143335) (xy 173.143613 -204.196039) (xy 173.127903 -204.246969) (xy 173.104777 -204.29499)
			(xy 173.074753 -204.339027) (xy 173.038501 -204.378098) (xy 172.99683 -204.411329) (xy 172.950672 -204.437978)
			(xy 172.901058 -204.45745) (xy 172.849096 -204.46931) (xy 172.795946 -204.473294) (xy 172.742796 -204.46931)
			(xy 172.690834 -204.45745) (xy 172.64122 -204.437978) (xy 172.595062 -204.411329) (xy 172.553391 -204.378098)
			(xy 172.517139 -204.339027) (xy 172.487115 -204.29499) (xy 172.463989 -204.246969) (xy 172.448279 -204.196039)
			(xy 172.440336 -204.143335) (xy 159.11576 -204.143335) (xy 159.11576 -204.993219) (xy 176.540404 -204.993219)
			(xy 176.540404 -204.939921) (xy 176.548347 -204.887217) (xy 176.564057 -204.836287) (xy 176.587183 -204.788266)
			(xy 176.617207 -204.744229) (xy 176.653459 -204.705158) (xy 176.69513 -204.671927) (xy 176.741288 -204.645278)
			(xy 176.790902 -204.625806) (xy 176.842864 -204.613946) (xy 176.896014 -204.609963) (xy 176.949164 -204.613946)
			(xy 177.001126 -204.625806) (xy 177.05074 -204.645278) (xy 177.096898 -204.671927) (xy 177.138569 -204.705158)
			(xy 177.174821 -204.744229) (xy 177.204845 -204.788266) (xy 177.227971 -204.836287) (xy 177.243681 -204.887217)
			(xy 177.251624 -204.939921) (xy 177.252122 -204.96657) (xy 177.251624 -204.993219) (xy 191.628004 -204.993219)
			(xy 191.628004 -204.939921) (xy 191.635947 -204.887217) (xy 191.651657 -204.836287) (xy 191.674783 -204.788266)
			(xy 191.704807 -204.744229) (xy 191.741059 -204.705158) (xy 191.78273 -204.671927) (xy 191.828888 -204.645278)
			(xy 191.878502 -204.625806) (xy 191.930464 -204.613946) (xy 191.983614 -204.609963) (xy 192.036764 -204.613946)
			(xy 192.088726 -204.625806) (xy 192.13834 -204.645278) (xy 192.184498 -204.671927) (xy 192.226169 -204.705158)
			(xy 192.262421 -204.744229) (xy 192.292445 -204.788266) (xy 192.315571 -204.836287) (xy 192.331281 -204.887217)
			(xy 192.339224 -204.939921) (xy 192.339722 -204.96657) (xy 192.339224 -204.993219) (xy 206.715604 -204.993219)
			(xy 206.715604 -204.939921) (xy 206.723547 -204.887217) (xy 206.739257 -204.836287) (xy 206.762383 -204.788266)
			(xy 206.792407 -204.744229) (xy 206.828659 -204.705158) (xy 206.87033 -204.671927) (xy 206.916488 -204.645278)
			(xy 206.966102 -204.625806) (xy 207.018064 -204.613946) (xy 207.071214 -204.609963) (xy 207.124364 -204.613946)
			(xy 207.176326 -204.625806) (xy 207.22594 -204.645278) (xy 207.272098 -204.671927) (xy 207.313769 -204.705158)
			(xy 207.350021 -204.744229) (xy 207.380045 -204.788266) (xy 207.403171 -204.836287) (xy 207.418881 -204.887217)
			(xy 207.426824 -204.939921) (xy 207.427322 -204.96657) (xy 207.426824 -204.993219) (xy 207.418881 -205.045923)
			(xy 207.403171 -205.096853) (xy 207.380045 -205.144874) (xy 207.350021 -205.188911) (xy 207.313769 -205.227982)
			(xy 207.272098 -205.261213) (xy 207.22594 -205.287862) (xy 207.176326 -205.307334) (xy 207.124364 -205.319194)
			(xy 207.071214 -205.323178) (xy 207.018064 -205.319194) (xy 206.966102 -205.307334) (xy 206.916488 -205.287862)
			(xy 206.87033 -205.261213) (xy 206.828659 -205.227982) (xy 206.792407 -205.188911) (xy 206.762383 -205.144874)
			(xy 206.739257 -205.096853) (xy 206.723547 -205.045923) (xy 206.715604 -204.993219) (xy 192.339224 -204.993219)
			(xy 192.331281 -205.045923) (xy 192.315571 -205.096853) (xy 192.292445 -205.144874) (xy 192.262421 -205.188911)
			(xy 192.226169 -205.227982) (xy 192.184498 -205.261213) (xy 192.13834 -205.287862) (xy 192.088726 -205.307334)
			(xy 192.036764 -205.319194) (xy 191.983614 -205.323178) (xy 191.930464 -205.319194) (xy 191.878502 -205.307334)
			(xy 191.828888 -205.287862) (xy 191.78273 -205.261213) (xy 191.741059 -205.227982) (xy 191.704807 -205.188911)
			(xy 191.674783 -205.144874) (xy 191.651657 -205.096853) (xy 191.635947 -205.045923) (xy 191.628004 -204.993219)
			(xy 177.251624 -204.993219) (xy 177.243681 -205.045923) (xy 177.227971 -205.096853) (xy 177.204845 -205.144874)
			(xy 177.174821 -205.188911) (xy 177.138569 -205.227982) (xy 177.096898 -205.261213) (xy 177.05074 -205.287862)
			(xy 177.001126 -205.307334) (xy 176.949164 -205.319194) (xy 176.896014 -205.323178) (xy 176.842864 -205.319194)
			(xy 176.790902 -205.307334) (xy 176.741288 -205.287862) (xy 176.69513 -205.261213) (xy 176.653459 -205.227982)
			(xy 176.617207 -205.188911) (xy 176.587183 -205.144874) (xy 176.564057 -205.096853) (xy 176.548347 -205.045923)
			(xy 176.540404 -204.993219) (xy 159.11576 -204.993219) (xy 159.11576 -205.843357) (xy 172.440336 -205.843357)
			(xy 172.440336 -205.790059) (xy 172.448279 -205.737355) (xy 172.463989 -205.686425) (xy 172.487115 -205.638404)
			(xy 172.517139 -205.594367) (xy 172.553391 -205.555296) (xy 172.595062 -205.522065) (xy 172.64122 -205.495416)
			(xy 172.690834 -205.475944) (xy 172.742796 -205.464084) (xy 172.795946 -205.460101) (xy 172.849096 -205.464084)
			(xy 172.901058 -205.475944) (xy 172.950672 -205.495416) (xy 172.99683 -205.522065) (xy 173.038501 -205.555296)
			(xy 173.074753 -205.594367) (xy 173.104777 -205.638404) (xy 173.127903 -205.686425) (xy 173.143613 -205.737355)
			(xy 173.151556 -205.790059) (xy 173.152054 -205.816708) (xy 173.151556 -205.843357) (xy 187.527936 -205.843357)
			(xy 187.527936 -205.790059) (xy 187.535879 -205.737355) (xy 187.551589 -205.686425) (xy 187.574715 -205.638404)
			(xy 187.604739 -205.594367) (xy 187.640991 -205.555296) (xy 187.682662 -205.522065) (xy 187.72882 -205.495416)
			(xy 187.778434 -205.475944) (xy 187.830396 -205.464084) (xy 187.883546 -205.460101) (xy 187.936696 -205.464084)
			(xy 187.988658 -205.475944) (xy 188.038272 -205.495416) (xy 188.08443 -205.522065) (xy 188.126101 -205.555296)
			(xy 188.162353 -205.594367) (xy 188.192377 -205.638404) (xy 188.215503 -205.686425) (xy 188.231213 -205.737355)
			(xy 188.239156 -205.790059) (xy 188.239654 -205.816708) (xy 188.239156 -205.843357) (xy 202.615536 -205.843357)
			(xy 202.615536 -205.790059) (xy 202.623479 -205.737355) (xy 202.639189 -205.686425) (xy 202.662315 -205.638404)
			(xy 202.692339 -205.594367) (xy 202.728591 -205.555296) (xy 202.770262 -205.522065) (xy 202.81642 -205.495416)
			(xy 202.866034 -205.475944) (xy 202.917996 -205.464084) (xy 202.971146 -205.460101) (xy 203.024296 -205.464084)
			(xy 203.076258 -205.475944) (xy 203.125872 -205.495416) (xy 203.17203 -205.522065) (xy 203.213701 -205.555296)
			(xy 203.249953 -205.594367) (xy 203.279977 -205.638404) (xy 203.303103 -205.686425) (xy 203.318813 -205.737355)
			(xy 203.326756 -205.790059) (xy 203.327254 -205.816708) (xy 203.326756 -205.843357) (xy 203.318813 -205.896061)
			(xy 203.303103 -205.946991) (xy 203.279977 -205.995012) (xy 203.249953 -206.039049) (xy 203.213701 -206.07812)
			(xy 203.17203 -206.111351) (xy 203.125872 -206.138) (xy 203.076258 -206.157472) (xy 203.024296 -206.169332)
			(xy 202.971146 -206.173316) (xy 202.917996 -206.169332) (xy 202.866034 -206.157472) (xy 202.81642 -206.138)
			(xy 202.770262 -206.111351) (xy 202.728591 -206.07812) (xy 202.692339 -206.039049) (xy 202.662315 -205.995012)
			(xy 202.639189 -205.946991) (xy 202.623479 -205.896061) (xy 202.615536 -205.843357) (xy 188.239156 -205.843357)
			(xy 188.231213 -205.896061) (xy 188.215503 -205.946991) (xy 188.192377 -205.995012) (xy 188.162353 -206.039049)
			(xy 188.126101 -206.07812) (xy 188.08443 -206.111351) (xy 188.038272 -206.138) (xy 187.988658 -206.157472)
			(xy 187.936696 -206.169332) (xy 187.883546 -206.173316) (xy 187.830396 -206.169332) (xy 187.778434 -206.157472)
			(xy 187.72882 -206.138) (xy 187.682662 -206.111351) (xy 187.640991 -206.07812) (xy 187.604739 -206.039049)
			(xy 187.574715 -205.995012) (xy 187.551589 -205.946991) (xy 187.535879 -205.896061) (xy 187.527936 -205.843357)
			(xy 173.151556 -205.843357) (xy 173.143613 -205.896061) (xy 173.127903 -205.946991) (xy 173.104777 -205.995012)
			(xy 173.074753 -206.039049) (xy 173.038501 -206.07812) (xy 172.99683 -206.111351) (xy 172.950672 -206.138)
			(xy 172.901058 -206.157472) (xy 172.849096 -206.169332) (xy 172.795946 -206.173316) (xy 172.742796 -206.169332)
			(xy 172.690834 -206.157472) (xy 172.64122 -206.138) (xy 172.595062 -206.111351) (xy 172.553391 -206.07812)
			(xy 172.517139 -206.039049) (xy 172.487115 -205.995012) (xy 172.463989 -205.946991) (xy 172.448279 -205.896061)
			(xy 172.440336 -205.843357) (xy 159.11576 -205.843357) (xy 159.11576 -206.693241) (xy 176.540404 -206.693241)
			(xy 176.540404 -206.639943) (xy 176.548347 -206.587239) (xy 176.564057 -206.536309) (xy 176.587183 -206.488288)
			(xy 176.617207 -206.444251) (xy 176.653459 -206.40518) (xy 176.69513 -206.371949) (xy 176.741288 -206.3453)
			(xy 176.790902 -206.325828) (xy 176.842864 -206.313968) (xy 176.896014 -206.309985) (xy 176.949164 -206.313968)
			(xy 177.001126 -206.325828) (xy 177.05074 -206.3453) (xy 177.096898 -206.371949) (xy 177.138569 -206.40518)
			(xy 177.174821 -206.444251) (xy 177.204845 -206.488288) (xy 177.227971 -206.536309) (xy 177.243681 -206.587239)
			(xy 177.251624 -206.639943) (xy 177.252122 -206.666592) (xy 177.251624 -206.693241) (xy 191.628004 -206.693241)
			(xy 191.628004 -206.639943) (xy 191.635947 -206.587239) (xy 191.651657 -206.536309) (xy 191.674783 -206.488288)
			(xy 191.704807 -206.444251) (xy 191.741059 -206.40518) (xy 191.78273 -206.371949) (xy 191.828888 -206.3453)
			(xy 191.878502 -206.325828) (xy 191.930464 -206.313968) (xy 191.983614 -206.309985) (xy 192.036764 -206.313968)
			(xy 192.088726 -206.325828) (xy 192.13834 -206.3453) (xy 192.184498 -206.371949) (xy 192.226169 -206.40518)
			(xy 192.262421 -206.444251) (xy 192.292445 -206.488288) (xy 192.315571 -206.536309) (xy 192.331281 -206.587239)
			(xy 192.339224 -206.639943) (xy 192.339722 -206.666592) (xy 192.339224 -206.693241) (xy 206.715604 -206.693241)
			(xy 206.715604 -206.639943) (xy 206.723547 -206.587239) (xy 206.739257 -206.536309) (xy 206.762383 -206.488288)
			(xy 206.792407 -206.444251) (xy 206.828659 -206.40518) (xy 206.87033 -206.371949) (xy 206.916488 -206.3453)
			(xy 206.966102 -206.325828) (xy 207.018064 -206.313968) (xy 207.071214 -206.309985) (xy 207.124364 -206.313968)
			(xy 207.176326 -206.325828) (xy 207.22594 -206.3453) (xy 207.272098 -206.371949) (xy 207.313769 -206.40518)
			(xy 207.350021 -206.444251) (xy 207.380045 -206.488288) (xy 207.403171 -206.536309) (xy 207.418881 -206.587239)
			(xy 207.426824 -206.639943) (xy 207.427322 -206.666592) (xy 207.426824 -206.693241) (xy 207.418881 -206.745945)
			(xy 207.403171 -206.796875) (xy 207.380045 -206.844896) (xy 207.350021 -206.888933) (xy 207.313769 -206.928004)
			(xy 207.272098 -206.961235) (xy 207.22594 -206.987884) (xy 207.176326 -207.007356) (xy 207.124364 -207.019216)
			(xy 207.071214 -207.0232) (xy 207.018064 -207.019216) (xy 206.966102 -207.007356) (xy 206.916488 -206.987884)
			(xy 206.87033 -206.961235) (xy 206.828659 -206.928004) (xy 206.792407 -206.888933) (xy 206.762383 -206.844896)
			(xy 206.739257 -206.796875) (xy 206.723547 -206.745945) (xy 206.715604 -206.693241) (xy 192.339224 -206.693241)
			(xy 192.331281 -206.745945) (xy 192.315571 -206.796875) (xy 192.292445 -206.844896) (xy 192.262421 -206.888933)
			(xy 192.226169 -206.928004) (xy 192.184498 -206.961235) (xy 192.13834 -206.987884) (xy 192.088726 -207.007356)
			(xy 192.036764 -207.019216) (xy 191.983614 -207.0232) (xy 191.930464 -207.019216) (xy 191.878502 -207.007356)
			(xy 191.828888 -206.987884) (xy 191.78273 -206.961235) (xy 191.741059 -206.928004) (xy 191.704807 -206.888933)
			(xy 191.674783 -206.844896) (xy 191.651657 -206.796875) (xy 191.635947 -206.745945) (xy 191.628004 -206.693241)
			(xy 177.251624 -206.693241) (xy 177.243681 -206.745945) (xy 177.227971 -206.796875) (xy 177.204845 -206.844896)
			(xy 177.174821 -206.888933) (xy 177.138569 -206.928004) (xy 177.096898 -206.961235) (xy 177.05074 -206.987884)
			(xy 177.001126 -207.007356) (xy 176.949164 -207.019216) (xy 176.896014 -207.0232) (xy 176.842864 -207.019216)
			(xy 176.790902 -207.007356) (xy 176.741288 -206.987884) (xy 176.69513 -206.961235) (xy 176.653459 -206.928004)
			(xy 176.617207 -206.888933) (xy 176.587183 -206.844896) (xy 176.564057 -206.796875) (xy 176.548347 -206.745945)
			(xy 176.540404 -206.693241) (xy 159.11576 -206.693241) (xy 159.11576 -207.543379) (xy 172.440336 -207.543379)
			(xy 172.440336 -207.490081) (xy 172.448279 -207.437377) (xy 172.463989 -207.386447) (xy 172.487115 -207.338426)
			(xy 172.517139 -207.294389) (xy 172.553391 -207.255318) (xy 172.595062 -207.222087) (xy 172.64122 -207.195438)
			(xy 172.690834 -207.175966) (xy 172.742796 -207.164106) (xy 172.795946 -207.160123) (xy 172.849096 -207.164106)
			(xy 172.901058 -207.175966) (xy 172.950672 -207.195438) (xy 172.99683 -207.222087) (xy 173.038501 -207.255318)
			(xy 173.074753 -207.294389) (xy 173.104777 -207.338426) (xy 173.127903 -207.386447) (xy 173.143613 -207.437377)
			(xy 173.151556 -207.490081) (xy 173.152054 -207.51673) (xy 173.151556 -207.543379) (xy 187.527936 -207.543379)
			(xy 187.527936 -207.490081) (xy 187.535879 -207.437377) (xy 187.551589 -207.386447) (xy 187.574715 -207.338426)
			(xy 187.604739 -207.294389) (xy 187.640991 -207.255318) (xy 187.682662 -207.222087) (xy 187.72882 -207.195438)
			(xy 187.778434 -207.175966) (xy 187.830396 -207.164106) (xy 187.883546 -207.160123) (xy 187.936696 -207.164106)
			(xy 187.988658 -207.175966) (xy 188.038272 -207.195438) (xy 188.08443 -207.222087) (xy 188.126101 -207.255318)
			(xy 188.162353 -207.294389) (xy 188.192377 -207.338426) (xy 188.215503 -207.386447) (xy 188.231213 -207.437377)
			(xy 188.239156 -207.490081) (xy 188.239654 -207.51673) (xy 188.239156 -207.543379) (xy 202.615536 -207.543379)
			(xy 202.615536 -207.490081) (xy 202.623479 -207.437377) (xy 202.639189 -207.386447) (xy 202.662315 -207.338426)
			(xy 202.692339 -207.294389) (xy 202.728591 -207.255318) (xy 202.770262 -207.222087) (xy 202.81642 -207.195438)
			(xy 202.866034 -207.175966) (xy 202.917996 -207.164106) (xy 202.971146 -207.160123) (xy 203.024296 -207.164106)
			(xy 203.076258 -207.175966) (xy 203.125872 -207.195438) (xy 203.17203 -207.222087) (xy 203.213701 -207.255318)
			(xy 203.249953 -207.294389) (xy 203.279977 -207.338426) (xy 203.303103 -207.386447) (xy 203.318813 -207.437377)
			(xy 203.326756 -207.490081) (xy 203.327254 -207.51673) (xy 203.326756 -207.543379) (xy 203.318813 -207.596083)
			(xy 203.303103 -207.647013) (xy 203.279977 -207.695034) (xy 203.249953 -207.739071) (xy 203.213701 -207.778142)
			(xy 203.17203 -207.811373) (xy 203.125872 -207.838022) (xy 203.076258 -207.857494) (xy 203.024296 -207.869354)
			(xy 202.971146 -207.873338) (xy 202.917996 -207.869354) (xy 202.866034 -207.857494) (xy 202.81642 -207.838022)
			(xy 202.770262 -207.811373) (xy 202.728591 -207.778142) (xy 202.692339 -207.739071) (xy 202.662315 -207.695034)
			(xy 202.639189 -207.647013) (xy 202.623479 -207.596083) (xy 202.615536 -207.543379) (xy 188.239156 -207.543379)
			(xy 188.231213 -207.596083) (xy 188.215503 -207.647013) (xy 188.192377 -207.695034) (xy 188.162353 -207.739071)
			(xy 188.126101 -207.778142) (xy 188.08443 -207.811373) (xy 188.038272 -207.838022) (xy 187.988658 -207.857494)
			(xy 187.936696 -207.869354) (xy 187.883546 -207.873338) (xy 187.830396 -207.869354) (xy 187.778434 -207.857494)
			(xy 187.72882 -207.838022) (xy 187.682662 -207.811373) (xy 187.640991 -207.778142) (xy 187.604739 -207.739071)
			(xy 187.574715 -207.695034) (xy 187.551589 -207.647013) (xy 187.535879 -207.596083) (xy 187.527936 -207.543379)
			(xy 173.151556 -207.543379) (xy 173.143613 -207.596083) (xy 173.127903 -207.647013) (xy 173.104777 -207.695034)
			(xy 173.074753 -207.739071) (xy 173.038501 -207.778142) (xy 172.99683 -207.811373) (xy 172.950672 -207.838022)
			(xy 172.901058 -207.857494) (xy 172.849096 -207.869354) (xy 172.795946 -207.873338) (xy 172.742796 -207.869354)
			(xy 172.690834 -207.857494) (xy 172.64122 -207.838022) (xy 172.595062 -207.811373) (xy 172.553391 -207.778142)
			(xy 172.517139 -207.739071) (xy 172.487115 -207.695034) (xy 172.463989 -207.647013) (xy 172.448279 -207.596083)
			(xy 172.440336 -207.543379) (xy 159.11576 -207.543379) (xy 159.11576 -208.393263) (xy 176.540404 -208.393263)
			(xy 176.540404 -208.339965) (xy 176.548347 -208.287261) (xy 176.564057 -208.236331) (xy 176.587183 -208.18831)
			(xy 176.617207 -208.144273) (xy 176.653459 -208.105202) (xy 176.69513 -208.071971) (xy 176.741288 -208.045322)
			(xy 176.790902 -208.02585) (xy 176.842864 -208.01399) (xy 176.896014 -208.010007) (xy 176.949164 -208.01399)
			(xy 177.001126 -208.02585) (xy 177.05074 -208.045322) (xy 177.096898 -208.071971) (xy 177.138569 -208.105202)
			(xy 177.174821 -208.144273) (xy 177.204845 -208.18831) (xy 177.227971 -208.236331) (xy 177.243681 -208.287261)
			(xy 177.251624 -208.339965) (xy 177.252122 -208.366614) (xy 177.251624 -208.393263) (xy 191.628004 -208.393263)
			(xy 191.628004 -208.339965) (xy 191.635947 -208.287261) (xy 191.651657 -208.236331) (xy 191.674783 -208.18831)
			(xy 191.704807 -208.144273) (xy 191.741059 -208.105202) (xy 191.78273 -208.071971) (xy 191.828888 -208.045322)
			(xy 191.878502 -208.02585) (xy 191.930464 -208.01399) (xy 191.983614 -208.010007) (xy 192.036764 -208.01399)
			(xy 192.088726 -208.02585) (xy 192.13834 -208.045322) (xy 192.184498 -208.071971) (xy 192.226169 -208.105202)
			(xy 192.262421 -208.144273) (xy 192.292445 -208.18831) (xy 192.315571 -208.236331) (xy 192.331281 -208.287261)
			(xy 192.339224 -208.339965) (xy 192.339722 -208.366614) (xy 192.339224 -208.393263) (xy 206.715604 -208.393263)
			(xy 206.715604 -208.339965) (xy 206.723547 -208.287261) (xy 206.739257 -208.236331) (xy 206.762383 -208.18831)
			(xy 206.792407 -208.144273) (xy 206.828659 -208.105202) (xy 206.87033 -208.071971) (xy 206.916488 -208.045322)
			(xy 206.966102 -208.02585) (xy 207.018064 -208.01399) (xy 207.071214 -208.010007) (xy 207.124364 -208.01399)
			(xy 207.176326 -208.02585) (xy 207.22594 -208.045322) (xy 207.272098 -208.071971) (xy 207.313769 -208.105202)
			(xy 207.350021 -208.144273) (xy 207.380045 -208.18831) (xy 207.403171 -208.236331) (xy 207.418881 -208.287261)
			(xy 207.426824 -208.339965) (xy 207.427322 -208.366614) (xy 207.426824 -208.393263) (xy 207.418881 -208.445967)
			(xy 207.403171 -208.496897) (xy 207.380045 -208.544918) (xy 207.350021 -208.588955) (xy 207.313769 -208.628026)
			(xy 207.272098 -208.661257) (xy 207.22594 -208.687906) (xy 207.176326 -208.707378) (xy 207.124364 -208.719238)
			(xy 207.071214 -208.723222) (xy 207.018064 -208.719238) (xy 206.966102 -208.707378) (xy 206.916488 -208.687906)
			(xy 206.87033 -208.661257) (xy 206.828659 -208.628026) (xy 206.792407 -208.588955) (xy 206.762383 -208.544918)
			(xy 206.739257 -208.496897) (xy 206.723547 -208.445967) (xy 206.715604 -208.393263) (xy 192.339224 -208.393263)
			(xy 192.331281 -208.445967) (xy 192.315571 -208.496897) (xy 192.292445 -208.544918) (xy 192.262421 -208.588955)
			(xy 192.226169 -208.628026) (xy 192.184498 -208.661257) (xy 192.13834 -208.687906) (xy 192.088726 -208.707378)
			(xy 192.036764 -208.719238) (xy 191.983614 -208.723222) (xy 191.930464 -208.719238) (xy 191.878502 -208.707378)
			(xy 191.828888 -208.687906) (xy 191.78273 -208.661257) (xy 191.741059 -208.628026) (xy 191.704807 -208.588955)
			(xy 191.674783 -208.544918) (xy 191.651657 -208.496897) (xy 191.635947 -208.445967) (xy 191.628004 -208.393263)
			(xy 177.251624 -208.393263) (xy 177.243681 -208.445967) (xy 177.227971 -208.496897) (xy 177.204845 -208.544918)
			(xy 177.174821 -208.588955) (xy 177.138569 -208.628026) (xy 177.096898 -208.661257) (xy 177.05074 -208.687906)
			(xy 177.001126 -208.707378) (xy 176.949164 -208.719238) (xy 176.896014 -208.723222) (xy 176.842864 -208.719238)
			(xy 176.790902 -208.707378) (xy 176.741288 -208.687906) (xy 176.69513 -208.661257) (xy 176.653459 -208.628026)
			(xy 176.617207 -208.588955) (xy 176.587183 -208.544918) (xy 176.564057 -208.496897) (xy 176.548347 -208.445967)
			(xy 176.540404 -208.393263) (xy 159.11576 -208.393263) (xy 159.11576 -209.243401) (xy 172.440336 -209.243401)
			(xy 172.440336 -209.190103) (xy 172.448279 -209.137399) (xy 172.463989 -209.086469) (xy 172.487115 -209.038448)
			(xy 172.517139 -208.994411) (xy 172.553391 -208.95534) (xy 172.595062 -208.922109) (xy 172.64122 -208.89546)
			(xy 172.690834 -208.875988) (xy 172.742796 -208.864128) (xy 172.795946 -208.860145) (xy 172.849096 -208.864128)
			(xy 172.901058 -208.875988) (xy 172.950672 -208.89546) (xy 172.99683 -208.922109) (xy 173.038501 -208.95534)
			(xy 173.074753 -208.994411) (xy 173.104777 -209.038448) (xy 173.127903 -209.086469) (xy 173.143613 -209.137399)
			(xy 173.151556 -209.190103) (xy 173.152054 -209.216752) (xy 173.151556 -209.243401) (xy 176.540404 -209.243401)
			(xy 176.540404 -209.190103) (xy 176.548347 -209.137399) (xy 176.564057 -209.086469) (xy 176.587183 -209.038448)
			(xy 176.617207 -208.994411) (xy 176.653459 -208.95534) (xy 176.69513 -208.922109) (xy 176.741288 -208.89546)
			(xy 176.790902 -208.875988) (xy 176.842864 -208.864128) (xy 176.896014 -208.860145) (xy 176.949164 -208.864128)
			(xy 177.001126 -208.875988) (xy 177.05074 -208.89546) (xy 177.096898 -208.922109) (xy 177.138569 -208.95534)
			(xy 177.174821 -208.994411) (xy 177.204845 -209.038448) (xy 177.227971 -209.086469) (xy 177.243681 -209.137399)
			(xy 177.251624 -209.190103) (xy 177.252122 -209.216752) (xy 177.251624 -209.243401) (xy 187.527936 -209.243401)
			(xy 187.527936 -209.190103) (xy 187.535879 -209.137399) (xy 187.551589 -209.086469) (xy 187.574715 -209.038448)
			(xy 187.604739 -208.994411) (xy 187.640991 -208.95534) (xy 187.682662 -208.922109) (xy 187.72882 -208.89546)
			(xy 187.778434 -208.875988) (xy 187.830396 -208.864128) (xy 187.883546 -208.860145) (xy 187.936696 -208.864128)
			(xy 187.988658 -208.875988) (xy 188.038272 -208.89546) (xy 188.08443 -208.922109) (xy 188.126101 -208.95534)
			(xy 188.162353 -208.994411) (xy 188.192377 -209.038448) (xy 188.215503 -209.086469) (xy 188.231213 -209.137399)
			(xy 188.239156 -209.190103) (xy 188.239654 -209.216752) (xy 188.239156 -209.243401) (xy 191.628004 -209.243401)
			(xy 191.628004 -209.190103) (xy 191.635947 -209.137399) (xy 191.651657 -209.086469) (xy 191.674783 -209.038448)
			(xy 191.704807 -208.994411) (xy 191.741059 -208.95534) (xy 191.78273 -208.922109) (xy 191.828888 -208.89546)
			(xy 191.878502 -208.875988) (xy 191.930464 -208.864128) (xy 191.983614 -208.860145) (xy 192.036764 -208.864128)
			(xy 192.088726 -208.875988) (xy 192.13834 -208.89546) (xy 192.184498 -208.922109) (xy 192.226169 -208.95534)
			(xy 192.262421 -208.994411) (xy 192.292445 -209.038448) (xy 192.315571 -209.086469) (xy 192.331281 -209.137399)
			(xy 192.339224 -209.190103) (xy 192.339722 -209.216752) (xy 192.339224 -209.243401) (xy 202.615536 -209.243401)
			(xy 202.615536 -209.190103) (xy 202.623479 -209.137399) (xy 202.639189 -209.086469) (xy 202.662315 -209.038448)
			(xy 202.692339 -208.994411) (xy 202.728591 -208.95534) (xy 202.770262 -208.922109) (xy 202.81642 -208.89546)
			(xy 202.866034 -208.875988) (xy 202.917996 -208.864128) (xy 202.971146 -208.860145) (xy 203.024296 -208.864128)
			(xy 203.076258 -208.875988) (xy 203.125872 -208.89546) (xy 203.17203 -208.922109) (xy 203.213701 -208.95534)
			(xy 203.249953 -208.994411) (xy 203.279977 -209.038448) (xy 203.303103 -209.086469) (xy 203.318813 -209.137399)
			(xy 203.326756 -209.190103) (xy 203.327254 -209.216752) (xy 203.326756 -209.243401) (xy 206.715604 -209.243401)
			(xy 206.715604 -209.190103) (xy 206.723547 -209.137399) (xy 206.739257 -209.086469) (xy 206.762383 -209.038448)
			(xy 206.792407 -208.994411) (xy 206.828659 -208.95534) (xy 206.87033 -208.922109) (xy 206.916488 -208.89546)
			(xy 206.966102 -208.875988) (xy 207.018064 -208.864128) (xy 207.071214 -208.860145) (xy 207.124364 -208.864128)
			(xy 207.176326 -208.875988) (xy 207.22594 -208.89546) (xy 207.272098 -208.922109) (xy 207.313769 -208.95534)
			(xy 207.350021 -208.994411) (xy 207.380045 -209.038448) (xy 207.403171 -209.086469) (xy 207.418881 -209.137399)
			(xy 207.426824 -209.190103) (xy 207.427322 -209.216752) (xy 207.426824 -209.243401) (xy 207.418881 -209.296105)
			(xy 207.403171 -209.347035) (xy 207.380045 -209.395056) (xy 207.350021 -209.439093) (xy 207.313769 -209.478164)
			(xy 207.272098 -209.511395) (xy 207.22594 -209.538044) (xy 207.176326 -209.557516) (xy 207.124364 -209.569376)
			(xy 207.071214 -209.57336) (xy 207.018064 -209.569376) (xy 206.966102 -209.557516) (xy 206.916488 -209.538044)
			(xy 206.87033 -209.511395) (xy 206.828659 -209.478164) (xy 206.792407 -209.439093) (xy 206.762383 -209.395056)
			(xy 206.739257 -209.347035) (xy 206.723547 -209.296105) (xy 206.715604 -209.243401) (xy 203.326756 -209.243401)
			(xy 203.318813 -209.296105) (xy 203.303103 -209.347035) (xy 203.279977 -209.395056) (xy 203.249953 -209.439093)
			(xy 203.213701 -209.478164) (xy 203.17203 -209.511395) (xy 203.125872 -209.538044) (xy 203.076258 -209.557516)
			(xy 203.024296 -209.569376) (xy 202.971146 -209.57336) (xy 202.917996 -209.569376) (xy 202.866034 -209.557516)
			(xy 202.81642 -209.538044) (xy 202.770262 -209.511395) (xy 202.728591 -209.478164) (xy 202.692339 -209.439093)
			(xy 202.662315 -209.395056) (xy 202.639189 -209.347035) (xy 202.623479 -209.296105) (xy 202.615536 -209.243401)
			(xy 192.339224 -209.243401) (xy 192.331281 -209.296105) (xy 192.315571 -209.347035) (xy 192.292445 -209.395056)
			(xy 192.262421 -209.439093) (xy 192.226169 -209.478164) (xy 192.184498 -209.511395) (xy 192.13834 -209.538044)
			(xy 192.088726 -209.557516) (xy 192.036764 -209.569376) (xy 191.983614 -209.57336) (xy 191.930464 -209.569376)
			(xy 191.878502 -209.557516) (xy 191.828888 -209.538044) (xy 191.78273 -209.511395) (xy 191.741059 -209.478164)
			(xy 191.704807 -209.439093) (xy 191.674783 -209.395056) (xy 191.651657 -209.347035) (xy 191.635947 -209.296105)
			(xy 191.628004 -209.243401) (xy 188.239156 -209.243401) (xy 188.231213 -209.296105) (xy 188.215503 -209.347035)
			(xy 188.192377 -209.395056) (xy 188.162353 -209.439093) (xy 188.126101 -209.478164) (xy 188.08443 -209.511395)
			(xy 188.038272 -209.538044) (xy 187.988658 -209.557516) (xy 187.936696 -209.569376) (xy 187.883546 -209.57336)
			(xy 187.830396 -209.569376) (xy 187.778434 -209.557516) (xy 187.72882 -209.538044) (xy 187.682662 -209.511395)
			(xy 187.640991 -209.478164) (xy 187.604739 -209.439093) (xy 187.574715 -209.395056) (xy 187.551589 -209.347035)
			(xy 187.535879 -209.296105) (xy 187.527936 -209.243401) (xy 177.251624 -209.243401) (xy 177.243681 -209.296105)
			(xy 177.227971 -209.347035) (xy 177.204845 -209.395056) (xy 177.174821 -209.439093) (xy 177.138569 -209.478164)
			(xy 177.096898 -209.511395) (xy 177.05074 -209.538044) (xy 177.001126 -209.557516) (xy 176.949164 -209.569376)
			(xy 176.896014 -209.57336) (xy 176.842864 -209.569376) (xy 176.790902 -209.557516) (xy 176.741288 -209.538044)
			(xy 176.69513 -209.511395) (xy 176.653459 -209.478164) (xy 176.617207 -209.439093) (xy 176.587183 -209.395056)
			(xy 176.564057 -209.347035) (xy 176.548347 -209.296105) (xy 176.540404 -209.243401) (xy 173.151556 -209.243401)
			(xy 173.143613 -209.296105) (xy 173.127903 -209.347035) (xy 173.104777 -209.395056) (xy 173.074753 -209.439093)
			(xy 173.038501 -209.478164) (xy 172.99683 -209.511395) (xy 172.950672 -209.538044) (xy 172.901058 -209.557516)
			(xy 172.849096 -209.569376) (xy 172.795946 -209.57336) (xy 172.742796 -209.569376) (xy 172.690834 -209.557516)
			(xy 172.64122 -209.538044) (xy 172.595062 -209.511395) (xy 172.553391 -209.478164) (xy 172.517139 -209.439093)
			(xy 172.487115 -209.395056) (xy 172.463989 -209.347035) (xy 172.448279 -209.296105) (xy 172.440336 -209.243401)
			(xy 159.11576 -209.243401) (xy 159.11576 -210.093285) (xy 172.440336 -210.093285) (xy 172.440336 -210.039987)
			(xy 172.448279 -209.987283) (xy 172.463989 -209.936353) (xy 172.487115 -209.888332) (xy 172.517139 -209.844295)
			(xy 172.553391 -209.805224) (xy 172.595062 -209.771993) (xy 172.64122 -209.745344) (xy 172.690834 -209.725872)
			(xy 172.742796 -209.714012) (xy 172.795946 -209.710029) (xy 172.849096 -209.714012) (xy 172.901058 -209.725872)
			(xy 172.950672 -209.745344) (xy 172.99683 -209.771993) (xy 173.038501 -209.805224) (xy 173.074753 -209.844295)
			(xy 173.104777 -209.888332) (xy 173.127903 -209.936353) (xy 173.143613 -209.987283) (xy 173.151556 -210.039987)
			(xy 173.152054 -210.066636) (xy 173.151556 -210.093285) (xy 187.527936 -210.093285) (xy 187.527936 -210.039987)
			(xy 187.535879 -209.987283) (xy 187.551589 -209.936353) (xy 187.574715 -209.888332) (xy 187.604739 -209.844295)
			(xy 187.640991 -209.805224) (xy 187.682662 -209.771993) (xy 187.72882 -209.745344) (xy 187.778434 -209.725872)
			(xy 187.830396 -209.714012) (xy 187.883546 -209.710029) (xy 187.936696 -209.714012) (xy 187.988658 -209.725872)
			(xy 188.038272 -209.745344) (xy 188.08443 -209.771993) (xy 188.126101 -209.805224) (xy 188.162353 -209.844295)
			(xy 188.192377 -209.888332) (xy 188.215503 -209.936353) (xy 188.231213 -209.987283) (xy 188.239156 -210.039987)
			(xy 188.239654 -210.066636) (xy 188.239156 -210.093285) (xy 202.615536 -210.093285) (xy 202.615536 -210.039987)
			(xy 202.623479 -209.987283) (xy 202.639189 -209.936353) (xy 202.662315 -209.888332) (xy 202.692339 -209.844295)
			(xy 202.728591 -209.805224) (xy 202.770262 -209.771993) (xy 202.81642 -209.745344) (xy 202.866034 -209.725872)
			(xy 202.917996 -209.714012) (xy 202.971146 -209.710029) (xy 203.024296 -209.714012) (xy 203.076258 -209.725872)
			(xy 203.125872 -209.745344) (xy 203.17203 -209.771993) (xy 203.213701 -209.805224) (xy 203.249953 -209.844295)
			(xy 203.279977 -209.888332) (xy 203.303103 -209.936353) (xy 203.318813 -209.987283) (xy 203.326756 -210.039987)
			(xy 203.327254 -210.066636) (xy 203.326756 -210.093285) (xy 203.318813 -210.145989) (xy 203.303103 -210.196919)
			(xy 203.279977 -210.24494) (xy 203.249953 -210.288977) (xy 203.213701 -210.328048) (xy 203.17203 -210.361279)
			(xy 203.125872 -210.387928) (xy 203.076258 -210.4074) (xy 203.024296 -210.41926) (xy 202.971146 -210.423244)
			(xy 202.917996 -210.41926) (xy 202.866034 -210.4074) (xy 202.81642 -210.387928) (xy 202.770262 -210.361279)
			(xy 202.728591 -210.328048) (xy 202.692339 -210.288977) (xy 202.662315 -210.24494) (xy 202.639189 -210.196919)
			(xy 202.623479 -210.145989) (xy 202.615536 -210.093285) (xy 188.239156 -210.093285) (xy 188.231213 -210.145989)
			(xy 188.215503 -210.196919) (xy 188.192377 -210.24494) (xy 188.162353 -210.288977) (xy 188.126101 -210.328048)
			(xy 188.08443 -210.361279) (xy 188.038272 -210.387928) (xy 187.988658 -210.4074) (xy 187.936696 -210.41926)
			(xy 187.883546 -210.423244) (xy 187.830396 -210.41926) (xy 187.778434 -210.4074) (xy 187.72882 -210.387928)
			(xy 187.682662 -210.361279) (xy 187.640991 -210.328048) (xy 187.604739 -210.288977) (xy 187.574715 -210.24494)
			(xy 187.551589 -210.196919) (xy 187.535879 -210.145989) (xy 187.527936 -210.093285) (xy 173.151556 -210.093285)
			(xy 173.143613 -210.145989) (xy 173.127903 -210.196919) (xy 173.104777 -210.24494) (xy 173.074753 -210.288977)
			(xy 173.038501 -210.328048) (xy 172.99683 -210.361279) (xy 172.950672 -210.387928) (xy 172.901058 -210.4074)
			(xy 172.849096 -210.41926) (xy 172.795946 -210.423244) (xy 172.742796 -210.41926) (xy 172.690834 -210.4074)
			(xy 172.64122 -210.387928) (xy 172.595062 -210.361279) (xy 172.553391 -210.328048) (xy 172.517139 -210.288977)
			(xy 172.487115 -210.24494) (xy 172.463989 -210.196919) (xy 172.448279 -210.145989) (xy 172.440336 -210.093285)
			(xy 159.11576 -210.093285) (xy 159.11576 -210.943423) (xy 176.540404 -210.943423) (xy 176.540404 -210.890125)
			(xy 176.548347 -210.837421) (xy 176.564057 -210.786491) (xy 176.587183 -210.73847) (xy 176.617207 -210.694433)
			(xy 176.653459 -210.655362) (xy 176.69513 -210.622131) (xy 176.741288 -210.595482) (xy 176.790902 -210.57601)
			(xy 176.842864 -210.56415) (xy 176.896014 -210.560167) (xy 176.949164 -210.56415) (xy 177.001126 -210.57601)
			(xy 177.05074 -210.595482) (xy 177.096898 -210.622131) (xy 177.138569 -210.655362) (xy 177.174821 -210.694433)
			(xy 177.204845 -210.73847) (xy 177.227971 -210.786491) (xy 177.243681 -210.837421) (xy 177.251624 -210.890125)
			(xy 177.252122 -210.916774) (xy 177.251624 -210.943423) (xy 191.628004 -210.943423) (xy 191.628004 -210.890125)
			(xy 191.635947 -210.837421) (xy 191.651657 -210.786491) (xy 191.674783 -210.73847) (xy 191.704807 -210.694433)
			(xy 191.741059 -210.655362) (xy 191.78273 -210.622131) (xy 191.828888 -210.595482) (xy 191.878502 -210.57601)
			(xy 191.930464 -210.56415) (xy 191.983614 -210.560167) (xy 192.036764 -210.56415) (xy 192.088726 -210.57601)
			(xy 192.13834 -210.595482) (xy 192.184498 -210.622131) (xy 192.226169 -210.655362) (xy 192.262421 -210.694433)
			(xy 192.292445 -210.73847) (xy 192.315571 -210.786491) (xy 192.331281 -210.837421) (xy 192.339224 -210.890125)
			(xy 192.339722 -210.916774) (xy 192.339224 -210.943423) (xy 206.715604 -210.943423) (xy 206.715604 -210.890125)
			(xy 206.723547 -210.837421) (xy 206.739257 -210.786491) (xy 206.762383 -210.73847) (xy 206.792407 -210.694433)
			(xy 206.828659 -210.655362) (xy 206.87033 -210.622131) (xy 206.916488 -210.595482) (xy 206.966102 -210.57601)
			(xy 207.018064 -210.56415) (xy 207.071214 -210.560167) (xy 207.124364 -210.56415) (xy 207.176326 -210.57601)
			(xy 207.22594 -210.595482) (xy 207.272098 -210.622131) (xy 207.313769 -210.655362) (xy 207.350021 -210.694433)
			(xy 207.380045 -210.73847) (xy 207.403171 -210.786491) (xy 207.418881 -210.837421) (xy 207.426824 -210.890125)
			(xy 207.427322 -210.916774) (xy 207.426824 -210.943423) (xy 207.418881 -210.996127) (xy 207.403171 -211.047057)
			(xy 207.380045 -211.095078) (xy 207.350021 -211.139115) (xy 207.313769 -211.178186) (xy 207.272098 -211.211417)
			(xy 207.22594 -211.238066) (xy 207.176326 -211.257538) (xy 207.124364 -211.269398) (xy 207.071214 -211.273382)
			(xy 207.018064 -211.269398) (xy 206.966102 -211.257538) (xy 206.916488 -211.238066) (xy 206.87033 -211.211417)
			(xy 206.828659 -211.178186) (xy 206.792407 -211.139115) (xy 206.762383 -211.095078) (xy 206.739257 -211.047057)
			(xy 206.723547 -210.996127) (xy 206.715604 -210.943423) (xy 192.339224 -210.943423) (xy 192.331281 -210.996127)
			(xy 192.315571 -211.047057) (xy 192.292445 -211.095078) (xy 192.262421 -211.139115) (xy 192.226169 -211.178186)
			(xy 192.184498 -211.211417) (xy 192.13834 -211.238066) (xy 192.088726 -211.257538) (xy 192.036764 -211.269398)
			(xy 191.983614 -211.273382) (xy 191.930464 -211.269398) (xy 191.878502 -211.257538) (xy 191.828888 -211.238066)
			(xy 191.78273 -211.211417) (xy 191.741059 -211.178186) (xy 191.704807 -211.139115) (xy 191.674783 -211.095078)
			(xy 191.651657 -211.047057) (xy 191.635947 -210.996127) (xy 191.628004 -210.943423) (xy 177.251624 -210.943423)
			(xy 177.243681 -210.996127) (xy 177.227971 -211.047057) (xy 177.204845 -211.095078) (xy 177.174821 -211.139115)
			(xy 177.138569 -211.178186) (xy 177.096898 -211.211417) (xy 177.05074 -211.238066) (xy 177.001126 -211.257538)
			(xy 176.949164 -211.269398) (xy 176.896014 -211.273382) (xy 176.842864 -211.269398) (xy 176.790902 -211.257538)
			(xy 176.741288 -211.238066) (xy 176.69513 -211.211417) (xy 176.653459 -211.178186) (xy 176.617207 -211.139115)
			(xy 176.587183 -211.095078) (xy 176.564057 -211.047057) (xy 176.548347 -210.996127) (xy 176.540404 -210.943423)
			(xy 159.11576 -210.943423) (xy 159.11576 -211.793307) (xy 172.440336 -211.793307) (xy 172.440336 -211.740009)
			(xy 172.448279 -211.687305) (xy 172.463989 -211.636375) (xy 172.487115 -211.588354) (xy 172.517139 -211.544317)
			(xy 172.553391 -211.505246) (xy 172.595062 -211.472015) (xy 172.64122 -211.445366) (xy 172.690834 -211.425894)
			(xy 172.742796 -211.414034) (xy 172.795946 -211.410051) (xy 172.849096 -211.414034) (xy 172.901058 -211.425894)
			(xy 172.950672 -211.445366) (xy 172.99683 -211.472015) (xy 173.038501 -211.505246) (xy 173.074753 -211.544317)
			(xy 173.104777 -211.588354) (xy 173.127903 -211.636375) (xy 173.143613 -211.687305) (xy 173.151556 -211.740009)
			(xy 173.152054 -211.766658) (xy 173.151556 -211.793307) (xy 187.527936 -211.793307) (xy 187.527936 -211.740009)
			(xy 187.535879 -211.687305) (xy 187.551589 -211.636375) (xy 187.574715 -211.588354) (xy 187.604739 -211.544317)
			(xy 187.640991 -211.505246) (xy 187.682662 -211.472015) (xy 187.72882 -211.445366) (xy 187.778434 -211.425894)
			(xy 187.830396 -211.414034) (xy 187.883546 -211.410051) (xy 187.936696 -211.414034) (xy 187.988658 -211.425894)
			(xy 188.038272 -211.445366) (xy 188.08443 -211.472015) (xy 188.126101 -211.505246) (xy 188.162353 -211.544317)
			(xy 188.192377 -211.588354) (xy 188.215503 -211.636375) (xy 188.231213 -211.687305) (xy 188.239156 -211.740009)
			(xy 188.239654 -211.766658) (xy 188.239156 -211.793307) (xy 202.615536 -211.793307) (xy 202.615536 -211.740009)
			(xy 202.623479 -211.687305) (xy 202.639189 -211.636375) (xy 202.662315 -211.588354) (xy 202.692339 -211.544317)
			(xy 202.728591 -211.505246) (xy 202.770262 -211.472015) (xy 202.81642 -211.445366) (xy 202.866034 -211.425894)
			(xy 202.917996 -211.414034) (xy 202.971146 -211.410051) (xy 203.024296 -211.414034) (xy 203.076258 -211.425894)
			(xy 203.125872 -211.445366) (xy 203.17203 -211.472015) (xy 203.213701 -211.505246) (xy 203.249953 -211.544317)
			(xy 203.279977 -211.588354) (xy 203.303103 -211.636375) (xy 203.318813 -211.687305) (xy 203.326756 -211.740009)
			(xy 203.327254 -211.766658) (xy 203.326756 -211.793307) (xy 203.318813 -211.846011) (xy 203.303103 -211.896941)
			(xy 203.279977 -211.944962) (xy 203.249953 -211.988999) (xy 203.213701 -212.02807) (xy 203.17203 -212.061301)
			(xy 203.125872 -212.08795) (xy 203.076258 -212.107422) (xy 203.024296 -212.119282) (xy 202.971146 -212.123266)
			(xy 202.917996 -212.119282) (xy 202.866034 -212.107422) (xy 202.81642 -212.08795) (xy 202.770262 -212.061301)
			(xy 202.728591 -212.02807) (xy 202.692339 -211.988999) (xy 202.662315 -211.944962) (xy 202.639189 -211.896941)
			(xy 202.623479 -211.846011) (xy 202.615536 -211.793307) (xy 188.239156 -211.793307) (xy 188.231213 -211.846011)
			(xy 188.215503 -211.896941) (xy 188.192377 -211.944962) (xy 188.162353 -211.988999) (xy 188.126101 -212.02807)
			(xy 188.08443 -212.061301) (xy 188.038272 -212.08795) (xy 187.988658 -212.107422) (xy 187.936696 -212.119282)
			(xy 187.883546 -212.123266) (xy 187.830396 -212.119282) (xy 187.778434 -212.107422) (xy 187.72882 -212.08795)
			(xy 187.682662 -212.061301) (xy 187.640991 -212.02807) (xy 187.604739 -211.988999) (xy 187.574715 -211.944962)
			(xy 187.551589 -211.896941) (xy 187.535879 -211.846011) (xy 187.527936 -211.793307) (xy 173.151556 -211.793307)
			(xy 173.143613 -211.846011) (xy 173.127903 -211.896941) (xy 173.104777 -211.944962) (xy 173.074753 -211.988999)
			(xy 173.038501 -212.02807) (xy 172.99683 -212.061301) (xy 172.950672 -212.08795) (xy 172.901058 -212.107422)
			(xy 172.849096 -212.119282) (xy 172.795946 -212.123266) (xy 172.742796 -212.119282) (xy 172.690834 -212.107422)
			(xy 172.64122 -212.08795) (xy 172.595062 -212.061301) (xy 172.553391 -212.02807) (xy 172.517139 -211.988999)
			(xy 172.487115 -211.944962) (xy 172.463989 -211.896941) (xy 172.448279 -211.846011) (xy 172.440336 -211.793307)
			(xy 159.11576 -211.793307) (xy 159.11576 -212.643445) (xy 176.540404 -212.643445) (xy 176.540404 -212.590147)
			(xy 176.548347 -212.537443) (xy 176.564057 -212.486513) (xy 176.587183 -212.438492) (xy 176.617207 -212.394455)
			(xy 176.653459 -212.355384) (xy 176.69513 -212.322153) (xy 176.741288 -212.295504) (xy 176.790902 -212.276032)
			(xy 176.842864 -212.264172) (xy 176.896014 -212.260189) (xy 176.949164 -212.264172) (xy 177.001126 -212.276032)
			(xy 177.05074 -212.295504) (xy 177.096898 -212.322153) (xy 177.138569 -212.355384) (xy 177.174821 -212.394455)
			(xy 177.204845 -212.438492) (xy 177.227971 -212.486513) (xy 177.243681 -212.537443) (xy 177.251624 -212.590147)
			(xy 177.252122 -212.616796) (xy 177.251624 -212.643445) (xy 191.628004 -212.643445) (xy 191.628004 -212.590147)
			(xy 191.635947 -212.537443) (xy 191.651657 -212.486513) (xy 191.674783 -212.438492) (xy 191.704807 -212.394455)
			(xy 191.741059 -212.355384) (xy 191.78273 -212.322153) (xy 191.828888 -212.295504) (xy 191.878502 -212.276032)
			(xy 191.930464 -212.264172) (xy 191.983614 -212.260189) (xy 192.036764 -212.264172) (xy 192.088726 -212.276032)
			(xy 192.13834 -212.295504) (xy 192.184498 -212.322153) (xy 192.226169 -212.355384) (xy 192.262421 -212.394455)
			(xy 192.292445 -212.438492) (xy 192.315571 -212.486513) (xy 192.331281 -212.537443) (xy 192.339224 -212.590147)
			(xy 192.339722 -212.616796) (xy 192.339224 -212.643445) (xy 206.715604 -212.643445) (xy 206.715604 -212.590147)
			(xy 206.723547 -212.537443) (xy 206.739257 -212.486513) (xy 206.762383 -212.438492) (xy 206.792407 -212.394455)
			(xy 206.828659 -212.355384) (xy 206.87033 -212.322153) (xy 206.916488 -212.295504) (xy 206.966102 -212.276032)
			(xy 207.018064 -212.264172) (xy 207.071214 -212.260189) (xy 207.124364 -212.264172) (xy 207.176326 -212.276032)
			(xy 207.22594 -212.295504) (xy 207.272098 -212.322153) (xy 207.313769 -212.355384) (xy 207.350021 -212.394455)
			(xy 207.380045 -212.438492) (xy 207.403171 -212.486513) (xy 207.418881 -212.537443) (xy 207.426824 -212.590147)
			(xy 207.427322 -212.616796) (xy 207.426824 -212.643445) (xy 207.418881 -212.696149) (xy 207.403171 -212.747079)
			(xy 207.380045 -212.7951) (xy 207.350021 -212.839137) (xy 207.313769 -212.878208) (xy 207.272098 -212.911439)
			(xy 207.22594 -212.938088) (xy 207.176326 -212.95756) (xy 207.124364 -212.96942) (xy 207.071214 -212.973404)
			(xy 207.018064 -212.96942) (xy 206.966102 -212.95756) (xy 206.916488 -212.938088) (xy 206.87033 -212.911439)
			(xy 206.828659 -212.878208) (xy 206.792407 -212.839137) (xy 206.762383 -212.7951) (xy 206.739257 -212.747079)
			(xy 206.723547 -212.696149) (xy 206.715604 -212.643445) (xy 192.339224 -212.643445) (xy 192.331281 -212.696149)
			(xy 192.315571 -212.747079) (xy 192.292445 -212.7951) (xy 192.262421 -212.839137) (xy 192.226169 -212.878208)
			(xy 192.184498 -212.911439) (xy 192.13834 -212.938088) (xy 192.088726 -212.95756) (xy 192.036764 -212.96942)
			(xy 191.983614 -212.973404) (xy 191.930464 -212.96942) (xy 191.878502 -212.95756) (xy 191.828888 -212.938088)
			(xy 191.78273 -212.911439) (xy 191.741059 -212.878208) (xy 191.704807 -212.839137) (xy 191.674783 -212.7951)
			(xy 191.651657 -212.747079) (xy 191.635947 -212.696149) (xy 191.628004 -212.643445) (xy 177.251624 -212.643445)
			(xy 177.243681 -212.696149) (xy 177.227971 -212.747079) (xy 177.204845 -212.7951) (xy 177.174821 -212.839137)
			(xy 177.138569 -212.878208) (xy 177.096898 -212.911439) (xy 177.05074 -212.938088) (xy 177.001126 -212.95756)
			(xy 176.949164 -212.96942) (xy 176.896014 -212.973404) (xy 176.842864 -212.96942) (xy 176.790902 -212.95756)
			(xy 176.741288 -212.938088) (xy 176.69513 -212.911439) (xy 176.653459 -212.878208) (xy 176.617207 -212.839137)
			(xy 176.587183 -212.7951) (xy 176.564057 -212.747079) (xy 176.548347 -212.696149) (xy 176.540404 -212.643445)
			(xy 159.11576 -212.643445) (xy 159.11576 -213.493329) (xy 172.440336 -213.493329) (xy 172.440336 -213.440031)
			(xy 172.448279 -213.387327) (xy 172.463989 -213.336397) (xy 172.487115 -213.288376) (xy 172.517139 -213.244339)
			(xy 172.553391 -213.205268) (xy 172.595062 -213.172037) (xy 172.64122 -213.145388) (xy 172.690834 -213.125916)
			(xy 172.742796 -213.114056) (xy 172.795946 -213.110073) (xy 172.849096 -213.114056) (xy 172.901058 -213.125916)
			(xy 172.950672 -213.145388) (xy 172.99683 -213.172037) (xy 173.038501 -213.205268) (xy 173.074753 -213.244339)
			(xy 173.104777 -213.288376) (xy 173.127903 -213.336397) (xy 173.143613 -213.387327) (xy 173.151556 -213.440031)
			(xy 173.152054 -213.46668) (xy 173.151556 -213.493329) (xy 187.527936 -213.493329) (xy 187.527936 -213.440031)
			(xy 187.535879 -213.387327) (xy 187.551589 -213.336397) (xy 187.574715 -213.288376) (xy 187.604739 -213.244339)
			(xy 187.640991 -213.205268) (xy 187.682662 -213.172037) (xy 187.72882 -213.145388) (xy 187.778434 -213.125916)
			(xy 187.830396 -213.114056) (xy 187.883546 -213.110073) (xy 187.936696 -213.114056) (xy 187.988658 -213.125916)
			(xy 188.038272 -213.145388) (xy 188.08443 -213.172037) (xy 188.126101 -213.205268) (xy 188.162353 -213.244339)
			(xy 188.192377 -213.288376) (xy 188.215503 -213.336397) (xy 188.231213 -213.387327) (xy 188.239156 -213.440031)
			(xy 188.239654 -213.46668) (xy 188.239156 -213.493329) (xy 202.615536 -213.493329) (xy 202.615536 -213.440031)
			(xy 202.623479 -213.387327) (xy 202.639189 -213.336397) (xy 202.662315 -213.288376) (xy 202.692339 -213.244339)
			(xy 202.728591 -213.205268) (xy 202.770262 -213.172037) (xy 202.81642 -213.145388) (xy 202.866034 -213.125916)
			(xy 202.917996 -213.114056) (xy 202.971146 -213.110073) (xy 203.024296 -213.114056) (xy 203.076258 -213.125916)
			(xy 203.125872 -213.145388) (xy 203.17203 -213.172037) (xy 203.213701 -213.205268) (xy 203.249953 -213.244339)
			(xy 203.279977 -213.288376) (xy 203.303103 -213.336397) (xy 203.318813 -213.387327) (xy 203.326756 -213.440031)
			(xy 203.327254 -213.46668) (xy 203.326756 -213.493329) (xy 203.318813 -213.546033) (xy 203.303103 -213.596963)
			(xy 203.279977 -213.644984) (xy 203.249953 -213.689021) (xy 203.213701 -213.728092) (xy 203.17203 -213.761323)
			(xy 203.125872 -213.787972) (xy 203.076258 -213.807444) (xy 203.024296 -213.819304) (xy 202.971146 -213.823288)
			(xy 202.917996 -213.819304) (xy 202.866034 -213.807444) (xy 202.81642 -213.787972) (xy 202.770262 -213.761323)
			(xy 202.728591 -213.728092) (xy 202.692339 -213.689021) (xy 202.662315 -213.644984) (xy 202.639189 -213.596963)
			(xy 202.623479 -213.546033) (xy 202.615536 -213.493329) (xy 188.239156 -213.493329) (xy 188.231213 -213.546033)
			(xy 188.215503 -213.596963) (xy 188.192377 -213.644984) (xy 188.162353 -213.689021) (xy 188.126101 -213.728092)
			(xy 188.08443 -213.761323) (xy 188.038272 -213.787972) (xy 187.988658 -213.807444) (xy 187.936696 -213.819304)
			(xy 187.883546 -213.823288) (xy 187.830396 -213.819304) (xy 187.778434 -213.807444) (xy 187.72882 -213.787972)
			(xy 187.682662 -213.761323) (xy 187.640991 -213.728092) (xy 187.604739 -213.689021) (xy 187.574715 -213.644984)
			(xy 187.551589 -213.596963) (xy 187.535879 -213.546033) (xy 187.527936 -213.493329) (xy 173.151556 -213.493329)
			(xy 173.143613 -213.546033) (xy 173.127903 -213.596963) (xy 173.104777 -213.644984) (xy 173.074753 -213.689021)
			(xy 173.038501 -213.728092) (xy 172.99683 -213.761323) (xy 172.950672 -213.787972) (xy 172.901058 -213.807444)
			(xy 172.849096 -213.819304) (xy 172.795946 -213.823288) (xy 172.742796 -213.819304) (xy 172.690834 -213.807444)
			(xy 172.64122 -213.787972) (xy 172.595062 -213.761323) (xy 172.553391 -213.728092) (xy 172.517139 -213.689021)
			(xy 172.487115 -213.644984) (xy 172.463989 -213.596963) (xy 172.448279 -213.546033) (xy 172.440336 -213.493329)
			(xy 159.11576 -213.493329) (xy 159.11576 -214.343213) (xy 176.540404 -214.343213) (xy 176.540404 -214.289915)
			(xy 176.548347 -214.237211) (xy 176.564057 -214.186281) (xy 176.587183 -214.13826) (xy 176.617207 -214.094223)
			(xy 176.653459 -214.055152) (xy 176.69513 -214.021921) (xy 176.741288 -213.995272) (xy 176.790902 -213.9758)
			(xy 176.842864 -213.96394) (xy 176.896014 -213.959957) (xy 176.949164 -213.96394) (xy 177.001126 -213.9758)
			(xy 177.05074 -213.995272) (xy 177.096898 -214.021921) (xy 177.138569 -214.055152) (xy 177.174821 -214.094223)
			(xy 177.204845 -214.13826) (xy 177.227971 -214.186281) (xy 177.243681 -214.237211) (xy 177.251624 -214.289915)
			(xy 177.252122 -214.316564) (xy 177.251624 -214.343213) (xy 191.628004 -214.343213) (xy 191.628004 -214.289915)
			(xy 191.635947 -214.237211) (xy 191.651657 -214.186281) (xy 191.674783 -214.13826) (xy 191.704807 -214.094223)
			(xy 191.741059 -214.055152) (xy 191.78273 -214.021921) (xy 191.828888 -213.995272) (xy 191.878502 -213.9758)
			(xy 191.930464 -213.96394) (xy 191.983614 -213.959957) (xy 192.036764 -213.96394) (xy 192.088726 -213.9758)
			(xy 192.13834 -213.995272) (xy 192.184498 -214.021921) (xy 192.226169 -214.055152) (xy 192.262421 -214.094223)
			(xy 192.292445 -214.13826) (xy 192.315571 -214.186281) (xy 192.331281 -214.237211) (xy 192.339224 -214.289915)
			(xy 192.339722 -214.316564) (xy 192.339224 -214.343213) (xy 206.715604 -214.343213) (xy 206.715604 -214.289915)
			(xy 206.723547 -214.237211) (xy 206.739257 -214.186281) (xy 206.762383 -214.13826) (xy 206.792407 -214.094223)
			(xy 206.828659 -214.055152) (xy 206.87033 -214.021921) (xy 206.916488 -213.995272) (xy 206.966102 -213.9758)
			(xy 207.018064 -213.96394) (xy 207.071214 -213.959957) (xy 207.124364 -213.96394) (xy 207.176326 -213.9758)
			(xy 207.22594 -213.995272) (xy 207.272098 -214.021921) (xy 207.313769 -214.055152) (xy 207.350021 -214.094223)
			(xy 207.380045 -214.13826) (xy 207.403171 -214.186281) (xy 207.418881 -214.237211) (xy 207.426824 -214.289915)
			(xy 207.427322 -214.316564) (xy 207.426824 -214.343213) (xy 207.418881 -214.395917) (xy 207.403171 -214.446847)
			(xy 207.380045 -214.494868) (xy 207.350021 -214.538905) (xy 207.313769 -214.577976) (xy 207.272098 -214.611207)
			(xy 207.22594 -214.637856) (xy 207.176326 -214.657328) (xy 207.124364 -214.669188) (xy 207.071214 -214.673172)
			(xy 207.018064 -214.669188) (xy 206.966102 -214.657328) (xy 206.916488 -214.637856) (xy 206.87033 -214.611207)
			(xy 206.828659 -214.577976) (xy 206.792407 -214.538905) (xy 206.762383 -214.494868) (xy 206.739257 -214.446847)
			(xy 206.723547 -214.395917) (xy 206.715604 -214.343213) (xy 192.339224 -214.343213) (xy 192.331281 -214.395917)
			(xy 192.315571 -214.446847) (xy 192.292445 -214.494868) (xy 192.262421 -214.538905) (xy 192.226169 -214.577976)
			(xy 192.184498 -214.611207) (xy 192.13834 -214.637856) (xy 192.088726 -214.657328) (xy 192.036764 -214.669188)
			(xy 191.983614 -214.673172) (xy 191.930464 -214.669188) (xy 191.878502 -214.657328) (xy 191.828888 -214.637856)
			(xy 191.78273 -214.611207) (xy 191.741059 -214.577976) (xy 191.704807 -214.538905) (xy 191.674783 -214.494868)
			(xy 191.651657 -214.446847) (xy 191.635947 -214.395917) (xy 191.628004 -214.343213) (xy 177.251624 -214.343213)
			(xy 177.243681 -214.395917) (xy 177.227971 -214.446847) (xy 177.204845 -214.494868) (xy 177.174821 -214.538905)
			(xy 177.138569 -214.577976) (xy 177.096898 -214.611207) (xy 177.05074 -214.637856) (xy 177.001126 -214.657328)
			(xy 176.949164 -214.669188) (xy 176.896014 -214.673172) (xy 176.842864 -214.669188) (xy 176.790902 -214.657328)
			(xy 176.741288 -214.637856) (xy 176.69513 -214.611207) (xy 176.653459 -214.577976) (xy 176.617207 -214.538905)
			(xy 176.587183 -214.494868) (xy 176.564057 -214.446847) (xy 176.548347 -214.395917) (xy 176.540404 -214.343213)
			(xy 159.11576 -214.343213) (xy 159.11576 -215.193351) (xy 172.440336 -215.193351) (xy 172.440336 -215.140053)
			(xy 172.448279 -215.087349) (xy 172.463989 -215.036419) (xy 172.487115 -214.988398) (xy 172.517139 -214.944361)
			(xy 172.553391 -214.90529) (xy 172.595062 -214.872059) (xy 172.64122 -214.84541) (xy 172.690834 -214.825938)
			(xy 172.742796 -214.814078) (xy 172.795946 -214.810095) (xy 172.849096 -214.814078) (xy 172.901058 -214.825938)
			(xy 172.950672 -214.84541) (xy 172.99683 -214.872059) (xy 173.038501 -214.90529) (xy 173.074753 -214.944361)
			(xy 173.104777 -214.988398) (xy 173.127903 -215.036419) (xy 173.143613 -215.087349) (xy 173.151556 -215.140053)
			(xy 173.152054 -215.166702) (xy 173.151556 -215.193351) (xy 187.527936 -215.193351) (xy 187.527936 -215.140053)
			(xy 187.535879 -215.087349) (xy 187.551589 -215.036419) (xy 187.574715 -214.988398) (xy 187.604739 -214.944361)
			(xy 187.640991 -214.90529) (xy 187.682662 -214.872059) (xy 187.72882 -214.84541) (xy 187.778434 -214.825938)
			(xy 187.830396 -214.814078) (xy 187.883546 -214.810095) (xy 187.936696 -214.814078) (xy 187.988658 -214.825938)
			(xy 188.038272 -214.84541) (xy 188.08443 -214.872059) (xy 188.126101 -214.90529) (xy 188.162353 -214.944361)
			(xy 188.192377 -214.988398) (xy 188.215503 -215.036419) (xy 188.231213 -215.087349) (xy 188.239156 -215.140053)
			(xy 188.239654 -215.166702) (xy 188.239156 -215.193351) (xy 202.615536 -215.193351) (xy 202.615536 -215.140053)
			(xy 202.623479 -215.087349) (xy 202.639189 -215.036419) (xy 202.662315 -214.988398) (xy 202.692339 -214.944361)
			(xy 202.728591 -214.90529) (xy 202.770262 -214.872059) (xy 202.81642 -214.84541) (xy 202.866034 -214.825938)
			(xy 202.917996 -214.814078) (xy 202.971146 -214.810095) (xy 203.024296 -214.814078) (xy 203.076258 -214.825938)
			(xy 203.125872 -214.84541) (xy 203.17203 -214.872059) (xy 203.213701 -214.90529) (xy 203.249953 -214.944361)
			(xy 203.279977 -214.988398) (xy 203.303103 -215.036419) (xy 203.318813 -215.087349) (xy 203.326756 -215.140053)
			(xy 203.327254 -215.166702) (xy 203.326756 -215.193351) (xy 203.318813 -215.246055) (xy 203.303103 -215.296985)
			(xy 203.279977 -215.345006) (xy 203.249953 -215.389043) (xy 203.213701 -215.428114) (xy 203.17203 -215.461345)
			(xy 203.125872 -215.487994) (xy 203.076258 -215.507466) (xy 203.024296 -215.519326) (xy 202.971146 -215.52331)
			(xy 202.917996 -215.519326) (xy 202.866034 -215.507466) (xy 202.81642 -215.487994) (xy 202.770262 -215.461345)
			(xy 202.728591 -215.428114) (xy 202.692339 -215.389043) (xy 202.662315 -215.345006) (xy 202.639189 -215.296985)
			(xy 202.623479 -215.246055) (xy 202.615536 -215.193351) (xy 188.239156 -215.193351) (xy 188.231213 -215.246055)
			(xy 188.215503 -215.296985) (xy 188.192377 -215.345006) (xy 188.162353 -215.389043) (xy 188.126101 -215.428114)
			(xy 188.08443 -215.461345) (xy 188.038272 -215.487994) (xy 187.988658 -215.507466) (xy 187.936696 -215.519326)
			(xy 187.883546 -215.52331) (xy 187.830396 -215.519326) (xy 187.778434 -215.507466) (xy 187.72882 -215.487994)
			(xy 187.682662 -215.461345) (xy 187.640991 -215.428114) (xy 187.604739 -215.389043) (xy 187.574715 -215.345006)
			(xy 187.551589 -215.296985) (xy 187.535879 -215.246055) (xy 187.527936 -215.193351) (xy 173.151556 -215.193351)
			(xy 173.143613 -215.246055) (xy 173.127903 -215.296985) (xy 173.104777 -215.345006) (xy 173.074753 -215.389043)
			(xy 173.038501 -215.428114) (xy 172.99683 -215.461345) (xy 172.950672 -215.487994) (xy 172.901058 -215.507466)
			(xy 172.849096 -215.519326) (xy 172.795946 -215.52331) (xy 172.742796 -215.519326) (xy 172.690834 -215.507466)
			(xy 172.64122 -215.487994) (xy 172.595062 -215.461345) (xy 172.553391 -215.428114) (xy 172.517139 -215.389043)
			(xy 172.487115 -215.345006) (xy 172.463989 -215.296985) (xy 172.448279 -215.246055) (xy 172.440336 -215.193351)
			(xy 159.11576 -215.193351) (xy 159.11576 -216.043235) (xy 176.540404 -216.043235) (xy 176.540404 -215.989937)
			(xy 176.548347 -215.937233) (xy 176.564057 -215.886303) (xy 176.587183 -215.838282) (xy 176.617207 -215.794245)
			(xy 176.653459 -215.755174) (xy 176.69513 -215.721943) (xy 176.741288 -215.695294) (xy 176.790902 -215.675822)
			(xy 176.842864 -215.663962) (xy 176.896014 -215.659979) (xy 176.949164 -215.663962) (xy 177.001126 -215.675822)
			(xy 177.05074 -215.695294) (xy 177.096898 -215.721943) (xy 177.138569 -215.755174) (xy 177.174821 -215.794245)
			(xy 177.204845 -215.838282) (xy 177.227971 -215.886303) (xy 177.243681 -215.937233) (xy 177.251624 -215.989937)
			(xy 177.252122 -216.016586) (xy 177.251624 -216.043235) (xy 191.628004 -216.043235) (xy 191.628004 -215.989937)
			(xy 191.635947 -215.937233) (xy 191.651657 -215.886303) (xy 191.674783 -215.838282) (xy 191.704807 -215.794245)
			(xy 191.741059 -215.755174) (xy 191.78273 -215.721943) (xy 191.828888 -215.695294) (xy 191.878502 -215.675822)
			(xy 191.930464 -215.663962) (xy 191.983614 -215.659979) (xy 192.036764 -215.663962) (xy 192.088726 -215.675822)
			(xy 192.13834 -215.695294) (xy 192.184498 -215.721943) (xy 192.226169 -215.755174) (xy 192.262421 -215.794245)
			(xy 192.292445 -215.838282) (xy 192.315571 -215.886303) (xy 192.331281 -215.937233) (xy 192.339224 -215.989937)
			(xy 192.339722 -216.016586) (xy 192.339224 -216.043235) (xy 206.715604 -216.043235) (xy 206.715604 -215.989937)
			(xy 206.723547 -215.937233) (xy 206.739257 -215.886303) (xy 206.762383 -215.838282) (xy 206.792407 -215.794245)
			(xy 206.828659 -215.755174) (xy 206.87033 -215.721943) (xy 206.916488 -215.695294) (xy 206.966102 -215.675822)
			(xy 207.018064 -215.663962) (xy 207.071214 -215.659979) (xy 207.124364 -215.663962) (xy 207.176326 -215.675822)
			(xy 207.22594 -215.695294) (xy 207.272098 -215.721943) (xy 207.313769 -215.755174) (xy 207.350021 -215.794245)
			(xy 207.380045 -215.838282) (xy 207.403171 -215.886303) (xy 207.418881 -215.937233) (xy 207.426824 -215.989937)
			(xy 207.427322 -216.016586) (xy 207.426824 -216.043235) (xy 207.418881 -216.095939) (xy 207.403171 -216.146869)
			(xy 207.380045 -216.19489) (xy 207.350021 -216.238927) (xy 207.313769 -216.277998) (xy 207.272098 -216.311229)
			(xy 207.22594 -216.337878) (xy 207.176326 -216.35735) (xy 207.124364 -216.36921) (xy 207.071214 -216.373194)
			(xy 207.018064 -216.36921) (xy 206.966102 -216.35735) (xy 206.916488 -216.337878) (xy 206.87033 -216.311229)
			(xy 206.828659 -216.277998) (xy 206.792407 -216.238927) (xy 206.762383 -216.19489) (xy 206.739257 -216.146869)
			(xy 206.723547 -216.095939) (xy 206.715604 -216.043235) (xy 192.339224 -216.043235) (xy 192.331281 -216.095939)
			(xy 192.315571 -216.146869) (xy 192.292445 -216.19489) (xy 192.262421 -216.238927) (xy 192.226169 -216.277998)
			(xy 192.184498 -216.311229) (xy 192.13834 -216.337878) (xy 192.088726 -216.35735) (xy 192.036764 -216.36921)
			(xy 191.983614 -216.373194) (xy 191.930464 -216.36921) (xy 191.878502 -216.35735) (xy 191.828888 -216.337878)
			(xy 191.78273 -216.311229) (xy 191.741059 -216.277998) (xy 191.704807 -216.238927) (xy 191.674783 -216.19489)
			(xy 191.651657 -216.146869) (xy 191.635947 -216.095939) (xy 191.628004 -216.043235) (xy 177.251624 -216.043235)
			(xy 177.243681 -216.095939) (xy 177.227971 -216.146869) (xy 177.204845 -216.19489) (xy 177.174821 -216.238927)
			(xy 177.138569 -216.277998) (xy 177.096898 -216.311229) (xy 177.05074 -216.337878) (xy 177.001126 -216.35735)
			(xy 176.949164 -216.36921) (xy 176.896014 -216.373194) (xy 176.842864 -216.36921) (xy 176.790902 -216.35735)
			(xy 176.741288 -216.337878) (xy 176.69513 -216.311229) (xy 176.653459 -216.277998) (xy 176.617207 -216.238927)
			(xy 176.587183 -216.19489) (xy 176.564057 -216.146869) (xy 176.548347 -216.095939) (xy 176.540404 -216.043235)
			(xy 159.11576 -216.043235) (xy 159.11576 -216.893373) (xy 172.440336 -216.893373) (xy 172.440336 -216.840075)
			(xy 172.448279 -216.787371) (xy 172.463989 -216.736441) (xy 172.487115 -216.68842) (xy 172.517139 -216.644383)
			(xy 172.553391 -216.605312) (xy 172.595062 -216.572081) (xy 172.64122 -216.545432) (xy 172.690834 -216.52596)
			(xy 172.742796 -216.5141) (xy 172.795946 -216.510117) (xy 172.849096 -216.5141) (xy 172.901058 -216.52596)
			(xy 172.950672 -216.545432) (xy 172.99683 -216.572081) (xy 173.038501 -216.605312) (xy 173.074753 -216.644383)
			(xy 173.104777 -216.68842) (xy 173.127903 -216.736441) (xy 173.143613 -216.787371) (xy 173.151556 -216.840075)
			(xy 173.152054 -216.866724) (xy 173.151556 -216.893373) (xy 187.527936 -216.893373) (xy 187.527936 -216.840075)
			(xy 187.535879 -216.787371) (xy 187.551589 -216.736441) (xy 187.574715 -216.68842) (xy 187.604739 -216.644383)
			(xy 187.640991 -216.605312) (xy 187.682662 -216.572081) (xy 187.72882 -216.545432) (xy 187.778434 -216.52596)
			(xy 187.830396 -216.5141) (xy 187.883546 -216.510117) (xy 187.936696 -216.5141) (xy 187.988658 -216.52596)
			(xy 188.038272 -216.545432) (xy 188.08443 -216.572081) (xy 188.126101 -216.605312) (xy 188.162353 -216.644383)
			(xy 188.192377 -216.68842) (xy 188.215503 -216.736441) (xy 188.231213 -216.787371) (xy 188.239156 -216.840075)
			(xy 188.239654 -216.866724) (xy 188.239156 -216.893373) (xy 202.615536 -216.893373) (xy 202.615536 -216.840075)
			(xy 202.623479 -216.787371) (xy 202.639189 -216.736441) (xy 202.662315 -216.68842) (xy 202.692339 -216.644383)
			(xy 202.728591 -216.605312) (xy 202.770262 -216.572081) (xy 202.81642 -216.545432) (xy 202.866034 -216.52596)
			(xy 202.917996 -216.5141) (xy 202.971146 -216.510117) (xy 203.024296 -216.5141) (xy 203.076258 -216.52596)
			(xy 203.125872 -216.545432) (xy 203.17203 -216.572081) (xy 203.213701 -216.605312) (xy 203.249953 -216.644383)
			(xy 203.279977 -216.68842) (xy 203.303103 -216.736441) (xy 203.318813 -216.787371) (xy 203.326756 -216.840075)
			(xy 203.327254 -216.866724) (xy 203.326756 -216.893373) (xy 203.318813 -216.946077) (xy 203.303103 -216.997007)
			(xy 203.279977 -217.045028) (xy 203.249953 -217.089065) (xy 203.213701 -217.128136) (xy 203.17203 -217.161367)
			(xy 203.125872 -217.188016) (xy 203.076258 -217.207488) (xy 203.024296 -217.219348) (xy 202.971146 -217.223332)
			(xy 202.917996 -217.219348) (xy 202.866034 -217.207488) (xy 202.81642 -217.188016) (xy 202.770262 -217.161367)
			(xy 202.728591 -217.128136) (xy 202.692339 -217.089065) (xy 202.662315 -217.045028) (xy 202.639189 -216.997007)
			(xy 202.623479 -216.946077) (xy 202.615536 -216.893373) (xy 188.239156 -216.893373) (xy 188.231213 -216.946077)
			(xy 188.215503 -216.997007) (xy 188.192377 -217.045028) (xy 188.162353 -217.089065) (xy 188.126101 -217.128136)
			(xy 188.08443 -217.161367) (xy 188.038272 -217.188016) (xy 187.988658 -217.207488) (xy 187.936696 -217.219348)
			(xy 187.883546 -217.223332) (xy 187.830396 -217.219348) (xy 187.778434 -217.207488) (xy 187.72882 -217.188016)
			(xy 187.682662 -217.161367) (xy 187.640991 -217.128136) (xy 187.604739 -217.089065) (xy 187.574715 -217.045028)
			(xy 187.551589 -216.997007) (xy 187.535879 -216.946077) (xy 187.527936 -216.893373) (xy 173.151556 -216.893373)
			(xy 173.143613 -216.946077) (xy 173.127903 -216.997007) (xy 173.104777 -217.045028) (xy 173.074753 -217.089065)
			(xy 173.038501 -217.128136) (xy 172.99683 -217.161367) (xy 172.950672 -217.188016) (xy 172.901058 -217.207488)
			(xy 172.849096 -217.219348) (xy 172.795946 -217.223332) (xy 172.742796 -217.219348) (xy 172.690834 -217.207488)
			(xy 172.64122 -217.188016) (xy 172.595062 -217.161367) (xy 172.553391 -217.128136) (xy 172.517139 -217.089065)
			(xy 172.487115 -217.045028) (xy 172.463989 -216.997007) (xy 172.448279 -216.946077) (xy 172.440336 -216.893373)
			(xy 159.11576 -216.893373) (xy 159.11576 -217.743257) (xy 176.540404 -217.743257) (xy 176.540404 -217.689959)
			(xy 176.548347 -217.637255) (xy 176.564057 -217.586325) (xy 176.587183 -217.538304) (xy 176.617207 -217.494267)
			(xy 176.653459 -217.455196) (xy 176.69513 -217.421965) (xy 176.741288 -217.395316) (xy 176.790902 -217.375844)
			(xy 176.842864 -217.363984) (xy 176.896014 -217.360001) (xy 176.949164 -217.363984) (xy 177.001126 -217.375844)
			(xy 177.05074 -217.395316) (xy 177.096898 -217.421965) (xy 177.138569 -217.455196) (xy 177.174821 -217.494267)
			(xy 177.204845 -217.538304) (xy 177.227971 -217.586325) (xy 177.243681 -217.637255) (xy 177.251624 -217.689959)
			(xy 177.252122 -217.716608) (xy 177.251624 -217.743257) (xy 191.628004 -217.743257) (xy 191.628004 -217.689959)
			(xy 191.635947 -217.637255) (xy 191.651657 -217.586325) (xy 191.674783 -217.538304) (xy 191.704807 -217.494267)
			(xy 191.741059 -217.455196) (xy 191.78273 -217.421965) (xy 191.828888 -217.395316) (xy 191.878502 -217.375844)
			(xy 191.930464 -217.363984) (xy 191.983614 -217.360001) (xy 192.036764 -217.363984) (xy 192.088726 -217.375844)
			(xy 192.13834 -217.395316) (xy 192.184498 -217.421965) (xy 192.226169 -217.455196) (xy 192.262421 -217.494267)
			(xy 192.292445 -217.538304) (xy 192.315571 -217.586325) (xy 192.331281 -217.637255) (xy 192.339224 -217.689959)
			(xy 192.339722 -217.716608) (xy 192.339224 -217.743257) (xy 206.715604 -217.743257) (xy 206.715604 -217.689959)
			(xy 206.723547 -217.637255) (xy 206.739257 -217.586325) (xy 206.762383 -217.538304) (xy 206.792407 -217.494267)
			(xy 206.828659 -217.455196) (xy 206.87033 -217.421965) (xy 206.916488 -217.395316) (xy 206.966102 -217.375844)
			(xy 207.018064 -217.363984) (xy 207.071214 -217.360001) (xy 207.124364 -217.363984) (xy 207.176326 -217.375844)
			(xy 207.22594 -217.395316) (xy 207.272098 -217.421965) (xy 207.313769 -217.455196) (xy 207.350021 -217.494267)
			(xy 207.380045 -217.538304) (xy 207.403171 -217.586325) (xy 207.418881 -217.637255) (xy 207.426824 -217.689959)
			(xy 207.427322 -217.716608) (xy 207.426824 -217.743257) (xy 207.418881 -217.795961) (xy 207.403171 -217.846891)
			(xy 207.380045 -217.894912) (xy 207.350021 -217.938949) (xy 207.313769 -217.97802) (xy 207.272098 -218.011251)
			(xy 207.22594 -218.0379) (xy 207.176326 -218.057372) (xy 207.124364 -218.069232) (xy 207.071214 -218.073216)
			(xy 207.018064 -218.069232) (xy 206.966102 -218.057372) (xy 206.916488 -218.0379) (xy 206.87033 -218.011251)
			(xy 206.828659 -217.97802) (xy 206.792407 -217.938949) (xy 206.762383 -217.894912) (xy 206.739257 -217.846891)
			(xy 206.723547 -217.795961) (xy 206.715604 -217.743257) (xy 192.339224 -217.743257) (xy 192.331281 -217.795961)
			(xy 192.315571 -217.846891) (xy 192.292445 -217.894912) (xy 192.262421 -217.938949) (xy 192.226169 -217.97802)
			(xy 192.184498 -218.011251) (xy 192.13834 -218.0379) (xy 192.088726 -218.057372) (xy 192.036764 -218.069232)
			(xy 191.983614 -218.073216) (xy 191.930464 -218.069232) (xy 191.878502 -218.057372) (xy 191.828888 -218.0379)
			(xy 191.78273 -218.011251) (xy 191.741059 -217.97802) (xy 191.704807 -217.938949) (xy 191.674783 -217.894912)
			(xy 191.651657 -217.846891) (xy 191.635947 -217.795961) (xy 191.628004 -217.743257) (xy 177.251624 -217.743257)
			(xy 177.243681 -217.795961) (xy 177.227971 -217.846891) (xy 177.204845 -217.894912) (xy 177.174821 -217.938949)
			(xy 177.138569 -217.97802) (xy 177.096898 -218.011251) (xy 177.05074 -218.0379) (xy 177.001126 -218.057372)
			(xy 176.949164 -218.069232) (xy 176.896014 -218.073216) (xy 176.842864 -218.069232) (xy 176.790902 -218.057372)
			(xy 176.741288 -218.0379) (xy 176.69513 -218.011251) (xy 176.653459 -217.97802) (xy 176.617207 -217.938949)
			(xy 176.587183 -217.894912) (xy 176.564057 -217.846891) (xy 176.548347 -217.795961) (xy 176.540404 -217.743257)
			(xy 159.11576 -217.743257) (xy 159.11576 -218.593395) (xy 172.440336 -218.593395) (xy 172.440336 -218.540097)
			(xy 172.448279 -218.487393) (xy 172.463989 -218.436463) (xy 172.487115 -218.388442) (xy 172.517139 -218.344405)
			(xy 172.553391 -218.305334) (xy 172.595062 -218.272103) (xy 172.64122 -218.245454) (xy 172.690834 -218.225982)
			(xy 172.742796 -218.214122) (xy 172.795946 -218.210139) (xy 172.849096 -218.214122) (xy 172.901058 -218.225982)
			(xy 172.950672 -218.245454) (xy 172.99683 -218.272103) (xy 173.038501 -218.305334) (xy 173.074753 -218.344405)
			(xy 173.104777 -218.388442) (xy 173.127903 -218.436463) (xy 173.143613 -218.487393) (xy 173.151556 -218.540097)
			(xy 173.152054 -218.566746) (xy 173.151556 -218.593395) (xy 176.540404 -218.593395) (xy 176.540404 -218.540097)
			(xy 176.548347 -218.487393) (xy 176.564057 -218.436463) (xy 176.587183 -218.388442) (xy 176.617207 -218.344405)
			(xy 176.653459 -218.305334) (xy 176.69513 -218.272103) (xy 176.741288 -218.245454) (xy 176.790902 -218.225982)
			(xy 176.842864 -218.214122) (xy 176.896014 -218.210139) (xy 176.949164 -218.214122) (xy 177.001126 -218.225982)
			(xy 177.05074 -218.245454) (xy 177.096898 -218.272103) (xy 177.138569 -218.305334) (xy 177.174821 -218.344405)
			(xy 177.204845 -218.388442) (xy 177.227971 -218.436463) (xy 177.243681 -218.487393) (xy 177.251624 -218.540097)
			(xy 177.252122 -218.566746) (xy 177.251624 -218.593395) (xy 187.527936 -218.593395) (xy 187.527936 -218.540097)
			(xy 187.535879 -218.487393) (xy 187.551589 -218.436463) (xy 187.574715 -218.388442) (xy 187.604739 -218.344405)
			(xy 187.640991 -218.305334) (xy 187.682662 -218.272103) (xy 187.72882 -218.245454) (xy 187.778434 -218.225982)
			(xy 187.830396 -218.214122) (xy 187.883546 -218.210139) (xy 187.936696 -218.214122) (xy 187.988658 -218.225982)
			(xy 188.038272 -218.245454) (xy 188.08443 -218.272103) (xy 188.126101 -218.305334) (xy 188.162353 -218.344405)
			(xy 188.192377 -218.388442) (xy 188.215503 -218.436463) (xy 188.231213 -218.487393) (xy 188.239156 -218.540097)
			(xy 188.239654 -218.566746) (xy 188.239156 -218.593395) (xy 191.628004 -218.593395) (xy 191.628004 -218.540097)
			(xy 191.635947 -218.487393) (xy 191.651657 -218.436463) (xy 191.674783 -218.388442) (xy 191.704807 -218.344405)
			(xy 191.741059 -218.305334) (xy 191.78273 -218.272103) (xy 191.828888 -218.245454) (xy 191.878502 -218.225982)
			(xy 191.930464 -218.214122) (xy 191.983614 -218.210139) (xy 192.036764 -218.214122) (xy 192.088726 -218.225982)
			(xy 192.13834 -218.245454) (xy 192.184498 -218.272103) (xy 192.226169 -218.305334) (xy 192.262421 -218.344405)
			(xy 192.292445 -218.388442) (xy 192.315571 -218.436463) (xy 192.331281 -218.487393) (xy 192.339224 -218.540097)
			(xy 192.339722 -218.566746) (xy 192.339224 -218.593395) (xy 202.615536 -218.593395) (xy 202.615536 -218.540097)
			(xy 202.623479 -218.487393) (xy 202.639189 -218.436463) (xy 202.662315 -218.388442) (xy 202.692339 -218.344405)
			(xy 202.728591 -218.305334) (xy 202.770262 -218.272103) (xy 202.81642 -218.245454) (xy 202.866034 -218.225982)
			(xy 202.917996 -218.214122) (xy 202.971146 -218.210139) (xy 203.024296 -218.214122) (xy 203.076258 -218.225982)
			(xy 203.125872 -218.245454) (xy 203.17203 -218.272103) (xy 203.213701 -218.305334) (xy 203.249953 -218.344405)
			(xy 203.279977 -218.388442) (xy 203.303103 -218.436463) (xy 203.318813 -218.487393) (xy 203.326756 -218.540097)
			(xy 203.327254 -218.566746) (xy 203.326756 -218.593395) (xy 206.715604 -218.593395) (xy 206.715604 -218.540097)
			(xy 206.723547 -218.487393) (xy 206.739257 -218.436463) (xy 206.762383 -218.388442) (xy 206.792407 -218.344405)
			(xy 206.828659 -218.305334) (xy 206.87033 -218.272103) (xy 206.916488 -218.245454) (xy 206.966102 -218.225982)
			(xy 207.018064 -218.214122) (xy 207.071214 -218.210139) (xy 207.124364 -218.214122) (xy 207.176326 -218.225982)
			(xy 207.22594 -218.245454) (xy 207.272098 -218.272103) (xy 207.313769 -218.305334) (xy 207.350021 -218.344405)
			(xy 207.380045 -218.388442) (xy 207.403171 -218.436463) (xy 207.418881 -218.487393) (xy 207.426824 -218.540097)
			(xy 207.427322 -218.566746) (xy 207.426824 -218.593395) (xy 207.418881 -218.646099) (xy 207.403171 -218.697029)
			(xy 207.380045 -218.74505) (xy 207.350021 -218.789087) (xy 207.313769 -218.828158) (xy 207.272098 -218.861389)
			(xy 207.22594 -218.888038) (xy 207.176326 -218.90751) (xy 207.124364 -218.91937) (xy 207.071214 -218.923354)
			(xy 207.018064 -218.91937) (xy 206.966102 -218.90751) (xy 206.916488 -218.888038) (xy 206.87033 -218.861389)
			(xy 206.828659 -218.828158) (xy 206.792407 -218.789087) (xy 206.762383 -218.74505) (xy 206.739257 -218.697029)
			(xy 206.723547 -218.646099) (xy 206.715604 -218.593395) (xy 203.326756 -218.593395) (xy 203.318813 -218.646099)
			(xy 203.303103 -218.697029) (xy 203.279977 -218.74505) (xy 203.249953 -218.789087) (xy 203.213701 -218.828158)
			(xy 203.17203 -218.861389) (xy 203.125872 -218.888038) (xy 203.076258 -218.90751) (xy 203.024296 -218.91937)
			(xy 202.971146 -218.923354) (xy 202.917996 -218.91937) (xy 202.866034 -218.90751) (xy 202.81642 -218.888038)
			(xy 202.770262 -218.861389) (xy 202.728591 -218.828158) (xy 202.692339 -218.789087) (xy 202.662315 -218.74505)
			(xy 202.639189 -218.697029) (xy 202.623479 -218.646099) (xy 202.615536 -218.593395) (xy 192.339224 -218.593395)
			(xy 192.331281 -218.646099) (xy 192.315571 -218.697029) (xy 192.292445 -218.74505) (xy 192.262421 -218.789087)
			(xy 192.226169 -218.828158) (xy 192.184498 -218.861389) (xy 192.13834 -218.888038) (xy 192.088726 -218.90751)
			(xy 192.036764 -218.91937) (xy 191.983614 -218.923354) (xy 191.930464 -218.91937) (xy 191.878502 -218.90751)
			(xy 191.828888 -218.888038) (xy 191.78273 -218.861389) (xy 191.741059 -218.828158) (xy 191.704807 -218.789087)
			(xy 191.674783 -218.74505) (xy 191.651657 -218.697029) (xy 191.635947 -218.646099) (xy 191.628004 -218.593395)
			(xy 188.239156 -218.593395) (xy 188.231213 -218.646099) (xy 188.215503 -218.697029) (xy 188.192377 -218.74505)
			(xy 188.162353 -218.789087) (xy 188.126101 -218.828158) (xy 188.08443 -218.861389) (xy 188.038272 -218.888038)
			(xy 187.988658 -218.90751) (xy 187.936696 -218.91937) (xy 187.883546 -218.923354) (xy 187.830396 -218.91937)
			(xy 187.778434 -218.90751) (xy 187.72882 -218.888038) (xy 187.682662 -218.861389) (xy 187.640991 -218.828158)
			(xy 187.604739 -218.789087) (xy 187.574715 -218.74505) (xy 187.551589 -218.697029) (xy 187.535879 -218.646099)
			(xy 187.527936 -218.593395) (xy 177.251624 -218.593395) (xy 177.243681 -218.646099) (xy 177.227971 -218.697029)
			(xy 177.204845 -218.74505) (xy 177.174821 -218.789087) (xy 177.138569 -218.828158) (xy 177.096898 -218.861389)
			(xy 177.05074 -218.888038) (xy 177.001126 -218.90751) (xy 176.949164 -218.91937) (xy 176.896014 -218.923354)
			(xy 176.842864 -218.91937) (xy 176.790902 -218.90751) (xy 176.741288 -218.888038) (xy 176.69513 -218.861389)
			(xy 176.653459 -218.828158) (xy 176.617207 -218.789087) (xy 176.587183 -218.74505) (xy 176.564057 -218.697029)
			(xy 176.548347 -218.646099) (xy 176.540404 -218.593395) (xy 173.151556 -218.593395) (xy 173.143613 -218.646099)
			(xy 173.127903 -218.697029) (xy 173.104777 -218.74505) (xy 173.074753 -218.789087) (xy 173.038501 -218.828158)
			(xy 172.99683 -218.861389) (xy 172.950672 -218.888038) (xy 172.901058 -218.90751) (xy 172.849096 -218.91937)
			(xy 172.795946 -218.923354) (xy 172.742796 -218.91937) (xy 172.690834 -218.90751) (xy 172.64122 -218.888038)
			(xy 172.595062 -218.861389) (xy 172.553391 -218.828158) (xy 172.517139 -218.789087) (xy 172.487115 -218.74505)
			(xy 172.463989 -218.697029) (xy 172.448279 -218.646099) (xy 172.440336 -218.593395) (xy 159.11576 -218.593395)
			(xy 159.11576 -219.443279) (xy 172.440336 -219.443279) (xy 172.440336 -219.389981) (xy 172.448279 -219.337277)
			(xy 172.463989 -219.286347) (xy 172.487115 -219.238326) (xy 172.517139 -219.194289) (xy 172.553391 -219.155218)
			(xy 172.595062 -219.121987) (xy 172.64122 -219.095338) (xy 172.690834 -219.075866) (xy 172.742796 -219.064006)
			(xy 172.795946 -219.060023) (xy 172.849096 -219.064006) (xy 172.901058 -219.075866) (xy 172.950672 -219.095338)
			(xy 172.99683 -219.121987) (xy 173.038501 -219.155218) (xy 173.074753 -219.194289) (xy 173.104777 -219.238326)
			(xy 173.127903 -219.286347) (xy 173.143613 -219.337277) (xy 173.151556 -219.389981) (xy 173.152054 -219.41663)
			(xy 173.151556 -219.443279) (xy 187.527936 -219.443279) (xy 187.527936 -219.389981) (xy 187.535879 -219.337277)
			(xy 187.551589 -219.286347) (xy 187.574715 -219.238326) (xy 187.604739 -219.194289) (xy 187.640991 -219.155218)
			(xy 187.682662 -219.121987) (xy 187.72882 -219.095338) (xy 187.778434 -219.075866) (xy 187.830396 -219.064006)
			(xy 187.883546 -219.060023) (xy 187.936696 -219.064006) (xy 187.988658 -219.075866) (xy 188.038272 -219.095338)
			(xy 188.08443 -219.121987) (xy 188.126101 -219.155218) (xy 188.162353 -219.194289) (xy 188.192377 -219.238326)
			(xy 188.215503 -219.286347) (xy 188.231213 -219.337277) (xy 188.239156 -219.389981) (xy 188.239654 -219.41663)
			(xy 188.239156 -219.443279) (xy 202.615536 -219.443279) (xy 202.615536 -219.389981) (xy 202.623479 -219.337277)
			(xy 202.639189 -219.286347) (xy 202.662315 -219.238326) (xy 202.692339 -219.194289) (xy 202.728591 -219.155218)
			(xy 202.770262 -219.121987) (xy 202.81642 -219.095338) (xy 202.866034 -219.075866) (xy 202.917996 -219.064006)
			(xy 202.971146 -219.060023) (xy 203.024296 -219.064006) (xy 203.076258 -219.075866) (xy 203.125872 -219.095338)
			(xy 203.17203 -219.121987) (xy 203.213701 -219.155218) (xy 203.249953 -219.194289) (xy 203.279977 -219.238326)
			(xy 203.303103 -219.286347) (xy 203.318813 -219.337277) (xy 203.326756 -219.389981) (xy 203.327254 -219.41663)
			(xy 203.326756 -219.443279) (xy 203.318813 -219.495983) (xy 203.303103 -219.546913) (xy 203.279977 -219.594934)
			(xy 203.249953 -219.638971) (xy 203.213701 -219.678042) (xy 203.17203 -219.711273) (xy 203.125872 -219.737922)
			(xy 203.076258 -219.757394) (xy 203.024296 -219.769254) (xy 202.971146 -219.773238) (xy 202.917996 -219.769254)
			(xy 202.866034 -219.757394) (xy 202.81642 -219.737922) (xy 202.770262 -219.711273) (xy 202.728591 -219.678042)
			(xy 202.692339 -219.638971) (xy 202.662315 -219.594934) (xy 202.639189 -219.546913) (xy 202.623479 -219.495983)
			(xy 202.615536 -219.443279) (xy 188.239156 -219.443279) (xy 188.231213 -219.495983) (xy 188.215503 -219.546913)
			(xy 188.192377 -219.594934) (xy 188.162353 -219.638971) (xy 188.126101 -219.678042) (xy 188.08443 -219.711273)
			(xy 188.038272 -219.737922) (xy 187.988658 -219.757394) (xy 187.936696 -219.769254) (xy 187.883546 -219.773238)
			(xy 187.830396 -219.769254) (xy 187.778434 -219.757394) (xy 187.72882 -219.737922) (xy 187.682662 -219.711273)
			(xy 187.640991 -219.678042) (xy 187.604739 -219.638971) (xy 187.574715 -219.594934) (xy 187.551589 -219.546913)
			(xy 187.535879 -219.495983) (xy 187.527936 -219.443279) (xy 173.151556 -219.443279) (xy 173.143613 -219.495983)
			(xy 173.127903 -219.546913) (xy 173.104777 -219.594934) (xy 173.074753 -219.638971) (xy 173.038501 -219.678042)
			(xy 172.99683 -219.711273) (xy 172.950672 -219.737922) (xy 172.901058 -219.757394) (xy 172.849096 -219.769254)
			(xy 172.795946 -219.773238) (xy 172.742796 -219.769254) (xy 172.690834 -219.757394) (xy 172.64122 -219.737922)
			(xy 172.595062 -219.711273) (xy 172.553391 -219.678042) (xy 172.517139 -219.638971) (xy 172.487115 -219.594934)
			(xy 172.463989 -219.546913) (xy 172.448279 -219.495983) (xy 172.440336 -219.443279) (xy 159.11576 -219.443279)
			(xy 159.11576 -220.293417) (xy 176.540404 -220.293417) (xy 176.540404 -220.240119) (xy 176.548347 -220.187415)
			(xy 176.564057 -220.136485) (xy 176.587183 -220.088464) (xy 176.617207 -220.044427) (xy 176.653459 -220.005356)
			(xy 176.69513 -219.972125) (xy 176.741288 -219.945476) (xy 176.790902 -219.926004) (xy 176.842864 -219.914144)
			(xy 176.896014 -219.910161) (xy 176.949164 -219.914144) (xy 177.001126 -219.926004) (xy 177.05074 -219.945476)
			(xy 177.096898 -219.972125) (xy 177.138569 -220.005356) (xy 177.174821 -220.044427) (xy 177.204845 -220.088464)
			(xy 177.227971 -220.136485) (xy 177.243681 -220.187415) (xy 177.251624 -220.240119) (xy 177.252122 -220.266768)
			(xy 177.251624 -220.293417) (xy 191.628004 -220.293417) (xy 191.628004 -220.240119) (xy 191.635947 -220.187415)
			(xy 191.651657 -220.136485) (xy 191.674783 -220.088464) (xy 191.704807 -220.044427) (xy 191.741059 -220.005356)
			(xy 191.78273 -219.972125) (xy 191.828888 -219.945476) (xy 191.878502 -219.926004) (xy 191.930464 -219.914144)
			(xy 191.983614 -219.910161) (xy 192.036764 -219.914144) (xy 192.088726 -219.926004) (xy 192.13834 -219.945476)
			(xy 192.184498 -219.972125) (xy 192.226169 -220.005356) (xy 192.262421 -220.044427) (xy 192.292445 -220.088464)
			(xy 192.315571 -220.136485) (xy 192.331281 -220.187415) (xy 192.339224 -220.240119) (xy 192.339722 -220.266768)
			(xy 192.339224 -220.293417) (xy 206.715604 -220.293417) (xy 206.715604 -220.240119) (xy 206.723547 -220.187415)
			(xy 206.739257 -220.136485) (xy 206.762383 -220.088464) (xy 206.792407 -220.044427) (xy 206.828659 -220.005356)
			(xy 206.87033 -219.972125) (xy 206.916488 -219.945476) (xy 206.966102 -219.926004) (xy 207.018064 -219.914144)
			(xy 207.071214 -219.910161) (xy 207.124364 -219.914144) (xy 207.176326 -219.926004) (xy 207.22594 -219.945476)
			(xy 207.272098 -219.972125) (xy 207.313769 -220.005356) (xy 207.350021 -220.044427) (xy 207.380045 -220.088464)
			(xy 207.403171 -220.136485) (xy 207.418881 -220.187415) (xy 207.426824 -220.240119) (xy 207.427322 -220.266768)
			(xy 207.426824 -220.293417) (xy 207.418881 -220.346121) (xy 207.403171 -220.397051) (xy 207.380045 -220.445072)
			(xy 207.350021 -220.489109) (xy 207.313769 -220.52818) (xy 207.272098 -220.561411) (xy 207.22594 -220.58806)
			(xy 207.176326 -220.607532) (xy 207.124364 -220.619392) (xy 207.071214 -220.623376) (xy 207.018064 -220.619392)
			(xy 206.966102 -220.607532) (xy 206.916488 -220.58806) (xy 206.87033 -220.561411) (xy 206.828659 -220.52818)
			(xy 206.792407 -220.489109) (xy 206.762383 -220.445072) (xy 206.739257 -220.397051) (xy 206.723547 -220.346121)
			(xy 206.715604 -220.293417) (xy 192.339224 -220.293417) (xy 192.331281 -220.346121) (xy 192.315571 -220.397051)
			(xy 192.292445 -220.445072) (xy 192.262421 -220.489109) (xy 192.226169 -220.52818) (xy 192.184498 -220.561411)
			(xy 192.13834 -220.58806) (xy 192.088726 -220.607532) (xy 192.036764 -220.619392) (xy 191.983614 -220.623376)
			(xy 191.930464 -220.619392) (xy 191.878502 -220.607532) (xy 191.828888 -220.58806) (xy 191.78273 -220.561411)
			(xy 191.741059 -220.52818) (xy 191.704807 -220.489109) (xy 191.674783 -220.445072) (xy 191.651657 -220.397051)
			(xy 191.635947 -220.346121) (xy 191.628004 -220.293417) (xy 177.251624 -220.293417) (xy 177.243681 -220.346121)
			(xy 177.227971 -220.397051) (xy 177.204845 -220.445072) (xy 177.174821 -220.489109) (xy 177.138569 -220.52818)
			(xy 177.096898 -220.561411) (xy 177.05074 -220.58806) (xy 177.001126 -220.607532) (xy 176.949164 -220.619392)
			(xy 176.896014 -220.623376) (xy 176.842864 -220.619392) (xy 176.790902 -220.607532) (xy 176.741288 -220.58806)
			(xy 176.69513 -220.561411) (xy 176.653459 -220.52818) (xy 176.617207 -220.489109) (xy 176.587183 -220.445072)
			(xy 176.564057 -220.397051) (xy 176.548347 -220.346121) (xy 176.540404 -220.293417) (xy 159.11576 -220.293417)
			(xy 159.11576 -221.143301) (xy 172.440336 -221.143301) (xy 172.440336 -221.090003) (xy 172.448279 -221.037299)
			(xy 172.463989 -220.986369) (xy 172.487115 -220.938348) (xy 172.517139 -220.894311) (xy 172.553391 -220.85524)
			(xy 172.595062 -220.822009) (xy 172.64122 -220.79536) (xy 172.690834 -220.775888) (xy 172.742796 -220.764028)
			(xy 172.795946 -220.760045) (xy 172.849096 -220.764028) (xy 172.901058 -220.775888) (xy 172.950672 -220.79536)
			(xy 172.99683 -220.822009) (xy 173.038501 -220.85524) (xy 173.074753 -220.894311) (xy 173.104777 -220.938348)
			(xy 173.127903 -220.986369) (xy 173.143613 -221.037299) (xy 173.151556 -221.090003) (xy 173.152054 -221.116652)
			(xy 173.151556 -221.143301) (xy 187.527936 -221.143301) (xy 187.527936 -221.090003) (xy 187.535879 -221.037299)
			(xy 187.551589 -220.986369) (xy 187.574715 -220.938348) (xy 187.604739 -220.894311) (xy 187.640991 -220.85524)
			(xy 187.682662 -220.822009) (xy 187.72882 -220.79536) (xy 187.778434 -220.775888) (xy 187.830396 -220.764028)
			(xy 187.883546 -220.760045) (xy 187.936696 -220.764028) (xy 187.988658 -220.775888) (xy 188.038272 -220.79536)
			(xy 188.08443 -220.822009) (xy 188.126101 -220.85524) (xy 188.162353 -220.894311) (xy 188.192377 -220.938348)
			(xy 188.215503 -220.986369) (xy 188.231213 -221.037299) (xy 188.239156 -221.090003) (xy 188.239654 -221.116652)
			(xy 188.239156 -221.143301) (xy 202.615536 -221.143301) (xy 202.615536 -221.090003) (xy 202.623479 -221.037299)
			(xy 202.639189 -220.986369) (xy 202.662315 -220.938348) (xy 202.692339 -220.894311) (xy 202.728591 -220.85524)
			(xy 202.770262 -220.822009) (xy 202.81642 -220.79536) (xy 202.866034 -220.775888) (xy 202.917996 -220.764028)
			(xy 202.971146 -220.760045) (xy 203.024296 -220.764028) (xy 203.076258 -220.775888) (xy 203.125872 -220.79536)
			(xy 203.17203 -220.822009) (xy 203.213701 -220.85524) (xy 203.249953 -220.894311) (xy 203.279977 -220.938348)
			(xy 203.303103 -220.986369) (xy 203.318813 -221.037299) (xy 203.326756 -221.090003) (xy 203.327254 -221.116652)
			(xy 203.326756 -221.143301) (xy 203.318813 -221.196005) (xy 203.303103 -221.246935) (xy 203.279977 -221.294956)
			(xy 203.249953 -221.338993) (xy 203.213701 -221.378064) (xy 203.17203 -221.411295) (xy 203.125872 -221.437944)
			(xy 203.076258 -221.457416) (xy 203.024296 -221.469276) (xy 202.971146 -221.47326) (xy 202.917996 -221.469276)
			(xy 202.866034 -221.457416) (xy 202.81642 -221.437944) (xy 202.770262 -221.411295) (xy 202.728591 -221.378064)
			(xy 202.692339 -221.338993) (xy 202.662315 -221.294956) (xy 202.639189 -221.246935) (xy 202.623479 -221.196005)
			(xy 202.615536 -221.143301) (xy 188.239156 -221.143301) (xy 188.231213 -221.196005) (xy 188.215503 -221.246935)
			(xy 188.192377 -221.294956) (xy 188.162353 -221.338993) (xy 188.126101 -221.378064) (xy 188.08443 -221.411295)
			(xy 188.038272 -221.437944) (xy 187.988658 -221.457416) (xy 187.936696 -221.469276) (xy 187.883546 -221.47326)
			(xy 187.830396 -221.469276) (xy 187.778434 -221.457416) (xy 187.72882 -221.437944) (xy 187.682662 -221.411295)
			(xy 187.640991 -221.378064) (xy 187.604739 -221.338993) (xy 187.574715 -221.294956) (xy 187.551589 -221.246935)
			(xy 187.535879 -221.196005) (xy 187.527936 -221.143301) (xy 173.151556 -221.143301) (xy 173.143613 -221.196005)
			(xy 173.127903 -221.246935) (xy 173.104777 -221.294956) (xy 173.074753 -221.338993) (xy 173.038501 -221.378064)
			(xy 172.99683 -221.411295) (xy 172.950672 -221.437944) (xy 172.901058 -221.457416) (xy 172.849096 -221.469276)
			(xy 172.795946 -221.47326) (xy 172.742796 -221.469276) (xy 172.690834 -221.457416) (xy 172.64122 -221.437944)
			(xy 172.595062 -221.411295) (xy 172.553391 -221.378064) (xy 172.517139 -221.338993) (xy 172.487115 -221.294956)
			(xy 172.463989 -221.246935) (xy 172.448279 -221.196005) (xy 172.440336 -221.143301) (xy 159.11576 -221.143301)
			(xy 159.11576 -221.993439) (xy 176.540404 -221.993439) (xy 176.540404 -221.940141) (xy 176.548347 -221.887437)
			(xy 176.564057 -221.836507) (xy 176.587183 -221.788486) (xy 176.617207 -221.744449) (xy 176.653459 -221.705378)
			(xy 176.69513 -221.672147) (xy 176.741288 -221.645498) (xy 176.790902 -221.626026) (xy 176.842864 -221.614166)
			(xy 176.896014 -221.610183) (xy 176.949164 -221.614166) (xy 177.001126 -221.626026) (xy 177.05074 -221.645498)
			(xy 177.096898 -221.672147) (xy 177.138569 -221.705378) (xy 177.174821 -221.744449) (xy 177.204845 -221.788486)
			(xy 177.227971 -221.836507) (xy 177.243681 -221.887437) (xy 177.251624 -221.940141) (xy 177.252122 -221.96679)
			(xy 177.251624 -221.993439) (xy 191.628004 -221.993439) (xy 191.628004 -221.940141) (xy 191.635947 -221.887437)
			(xy 191.651657 -221.836507) (xy 191.674783 -221.788486) (xy 191.704807 -221.744449) (xy 191.741059 -221.705378)
			(xy 191.78273 -221.672147) (xy 191.828888 -221.645498) (xy 191.878502 -221.626026) (xy 191.930464 -221.614166)
			(xy 191.983614 -221.610183) (xy 192.036764 -221.614166) (xy 192.088726 -221.626026) (xy 192.13834 -221.645498)
			(xy 192.184498 -221.672147) (xy 192.226169 -221.705378) (xy 192.262421 -221.744449) (xy 192.292445 -221.788486)
			(xy 192.315571 -221.836507) (xy 192.331281 -221.887437) (xy 192.339224 -221.940141) (xy 192.339722 -221.96679)
			(xy 192.339224 -221.993439) (xy 206.715604 -221.993439) (xy 206.715604 -221.940141) (xy 206.723547 -221.887437)
			(xy 206.739257 -221.836507) (xy 206.762383 -221.788486) (xy 206.792407 -221.744449) (xy 206.828659 -221.705378)
			(xy 206.87033 -221.672147) (xy 206.916488 -221.645498) (xy 206.966102 -221.626026) (xy 207.018064 -221.614166)
			(xy 207.071214 -221.610183) (xy 207.124364 -221.614166) (xy 207.176326 -221.626026) (xy 207.22594 -221.645498)
			(xy 207.272098 -221.672147) (xy 207.313769 -221.705378) (xy 207.350021 -221.744449) (xy 207.380045 -221.788486)
			(xy 207.403171 -221.836507) (xy 207.418881 -221.887437) (xy 207.426824 -221.940141) (xy 207.427322 -221.96679)
			(xy 207.426824 -221.993439) (xy 207.418881 -222.046143) (xy 207.403171 -222.097073) (xy 207.380045 -222.145094)
			(xy 207.350021 -222.189131) (xy 207.313769 -222.228202) (xy 207.272098 -222.261433) (xy 207.22594 -222.288082)
			(xy 207.176326 -222.307554) (xy 207.124364 -222.319414) (xy 207.071214 -222.323398) (xy 207.018064 -222.319414)
			(xy 206.966102 -222.307554) (xy 206.916488 -222.288082) (xy 206.87033 -222.261433) (xy 206.828659 -222.228202)
			(xy 206.792407 -222.189131) (xy 206.762383 -222.145094) (xy 206.739257 -222.097073) (xy 206.723547 -222.046143)
			(xy 206.715604 -221.993439) (xy 192.339224 -221.993439) (xy 192.331281 -222.046143) (xy 192.315571 -222.097073)
			(xy 192.292445 -222.145094) (xy 192.262421 -222.189131) (xy 192.226169 -222.228202) (xy 192.184498 -222.261433)
			(xy 192.13834 -222.288082) (xy 192.088726 -222.307554) (xy 192.036764 -222.319414) (xy 191.983614 -222.323398)
			(xy 191.930464 -222.319414) (xy 191.878502 -222.307554) (xy 191.828888 -222.288082) (xy 191.78273 -222.261433)
			(xy 191.741059 -222.228202) (xy 191.704807 -222.189131) (xy 191.674783 -222.145094) (xy 191.651657 -222.097073)
			(xy 191.635947 -222.046143) (xy 191.628004 -221.993439) (xy 177.251624 -221.993439) (xy 177.243681 -222.046143)
			(xy 177.227971 -222.097073) (xy 177.204845 -222.145094) (xy 177.174821 -222.189131) (xy 177.138569 -222.228202)
			(xy 177.096898 -222.261433) (xy 177.05074 -222.288082) (xy 177.001126 -222.307554) (xy 176.949164 -222.319414)
			(xy 176.896014 -222.323398) (xy 176.842864 -222.319414) (xy 176.790902 -222.307554) (xy 176.741288 -222.288082)
			(xy 176.69513 -222.261433) (xy 176.653459 -222.228202) (xy 176.617207 -222.189131) (xy 176.587183 -222.145094)
			(xy 176.564057 -222.097073) (xy 176.548347 -222.046143) (xy 176.540404 -221.993439) (xy 159.11576 -221.993439)
			(xy 159.11576 -222.843323) (xy 172.440336 -222.843323) (xy 172.440336 -222.790025) (xy 172.448279 -222.737321)
			(xy 172.463989 -222.686391) (xy 172.487115 -222.63837) (xy 172.517139 -222.594333) (xy 172.553391 -222.555262)
			(xy 172.595062 -222.522031) (xy 172.64122 -222.495382) (xy 172.690834 -222.47591) (xy 172.742796 -222.46405)
			(xy 172.795946 -222.460067) (xy 172.849096 -222.46405) (xy 172.901058 -222.47591) (xy 172.950672 -222.495382)
			(xy 172.99683 -222.522031) (xy 173.038501 -222.555262) (xy 173.074753 -222.594333) (xy 173.104777 -222.63837)
			(xy 173.127903 -222.686391) (xy 173.143613 -222.737321) (xy 173.151556 -222.790025) (xy 173.152054 -222.816674)
			(xy 173.151556 -222.843323) (xy 187.527936 -222.843323) (xy 187.527936 -222.790025) (xy 187.535879 -222.737321)
			(xy 187.551589 -222.686391) (xy 187.574715 -222.63837) (xy 187.604739 -222.594333) (xy 187.640991 -222.555262)
			(xy 187.682662 -222.522031) (xy 187.72882 -222.495382) (xy 187.778434 -222.47591) (xy 187.830396 -222.46405)
			(xy 187.883546 -222.460067) (xy 187.936696 -222.46405) (xy 187.988658 -222.47591) (xy 188.038272 -222.495382)
			(xy 188.08443 -222.522031) (xy 188.126101 -222.555262) (xy 188.162353 -222.594333) (xy 188.192377 -222.63837)
			(xy 188.215503 -222.686391) (xy 188.231213 -222.737321) (xy 188.239156 -222.790025) (xy 188.239654 -222.816674)
			(xy 188.239156 -222.843323) (xy 202.615536 -222.843323) (xy 202.615536 -222.790025) (xy 202.623479 -222.737321)
			(xy 202.639189 -222.686391) (xy 202.662315 -222.63837) (xy 202.692339 -222.594333) (xy 202.728591 -222.555262)
			(xy 202.770262 -222.522031) (xy 202.81642 -222.495382) (xy 202.866034 -222.47591) (xy 202.917996 -222.46405)
			(xy 202.971146 -222.460067) (xy 203.024296 -222.46405) (xy 203.076258 -222.47591) (xy 203.125872 -222.495382)
			(xy 203.17203 -222.522031) (xy 203.213701 -222.555262) (xy 203.249953 -222.594333) (xy 203.279977 -222.63837)
			(xy 203.303103 -222.686391) (xy 203.318813 -222.737321) (xy 203.326756 -222.790025) (xy 203.327254 -222.816674)
			(xy 203.326756 -222.843323) (xy 203.318813 -222.896027) (xy 203.303103 -222.946957) (xy 203.279977 -222.994978)
			(xy 203.249953 -223.039015) (xy 203.213701 -223.078086) (xy 203.17203 -223.111317) (xy 203.125872 -223.137966)
			(xy 203.076258 -223.157438) (xy 203.024296 -223.169298) (xy 202.971146 -223.173282) (xy 202.917996 -223.169298)
			(xy 202.866034 -223.157438) (xy 202.81642 -223.137966) (xy 202.770262 -223.111317) (xy 202.728591 -223.078086)
			(xy 202.692339 -223.039015) (xy 202.662315 -222.994978) (xy 202.639189 -222.946957) (xy 202.623479 -222.896027)
			(xy 202.615536 -222.843323) (xy 188.239156 -222.843323) (xy 188.231213 -222.896027) (xy 188.215503 -222.946957)
			(xy 188.192377 -222.994978) (xy 188.162353 -223.039015) (xy 188.126101 -223.078086) (xy 188.08443 -223.111317)
			(xy 188.038272 -223.137966) (xy 187.988658 -223.157438) (xy 187.936696 -223.169298) (xy 187.883546 -223.173282)
			(xy 187.830396 -223.169298) (xy 187.778434 -223.157438) (xy 187.72882 -223.137966) (xy 187.682662 -223.111317)
			(xy 187.640991 -223.078086) (xy 187.604739 -223.039015) (xy 187.574715 -222.994978) (xy 187.551589 -222.946957)
			(xy 187.535879 -222.896027) (xy 187.527936 -222.843323) (xy 173.151556 -222.843323) (xy 173.143613 -222.896027)
			(xy 173.127903 -222.946957) (xy 173.104777 -222.994978) (xy 173.074753 -223.039015) (xy 173.038501 -223.078086)
			(xy 172.99683 -223.111317) (xy 172.950672 -223.137966) (xy 172.901058 -223.157438) (xy 172.849096 -223.169298)
			(xy 172.795946 -223.173282) (xy 172.742796 -223.169298) (xy 172.690834 -223.157438) (xy 172.64122 -223.137966)
			(xy 172.595062 -223.111317) (xy 172.553391 -223.078086) (xy 172.517139 -223.039015) (xy 172.487115 -222.994978)
			(xy 172.463989 -222.946957) (xy 172.448279 -222.896027) (xy 172.440336 -222.843323) (xy 159.11576 -222.843323)
			(xy 159.11576 -223.693207) (xy 161.427404 -223.693207) (xy 161.427404 -223.639909) (xy 161.435347 -223.587205)
			(xy 161.451057 -223.536275) (xy 161.474183 -223.488254) (xy 161.504207 -223.444217) (xy 161.540459 -223.405146)
			(xy 161.58213 -223.371915) (xy 161.628288 -223.345266) (xy 161.677902 -223.325794) (xy 161.729864 -223.313934)
			(xy 161.783014 -223.309951) (xy 161.836164 -223.313934) (xy 161.888126 -223.325794) (xy 161.93774 -223.345266)
			(xy 161.983898 -223.371915) (xy 162.025569 -223.405146) (xy 162.061821 -223.444217) (xy 162.091845 -223.488254)
			(xy 162.114971 -223.536275) (xy 162.130681 -223.587205) (xy 162.138624 -223.639909) (xy 162.139122 -223.666558)
			(xy 162.138624 -223.693207) (xy 176.540404 -223.693207) (xy 176.540404 -223.639909) (xy 176.548347 -223.587205)
			(xy 176.564057 -223.536275) (xy 176.587183 -223.488254) (xy 176.617207 -223.444217) (xy 176.653459 -223.405146)
			(xy 176.69513 -223.371915) (xy 176.741288 -223.345266) (xy 176.790902 -223.325794) (xy 176.842864 -223.313934)
			(xy 176.896014 -223.309951) (xy 176.949164 -223.313934) (xy 177.001126 -223.325794) (xy 177.05074 -223.345266)
			(xy 177.096898 -223.371915) (xy 177.138569 -223.405146) (xy 177.174821 -223.444217) (xy 177.204845 -223.488254)
			(xy 177.227971 -223.536275) (xy 177.243681 -223.587205) (xy 177.251624 -223.639909) (xy 177.252122 -223.666558)
			(xy 177.251624 -223.693207) (xy 191.628004 -223.693207) (xy 191.628004 -223.639909) (xy 191.635947 -223.587205)
			(xy 191.651657 -223.536275) (xy 191.674783 -223.488254) (xy 191.704807 -223.444217) (xy 191.741059 -223.405146)
			(xy 191.78273 -223.371915) (xy 191.828888 -223.345266) (xy 191.878502 -223.325794) (xy 191.930464 -223.313934)
			(xy 191.983614 -223.309951) (xy 192.036764 -223.313934) (xy 192.088726 -223.325794) (xy 192.13834 -223.345266)
			(xy 192.184498 -223.371915) (xy 192.226169 -223.405146) (xy 192.262421 -223.444217) (xy 192.292445 -223.488254)
			(xy 192.315571 -223.536275) (xy 192.331281 -223.587205) (xy 192.339224 -223.639909) (xy 192.339722 -223.666558)
			(xy 192.339224 -223.693207) (xy 206.715604 -223.693207) (xy 206.715604 -223.639909) (xy 206.723547 -223.587205)
			(xy 206.739257 -223.536275) (xy 206.762383 -223.488254) (xy 206.792407 -223.444217) (xy 206.828659 -223.405146)
			(xy 206.87033 -223.371915) (xy 206.916488 -223.345266) (xy 206.966102 -223.325794) (xy 207.018064 -223.313934)
			(xy 207.071214 -223.309951) (xy 207.124364 -223.313934) (xy 207.176326 -223.325794) (xy 207.22594 -223.345266)
			(xy 207.272098 -223.371915) (xy 207.313769 -223.405146) (xy 207.350021 -223.444217) (xy 207.380045 -223.488254)
			(xy 207.403171 -223.536275) (xy 207.418881 -223.587205) (xy 207.426824 -223.639909) (xy 207.427322 -223.666558)
			(xy 207.426824 -223.693207) (xy 207.418881 -223.745911) (xy 207.403171 -223.796841) (xy 207.380045 -223.844862)
			(xy 207.350021 -223.888899) (xy 207.313769 -223.92797) (xy 207.272098 -223.961201) (xy 207.22594 -223.98785)
			(xy 207.176326 -224.007322) (xy 207.124364 -224.019182) (xy 207.071214 -224.023166) (xy 207.018064 -224.019182)
			(xy 206.966102 -224.007322) (xy 206.916488 -223.98785) (xy 206.87033 -223.961201) (xy 206.828659 -223.92797)
			(xy 206.792407 -223.888899) (xy 206.762383 -223.844862) (xy 206.739257 -223.796841) (xy 206.723547 -223.745911)
			(xy 206.715604 -223.693207) (xy 192.339224 -223.693207) (xy 192.331281 -223.745911) (xy 192.315571 -223.796841)
			(xy 192.292445 -223.844862) (xy 192.262421 -223.888899) (xy 192.226169 -223.92797) (xy 192.184498 -223.961201)
			(xy 192.13834 -223.98785) (xy 192.088726 -224.007322) (xy 192.036764 -224.019182) (xy 191.983614 -224.023166)
			(xy 191.930464 -224.019182) (xy 191.878502 -224.007322) (xy 191.828888 -223.98785) (xy 191.78273 -223.961201)
			(xy 191.741059 -223.92797) (xy 191.704807 -223.888899) (xy 191.674783 -223.844862) (xy 191.651657 -223.796841)
			(xy 191.635947 -223.745911) (xy 191.628004 -223.693207) (xy 177.251624 -223.693207) (xy 177.243681 -223.745911)
			(xy 177.227971 -223.796841) (xy 177.204845 -223.844862) (xy 177.174821 -223.888899) (xy 177.138569 -223.92797)
			(xy 177.096898 -223.961201) (xy 177.05074 -223.98785) (xy 177.001126 -224.007322) (xy 176.949164 -224.019182)
			(xy 176.896014 -224.023166) (xy 176.842864 -224.019182) (xy 176.790902 -224.007322) (xy 176.741288 -223.98785)
			(xy 176.69513 -223.961201) (xy 176.653459 -223.92797) (xy 176.617207 -223.888899) (xy 176.587183 -223.844862)
			(xy 176.564057 -223.796841) (xy 176.548347 -223.745911) (xy 176.540404 -223.693207) (xy 162.138624 -223.693207)
			(xy 162.130681 -223.745911) (xy 162.114971 -223.796841) (xy 162.091845 -223.844862) (xy 162.061821 -223.888899)
			(xy 162.025569 -223.92797) (xy 161.983898 -223.961201) (xy 161.93774 -223.98785) (xy 161.888126 -224.007322)
			(xy 161.836164 -224.019182) (xy 161.783014 -224.023166) (xy 161.729864 -224.019182) (xy 161.677902 -224.007322)
			(xy 161.628288 -223.98785) (xy 161.58213 -223.961201) (xy 161.540459 -223.92797) (xy 161.504207 -223.888899)
			(xy 161.474183 -223.844862) (xy 161.451057 -223.796841) (xy 161.435347 -223.745911) (xy 161.427404 -223.693207)
			(xy 159.11576 -223.693207) (xy 159.11576 -224.543345) (xy 172.440336 -224.543345) (xy 172.440336 -224.490047)
			(xy 172.448279 -224.437343) (xy 172.463989 -224.386413) (xy 172.487115 -224.338392) (xy 172.517139 -224.294355)
			(xy 172.553391 -224.255284) (xy 172.595062 -224.222053) (xy 172.64122 -224.195404) (xy 172.690834 -224.175932)
			(xy 172.742796 -224.164072) (xy 172.795946 -224.160089) (xy 172.849096 -224.164072) (xy 172.901058 -224.175932)
			(xy 172.950672 -224.195404) (xy 172.99683 -224.222053) (xy 173.038501 -224.255284) (xy 173.074753 -224.294355)
			(xy 173.104777 -224.338392) (xy 173.127903 -224.386413) (xy 173.143613 -224.437343) (xy 173.151556 -224.490047)
			(xy 173.152054 -224.516696) (xy 173.151556 -224.543345) (xy 187.527936 -224.543345) (xy 187.527936 -224.490047)
			(xy 187.535879 -224.437343) (xy 187.551589 -224.386413) (xy 187.574715 -224.338392) (xy 187.604739 -224.294355)
			(xy 187.640991 -224.255284) (xy 187.682662 -224.222053) (xy 187.72882 -224.195404) (xy 187.778434 -224.175932)
			(xy 187.830396 -224.164072) (xy 187.883546 -224.160089) (xy 187.936696 -224.164072) (xy 187.988658 -224.175932)
			(xy 188.038272 -224.195404) (xy 188.08443 -224.222053) (xy 188.126101 -224.255284) (xy 188.162353 -224.294355)
			(xy 188.192377 -224.338392) (xy 188.215503 -224.386413) (xy 188.231213 -224.437343) (xy 188.239156 -224.490047)
			(xy 188.239654 -224.516696) (xy 188.239156 -224.543345) (xy 202.615536 -224.543345) (xy 202.615536 -224.490047)
			(xy 202.623479 -224.437343) (xy 202.639189 -224.386413) (xy 202.662315 -224.338392) (xy 202.692339 -224.294355)
			(xy 202.728591 -224.255284) (xy 202.770262 -224.222053) (xy 202.81642 -224.195404) (xy 202.866034 -224.175932)
			(xy 202.917996 -224.164072) (xy 202.971146 -224.160089) (xy 203.024296 -224.164072) (xy 203.076258 -224.175932)
			(xy 203.125872 -224.195404) (xy 203.17203 -224.222053) (xy 203.213701 -224.255284) (xy 203.249953 -224.294355)
			(xy 203.279977 -224.338392) (xy 203.303103 -224.386413) (xy 203.318813 -224.437343) (xy 203.326756 -224.490047)
			(xy 203.327254 -224.516696) (xy 203.326756 -224.543345) (xy 203.318813 -224.596049) (xy 203.303103 -224.646979)
			(xy 203.279977 -224.695) (xy 203.249953 -224.739037) (xy 203.213701 -224.778108) (xy 203.17203 -224.811339)
			(xy 203.125872 -224.837988) (xy 203.076258 -224.85746) (xy 203.024296 -224.86932) (xy 202.971146 -224.873304)
			(xy 202.917996 -224.86932) (xy 202.866034 -224.85746) (xy 202.81642 -224.837988) (xy 202.770262 -224.811339)
			(xy 202.728591 -224.778108) (xy 202.692339 -224.739037) (xy 202.662315 -224.695) (xy 202.639189 -224.646979)
			(xy 202.623479 -224.596049) (xy 202.615536 -224.543345) (xy 188.239156 -224.543345) (xy 188.231213 -224.596049)
			(xy 188.215503 -224.646979) (xy 188.192377 -224.695) (xy 188.162353 -224.739037) (xy 188.126101 -224.778108)
			(xy 188.08443 -224.811339) (xy 188.038272 -224.837988) (xy 187.988658 -224.85746) (xy 187.936696 -224.86932)
			(xy 187.883546 -224.873304) (xy 187.830396 -224.86932) (xy 187.778434 -224.85746) (xy 187.72882 -224.837988)
			(xy 187.682662 -224.811339) (xy 187.640991 -224.778108) (xy 187.604739 -224.739037) (xy 187.574715 -224.695)
			(xy 187.551589 -224.646979) (xy 187.535879 -224.596049) (xy 187.527936 -224.543345) (xy 173.151556 -224.543345)
			(xy 173.143613 -224.596049) (xy 173.127903 -224.646979) (xy 173.104777 -224.695) (xy 173.074753 -224.739037)
			(xy 173.038501 -224.778108) (xy 172.99683 -224.811339) (xy 172.950672 -224.837988) (xy 172.901058 -224.85746)
			(xy 172.849096 -224.86932) (xy 172.795946 -224.873304) (xy 172.742796 -224.86932) (xy 172.690834 -224.85746)
			(xy 172.64122 -224.837988) (xy 172.595062 -224.811339) (xy 172.553391 -224.778108) (xy 172.517139 -224.739037)
			(xy 172.487115 -224.695) (xy 172.463989 -224.646979) (xy 172.448279 -224.596049) (xy 172.440336 -224.543345)
			(xy 159.11576 -224.543345) (xy 159.11576 -225.393229) (xy 161.427404 -225.393229) (xy 161.427404 -225.339931)
			(xy 161.435347 -225.287227) (xy 161.451057 -225.236297) (xy 161.474183 -225.188276) (xy 161.504207 -225.144239)
			(xy 161.540459 -225.105168) (xy 161.58213 -225.071937) (xy 161.628288 -225.045288) (xy 161.677902 -225.025816)
			(xy 161.729864 -225.013956) (xy 161.783014 -225.009973) (xy 161.836164 -225.013956) (xy 161.888126 -225.025816)
			(xy 161.93774 -225.045288) (xy 161.983898 -225.071937) (xy 162.025569 -225.105168) (xy 162.061821 -225.144239)
			(xy 162.091845 -225.188276) (xy 162.114971 -225.236297) (xy 162.130681 -225.287227) (xy 162.138624 -225.339931)
			(xy 162.139122 -225.36658) (xy 162.138624 -225.393229) (xy 176.540404 -225.393229) (xy 176.540404 -225.339931)
			(xy 176.548347 -225.287227) (xy 176.564057 -225.236297) (xy 176.587183 -225.188276) (xy 176.617207 -225.144239)
			(xy 176.653459 -225.105168) (xy 176.69513 -225.071937) (xy 176.741288 -225.045288) (xy 176.790902 -225.025816)
			(xy 176.842864 -225.013956) (xy 176.896014 -225.009973) (xy 176.949164 -225.013956) (xy 177.001126 -225.025816)
			(xy 177.05074 -225.045288) (xy 177.096898 -225.071937) (xy 177.138569 -225.105168) (xy 177.174821 -225.144239)
			(xy 177.204845 -225.188276) (xy 177.227971 -225.236297) (xy 177.243681 -225.287227) (xy 177.251624 -225.339931)
			(xy 177.252122 -225.36658) (xy 177.251624 -225.393229) (xy 191.628004 -225.393229) (xy 191.628004 -225.339931)
			(xy 191.635947 -225.287227) (xy 191.651657 -225.236297) (xy 191.674783 -225.188276) (xy 191.704807 -225.144239)
			(xy 191.741059 -225.105168) (xy 191.78273 -225.071937) (xy 191.828888 -225.045288) (xy 191.878502 -225.025816)
			(xy 191.930464 -225.013956) (xy 191.983614 -225.009973) (xy 192.036764 -225.013956) (xy 192.088726 -225.025816)
			(xy 192.13834 -225.045288) (xy 192.184498 -225.071937) (xy 192.226169 -225.105168) (xy 192.262421 -225.144239)
			(xy 192.292445 -225.188276) (xy 192.315571 -225.236297) (xy 192.331281 -225.287227) (xy 192.339224 -225.339931)
			(xy 192.339722 -225.36658) (xy 192.339224 -225.393229) (xy 206.715604 -225.393229) (xy 206.715604 -225.339931)
			(xy 206.723547 -225.287227) (xy 206.739257 -225.236297) (xy 206.762383 -225.188276) (xy 206.792407 -225.144239)
			(xy 206.828659 -225.105168) (xy 206.87033 -225.071937) (xy 206.916488 -225.045288) (xy 206.966102 -225.025816)
			(xy 207.018064 -225.013956) (xy 207.071214 -225.009973) (xy 207.124364 -225.013956) (xy 207.176326 -225.025816)
			(xy 207.22594 -225.045288) (xy 207.272098 -225.071937) (xy 207.313769 -225.105168) (xy 207.350021 -225.144239)
			(xy 207.380045 -225.188276) (xy 207.403171 -225.236297) (xy 207.418881 -225.287227) (xy 207.426824 -225.339931)
			(xy 207.427322 -225.36658) (xy 207.426824 -225.393229) (xy 207.418881 -225.445933) (xy 207.403171 -225.496863)
			(xy 207.380045 -225.544884) (xy 207.350021 -225.588921) (xy 207.313769 -225.627992) (xy 207.272098 -225.661223)
			(xy 207.22594 -225.687872) (xy 207.176326 -225.707344) (xy 207.124364 -225.719204) (xy 207.071214 -225.723188)
			(xy 207.018064 -225.719204) (xy 206.966102 -225.707344) (xy 206.916488 -225.687872) (xy 206.87033 -225.661223)
			(xy 206.828659 -225.627992) (xy 206.792407 -225.588921) (xy 206.762383 -225.544884) (xy 206.739257 -225.496863)
			(xy 206.723547 -225.445933) (xy 206.715604 -225.393229) (xy 192.339224 -225.393229) (xy 192.331281 -225.445933)
			(xy 192.315571 -225.496863) (xy 192.292445 -225.544884) (xy 192.262421 -225.588921) (xy 192.226169 -225.627992)
			(xy 192.184498 -225.661223) (xy 192.13834 -225.687872) (xy 192.088726 -225.707344) (xy 192.036764 -225.719204)
			(xy 191.983614 -225.723188) (xy 191.930464 -225.719204) (xy 191.878502 -225.707344) (xy 191.828888 -225.687872)
			(xy 191.78273 -225.661223) (xy 191.741059 -225.627992) (xy 191.704807 -225.588921) (xy 191.674783 -225.544884)
			(xy 191.651657 -225.496863) (xy 191.635947 -225.445933) (xy 191.628004 -225.393229) (xy 177.251624 -225.393229)
			(xy 177.243681 -225.445933) (xy 177.227971 -225.496863) (xy 177.204845 -225.544884) (xy 177.174821 -225.588921)
			(xy 177.138569 -225.627992) (xy 177.096898 -225.661223) (xy 177.05074 -225.687872) (xy 177.001126 -225.707344)
			(xy 176.949164 -225.719204) (xy 176.896014 -225.723188) (xy 176.842864 -225.719204) (xy 176.790902 -225.707344)
			(xy 176.741288 -225.687872) (xy 176.69513 -225.661223) (xy 176.653459 -225.627992) (xy 176.617207 -225.588921)
			(xy 176.587183 -225.544884) (xy 176.564057 -225.496863) (xy 176.548347 -225.445933) (xy 176.540404 -225.393229)
			(xy 162.138624 -225.393229) (xy 162.130681 -225.445933) (xy 162.114971 -225.496863) (xy 162.091845 -225.544884)
			(xy 162.061821 -225.588921) (xy 162.025569 -225.627992) (xy 161.983898 -225.661223) (xy 161.93774 -225.687872)
			(xy 161.888126 -225.707344) (xy 161.836164 -225.719204) (xy 161.783014 -225.723188) (xy 161.729864 -225.719204)
			(xy 161.677902 -225.707344) (xy 161.628288 -225.687872) (xy 161.58213 -225.661223) (xy 161.540459 -225.627992)
			(xy 161.504207 -225.588921) (xy 161.474183 -225.544884) (xy 161.451057 -225.496863) (xy 161.435347 -225.445933)
			(xy 161.427404 -225.393229) (xy 159.11576 -225.393229) (xy 159.11576 -226.243367) (xy 172.440336 -226.243367)
			(xy 172.440336 -226.190069) (xy 172.448279 -226.137365) (xy 172.463989 -226.086435) (xy 172.487115 -226.038414)
			(xy 172.517139 -225.994377) (xy 172.553391 -225.955306) (xy 172.595062 -225.922075) (xy 172.64122 -225.895426)
			(xy 172.690834 -225.875954) (xy 172.742796 -225.864094) (xy 172.795946 -225.860111) (xy 172.849096 -225.864094)
			(xy 172.901058 -225.875954) (xy 172.950672 -225.895426) (xy 172.99683 -225.922075) (xy 173.038501 -225.955306)
			(xy 173.074753 -225.994377) (xy 173.104777 -226.038414) (xy 173.127903 -226.086435) (xy 173.143613 -226.137365)
			(xy 173.151556 -226.190069) (xy 173.152054 -226.216718) (xy 173.151556 -226.243367) (xy 187.527936 -226.243367)
			(xy 187.527936 -226.190069) (xy 187.535879 -226.137365) (xy 187.551589 -226.086435) (xy 187.574715 -226.038414)
			(xy 187.604739 -225.994377) (xy 187.640991 -225.955306) (xy 187.682662 -225.922075) (xy 187.72882 -225.895426)
			(xy 187.778434 -225.875954) (xy 187.830396 -225.864094) (xy 187.883546 -225.860111) (xy 187.936696 -225.864094)
			(xy 187.988658 -225.875954) (xy 188.038272 -225.895426) (xy 188.08443 -225.922075) (xy 188.126101 -225.955306)
			(xy 188.162353 -225.994377) (xy 188.192377 -226.038414) (xy 188.215503 -226.086435) (xy 188.231213 -226.137365)
			(xy 188.239156 -226.190069) (xy 188.239654 -226.216718) (xy 188.239156 -226.243367) (xy 202.615536 -226.243367)
			(xy 202.615536 -226.190069) (xy 202.623479 -226.137365) (xy 202.639189 -226.086435) (xy 202.662315 -226.038414)
			(xy 202.692339 -225.994377) (xy 202.728591 -225.955306) (xy 202.770262 -225.922075) (xy 202.81642 -225.895426)
			(xy 202.866034 -225.875954) (xy 202.917996 -225.864094) (xy 202.971146 -225.860111) (xy 203.024296 -225.864094)
			(xy 203.076258 -225.875954) (xy 203.125872 -225.895426) (xy 203.17203 -225.922075) (xy 203.213701 -225.955306)
			(xy 203.249953 -225.994377) (xy 203.279977 -226.038414) (xy 203.303103 -226.086435) (xy 203.318813 -226.137365)
			(xy 203.326756 -226.190069) (xy 203.327254 -226.216718) (xy 203.326756 -226.243367) (xy 203.318813 -226.296071)
			(xy 203.303103 -226.347001) (xy 203.279977 -226.395022) (xy 203.249953 -226.439059) (xy 203.213701 -226.47813)
			(xy 203.17203 -226.511361) (xy 203.125872 -226.53801) (xy 203.076258 -226.557482) (xy 203.024296 -226.569342)
			(xy 202.971146 -226.573326) (xy 202.917996 -226.569342) (xy 202.866034 -226.557482) (xy 202.81642 -226.53801)
			(xy 202.770262 -226.511361) (xy 202.728591 -226.47813) (xy 202.692339 -226.439059) (xy 202.662315 -226.395022)
			(xy 202.639189 -226.347001) (xy 202.623479 -226.296071) (xy 202.615536 -226.243367) (xy 188.239156 -226.243367)
			(xy 188.231213 -226.296071) (xy 188.215503 -226.347001) (xy 188.192377 -226.395022) (xy 188.162353 -226.439059)
			(xy 188.126101 -226.47813) (xy 188.08443 -226.511361) (xy 188.038272 -226.53801) (xy 187.988658 -226.557482)
			(xy 187.936696 -226.569342) (xy 187.883546 -226.573326) (xy 187.830396 -226.569342) (xy 187.778434 -226.557482)
			(xy 187.72882 -226.53801) (xy 187.682662 -226.511361) (xy 187.640991 -226.47813) (xy 187.604739 -226.439059)
			(xy 187.574715 -226.395022) (xy 187.551589 -226.347001) (xy 187.535879 -226.296071) (xy 187.527936 -226.243367)
			(xy 173.151556 -226.243367) (xy 173.143613 -226.296071) (xy 173.127903 -226.347001) (xy 173.104777 -226.395022)
			(xy 173.074753 -226.439059) (xy 173.038501 -226.47813) (xy 172.99683 -226.511361) (xy 172.950672 -226.53801)
			(xy 172.901058 -226.557482) (xy 172.849096 -226.569342) (xy 172.795946 -226.573326) (xy 172.742796 -226.569342)
			(xy 172.690834 -226.557482) (xy 172.64122 -226.53801) (xy 172.595062 -226.511361) (xy 172.553391 -226.47813)
			(xy 172.517139 -226.439059) (xy 172.487115 -226.395022) (xy 172.463989 -226.347001) (xy 172.448279 -226.296071)
			(xy 172.440336 -226.243367) (xy 159.11576 -226.243367) (xy 159.11576 -227.093251) (xy 161.427404 -227.093251)
			(xy 161.427404 -227.039953) (xy 161.435347 -226.987249) (xy 161.451057 -226.936319) (xy 161.474183 -226.888298)
			(xy 161.504207 -226.844261) (xy 161.540459 -226.80519) (xy 161.58213 -226.771959) (xy 161.628288 -226.74531)
			(xy 161.677902 -226.725838) (xy 161.729864 -226.713978) (xy 161.783014 -226.709995) (xy 161.836164 -226.713978)
			(xy 161.888126 -226.725838) (xy 161.93774 -226.74531) (xy 161.983898 -226.771959) (xy 162.025569 -226.80519)
			(xy 162.061821 -226.844261) (xy 162.091845 -226.888298) (xy 162.114971 -226.936319) (xy 162.130681 -226.987249)
			(xy 162.138624 -227.039953) (xy 162.139122 -227.066602) (xy 162.138624 -227.093251) (xy 176.540404 -227.093251)
			(xy 176.540404 -227.039953) (xy 176.548347 -226.987249) (xy 176.564057 -226.936319) (xy 176.587183 -226.888298)
			(xy 176.617207 -226.844261) (xy 176.653459 -226.80519) (xy 176.69513 -226.771959) (xy 176.741288 -226.74531)
			(xy 176.790902 -226.725838) (xy 176.842864 -226.713978) (xy 176.896014 -226.709995) (xy 176.949164 -226.713978)
			(xy 177.001126 -226.725838) (xy 177.05074 -226.74531) (xy 177.096898 -226.771959) (xy 177.138569 -226.80519)
			(xy 177.174821 -226.844261) (xy 177.204845 -226.888298) (xy 177.227971 -226.936319) (xy 177.243681 -226.987249)
			(xy 177.251624 -227.039953) (xy 177.252122 -227.066602) (xy 177.251624 -227.093251) (xy 191.628004 -227.093251)
			(xy 191.628004 -227.039953) (xy 191.635947 -226.987249) (xy 191.651657 -226.936319) (xy 191.674783 -226.888298)
			(xy 191.704807 -226.844261) (xy 191.741059 -226.80519) (xy 191.78273 -226.771959) (xy 191.828888 -226.74531)
			(xy 191.878502 -226.725838) (xy 191.930464 -226.713978) (xy 191.983614 -226.709995) (xy 192.036764 -226.713978)
			(xy 192.088726 -226.725838) (xy 192.13834 -226.74531) (xy 192.184498 -226.771959) (xy 192.226169 -226.80519)
			(xy 192.262421 -226.844261) (xy 192.292445 -226.888298) (xy 192.315571 -226.936319) (xy 192.331281 -226.987249)
			(xy 192.339224 -227.039953) (xy 192.339722 -227.066602) (xy 192.339224 -227.093251) (xy 206.715604 -227.093251)
			(xy 206.715604 -227.039953) (xy 206.723547 -226.987249) (xy 206.739257 -226.936319) (xy 206.762383 -226.888298)
			(xy 206.792407 -226.844261) (xy 206.828659 -226.80519) (xy 206.87033 -226.771959) (xy 206.916488 -226.74531)
			(xy 206.966102 -226.725838) (xy 207.018064 -226.713978) (xy 207.071214 -226.709995) (xy 207.124364 -226.713978)
			(xy 207.176326 -226.725838) (xy 207.22594 -226.74531) (xy 207.272098 -226.771959) (xy 207.313769 -226.80519)
			(xy 207.350021 -226.844261) (xy 207.380045 -226.888298) (xy 207.403171 -226.936319) (xy 207.418881 -226.987249)
			(xy 207.426824 -227.039953) (xy 207.427322 -227.066602) (xy 207.426824 -227.093251) (xy 207.418881 -227.145955)
			(xy 207.403171 -227.196885) (xy 207.380045 -227.244906) (xy 207.350021 -227.288943) (xy 207.313769 -227.328014)
			(xy 207.272098 -227.361245) (xy 207.22594 -227.387894) (xy 207.176326 -227.407366) (xy 207.124364 -227.419226)
			(xy 207.071214 -227.42321) (xy 207.018064 -227.419226) (xy 206.966102 -227.407366) (xy 206.916488 -227.387894)
			(xy 206.87033 -227.361245) (xy 206.828659 -227.328014) (xy 206.792407 -227.288943) (xy 206.762383 -227.244906)
			(xy 206.739257 -227.196885) (xy 206.723547 -227.145955) (xy 206.715604 -227.093251) (xy 192.339224 -227.093251)
			(xy 192.331281 -227.145955) (xy 192.315571 -227.196885) (xy 192.292445 -227.244906) (xy 192.262421 -227.288943)
			(xy 192.226169 -227.328014) (xy 192.184498 -227.361245) (xy 192.13834 -227.387894) (xy 192.088726 -227.407366)
			(xy 192.036764 -227.419226) (xy 191.983614 -227.42321) (xy 191.930464 -227.419226) (xy 191.878502 -227.407366)
			(xy 191.828888 -227.387894) (xy 191.78273 -227.361245) (xy 191.741059 -227.328014) (xy 191.704807 -227.288943)
			(xy 191.674783 -227.244906) (xy 191.651657 -227.196885) (xy 191.635947 -227.145955) (xy 191.628004 -227.093251)
			(xy 177.251624 -227.093251) (xy 177.243681 -227.145955) (xy 177.227971 -227.196885) (xy 177.204845 -227.244906)
			(xy 177.174821 -227.288943) (xy 177.138569 -227.328014) (xy 177.096898 -227.361245) (xy 177.05074 -227.387894)
			(xy 177.001126 -227.407366) (xy 176.949164 -227.419226) (xy 176.896014 -227.42321) (xy 176.842864 -227.419226)
			(xy 176.790902 -227.407366) (xy 176.741288 -227.387894) (xy 176.69513 -227.361245) (xy 176.653459 -227.328014)
			(xy 176.617207 -227.288943) (xy 176.587183 -227.244906) (xy 176.564057 -227.196885) (xy 176.548347 -227.145955)
			(xy 176.540404 -227.093251) (xy 162.138624 -227.093251) (xy 162.130681 -227.145955) (xy 162.114971 -227.196885)
			(xy 162.091845 -227.244906) (xy 162.061821 -227.288943) (xy 162.025569 -227.328014) (xy 161.983898 -227.361245)
			(xy 161.93774 -227.387894) (xy 161.888126 -227.407366) (xy 161.836164 -227.419226) (xy 161.783014 -227.42321)
			(xy 161.729864 -227.419226) (xy 161.677902 -227.407366) (xy 161.628288 -227.387894) (xy 161.58213 -227.361245)
			(xy 161.540459 -227.328014) (xy 161.504207 -227.288943) (xy 161.474183 -227.244906) (xy 161.451057 -227.196885)
			(xy 161.435347 -227.145955) (xy 161.427404 -227.093251) (xy 159.11576 -227.093251) (xy 159.11576 -227.943389)
			(xy 161.427404 -227.943389) (xy 161.427404 -227.890091) (xy 161.435347 -227.837387) (xy 161.451057 -227.786457)
			(xy 161.474183 -227.738436) (xy 161.504207 -227.694399) (xy 161.540459 -227.655328) (xy 161.58213 -227.622097)
			(xy 161.628288 -227.595448) (xy 161.677902 -227.575976) (xy 161.729864 -227.564116) (xy 161.783014 -227.560133)
			(xy 161.836164 -227.564116) (xy 161.888126 -227.575976) (xy 161.93774 -227.595448) (xy 161.983898 -227.622097)
			(xy 162.025569 -227.655328) (xy 162.061821 -227.694399) (xy 162.091845 -227.738436) (xy 162.114971 -227.786457)
			(xy 162.130681 -227.837387) (xy 162.138624 -227.890091) (xy 162.139122 -227.91674) (xy 162.138624 -227.943389)
			(xy 172.440336 -227.943389) (xy 172.440336 -227.890091) (xy 172.448279 -227.837387) (xy 172.463989 -227.786457)
			(xy 172.487115 -227.738436) (xy 172.517139 -227.694399) (xy 172.553391 -227.655328) (xy 172.595062 -227.622097)
			(xy 172.64122 -227.595448) (xy 172.690834 -227.575976) (xy 172.742796 -227.564116) (xy 172.795946 -227.560133)
			(xy 172.849096 -227.564116) (xy 172.901058 -227.575976) (xy 172.950672 -227.595448) (xy 172.99683 -227.622097)
			(xy 173.038501 -227.655328) (xy 173.074753 -227.694399) (xy 173.104777 -227.738436) (xy 173.127903 -227.786457)
			(xy 173.143613 -227.837387) (xy 173.151556 -227.890091) (xy 173.152054 -227.91674) (xy 173.151556 -227.943389)
			(xy 176.540404 -227.943389) (xy 176.540404 -227.890091) (xy 176.548347 -227.837387) (xy 176.564057 -227.786457)
			(xy 176.587183 -227.738436) (xy 176.617207 -227.694399) (xy 176.653459 -227.655328) (xy 176.69513 -227.622097)
			(xy 176.741288 -227.595448) (xy 176.790902 -227.575976) (xy 176.842864 -227.564116) (xy 176.896014 -227.560133)
			(xy 176.949164 -227.564116) (xy 177.001126 -227.575976) (xy 177.05074 -227.595448) (xy 177.096898 -227.622097)
			(xy 177.138569 -227.655328) (xy 177.174821 -227.694399) (xy 177.204845 -227.738436) (xy 177.227971 -227.786457)
			(xy 177.243681 -227.837387) (xy 177.251624 -227.890091) (xy 177.252122 -227.91674) (xy 177.251624 -227.943389)
			(xy 187.527936 -227.943389) (xy 187.527936 -227.890091) (xy 187.535879 -227.837387) (xy 187.551589 -227.786457)
			(xy 187.574715 -227.738436) (xy 187.604739 -227.694399) (xy 187.640991 -227.655328) (xy 187.682662 -227.622097)
			(xy 187.72882 -227.595448) (xy 187.778434 -227.575976) (xy 187.830396 -227.564116) (xy 187.883546 -227.560133)
			(xy 187.936696 -227.564116) (xy 187.988658 -227.575976) (xy 188.038272 -227.595448) (xy 188.08443 -227.622097)
			(xy 188.126101 -227.655328) (xy 188.162353 -227.694399) (xy 188.192377 -227.738436) (xy 188.215503 -227.786457)
			(xy 188.231213 -227.837387) (xy 188.239156 -227.890091) (xy 188.239654 -227.91674) (xy 188.239156 -227.943389)
			(xy 191.628004 -227.943389) (xy 191.628004 -227.890091) (xy 191.635947 -227.837387) (xy 191.651657 -227.786457)
			(xy 191.674783 -227.738436) (xy 191.704807 -227.694399) (xy 191.741059 -227.655328) (xy 191.78273 -227.622097)
			(xy 191.828888 -227.595448) (xy 191.878502 -227.575976) (xy 191.930464 -227.564116) (xy 191.983614 -227.560133)
			(xy 192.036764 -227.564116) (xy 192.088726 -227.575976) (xy 192.13834 -227.595448) (xy 192.184498 -227.622097)
			(xy 192.226169 -227.655328) (xy 192.262421 -227.694399) (xy 192.292445 -227.738436) (xy 192.315571 -227.786457)
			(xy 192.331281 -227.837387) (xy 192.339224 -227.890091) (xy 192.339722 -227.91674) (xy 192.339224 -227.943389)
			(xy 202.615536 -227.943389) (xy 202.615536 -227.890091) (xy 202.623479 -227.837387) (xy 202.639189 -227.786457)
			(xy 202.662315 -227.738436) (xy 202.692339 -227.694399) (xy 202.728591 -227.655328) (xy 202.770262 -227.622097)
			(xy 202.81642 -227.595448) (xy 202.866034 -227.575976) (xy 202.917996 -227.564116) (xy 202.971146 -227.560133)
			(xy 203.024296 -227.564116) (xy 203.076258 -227.575976) (xy 203.125872 -227.595448) (xy 203.17203 -227.622097)
			(xy 203.213701 -227.655328) (xy 203.249953 -227.694399) (xy 203.279977 -227.738436) (xy 203.303103 -227.786457)
			(xy 203.318813 -227.837387) (xy 203.326756 -227.890091) (xy 203.327254 -227.91674) (xy 203.326756 -227.943389)
			(xy 206.715604 -227.943389) (xy 206.715604 -227.890091) (xy 206.723547 -227.837387) (xy 206.739257 -227.786457)
			(xy 206.762383 -227.738436) (xy 206.792407 -227.694399) (xy 206.828659 -227.655328) (xy 206.87033 -227.622097)
			(xy 206.916488 -227.595448) (xy 206.966102 -227.575976) (xy 207.018064 -227.564116) (xy 207.071214 -227.560133)
			(xy 207.124364 -227.564116) (xy 207.176326 -227.575976) (xy 207.22594 -227.595448) (xy 207.272098 -227.622097)
			(xy 207.313769 -227.655328) (xy 207.350021 -227.694399) (xy 207.380045 -227.738436) (xy 207.403171 -227.786457)
			(xy 207.418881 -227.837387) (xy 207.426824 -227.890091) (xy 207.427322 -227.91674) (xy 207.426824 -227.943389)
			(xy 207.418881 -227.996093) (xy 207.403171 -228.047023) (xy 207.380045 -228.095044) (xy 207.350021 -228.139081)
			(xy 207.313769 -228.178152) (xy 207.272098 -228.211383) (xy 207.22594 -228.238032) (xy 207.176326 -228.257504)
			(xy 207.124364 -228.269364) (xy 207.071214 -228.273348) (xy 207.018064 -228.269364) (xy 206.966102 -228.257504)
			(xy 206.916488 -228.238032) (xy 206.87033 -228.211383) (xy 206.828659 -228.178152) (xy 206.792407 -228.139081)
			(xy 206.762383 -228.095044) (xy 206.739257 -228.047023) (xy 206.723547 -227.996093) (xy 206.715604 -227.943389)
			(xy 203.326756 -227.943389) (xy 203.318813 -227.996093) (xy 203.303103 -228.047023) (xy 203.279977 -228.095044)
			(xy 203.249953 -228.139081) (xy 203.213701 -228.178152) (xy 203.17203 -228.211383) (xy 203.125872 -228.238032)
			(xy 203.076258 -228.257504) (xy 203.024296 -228.269364) (xy 202.971146 -228.273348) (xy 202.917996 -228.269364)
			(xy 202.866034 -228.257504) (xy 202.81642 -228.238032) (xy 202.770262 -228.211383) (xy 202.728591 -228.178152)
			(xy 202.692339 -228.139081) (xy 202.662315 -228.095044) (xy 202.639189 -228.047023) (xy 202.623479 -227.996093)
			(xy 202.615536 -227.943389) (xy 192.339224 -227.943389) (xy 192.331281 -227.996093) (xy 192.315571 -228.047023)
			(xy 192.292445 -228.095044) (xy 192.262421 -228.139081) (xy 192.226169 -228.178152) (xy 192.184498 -228.211383)
			(xy 192.13834 -228.238032) (xy 192.088726 -228.257504) (xy 192.036764 -228.269364) (xy 191.983614 -228.273348)
			(xy 191.930464 -228.269364) (xy 191.878502 -228.257504) (xy 191.828888 -228.238032) (xy 191.78273 -228.211383)
			(xy 191.741059 -228.178152) (xy 191.704807 -228.139081) (xy 191.674783 -228.095044) (xy 191.651657 -228.047023)
			(xy 191.635947 -227.996093) (xy 191.628004 -227.943389) (xy 188.239156 -227.943389) (xy 188.231213 -227.996093)
			(xy 188.215503 -228.047023) (xy 188.192377 -228.095044) (xy 188.162353 -228.139081) (xy 188.126101 -228.178152)
			(xy 188.08443 -228.211383) (xy 188.038272 -228.238032) (xy 187.988658 -228.257504) (xy 187.936696 -228.269364)
			(xy 187.883546 -228.273348) (xy 187.830396 -228.269364) (xy 187.778434 -228.257504) (xy 187.72882 -228.238032)
			(xy 187.682662 -228.211383) (xy 187.640991 -228.178152) (xy 187.604739 -228.139081) (xy 187.574715 -228.095044)
			(xy 187.551589 -228.047023) (xy 187.535879 -227.996093) (xy 187.527936 -227.943389) (xy 177.251624 -227.943389)
			(xy 177.243681 -227.996093) (xy 177.227971 -228.047023) (xy 177.204845 -228.095044) (xy 177.174821 -228.139081)
			(xy 177.138569 -228.178152) (xy 177.096898 -228.211383) (xy 177.05074 -228.238032) (xy 177.001126 -228.257504)
			(xy 176.949164 -228.269364) (xy 176.896014 -228.273348) (xy 176.842864 -228.269364) (xy 176.790902 -228.257504)
			(xy 176.741288 -228.238032) (xy 176.69513 -228.211383) (xy 176.653459 -228.178152) (xy 176.617207 -228.139081)
			(xy 176.587183 -228.095044) (xy 176.564057 -228.047023) (xy 176.548347 -227.996093) (xy 176.540404 -227.943389)
			(xy 173.151556 -227.943389) (xy 173.143613 -227.996093) (xy 173.127903 -228.047023) (xy 173.104777 -228.095044)
			(xy 173.074753 -228.139081) (xy 173.038501 -228.178152) (xy 172.99683 -228.211383) (xy 172.950672 -228.238032)
			(xy 172.901058 -228.257504) (xy 172.849096 -228.269364) (xy 172.795946 -228.273348) (xy 172.742796 -228.269364)
			(xy 172.690834 -228.257504) (xy 172.64122 -228.238032) (xy 172.595062 -228.211383) (xy 172.553391 -228.178152)
			(xy 172.517139 -228.139081) (xy 172.487115 -228.095044) (xy 172.463989 -228.047023) (xy 172.448279 -227.996093)
			(xy 172.440336 -227.943389) (xy 162.138624 -227.943389) (xy 162.130681 -227.996093) (xy 162.114971 -228.047023)
			(xy 162.091845 -228.095044) (xy 162.061821 -228.139081) (xy 162.025569 -228.178152) (xy 161.983898 -228.211383)
			(xy 161.93774 -228.238032) (xy 161.888126 -228.257504) (xy 161.836164 -228.269364) (xy 161.783014 -228.273348)
			(xy 161.729864 -228.269364) (xy 161.677902 -228.257504) (xy 161.628288 -228.238032) (xy 161.58213 -228.211383)
			(xy 161.540459 -228.178152) (xy 161.504207 -228.139081) (xy 161.474183 -228.095044) (xy 161.451057 -228.047023)
			(xy 161.435347 -227.996093) (xy 161.427404 -227.943389) (xy 159.11576 -227.943389) (xy 159.11576 -228.793273)
			(xy 172.440336 -228.793273) (xy 172.440336 -228.739975) (xy 172.448279 -228.687271) (xy 172.463989 -228.636341)
			(xy 172.487115 -228.58832) (xy 172.517139 -228.544283) (xy 172.553391 -228.505212) (xy 172.595062 -228.471981)
			(xy 172.64122 -228.445332) (xy 172.690834 -228.42586) (xy 172.742796 -228.414) (xy 172.795946 -228.410017)
			(xy 172.849096 -228.414) (xy 172.901058 -228.42586) (xy 172.950672 -228.445332) (xy 172.99683 -228.471981)
			(xy 173.038501 -228.505212) (xy 173.074753 -228.544283) (xy 173.104777 -228.58832) (xy 173.127903 -228.636341)
			(xy 173.143613 -228.687271) (xy 173.151556 -228.739975) (xy 173.152054 -228.766624) (xy 173.151556 -228.793273)
			(xy 187.527936 -228.793273) (xy 187.527936 -228.739975) (xy 187.535879 -228.687271) (xy 187.551589 -228.636341)
			(xy 187.574715 -228.58832) (xy 187.604739 -228.544283) (xy 187.640991 -228.505212) (xy 187.682662 -228.471981)
			(xy 187.72882 -228.445332) (xy 187.778434 -228.42586) (xy 187.830396 -228.414) (xy 187.883546 -228.410017)
			(xy 187.936696 -228.414) (xy 187.988658 -228.42586) (xy 188.038272 -228.445332) (xy 188.08443 -228.471981)
			(xy 188.126101 -228.505212) (xy 188.162353 -228.544283) (xy 188.192377 -228.58832) (xy 188.215503 -228.636341)
			(xy 188.231213 -228.687271) (xy 188.239156 -228.739975) (xy 188.239654 -228.766624) (xy 188.239156 -228.793273)
			(xy 202.615536 -228.793273) (xy 202.615536 -228.739975) (xy 202.623479 -228.687271) (xy 202.639189 -228.636341)
			(xy 202.662315 -228.58832) (xy 202.692339 -228.544283) (xy 202.728591 -228.505212) (xy 202.770262 -228.471981)
			(xy 202.81642 -228.445332) (xy 202.866034 -228.42586) (xy 202.917996 -228.414) (xy 202.971146 -228.410017)
			(xy 203.024296 -228.414) (xy 203.076258 -228.42586) (xy 203.125872 -228.445332) (xy 203.17203 -228.471981)
			(xy 203.213701 -228.505212) (xy 203.249953 -228.544283) (xy 203.279977 -228.58832) (xy 203.303103 -228.636341)
			(xy 203.318813 -228.687271) (xy 203.326756 -228.739975) (xy 203.327254 -228.766624) (xy 203.326756 -228.793273)
			(xy 203.318813 -228.845977) (xy 203.303103 -228.896907) (xy 203.279977 -228.944928) (xy 203.249953 -228.988965)
			(xy 203.213701 -229.028036) (xy 203.17203 -229.061267) (xy 203.125872 -229.087916) (xy 203.076258 -229.107388)
			(xy 203.024296 -229.119248) (xy 202.971146 -229.123232) (xy 202.917996 -229.119248) (xy 202.866034 -229.107388)
			(xy 202.81642 -229.087916) (xy 202.770262 -229.061267) (xy 202.728591 -229.028036) (xy 202.692339 -228.988965)
			(xy 202.662315 -228.944928) (xy 202.639189 -228.896907) (xy 202.623479 -228.845977) (xy 202.615536 -228.793273)
			(xy 188.239156 -228.793273) (xy 188.231213 -228.845977) (xy 188.215503 -228.896907) (xy 188.192377 -228.944928)
			(xy 188.162353 -228.988965) (xy 188.126101 -229.028036) (xy 188.08443 -229.061267) (xy 188.038272 -229.087916)
			(xy 187.988658 -229.107388) (xy 187.936696 -229.119248) (xy 187.883546 -229.123232) (xy 187.830396 -229.119248)
			(xy 187.778434 -229.107388) (xy 187.72882 -229.087916) (xy 187.682662 -229.061267) (xy 187.640991 -229.028036)
			(xy 187.604739 -228.988965) (xy 187.574715 -228.944928) (xy 187.551589 -228.896907) (xy 187.535879 -228.845977)
			(xy 187.527936 -228.793273) (xy 173.151556 -228.793273) (xy 173.143613 -228.845977) (xy 173.127903 -228.896907)
			(xy 173.104777 -228.944928) (xy 173.074753 -228.988965) (xy 173.038501 -229.028036) (xy 172.99683 -229.061267)
			(xy 172.950672 -229.087916) (xy 172.901058 -229.107388) (xy 172.849096 -229.119248) (xy 172.795946 -229.123232)
			(xy 172.742796 -229.119248) (xy 172.690834 -229.107388) (xy 172.64122 -229.087916) (xy 172.595062 -229.061267)
			(xy 172.553391 -229.028036) (xy 172.517139 -228.988965) (xy 172.487115 -228.944928) (xy 172.463989 -228.896907)
			(xy 172.448279 -228.845977) (xy 172.440336 -228.793273) (xy 159.11576 -228.793273) (xy 159.11576 -229.643411)
			(xy 161.427404 -229.643411) (xy 161.427404 -229.590113) (xy 161.435347 -229.537409) (xy 161.451057 -229.486479)
			(xy 161.474183 -229.438458) (xy 161.504207 -229.394421) (xy 161.540459 -229.35535) (xy 161.58213 -229.322119)
			(xy 161.628288 -229.29547) (xy 161.677902 -229.275998) (xy 161.729864 -229.264138) (xy 161.783014 -229.260155)
			(xy 161.836164 -229.264138) (xy 161.888126 -229.275998) (xy 161.93774 -229.29547) (xy 161.983898 -229.322119)
			(xy 162.025569 -229.35535) (xy 162.061821 -229.394421) (xy 162.091845 -229.438458) (xy 162.114971 -229.486479)
			(xy 162.130681 -229.537409) (xy 162.138624 -229.590113) (xy 162.139122 -229.616762) (xy 162.138624 -229.643411)
			(xy 176.540404 -229.643411) (xy 176.540404 -229.590113) (xy 176.548347 -229.537409) (xy 176.564057 -229.486479)
			(xy 176.587183 -229.438458) (xy 176.617207 -229.394421) (xy 176.653459 -229.35535) (xy 176.69513 -229.322119)
			(xy 176.741288 -229.29547) (xy 176.790902 -229.275998) (xy 176.842864 -229.264138) (xy 176.896014 -229.260155)
			(xy 176.949164 -229.264138) (xy 177.001126 -229.275998) (xy 177.05074 -229.29547) (xy 177.096898 -229.322119)
			(xy 177.138569 -229.35535) (xy 177.174821 -229.394421) (xy 177.204845 -229.438458) (xy 177.227971 -229.486479)
			(xy 177.243681 -229.537409) (xy 177.251624 -229.590113) (xy 177.252122 -229.616762) (xy 177.251624 -229.643411)
			(xy 191.628004 -229.643411) (xy 191.628004 -229.590113) (xy 191.635947 -229.537409) (xy 191.651657 -229.486479)
			(xy 191.674783 -229.438458) (xy 191.704807 -229.394421) (xy 191.741059 -229.35535) (xy 191.78273 -229.322119)
			(xy 191.828888 -229.29547) (xy 191.878502 -229.275998) (xy 191.930464 -229.264138) (xy 191.983614 -229.260155)
			(xy 192.036764 -229.264138) (xy 192.088726 -229.275998) (xy 192.13834 -229.29547) (xy 192.184498 -229.322119)
			(xy 192.226169 -229.35535) (xy 192.262421 -229.394421) (xy 192.292445 -229.438458) (xy 192.315571 -229.486479)
			(xy 192.331281 -229.537409) (xy 192.339224 -229.590113) (xy 192.339722 -229.616762) (xy 192.339224 -229.643411)
			(xy 206.715604 -229.643411) (xy 206.715604 -229.590113) (xy 206.723547 -229.537409) (xy 206.739257 -229.486479)
			(xy 206.762383 -229.438458) (xy 206.792407 -229.394421) (xy 206.828659 -229.35535) (xy 206.87033 -229.322119)
			(xy 206.916488 -229.29547) (xy 206.966102 -229.275998) (xy 207.018064 -229.264138) (xy 207.071214 -229.260155)
			(xy 207.124364 -229.264138) (xy 207.176326 -229.275998) (xy 207.22594 -229.29547) (xy 207.272098 -229.322119)
			(xy 207.313769 -229.35535) (xy 207.350021 -229.394421) (xy 207.380045 -229.438458) (xy 207.403171 -229.486479)
			(xy 207.418881 -229.537409) (xy 207.426824 -229.590113) (xy 207.427322 -229.616762) (xy 207.426824 -229.643411)
			(xy 207.418881 -229.696115) (xy 207.403171 -229.747045) (xy 207.380045 -229.795066) (xy 207.350021 -229.839103)
			(xy 207.313769 -229.878174) (xy 207.272098 -229.911405) (xy 207.22594 -229.938054) (xy 207.176326 -229.957526)
			(xy 207.124364 -229.969386) (xy 207.071214 -229.97337) (xy 207.018064 -229.969386) (xy 206.966102 -229.957526)
			(xy 206.916488 -229.938054) (xy 206.87033 -229.911405) (xy 206.828659 -229.878174) (xy 206.792407 -229.839103)
			(xy 206.762383 -229.795066) (xy 206.739257 -229.747045) (xy 206.723547 -229.696115) (xy 206.715604 -229.643411)
			(xy 192.339224 -229.643411) (xy 192.331281 -229.696115) (xy 192.315571 -229.747045) (xy 192.292445 -229.795066)
			(xy 192.262421 -229.839103) (xy 192.226169 -229.878174) (xy 192.184498 -229.911405) (xy 192.13834 -229.938054)
			(xy 192.088726 -229.957526) (xy 192.036764 -229.969386) (xy 191.983614 -229.97337) (xy 191.930464 -229.969386)
			(xy 191.878502 -229.957526) (xy 191.828888 -229.938054) (xy 191.78273 -229.911405) (xy 191.741059 -229.878174)
			(xy 191.704807 -229.839103) (xy 191.674783 -229.795066) (xy 191.651657 -229.747045) (xy 191.635947 -229.696115)
			(xy 191.628004 -229.643411) (xy 177.251624 -229.643411) (xy 177.243681 -229.696115) (xy 177.227971 -229.747045)
			(xy 177.204845 -229.795066) (xy 177.174821 -229.839103) (xy 177.138569 -229.878174) (xy 177.096898 -229.911405)
			(xy 177.05074 -229.938054) (xy 177.001126 -229.957526) (xy 176.949164 -229.969386) (xy 176.896014 -229.97337)
			(xy 176.842864 -229.969386) (xy 176.790902 -229.957526) (xy 176.741288 -229.938054) (xy 176.69513 -229.911405)
			(xy 176.653459 -229.878174) (xy 176.617207 -229.839103) (xy 176.587183 -229.795066) (xy 176.564057 -229.747045)
			(xy 176.548347 -229.696115) (xy 176.540404 -229.643411) (xy 162.138624 -229.643411) (xy 162.130681 -229.696115)
			(xy 162.114971 -229.747045) (xy 162.091845 -229.795066) (xy 162.061821 -229.839103) (xy 162.025569 -229.878174)
			(xy 161.983898 -229.911405) (xy 161.93774 -229.938054) (xy 161.888126 -229.957526) (xy 161.836164 -229.969386)
			(xy 161.783014 -229.97337) (xy 161.729864 -229.969386) (xy 161.677902 -229.957526) (xy 161.628288 -229.938054)
			(xy 161.58213 -229.911405) (xy 161.540459 -229.878174) (xy 161.504207 -229.839103) (xy 161.474183 -229.795066)
			(xy 161.451057 -229.747045) (xy 161.435347 -229.696115) (xy 161.427404 -229.643411) (xy 159.11576 -229.643411)
			(xy 159.11576 -230.493295) (xy 172.440336 -230.493295) (xy 172.440336 -230.439997) (xy 172.448279 -230.387293)
			(xy 172.463989 -230.336363) (xy 172.487115 -230.288342) (xy 172.517139 -230.244305) (xy 172.553391 -230.205234)
			(xy 172.595062 -230.172003) (xy 172.64122 -230.145354) (xy 172.690834 -230.125882) (xy 172.742796 -230.114022)
			(xy 172.795946 -230.110039) (xy 172.849096 -230.114022) (xy 172.901058 -230.125882) (xy 172.950672 -230.145354)
			(xy 172.99683 -230.172003) (xy 173.038501 -230.205234) (xy 173.074753 -230.244305) (xy 173.104777 -230.288342)
			(xy 173.127903 -230.336363) (xy 173.143613 -230.387293) (xy 173.151556 -230.439997) (xy 173.152054 -230.466646)
			(xy 173.151556 -230.493295) (xy 187.527936 -230.493295) (xy 187.527936 -230.439997) (xy 187.535879 -230.387293)
			(xy 187.551589 -230.336363) (xy 187.574715 -230.288342) (xy 187.604739 -230.244305) (xy 187.640991 -230.205234)
			(xy 187.682662 -230.172003) (xy 187.72882 -230.145354) (xy 187.778434 -230.125882) (xy 187.830396 -230.114022)
			(xy 187.883546 -230.110039) (xy 187.936696 -230.114022) (xy 187.988658 -230.125882) (xy 188.038272 -230.145354)
			(xy 188.08443 -230.172003) (xy 188.126101 -230.205234) (xy 188.162353 -230.244305) (xy 188.192377 -230.288342)
			(xy 188.215503 -230.336363) (xy 188.231213 -230.387293) (xy 188.239156 -230.439997) (xy 188.239654 -230.466646)
			(xy 188.239156 -230.493295) (xy 202.615536 -230.493295) (xy 202.615536 -230.439997) (xy 202.623479 -230.387293)
			(xy 202.639189 -230.336363) (xy 202.662315 -230.288342) (xy 202.692339 -230.244305) (xy 202.728591 -230.205234)
			(xy 202.770262 -230.172003) (xy 202.81642 -230.145354) (xy 202.866034 -230.125882) (xy 202.917996 -230.114022)
			(xy 202.971146 -230.110039) (xy 203.024296 -230.114022) (xy 203.076258 -230.125882) (xy 203.125872 -230.145354)
			(xy 203.17203 -230.172003) (xy 203.213701 -230.205234) (xy 203.249953 -230.244305) (xy 203.279977 -230.288342)
			(xy 203.303103 -230.336363) (xy 203.318813 -230.387293) (xy 203.326756 -230.439997) (xy 203.327254 -230.466646)
			(xy 203.326756 -230.493295) (xy 203.318813 -230.545999) (xy 203.303103 -230.596929) (xy 203.279977 -230.64495)
			(xy 203.249953 -230.688987) (xy 203.213701 -230.728058) (xy 203.17203 -230.761289) (xy 203.125872 -230.787938)
			(xy 203.076258 -230.80741) (xy 203.024296 -230.81927) (xy 202.971146 -230.823254) (xy 202.917996 -230.81927)
			(xy 202.866034 -230.80741) (xy 202.81642 -230.787938) (xy 202.770262 -230.761289) (xy 202.728591 -230.728058)
			(xy 202.692339 -230.688987) (xy 202.662315 -230.64495) (xy 202.639189 -230.596929) (xy 202.623479 -230.545999)
			(xy 202.615536 -230.493295) (xy 188.239156 -230.493295) (xy 188.231213 -230.545999) (xy 188.215503 -230.596929)
			(xy 188.192377 -230.64495) (xy 188.162353 -230.688987) (xy 188.126101 -230.728058) (xy 188.08443 -230.761289)
			(xy 188.038272 -230.787938) (xy 187.988658 -230.80741) (xy 187.936696 -230.81927) (xy 187.883546 -230.823254)
			(xy 187.830396 -230.81927) (xy 187.778434 -230.80741) (xy 187.72882 -230.787938) (xy 187.682662 -230.761289)
			(xy 187.640991 -230.728058) (xy 187.604739 -230.688987) (xy 187.574715 -230.64495) (xy 187.551589 -230.596929)
			(xy 187.535879 -230.545999) (xy 187.527936 -230.493295) (xy 173.151556 -230.493295) (xy 173.143613 -230.545999)
			(xy 173.127903 -230.596929) (xy 173.104777 -230.64495) (xy 173.074753 -230.688987) (xy 173.038501 -230.728058)
			(xy 172.99683 -230.761289) (xy 172.950672 -230.787938) (xy 172.901058 -230.80741) (xy 172.849096 -230.81927)
			(xy 172.795946 -230.823254) (xy 172.742796 -230.81927) (xy 172.690834 -230.80741) (xy 172.64122 -230.787938)
			(xy 172.595062 -230.761289) (xy 172.553391 -230.728058) (xy 172.517139 -230.688987) (xy 172.487115 -230.64495)
			(xy 172.463989 -230.596929) (xy 172.448279 -230.545999) (xy 172.440336 -230.493295) (xy 159.11576 -230.493295)
			(xy 159.11576 -231.343433) (xy 161.427404 -231.343433) (xy 161.427404 -231.290135) (xy 161.435347 -231.237431)
			(xy 161.451057 -231.186501) (xy 161.474183 -231.13848) (xy 161.504207 -231.094443) (xy 161.540459 -231.055372)
			(xy 161.58213 -231.022141) (xy 161.628288 -230.995492) (xy 161.677902 -230.97602) (xy 161.729864 -230.96416)
			(xy 161.783014 -230.960177) (xy 161.836164 -230.96416) (xy 161.888126 -230.97602) (xy 161.93774 -230.995492)
			(xy 161.983898 -231.022141) (xy 162.025569 -231.055372) (xy 162.061821 -231.094443) (xy 162.091845 -231.13848)
			(xy 162.114971 -231.186501) (xy 162.130681 -231.237431) (xy 162.138624 -231.290135) (xy 162.139122 -231.316784)
			(xy 162.138624 -231.343433) (xy 176.540404 -231.343433) (xy 176.540404 -231.290135) (xy 176.548347 -231.237431)
			(xy 176.564057 -231.186501) (xy 176.587183 -231.13848) (xy 176.617207 -231.094443) (xy 176.653459 -231.055372)
			(xy 176.69513 -231.022141) (xy 176.741288 -230.995492) (xy 176.790902 -230.97602) (xy 176.842864 -230.96416)
			(xy 176.896014 -230.960177) (xy 176.949164 -230.96416) (xy 177.001126 -230.97602) (xy 177.05074 -230.995492)
			(xy 177.096898 -231.022141) (xy 177.138569 -231.055372) (xy 177.174821 -231.094443) (xy 177.204845 -231.13848)
			(xy 177.227971 -231.186501) (xy 177.243681 -231.237431) (xy 177.251624 -231.290135) (xy 177.252122 -231.316784)
			(xy 177.251624 -231.343433) (xy 191.628004 -231.343433) (xy 191.628004 -231.290135) (xy 191.635947 -231.237431)
			(xy 191.651657 -231.186501) (xy 191.674783 -231.13848) (xy 191.704807 -231.094443) (xy 191.741059 -231.055372)
			(xy 191.78273 -231.022141) (xy 191.828888 -230.995492) (xy 191.878502 -230.97602) (xy 191.930464 -230.96416)
			(xy 191.983614 -230.960177) (xy 192.036764 -230.96416) (xy 192.088726 -230.97602) (xy 192.13834 -230.995492)
			(xy 192.184498 -231.022141) (xy 192.226169 -231.055372) (xy 192.262421 -231.094443) (xy 192.292445 -231.13848)
			(xy 192.315571 -231.186501) (xy 192.331281 -231.237431) (xy 192.339224 -231.290135) (xy 192.339722 -231.316784)
			(xy 192.339224 -231.343433) (xy 206.715604 -231.343433) (xy 206.715604 -231.290135) (xy 206.723547 -231.237431)
			(xy 206.739257 -231.186501) (xy 206.762383 -231.13848) (xy 206.792407 -231.094443) (xy 206.828659 -231.055372)
			(xy 206.87033 -231.022141) (xy 206.916488 -230.995492) (xy 206.966102 -230.97602) (xy 207.018064 -230.96416)
			(xy 207.071214 -230.960177) (xy 207.124364 -230.96416) (xy 207.176326 -230.97602) (xy 207.22594 -230.995492)
			(xy 207.272098 -231.022141) (xy 207.313769 -231.055372) (xy 207.350021 -231.094443) (xy 207.380045 -231.13848)
			(xy 207.403171 -231.186501) (xy 207.418881 -231.237431) (xy 207.426824 -231.290135) (xy 207.427322 -231.316784)
			(xy 207.426824 -231.343433) (xy 207.418881 -231.396137) (xy 207.403171 -231.447067) (xy 207.380045 -231.495088)
			(xy 207.350021 -231.539125) (xy 207.313769 -231.578196) (xy 207.272098 -231.611427) (xy 207.22594 -231.638076)
			(xy 207.176326 -231.657548) (xy 207.124364 -231.669408) (xy 207.071214 -231.673392) (xy 207.018064 -231.669408)
			(xy 206.966102 -231.657548) (xy 206.916488 -231.638076) (xy 206.87033 -231.611427) (xy 206.828659 -231.578196)
			(xy 206.792407 -231.539125) (xy 206.762383 -231.495088) (xy 206.739257 -231.447067) (xy 206.723547 -231.396137)
			(xy 206.715604 -231.343433) (xy 192.339224 -231.343433) (xy 192.331281 -231.396137) (xy 192.315571 -231.447067)
			(xy 192.292445 -231.495088) (xy 192.262421 -231.539125) (xy 192.226169 -231.578196) (xy 192.184498 -231.611427)
			(xy 192.13834 -231.638076) (xy 192.088726 -231.657548) (xy 192.036764 -231.669408) (xy 191.983614 -231.673392)
			(xy 191.930464 -231.669408) (xy 191.878502 -231.657548) (xy 191.828888 -231.638076) (xy 191.78273 -231.611427)
			(xy 191.741059 -231.578196) (xy 191.704807 -231.539125) (xy 191.674783 -231.495088) (xy 191.651657 -231.447067)
			(xy 191.635947 -231.396137) (xy 191.628004 -231.343433) (xy 177.251624 -231.343433) (xy 177.243681 -231.396137)
			(xy 177.227971 -231.447067) (xy 177.204845 -231.495088) (xy 177.174821 -231.539125) (xy 177.138569 -231.578196)
			(xy 177.096898 -231.611427) (xy 177.05074 -231.638076) (xy 177.001126 -231.657548) (xy 176.949164 -231.669408)
			(xy 176.896014 -231.673392) (xy 176.842864 -231.669408) (xy 176.790902 -231.657548) (xy 176.741288 -231.638076)
			(xy 176.69513 -231.611427) (xy 176.653459 -231.578196) (xy 176.617207 -231.539125) (xy 176.587183 -231.495088)
			(xy 176.564057 -231.447067) (xy 176.548347 -231.396137) (xy 176.540404 -231.343433) (xy 162.138624 -231.343433)
			(xy 162.130681 -231.396137) (xy 162.114971 -231.447067) (xy 162.091845 -231.495088) (xy 162.061821 -231.539125)
			(xy 162.025569 -231.578196) (xy 161.983898 -231.611427) (xy 161.93774 -231.638076) (xy 161.888126 -231.657548)
			(xy 161.836164 -231.669408) (xy 161.783014 -231.673392) (xy 161.729864 -231.669408) (xy 161.677902 -231.657548)
			(xy 161.628288 -231.638076) (xy 161.58213 -231.611427) (xy 161.540459 -231.578196) (xy 161.504207 -231.539125)
			(xy 161.474183 -231.495088) (xy 161.451057 -231.447067) (xy 161.435347 -231.396137) (xy 161.427404 -231.343433)
			(xy 159.11576 -231.343433) (xy 159.11576 -232.193317) (xy 172.440336 -232.193317) (xy 172.440336 -232.140019)
			(xy 172.448279 -232.087315) (xy 172.463989 -232.036385) (xy 172.487115 -231.988364) (xy 172.517139 -231.944327)
			(xy 172.553391 -231.905256) (xy 172.595062 -231.872025) (xy 172.64122 -231.845376) (xy 172.690834 -231.825904)
			(xy 172.742796 -231.814044) (xy 172.795946 -231.810061) (xy 172.849096 -231.814044) (xy 172.901058 -231.825904)
			(xy 172.950672 -231.845376) (xy 172.99683 -231.872025) (xy 173.038501 -231.905256) (xy 173.074753 -231.944327)
			(xy 173.104777 -231.988364) (xy 173.127903 -232.036385) (xy 173.143613 -232.087315) (xy 173.151556 -232.140019)
			(xy 173.152054 -232.166668) (xy 173.151556 -232.193317) (xy 187.527936 -232.193317) (xy 187.527936 -232.140019)
			(xy 187.535879 -232.087315) (xy 187.551589 -232.036385) (xy 187.574715 -231.988364) (xy 187.604739 -231.944327)
			(xy 187.640991 -231.905256) (xy 187.682662 -231.872025) (xy 187.72882 -231.845376) (xy 187.778434 -231.825904)
			(xy 187.830396 -231.814044) (xy 187.883546 -231.810061) (xy 187.936696 -231.814044) (xy 187.988658 -231.825904)
			(xy 188.038272 -231.845376) (xy 188.08443 -231.872025) (xy 188.126101 -231.905256) (xy 188.162353 -231.944327)
			(xy 188.192377 -231.988364) (xy 188.215503 -232.036385) (xy 188.231213 -232.087315) (xy 188.239156 -232.140019)
			(xy 188.239654 -232.166668) (xy 188.239156 -232.193317) (xy 202.615536 -232.193317) (xy 202.615536 -232.140019)
			(xy 202.623479 -232.087315) (xy 202.639189 -232.036385) (xy 202.662315 -231.988364) (xy 202.692339 -231.944327)
			(xy 202.728591 -231.905256) (xy 202.770262 -231.872025) (xy 202.81642 -231.845376) (xy 202.866034 -231.825904)
			(xy 202.917996 -231.814044) (xy 202.971146 -231.810061) (xy 203.024296 -231.814044) (xy 203.076258 -231.825904)
			(xy 203.125872 -231.845376) (xy 203.17203 -231.872025) (xy 203.213701 -231.905256) (xy 203.249953 -231.944327)
			(xy 203.279977 -231.988364) (xy 203.303103 -232.036385) (xy 203.318813 -232.087315) (xy 203.326756 -232.140019)
			(xy 203.327254 -232.166668) (xy 203.326756 -232.193317) (xy 203.318813 -232.246021) (xy 203.303103 -232.296951)
			(xy 203.279977 -232.344972) (xy 203.249953 -232.389009) (xy 203.213701 -232.42808) (xy 203.17203 -232.461311)
			(xy 203.125872 -232.48796) (xy 203.076258 -232.507432) (xy 203.024296 -232.519292) (xy 202.971146 -232.523276)
			(xy 202.917996 -232.519292) (xy 202.866034 -232.507432) (xy 202.81642 -232.48796) (xy 202.770262 -232.461311)
			(xy 202.728591 -232.42808) (xy 202.692339 -232.389009) (xy 202.662315 -232.344972) (xy 202.639189 -232.296951)
			(xy 202.623479 -232.246021) (xy 202.615536 -232.193317) (xy 188.239156 -232.193317) (xy 188.231213 -232.246021)
			(xy 188.215503 -232.296951) (xy 188.192377 -232.344972) (xy 188.162353 -232.389009) (xy 188.126101 -232.42808)
			(xy 188.08443 -232.461311) (xy 188.038272 -232.48796) (xy 187.988658 -232.507432) (xy 187.936696 -232.519292)
			(xy 187.883546 -232.523276) (xy 187.830396 -232.519292) (xy 187.778434 -232.507432) (xy 187.72882 -232.48796)
			(xy 187.682662 -232.461311) (xy 187.640991 -232.42808) (xy 187.604739 -232.389009) (xy 187.574715 -232.344972)
			(xy 187.551589 -232.296951) (xy 187.535879 -232.246021) (xy 187.527936 -232.193317) (xy 173.151556 -232.193317)
			(xy 173.143613 -232.246021) (xy 173.127903 -232.296951) (xy 173.104777 -232.344972) (xy 173.074753 -232.389009)
			(xy 173.038501 -232.42808) (xy 172.99683 -232.461311) (xy 172.950672 -232.48796) (xy 172.901058 -232.507432)
			(xy 172.849096 -232.519292) (xy 172.795946 -232.523276) (xy 172.742796 -232.519292) (xy 172.690834 -232.507432)
			(xy 172.64122 -232.48796) (xy 172.595062 -232.461311) (xy 172.553391 -232.42808) (xy 172.517139 -232.389009)
			(xy 172.487115 -232.344972) (xy 172.463989 -232.296951) (xy 172.448279 -232.246021) (xy 172.440336 -232.193317)
			(xy 159.11576 -232.193317) (xy 159.11576 -233.043455) (xy 176.540404 -233.043455) (xy 176.540404 -232.990157)
			(xy 176.548347 -232.937453) (xy 176.564057 -232.886523) (xy 176.587183 -232.838502) (xy 176.617207 -232.794465)
			(xy 176.653459 -232.755394) (xy 176.69513 -232.722163) (xy 176.741288 -232.695514) (xy 176.790902 -232.676042)
			(xy 176.842864 -232.664182) (xy 176.896014 -232.660199) (xy 176.949164 -232.664182) (xy 177.001126 -232.676042)
			(xy 177.05074 -232.695514) (xy 177.096898 -232.722163) (xy 177.138569 -232.755394) (xy 177.174821 -232.794465)
			(xy 177.204845 -232.838502) (xy 177.227971 -232.886523) (xy 177.243681 -232.937453) (xy 177.251624 -232.990157)
			(xy 177.252122 -233.016806) (xy 177.251624 -233.043455) (xy 191.628004 -233.043455) (xy 191.628004 -232.990157)
			(xy 191.635947 -232.937453) (xy 191.651657 -232.886523) (xy 191.674783 -232.838502) (xy 191.704807 -232.794465)
			(xy 191.741059 -232.755394) (xy 191.78273 -232.722163) (xy 191.828888 -232.695514) (xy 191.878502 -232.676042)
			(xy 191.930464 -232.664182) (xy 191.983614 -232.660199) (xy 192.036764 -232.664182) (xy 192.088726 -232.676042)
			(xy 192.13834 -232.695514) (xy 192.184498 -232.722163) (xy 192.226169 -232.755394) (xy 192.262421 -232.794465)
			(xy 192.292445 -232.838502) (xy 192.315571 -232.886523) (xy 192.331281 -232.937453) (xy 192.339224 -232.990157)
			(xy 192.339722 -233.016806) (xy 192.339224 -233.043455) (xy 206.715604 -233.043455) (xy 206.715604 -232.990157)
			(xy 206.723547 -232.937453) (xy 206.739257 -232.886523) (xy 206.762383 -232.838502) (xy 206.792407 -232.794465)
			(xy 206.828659 -232.755394) (xy 206.87033 -232.722163) (xy 206.916488 -232.695514) (xy 206.966102 -232.676042)
			(xy 207.018064 -232.664182) (xy 207.071214 -232.660199) (xy 207.124364 -232.664182) (xy 207.176326 -232.676042)
			(xy 207.22594 -232.695514) (xy 207.272098 -232.722163) (xy 207.313769 -232.755394) (xy 207.350021 -232.794465)
			(xy 207.380045 -232.838502) (xy 207.403171 -232.886523) (xy 207.418881 -232.937453) (xy 207.426824 -232.990157)
			(xy 207.427322 -233.016806) (xy 207.426824 -233.043455) (xy 207.418881 -233.096159) (xy 207.403171 -233.147089)
			(xy 207.380045 -233.19511) (xy 207.350021 -233.239147) (xy 207.313769 -233.278218) (xy 207.272098 -233.311449)
			(xy 207.22594 -233.338098) (xy 207.176326 -233.35757) (xy 207.124364 -233.36943) (xy 207.071214 -233.373414)
			(xy 207.018064 -233.36943) (xy 206.966102 -233.35757) (xy 206.916488 -233.338098) (xy 206.87033 -233.311449)
			(xy 206.828659 -233.278218) (xy 206.792407 -233.239147) (xy 206.762383 -233.19511) (xy 206.739257 -233.147089)
			(xy 206.723547 -233.096159) (xy 206.715604 -233.043455) (xy 192.339224 -233.043455) (xy 192.331281 -233.096159)
			(xy 192.315571 -233.147089) (xy 192.292445 -233.19511) (xy 192.262421 -233.239147) (xy 192.226169 -233.278218)
			(xy 192.184498 -233.311449) (xy 192.13834 -233.338098) (xy 192.088726 -233.35757) (xy 192.036764 -233.36943)
			(xy 191.983614 -233.373414) (xy 191.930464 -233.36943) (xy 191.878502 -233.35757) (xy 191.828888 -233.338098)
			(xy 191.78273 -233.311449) (xy 191.741059 -233.278218) (xy 191.704807 -233.239147) (xy 191.674783 -233.19511)
			(xy 191.651657 -233.147089) (xy 191.635947 -233.096159) (xy 191.628004 -233.043455) (xy 177.251624 -233.043455)
			(xy 177.243681 -233.096159) (xy 177.227971 -233.147089) (xy 177.204845 -233.19511) (xy 177.174821 -233.239147)
			(xy 177.138569 -233.278218) (xy 177.096898 -233.311449) (xy 177.05074 -233.338098) (xy 177.001126 -233.35757)
			(xy 176.949164 -233.36943) (xy 176.896014 -233.373414) (xy 176.842864 -233.36943) (xy 176.790902 -233.35757)
			(xy 176.741288 -233.338098) (xy 176.69513 -233.311449) (xy 176.653459 -233.278218) (xy 176.617207 -233.239147)
			(xy 176.587183 -233.19511) (xy 176.564057 -233.147089) (xy 176.548347 -233.096159) (xy 176.540404 -233.043455)
			(xy 159.11576 -233.043455) (xy 159.11576 -233.893339) (xy 172.440336 -233.893339) (xy 172.440336 -233.840041)
			(xy 172.448279 -233.787337) (xy 172.463989 -233.736407) (xy 172.487115 -233.688386) (xy 172.517139 -233.644349)
			(xy 172.553391 -233.605278) (xy 172.595062 -233.572047) (xy 172.64122 -233.545398) (xy 172.690834 -233.525926)
			(xy 172.742796 -233.514066) (xy 172.795946 -233.510083) (xy 172.849096 -233.514066) (xy 172.901058 -233.525926)
			(xy 172.950672 -233.545398) (xy 172.99683 -233.572047) (xy 173.038501 -233.605278) (xy 173.074753 -233.644349)
			(xy 173.104777 -233.688386) (xy 173.127903 -233.736407) (xy 173.143613 -233.787337) (xy 173.151556 -233.840041)
			(xy 173.152054 -233.86669) (xy 173.151556 -233.893339) (xy 187.527936 -233.893339) (xy 187.527936 -233.840041)
			(xy 187.535879 -233.787337) (xy 187.551589 -233.736407) (xy 187.574715 -233.688386) (xy 187.604739 -233.644349)
			(xy 187.640991 -233.605278) (xy 187.682662 -233.572047) (xy 187.72882 -233.545398) (xy 187.778434 -233.525926)
			(xy 187.830396 -233.514066) (xy 187.883546 -233.510083) (xy 187.936696 -233.514066) (xy 187.988658 -233.525926)
			(xy 188.038272 -233.545398) (xy 188.08443 -233.572047) (xy 188.126101 -233.605278) (xy 188.162353 -233.644349)
			(xy 188.192377 -233.688386) (xy 188.215503 -233.736407) (xy 188.231213 -233.787337) (xy 188.239156 -233.840041)
			(xy 188.239654 -233.86669) (xy 188.239156 -233.893339) (xy 202.615536 -233.893339) (xy 202.615536 -233.840041)
			(xy 202.623479 -233.787337) (xy 202.639189 -233.736407) (xy 202.662315 -233.688386) (xy 202.692339 -233.644349)
			(xy 202.728591 -233.605278) (xy 202.770262 -233.572047) (xy 202.81642 -233.545398) (xy 202.866034 -233.525926)
			(xy 202.917996 -233.514066) (xy 202.971146 -233.510083) (xy 203.024296 -233.514066) (xy 203.076258 -233.525926)
			(xy 203.125872 -233.545398) (xy 203.17203 -233.572047) (xy 203.213701 -233.605278) (xy 203.249953 -233.644349)
			(xy 203.279977 -233.688386) (xy 203.303103 -233.736407) (xy 203.318813 -233.787337) (xy 203.326756 -233.840041)
			(xy 203.327254 -233.86669) (xy 203.326756 -233.893339) (xy 203.318813 -233.946043) (xy 203.303103 -233.996973)
			(xy 203.279977 -234.044994) (xy 203.249953 -234.089031) (xy 203.213701 -234.128102) (xy 203.17203 -234.161333)
			(xy 203.125872 -234.187982) (xy 203.076258 -234.207454) (xy 203.024296 -234.219314) (xy 202.971146 -234.223298)
			(xy 202.917996 -234.219314) (xy 202.866034 -234.207454) (xy 202.81642 -234.187982) (xy 202.770262 -234.161333)
			(xy 202.728591 -234.128102) (xy 202.692339 -234.089031) (xy 202.662315 -234.044994) (xy 202.639189 -233.996973)
			(xy 202.623479 -233.946043) (xy 202.615536 -233.893339) (xy 188.239156 -233.893339) (xy 188.231213 -233.946043)
			(xy 188.215503 -233.996973) (xy 188.192377 -234.044994) (xy 188.162353 -234.089031) (xy 188.126101 -234.128102)
			(xy 188.08443 -234.161333) (xy 188.038272 -234.187982) (xy 187.988658 -234.207454) (xy 187.936696 -234.219314)
			(xy 187.883546 -234.223298) (xy 187.830396 -234.219314) (xy 187.778434 -234.207454) (xy 187.72882 -234.187982)
			(xy 187.682662 -234.161333) (xy 187.640991 -234.128102) (xy 187.604739 -234.089031) (xy 187.574715 -234.044994)
			(xy 187.551589 -233.996973) (xy 187.535879 -233.946043) (xy 187.527936 -233.893339) (xy 173.151556 -233.893339)
			(xy 173.143613 -233.946043) (xy 173.127903 -233.996973) (xy 173.104777 -234.044994) (xy 173.074753 -234.089031)
			(xy 173.038501 -234.128102) (xy 172.99683 -234.161333) (xy 172.950672 -234.187982) (xy 172.901058 -234.207454)
			(xy 172.849096 -234.219314) (xy 172.795946 -234.223298) (xy 172.742796 -234.219314) (xy 172.690834 -234.207454)
			(xy 172.64122 -234.187982) (xy 172.595062 -234.161333) (xy 172.553391 -234.128102) (xy 172.517139 -234.089031)
			(xy 172.487115 -234.044994) (xy 172.463989 -233.996973) (xy 172.448279 -233.946043) (xy 172.440336 -233.893339)
			(xy 159.11576 -233.893339) (xy 159.11576 -234.743223) (xy 176.540404 -234.743223) (xy 176.540404 -234.689925)
			(xy 176.548347 -234.637221) (xy 176.564057 -234.586291) (xy 176.587183 -234.53827) (xy 176.617207 -234.494233)
			(xy 176.653459 -234.455162) (xy 176.69513 -234.421931) (xy 176.741288 -234.395282) (xy 176.790902 -234.37581)
			(xy 176.842864 -234.36395) (xy 176.896014 -234.359967) (xy 176.949164 -234.36395) (xy 177.001126 -234.37581)
			(xy 177.05074 -234.395282) (xy 177.096898 -234.421931) (xy 177.138569 -234.455162) (xy 177.174821 -234.494233)
			(xy 177.204845 -234.53827) (xy 177.227971 -234.586291) (xy 177.243681 -234.637221) (xy 177.251624 -234.689925)
			(xy 177.252122 -234.716574) (xy 177.251624 -234.743223) (xy 191.628004 -234.743223) (xy 191.628004 -234.689925)
			(xy 191.635947 -234.637221) (xy 191.651657 -234.586291) (xy 191.674783 -234.53827) (xy 191.704807 -234.494233)
			(xy 191.741059 -234.455162) (xy 191.78273 -234.421931) (xy 191.828888 -234.395282) (xy 191.878502 -234.37581)
			(xy 191.930464 -234.36395) (xy 191.983614 -234.359967) (xy 192.036764 -234.36395) (xy 192.088726 -234.37581)
			(xy 192.13834 -234.395282) (xy 192.184498 -234.421931) (xy 192.226169 -234.455162) (xy 192.262421 -234.494233)
			(xy 192.292445 -234.53827) (xy 192.315571 -234.586291) (xy 192.331281 -234.637221) (xy 192.339224 -234.689925)
			(xy 192.339722 -234.716574) (xy 192.339224 -234.743223) (xy 206.715604 -234.743223) (xy 206.715604 -234.689925)
			(xy 206.723547 -234.637221) (xy 206.739257 -234.586291) (xy 206.762383 -234.53827) (xy 206.792407 -234.494233)
			(xy 206.828659 -234.455162) (xy 206.87033 -234.421931) (xy 206.916488 -234.395282) (xy 206.966102 -234.37581)
			(xy 207.018064 -234.36395) (xy 207.071214 -234.359967) (xy 207.124364 -234.36395) (xy 207.176326 -234.37581)
			(xy 207.22594 -234.395282) (xy 207.272098 -234.421931) (xy 207.313769 -234.455162) (xy 207.350021 -234.494233)
			(xy 207.380045 -234.53827) (xy 207.403171 -234.586291) (xy 207.418881 -234.637221) (xy 207.426824 -234.689925)
			(xy 207.427322 -234.716574) (xy 207.426824 -234.743223) (xy 207.418881 -234.795927) (xy 207.403171 -234.846857)
			(xy 207.380045 -234.894878) (xy 207.350021 -234.938915) (xy 207.313769 -234.977986) (xy 207.272098 -235.011217)
			(xy 207.22594 -235.037866) (xy 207.176326 -235.057338) (xy 207.124364 -235.069198) (xy 207.071214 -235.073182)
			(xy 207.018064 -235.069198) (xy 206.966102 -235.057338) (xy 206.916488 -235.037866) (xy 206.87033 -235.011217)
			(xy 206.828659 -234.977986) (xy 206.792407 -234.938915) (xy 206.762383 -234.894878) (xy 206.739257 -234.846857)
			(xy 206.723547 -234.795927) (xy 206.715604 -234.743223) (xy 192.339224 -234.743223) (xy 192.331281 -234.795927)
			(xy 192.315571 -234.846857) (xy 192.292445 -234.894878) (xy 192.262421 -234.938915) (xy 192.226169 -234.977986)
			(xy 192.184498 -235.011217) (xy 192.13834 -235.037866) (xy 192.088726 -235.057338) (xy 192.036764 -235.069198)
			(xy 191.983614 -235.073182) (xy 191.930464 -235.069198) (xy 191.878502 -235.057338) (xy 191.828888 -235.037866)
			(xy 191.78273 -235.011217) (xy 191.741059 -234.977986) (xy 191.704807 -234.938915) (xy 191.674783 -234.894878)
			(xy 191.651657 -234.846857) (xy 191.635947 -234.795927) (xy 191.628004 -234.743223) (xy 177.251624 -234.743223)
			(xy 177.243681 -234.795927) (xy 177.227971 -234.846857) (xy 177.204845 -234.894878) (xy 177.174821 -234.938915)
			(xy 177.138569 -234.977986) (xy 177.096898 -235.011217) (xy 177.05074 -235.037866) (xy 177.001126 -235.057338)
			(xy 176.949164 -235.069198) (xy 176.896014 -235.073182) (xy 176.842864 -235.069198) (xy 176.790902 -235.057338)
			(xy 176.741288 -235.037866) (xy 176.69513 -235.011217) (xy 176.653459 -234.977986) (xy 176.617207 -234.938915)
			(xy 176.587183 -234.894878) (xy 176.564057 -234.846857) (xy 176.548347 -234.795927) (xy 176.540404 -234.743223)
			(xy 159.11576 -234.743223) (xy 159.11576 -235.593361) (xy 172.440336 -235.593361) (xy 172.440336 -235.540063)
			(xy 172.448279 -235.487359) (xy 172.463989 -235.436429) (xy 172.487115 -235.388408) (xy 172.517139 -235.344371)
			(xy 172.553391 -235.3053) (xy 172.595062 -235.272069) (xy 172.64122 -235.24542) (xy 172.690834 -235.225948)
			(xy 172.742796 -235.214088) (xy 172.795946 -235.210105) (xy 172.849096 -235.214088) (xy 172.901058 -235.225948)
			(xy 172.950672 -235.24542) (xy 172.99683 -235.272069) (xy 173.038501 -235.3053) (xy 173.074753 -235.344371)
			(xy 173.104777 -235.388408) (xy 173.127903 -235.436429) (xy 173.143613 -235.487359) (xy 173.151556 -235.540063)
			(xy 173.152054 -235.566712) (xy 173.151556 -235.593361) (xy 187.527936 -235.593361) (xy 187.527936 -235.540063)
			(xy 187.535879 -235.487359) (xy 187.551589 -235.436429) (xy 187.574715 -235.388408) (xy 187.604739 -235.344371)
			(xy 187.640991 -235.3053) (xy 187.682662 -235.272069) (xy 187.72882 -235.24542) (xy 187.778434 -235.225948)
			(xy 187.830396 -235.214088) (xy 187.883546 -235.210105) (xy 187.936696 -235.214088) (xy 187.988658 -235.225948)
			(xy 188.038272 -235.24542) (xy 188.08443 -235.272069) (xy 188.126101 -235.3053) (xy 188.162353 -235.344371)
			(xy 188.192377 -235.388408) (xy 188.215503 -235.436429) (xy 188.231213 -235.487359) (xy 188.239156 -235.540063)
			(xy 188.239654 -235.566712) (xy 188.239156 -235.593361) (xy 202.615536 -235.593361) (xy 202.615536 -235.540063)
			(xy 202.623479 -235.487359) (xy 202.639189 -235.436429) (xy 202.662315 -235.388408) (xy 202.692339 -235.344371)
			(xy 202.728591 -235.3053) (xy 202.770262 -235.272069) (xy 202.81642 -235.24542) (xy 202.866034 -235.225948)
			(xy 202.917996 -235.214088) (xy 202.971146 -235.210105) (xy 203.024296 -235.214088) (xy 203.076258 -235.225948)
			(xy 203.125872 -235.24542) (xy 203.17203 -235.272069) (xy 203.213701 -235.3053) (xy 203.249953 -235.344371)
			(xy 203.279977 -235.388408) (xy 203.303103 -235.436429) (xy 203.318813 -235.487359) (xy 203.326756 -235.540063)
			(xy 203.327254 -235.566712) (xy 203.326756 -235.593361) (xy 203.318813 -235.646065) (xy 203.303103 -235.696995)
			(xy 203.279977 -235.745016) (xy 203.249953 -235.789053) (xy 203.213701 -235.828124) (xy 203.17203 -235.861355)
			(xy 203.125872 -235.888004) (xy 203.076258 -235.907476) (xy 203.024296 -235.919336) (xy 202.971146 -235.92332)
			(xy 202.917996 -235.919336) (xy 202.866034 -235.907476) (xy 202.81642 -235.888004) (xy 202.770262 -235.861355)
			(xy 202.728591 -235.828124) (xy 202.692339 -235.789053) (xy 202.662315 -235.745016) (xy 202.639189 -235.696995)
			(xy 202.623479 -235.646065) (xy 202.615536 -235.593361) (xy 188.239156 -235.593361) (xy 188.231213 -235.646065)
			(xy 188.215503 -235.696995) (xy 188.192377 -235.745016) (xy 188.162353 -235.789053) (xy 188.126101 -235.828124)
			(xy 188.08443 -235.861355) (xy 188.038272 -235.888004) (xy 187.988658 -235.907476) (xy 187.936696 -235.919336)
			(xy 187.883546 -235.92332) (xy 187.830396 -235.919336) (xy 187.778434 -235.907476) (xy 187.72882 -235.888004)
			(xy 187.682662 -235.861355) (xy 187.640991 -235.828124) (xy 187.604739 -235.789053) (xy 187.574715 -235.745016)
			(xy 187.551589 -235.696995) (xy 187.535879 -235.646065) (xy 187.527936 -235.593361) (xy 173.151556 -235.593361)
			(xy 173.143613 -235.646065) (xy 173.127903 -235.696995) (xy 173.104777 -235.745016) (xy 173.074753 -235.789053)
			(xy 173.038501 -235.828124) (xy 172.99683 -235.861355) (xy 172.950672 -235.888004) (xy 172.901058 -235.907476)
			(xy 172.849096 -235.919336) (xy 172.795946 -235.92332) (xy 172.742796 -235.919336) (xy 172.690834 -235.907476)
			(xy 172.64122 -235.888004) (xy 172.595062 -235.861355) (xy 172.553391 -235.828124) (xy 172.517139 -235.789053)
			(xy 172.487115 -235.745016) (xy 172.463989 -235.696995) (xy 172.448279 -235.646065) (xy 172.440336 -235.593361)
			(xy 159.11576 -235.593361) (xy 159.11576 -236.443245) (xy 176.540404 -236.443245) (xy 176.540404 -236.389947)
			(xy 176.548347 -236.337243) (xy 176.564057 -236.286313) (xy 176.587183 -236.238292) (xy 176.617207 -236.194255)
			(xy 176.653459 -236.155184) (xy 176.69513 -236.121953) (xy 176.741288 -236.095304) (xy 176.790902 -236.075832)
			(xy 176.842864 -236.063972) (xy 176.896014 -236.059989) (xy 176.949164 -236.063972) (xy 177.001126 -236.075832)
			(xy 177.05074 -236.095304) (xy 177.096898 -236.121953) (xy 177.138569 -236.155184) (xy 177.174821 -236.194255)
			(xy 177.204845 -236.238292) (xy 177.227971 -236.286313) (xy 177.243681 -236.337243) (xy 177.251624 -236.389947)
			(xy 177.252122 -236.416596) (xy 177.251624 -236.443245) (xy 191.628004 -236.443245) (xy 191.628004 -236.389947)
			(xy 191.635947 -236.337243) (xy 191.651657 -236.286313) (xy 191.674783 -236.238292) (xy 191.704807 -236.194255)
			(xy 191.741059 -236.155184) (xy 191.78273 -236.121953) (xy 191.828888 -236.095304) (xy 191.878502 -236.075832)
			(xy 191.930464 -236.063972) (xy 191.983614 -236.059989) (xy 192.036764 -236.063972) (xy 192.088726 -236.075832)
			(xy 192.13834 -236.095304) (xy 192.184498 -236.121953) (xy 192.226169 -236.155184) (xy 192.262421 -236.194255)
			(xy 192.292445 -236.238292) (xy 192.315571 -236.286313) (xy 192.331281 -236.337243) (xy 192.339224 -236.389947)
			(xy 192.339722 -236.416596) (xy 192.339224 -236.443245) (xy 206.715604 -236.443245) (xy 206.715604 -236.389947)
			(xy 206.723547 -236.337243) (xy 206.739257 -236.286313) (xy 206.762383 -236.238292) (xy 206.792407 -236.194255)
			(xy 206.828659 -236.155184) (xy 206.87033 -236.121953) (xy 206.916488 -236.095304) (xy 206.966102 -236.075832)
			(xy 207.018064 -236.063972) (xy 207.071214 -236.059989) (xy 207.124364 -236.063972) (xy 207.176326 -236.075832)
			(xy 207.22594 -236.095304) (xy 207.272098 -236.121953) (xy 207.313769 -236.155184) (xy 207.350021 -236.194255)
			(xy 207.380045 -236.238292) (xy 207.403171 -236.286313) (xy 207.418881 -236.337243) (xy 207.426824 -236.389947)
			(xy 207.427322 -236.416596) (xy 207.426824 -236.443245) (xy 207.418881 -236.495949) (xy 207.403171 -236.546879)
			(xy 207.380045 -236.5949) (xy 207.350021 -236.638937) (xy 207.313769 -236.678008) (xy 207.272098 -236.711239)
			(xy 207.22594 -236.737888) (xy 207.176326 -236.75736) (xy 207.124364 -236.76922) (xy 207.071214 -236.773204)
			(xy 207.018064 -236.76922) (xy 206.966102 -236.75736) (xy 206.916488 -236.737888) (xy 206.87033 -236.711239)
			(xy 206.828659 -236.678008) (xy 206.792407 -236.638937) (xy 206.762383 -236.5949) (xy 206.739257 -236.546879)
			(xy 206.723547 -236.495949) (xy 206.715604 -236.443245) (xy 192.339224 -236.443245) (xy 192.331281 -236.495949)
			(xy 192.315571 -236.546879) (xy 192.292445 -236.5949) (xy 192.262421 -236.638937) (xy 192.226169 -236.678008)
			(xy 192.184498 -236.711239) (xy 192.13834 -236.737888) (xy 192.088726 -236.75736) (xy 192.036764 -236.76922)
			(xy 191.983614 -236.773204) (xy 191.930464 -236.76922) (xy 191.878502 -236.75736) (xy 191.828888 -236.737888)
			(xy 191.78273 -236.711239) (xy 191.741059 -236.678008) (xy 191.704807 -236.638937) (xy 191.674783 -236.5949)
			(xy 191.651657 -236.546879) (xy 191.635947 -236.495949) (xy 191.628004 -236.443245) (xy 177.251624 -236.443245)
			(xy 177.243681 -236.495949) (xy 177.227971 -236.546879) (xy 177.204845 -236.5949) (xy 177.174821 -236.638937)
			(xy 177.138569 -236.678008) (xy 177.096898 -236.711239) (xy 177.05074 -236.737888) (xy 177.001126 -236.75736)
			(xy 176.949164 -236.76922) (xy 176.896014 -236.773204) (xy 176.842864 -236.76922) (xy 176.790902 -236.75736)
			(xy 176.741288 -236.737888) (xy 176.69513 -236.711239) (xy 176.653459 -236.678008) (xy 176.617207 -236.638937)
			(xy 176.587183 -236.5949) (xy 176.564057 -236.546879) (xy 176.548347 -236.495949) (xy 176.540404 -236.443245)
			(xy 159.11576 -236.443245) (xy 159.11576 -237.293383) (xy 172.440336 -237.293383) (xy 172.440336 -237.240085)
			(xy 172.448279 -237.187381) (xy 172.463989 -237.136451) (xy 172.487115 -237.08843) (xy 172.517139 -237.044393)
			(xy 172.553391 -237.005322) (xy 172.595062 -236.972091) (xy 172.64122 -236.945442) (xy 172.690834 -236.92597)
			(xy 172.742796 -236.91411) (xy 172.795946 -236.910127) (xy 172.849096 -236.91411) (xy 172.901058 -236.92597)
			(xy 172.950672 -236.945442) (xy 172.99683 -236.972091) (xy 173.038501 -237.005322) (xy 173.074753 -237.044393)
			(xy 173.104777 -237.08843) (xy 173.127903 -237.136451) (xy 173.143613 -237.187381) (xy 173.151556 -237.240085)
			(xy 173.152054 -237.266734) (xy 173.151556 -237.293383) (xy 176.540404 -237.293383) (xy 176.540404 -237.240085)
			(xy 176.548347 -237.187381) (xy 176.564057 -237.136451) (xy 176.587183 -237.08843) (xy 176.617207 -237.044393)
			(xy 176.653459 -237.005322) (xy 176.69513 -236.972091) (xy 176.741288 -236.945442) (xy 176.790902 -236.92597)
			(xy 176.842864 -236.91411) (xy 176.896014 -236.910127) (xy 176.949164 -236.91411) (xy 177.001126 -236.92597)
			(xy 177.05074 -236.945442) (xy 177.096898 -236.972091) (xy 177.138569 -237.005322) (xy 177.174821 -237.044393)
			(xy 177.204845 -237.08843) (xy 177.227971 -237.136451) (xy 177.243681 -237.187381) (xy 177.251624 -237.240085)
			(xy 177.252122 -237.266734) (xy 177.251624 -237.293383) (xy 187.527936 -237.293383) (xy 187.527936 -237.240085)
			(xy 187.535879 -237.187381) (xy 187.551589 -237.136451) (xy 187.574715 -237.08843) (xy 187.604739 -237.044393)
			(xy 187.640991 -237.005322) (xy 187.682662 -236.972091) (xy 187.72882 -236.945442) (xy 187.778434 -236.92597)
			(xy 187.830396 -236.91411) (xy 187.883546 -236.910127) (xy 187.936696 -236.91411) (xy 187.988658 -236.92597)
			(xy 188.038272 -236.945442) (xy 188.08443 -236.972091) (xy 188.126101 -237.005322) (xy 188.162353 -237.044393)
			(xy 188.192377 -237.08843) (xy 188.215503 -237.136451) (xy 188.231213 -237.187381) (xy 188.239156 -237.240085)
			(xy 188.239654 -237.266734) (xy 188.239156 -237.293383) (xy 191.628004 -237.293383) (xy 191.628004 -237.240085)
			(xy 191.635947 -237.187381) (xy 191.651657 -237.136451) (xy 191.674783 -237.08843) (xy 191.704807 -237.044393)
			(xy 191.741059 -237.005322) (xy 191.78273 -236.972091) (xy 191.828888 -236.945442) (xy 191.878502 -236.92597)
			(xy 191.930464 -236.91411) (xy 191.983614 -236.910127) (xy 192.036764 -236.91411) (xy 192.088726 -236.92597)
			(xy 192.13834 -236.945442) (xy 192.184498 -236.972091) (xy 192.226169 -237.005322) (xy 192.262421 -237.044393)
			(xy 192.292445 -237.08843) (xy 192.315571 -237.136451) (xy 192.331281 -237.187381) (xy 192.339224 -237.240085)
			(xy 192.339722 -237.266734) (xy 192.339224 -237.293383) (xy 202.615536 -237.293383) (xy 202.615536 -237.240085)
			(xy 202.623479 -237.187381) (xy 202.639189 -237.136451) (xy 202.662315 -237.08843) (xy 202.692339 -237.044393)
			(xy 202.728591 -237.005322) (xy 202.770262 -236.972091) (xy 202.81642 -236.945442) (xy 202.866034 -236.92597)
			(xy 202.917996 -236.91411) (xy 202.971146 -236.910127) (xy 203.024296 -236.91411) (xy 203.076258 -236.92597)
			(xy 203.125872 -236.945442) (xy 203.17203 -236.972091) (xy 203.213701 -237.005322) (xy 203.249953 -237.044393)
			(xy 203.279977 -237.08843) (xy 203.303103 -237.136451) (xy 203.318813 -237.187381) (xy 203.326756 -237.240085)
			(xy 203.327254 -237.266734) (xy 203.326756 -237.293383) (xy 206.715604 -237.293383) (xy 206.715604 -237.240085)
			(xy 206.723547 -237.187381) (xy 206.739257 -237.136451) (xy 206.762383 -237.08843) (xy 206.792407 -237.044393)
			(xy 206.828659 -237.005322) (xy 206.87033 -236.972091) (xy 206.916488 -236.945442) (xy 206.966102 -236.92597)
			(xy 207.018064 -236.91411) (xy 207.071214 -236.910127) (xy 207.124364 -236.91411) (xy 207.176326 -236.92597)
			(xy 207.22594 -236.945442) (xy 207.272098 -236.972091) (xy 207.313769 -237.005322) (xy 207.350021 -237.044393)
			(xy 207.380045 -237.08843) (xy 207.403171 -237.136451) (xy 207.418881 -237.187381) (xy 207.426824 -237.240085)
			(xy 207.427322 -237.266734) (xy 207.426824 -237.293383) (xy 207.418881 -237.346087) (xy 207.403171 -237.397017)
			(xy 207.380045 -237.445038) (xy 207.350021 -237.489075) (xy 207.313769 -237.528146) (xy 207.272098 -237.561377)
			(xy 207.22594 -237.588026) (xy 207.176326 -237.607498) (xy 207.124364 -237.619358) (xy 207.071214 -237.623342)
			(xy 207.018064 -237.619358) (xy 206.966102 -237.607498) (xy 206.916488 -237.588026) (xy 206.87033 -237.561377)
			(xy 206.828659 -237.528146) (xy 206.792407 -237.489075) (xy 206.762383 -237.445038) (xy 206.739257 -237.397017)
			(xy 206.723547 -237.346087) (xy 206.715604 -237.293383) (xy 203.326756 -237.293383) (xy 203.318813 -237.346087)
			(xy 203.303103 -237.397017) (xy 203.279977 -237.445038) (xy 203.249953 -237.489075) (xy 203.213701 -237.528146)
			(xy 203.17203 -237.561377) (xy 203.125872 -237.588026) (xy 203.076258 -237.607498) (xy 203.024296 -237.619358)
			(xy 202.971146 -237.623342) (xy 202.917996 -237.619358) (xy 202.866034 -237.607498) (xy 202.81642 -237.588026)
			(xy 202.770262 -237.561377) (xy 202.728591 -237.528146) (xy 202.692339 -237.489075) (xy 202.662315 -237.445038)
			(xy 202.639189 -237.397017) (xy 202.623479 -237.346087) (xy 202.615536 -237.293383) (xy 192.339224 -237.293383)
			(xy 192.331281 -237.346087) (xy 192.315571 -237.397017) (xy 192.292445 -237.445038) (xy 192.262421 -237.489075)
			(xy 192.226169 -237.528146) (xy 192.184498 -237.561377) (xy 192.13834 -237.588026) (xy 192.088726 -237.607498)
			(xy 192.036764 -237.619358) (xy 191.983614 -237.623342) (xy 191.930464 -237.619358) (xy 191.878502 -237.607498)
			(xy 191.828888 -237.588026) (xy 191.78273 -237.561377) (xy 191.741059 -237.528146) (xy 191.704807 -237.489075)
			(xy 191.674783 -237.445038) (xy 191.651657 -237.397017) (xy 191.635947 -237.346087) (xy 191.628004 -237.293383)
			(xy 188.239156 -237.293383) (xy 188.231213 -237.346087) (xy 188.215503 -237.397017) (xy 188.192377 -237.445038)
			(xy 188.162353 -237.489075) (xy 188.126101 -237.528146) (xy 188.08443 -237.561377) (xy 188.038272 -237.588026)
			(xy 187.988658 -237.607498) (xy 187.936696 -237.619358) (xy 187.883546 -237.623342) (xy 187.830396 -237.619358)
			(xy 187.778434 -237.607498) (xy 187.72882 -237.588026) (xy 187.682662 -237.561377) (xy 187.640991 -237.528146)
			(xy 187.604739 -237.489075) (xy 187.574715 -237.445038) (xy 187.551589 -237.397017) (xy 187.535879 -237.346087)
			(xy 187.527936 -237.293383) (xy 177.251624 -237.293383) (xy 177.243681 -237.346087) (xy 177.227971 -237.397017)
			(xy 177.204845 -237.445038) (xy 177.174821 -237.489075) (xy 177.138569 -237.528146) (xy 177.096898 -237.561377)
			(xy 177.05074 -237.588026) (xy 177.001126 -237.607498) (xy 176.949164 -237.619358) (xy 176.896014 -237.623342)
			(xy 176.842864 -237.619358) (xy 176.790902 -237.607498) (xy 176.741288 -237.588026) (xy 176.69513 -237.561377)
			(xy 176.653459 -237.528146) (xy 176.617207 -237.489075) (xy 176.587183 -237.445038) (xy 176.564057 -237.397017)
			(xy 176.548347 -237.346087) (xy 176.540404 -237.293383) (xy 173.151556 -237.293383) (xy 173.143613 -237.346087)
			(xy 173.127903 -237.397017) (xy 173.104777 -237.445038) (xy 173.074753 -237.489075) (xy 173.038501 -237.528146)
			(xy 172.99683 -237.561377) (xy 172.950672 -237.588026) (xy 172.901058 -237.607498) (xy 172.849096 -237.619358)
			(xy 172.795946 -237.623342) (xy 172.742796 -237.619358) (xy 172.690834 -237.607498) (xy 172.64122 -237.588026)
			(xy 172.595062 -237.561377) (xy 172.553391 -237.528146) (xy 172.517139 -237.489075) (xy 172.487115 -237.445038)
			(xy 172.463989 -237.397017) (xy 172.448279 -237.346087) (xy 172.440336 -237.293383) (xy 159.11576 -237.293383)
			(xy 159.11576 -238.143267) (xy 172.440336 -238.143267) (xy 172.440336 -238.089969) (xy 172.448279 -238.037265)
			(xy 172.463989 -237.986335) (xy 172.487115 -237.938314) (xy 172.517139 -237.894277) (xy 172.553391 -237.855206)
			(xy 172.595062 -237.821975) (xy 172.64122 -237.795326) (xy 172.690834 -237.775854) (xy 172.742796 -237.763994)
			(xy 172.795946 -237.760011) (xy 172.849096 -237.763994) (xy 172.901058 -237.775854) (xy 172.950672 -237.795326)
			(xy 172.99683 -237.821975) (xy 173.038501 -237.855206) (xy 173.074753 -237.894277) (xy 173.104777 -237.938314)
			(xy 173.127903 -237.986335) (xy 173.143613 -238.037265) (xy 173.151556 -238.089969) (xy 173.152054 -238.116618)
			(xy 173.151556 -238.143267) (xy 187.527936 -238.143267) (xy 187.527936 -238.089969) (xy 187.535879 -238.037265)
			(xy 187.551589 -237.986335) (xy 187.574715 -237.938314) (xy 187.604739 -237.894277) (xy 187.640991 -237.855206)
			(xy 187.682662 -237.821975) (xy 187.72882 -237.795326) (xy 187.778434 -237.775854) (xy 187.830396 -237.763994)
			(xy 187.883546 -237.760011) (xy 187.936696 -237.763994) (xy 187.988658 -237.775854) (xy 188.038272 -237.795326)
			(xy 188.08443 -237.821975) (xy 188.126101 -237.855206) (xy 188.162353 -237.894277) (xy 188.192377 -237.938314)
			(xy 188.215503 -237.986335) (xy 188.231213 -238.037265) (xy 188.239156 -238.089969) (xy 188.239654 -238.116618)
			(xy 188.239156 -238.143267) (xy 202.615536 -238.143267) (xy 202.615536 -238.089969) (xy 202.623479 -238.037265)
			(xy 202.639189 -237.986335) (xy 202.662315 -237.938314) (xy 202.692339 -237.894277) (xy 202.728591 -237.855206)
			(xy 202.770262 -237.821975) (xy 202.81642 -237.795326) (xy 202.866034 -237.775854) (xy 202.917996 -237.763994)
			(xy 202.971146 -237.760011) (xy 203.024296 -237.763994) (xy 203.076258 -237.775854) (xy 203.125872 -237.795326)
			(xy 203.17203 -237.821975) (xy 203.213701 -237.855206) (xy 203.249953 -237.894277) (xy 203.279977 -237.938314)
			(xy 203.303103 -237.986335) (xy 203.318813 -238.037265) (xy 203.326756 -238.089969) (xy 203.327254 -238.116618)
			(xy 203.326756 -238.143267) (xy 203.318813 -238.195971) (xy 203.303103 -238.246901) (xy 203.279977 -238.294922)
			(xy 203.249953 -238.338959) (xy 203.213701 -238.37803) (xy 203.17203 -238.411261) (xy 203.125872 -238.43791)
			(xy 203.076258 -238.457382) (xy 203.024296 -238.469242) (xy 202.971146 -238.473226) (xy 202.917996 -238.469242)
			(xy 202.866034 -238.457382) (xy 202.81642 -238.43791) (xy 202.770262 -238.411261) (xy 202.728591 -238.37803)
			(xy 202.692339 -238.338959) (xy 202.662315 -238.294922) (xy 202.639189 -238.246901) (xy 202.623479 -238.195971)
			(xy 202.615536 -238.143267) (xy 188.239156 -238.143267) (xy 188.231213 -238.195971) (xy 188.215503 -238.246901)
			(xy 188.192377 -238.294922) (xy 188.162353 -238.338959) (xy 188.126101 -238.37803) (xy 188.08443 -238.411261)
			(xy 188.038272 -238.43791) (xy 187.988658 -238.457382) (xy 187.936696 -238.469242) (xy 187.883546 -238.473226)
			(xy 187.830396 -238.469242) (xy 187.778434 -238.457382) (xy 187.72882 -238.43791) (xy 187.682662 -238.411261)
			(xy 187.640991 -238.37803) (xy 187.604739 -238.338959) (xy 187.574715 -238.294922) (xy 187.551589 -238.246901)
			(xy 187.535879 -238.195971) (xy 187.527936 -238.143267) (xy 173.151556 -238.143267) (xy 173.143613 -238.195971)
			(xy 173.127903 -238.246901) (xy 173.104777 -238.294922) (xy 173.074753 -238.338959) (xy 173.038501 -238.37803)
			(xy 172.99683 -238.411261) (xy 172.950672 -238.43791) (xy 172.901058 -238.457382) (xy 172.849096 -238.469242)
			(xy 172.795946 -238.473226) (xy 172.742796 -238.469242) (xy 172.690834 -238.457382) (xy 172.64122 -238.43791)
			(xy 172.595062 -238.411261) (xy 172.553391 -238.37803) (xy 172.517139 -238.338959) (xy 172.487115 -238.294922)
			(xy 172.463989 -238.246901) (xy 172.448279 -238.195971) (xy 172.440336 -238.143267) (xy 159.11576 -238.143267)
			(xy 159.11576 -238.993405) (xy 176.540404 -238.993405) (xy 176.540404 -238.940107) (xy 176.548347 -238.887403)
			(xy 176.564057 -238.836473) (xy 176.587183 -238.788452) (xy 176.617207 -238.744415) (xy 176.653459 -238.705344)
			(xy 176.69513 -238.672113) (xy 176.741288 -238.645464) (xy 176.790902 -238.625992) (xy 176.842864 -238.614132)
			(xy 176.896014 -238.610149) (xy 176.949164 -238.614132) (xy 177.001126 -238.625992) (xy 177.05074 -238.645464)
			(xy 177.096898 -238.672113) (xy 177.138569 -238.705344) (xy 177.174821 -238.744415) (xy 177.204845 -238.788452)
			(xy 177.227971 -238.836473) (xy 177.243681 -238.887403) (xy 177.251624 -238.940107) (xy 177.252122 -238.966756)
			(xy 177.251624 -238.993405) (xy 191.628004 -238.993405) (xy 191.628004 -238.940107) (xy 191.635947 -238.887403)
			(xy 191.651657 -238.836473) (xy 191.674783 -238.788452) (xy 191.704807 -238.744415) (xy 191.741059 -238.705344)
			(xy 191.78273 -238.672113) (xy 191.828888 -238.645464) (xy 191.878502 -238.625992) (xy 191.930464 -238.614132)
			(xy 191.983614 -238.610149) (xy 192.036764 -238.614132) (xy 192.088726 -238.625992) (xy 192.13834 -238.645464)
			(xy 192.184498 -238.672113) (xy 192.226169 -238.705344) (xy 192.262421 -238.744415) (xy 192.292445 -238.788452)
			(xy 192.315571 -238.836473) (xy 192.331281 -238.887403) (xy 192.339224 -238.940107) (xy 192.339722 -238.966756)
			(xy 192.339224 -238.993405) (xy 206.715604 -238.993405) (xy 206.715604 -238.940107) (xy 206.723547 -238.887403)
			(xy 206.739257 -238.836473) (xy 206.762383 -238.788452) (xy 206.792407 -238.744415) (xy 206.828659 -238.705344)
			(xy 206.87033 -238.672113) (xy 206.916488 -238.645464) (xy 206.966102 -238.625992) (xy 207.018064 -238.614132)
			(xy 207.071214 -238.610149) (xy 207.124364 -238.614132) (xy 207.176326 -238.625992) (xy 207.22594 -238.645464)
			(xy 207.272098 -238.672113) (xy 207.313769 -238.705344) (xy 207.350021 -238.744415) (xy 207.380045 -238.788452)
			(xy 207.403171 -238.836473) (xy 207.418881 -238.887403) (xy 207.426824 -238.940107) (xy 207.427322 -238.966756)
			(xy 207.426824 -238.993405) (xy 207.418881 -239.046109) (xy 207.403171 -239.097039) (xy 207.380045 -239.14506)
			(xy 207.350021 -239.189097) (xy 207.313769 -239.228168) (xy 207.272098 -239.261399) (xy 207.22594 -239.288048)
			(xy 207.176326 -239.30752) (xy 207.124364 -239.31938) (xy 207.071214 -239.323364) (xy 207.018064 -239.31938)
			(xy 206.966102 -239.30752) (xy 206.916488 -239.288048) (xy 206.87033 -239.261399) (xy 206.828659 -239.228168)
			(xy 206.792407 -239.189097) (xy 206.762383 -239.14506) (xy 206.739257 -239.097039) (xy 206.723547 -239.046109)
			(xy 206.715604 -238.993405) (xy 192.339224 -238.993405) (xy 192.331281 -239.046109) (xy 192.315571 -239.097039)
			(xy 192.292445 -239.14506) (xy 192.262421 -239.189097) (xy 192.226169 -239.228168) (xy 192.184498 -239.261399)
			(xy 192.13834 -239.288048) (xy 192.088726 -239.30752) (xy 192.036764 -239.31938) (xy 191.983614 -239.323364)
			(xy 191.930464 -239.31938) (xy 191.878502 -239.30752) (xy 191.828888 -239.288048) (xy 191.78273 -239.261399)
			(xy 191.741059 -239.228168) (xy 191.704807 -239.189097) (xy 191.674783 -239.14506) (xy 191.651657 -239.097039)
			(xy 191.635947 -239.046109) (xy 191.628004 -238.993405) (xy 177.251624 -238.993405) (xy 177.243681 -239.046109)
			(xy 177.227971 -239.097039) (xy 177.204845 -239.14506) (xy 177.174821 -239.189097) (xy 177.138569 -239.228168)
			(xy 177.096898 -239.261399) (xy 177.05074 -239.288048) (xy 177.001126 -239.30752) (xy 176.949164 -239.31938)
			(xy 176.896014 -239.323364) (xy 176.842864 -239.31938) (xy 176.790902 -239.30752) (xy 176.741288 -239.288048)
			(xy 176.69513 -239.261399) (xy 176.653459 -239.228168) (xy 176.617207 -239.189097) (xy 176.587183 -239.14506)
			(xy 176.564057 -239.097039) (xy 176.548347 -239.046109) (xy 176.540404 -238.993405) (xy 159.11576 -238.993405)
			(xy 159.11576 -239.843289) (xy 172.440336 -239.843289) (xy 172.440336 -239.789991) (xy 172.448279 -239.737287)
			(xy 172.463989 -239.686357) (xy 172.487115 -239.638336) (xy 172.517139 -239.594299) (xy 172.553391 -239.555228)
			(xy 172.595062 -239.521997) (xy 172.64122 -239.495348) (xy 172.690834 -239.475876) (xy 172.742796 -239.464016)
			(xy 172.795946 -239.460033) (xy 172.849096 -239.464016) (xy 172.901058 -239.475876) (xy 172.950672 -239.495348)
			(xy 172.99683 -239.521997) (xy 173.038501 -239.555228) (xy 173.074753 -239.594299) (xy 173.104777 -239.638336)
			(xy 173.127903 -239.686357) (xy 173.143613 -239.737287) (xy 173.151556 -239.789991) (xy 173.152054 -239.81664)
			(xy 173.151556 -239.843289) (xy 187.527936 -239.843289) (xy 187.527936 -239.789991) (xy 187.535879 -239.737287)
			(xy 187.551589 -239.686357) (xy 187.574715 -239.638336) (xy 187.604739 -239.594299) (xy 187.640991 -239.555228)
			(xy 187.682662 -239.521997) (xy 187.72882 -239.495348) (xy 187.778434 -239.475876) (xy 187.830396 -239.464016)
			(xy 187.883546 -239.460033) (xy 187.936696 -239.464016) (xy 187.988658 -239.475876) (xy 188.038272 -239.495348)
			(xy 188.08443 -239.521997) (xy 188.126101 -239.555228) (xy 188.162353 -239.594299) (xy 188.192377 -239.638336)
			(xy 188.215503 -239.686357) (xy 188.231213 -239.737287) (xy 188.239156 -239.789991) (xy 188.239654 -239.81664)
			(xy 188.239156 -239.843289) (xy 202.615536 -239.843289) (xy 202.615536 -239.789991) (xy 202.623479 -239.737287)
			(xy 202.639189 -239.686357) (xy 202.662315 -239.638336) (xy 202.692339 -239.594299) (xy 202.728591 -239.555228)
			(xy 202.770262 -239.521997) (xy 202.81642 -239.495348) (xy 202.866034 -239.475876) (xy 202.917996 -239.464016)
			(xy 202.971146 -239.460033) (xy 203.024296 -239.464016) (xy 203.076258 -239.475876) (xy 203.125872 -239.495348)
			(xy 203.17203 -239.521997) (xy 203.213701 -239.555228) (xy 203.249953 -239.594299) (xy 203.279977 -239.638336)
			(xy 203.303103 -239.686357) (xy 203.318813 -239.737287) (xy 203.326756 -239.789991) (xy 203.327254 -239.81664)
			(xy 203.326756 -239.843289) (xy 203.318813 -239.895993) (xy 203.303103 -239.946923) (xy 203.279977 -239.994944)
			(xy 203.249953 -240.038981) (xy 203.213701 -240.078052) (xy 203.17203 -240.111283) (xy 203.125872 -240.137932)
			(xy 203.076258 -240.157404) (xy 203.024296 -240.169264) (xy 202.971146 -240.173248) (xy 202.917996 -240.169264)
			(xy 202.866034 -240.157404) (xy 202.81642 -240.137932) (xy 202.770262 -240.111283) (xy 202.728591 -240.078052)
			(xy 202.692339 -240.038981) (xy 202.662315 -239.994944) (xy 202.639189 -239.946923) (xy 202.623479 -239.895993)
			(xy 202.615536 -239.843289) (xy 188.239156 -239.843289) (xy 188.231213 -239.895993) (xy 188.215503 -239.946923)
			(xy 188.192377 -239.994944) (xy 188.162353 -240.038981) (xy 188.126101 -240.078052) (xy 188.08443 -240.111283)
			(xy 188.038272 -240.137932) (xy 187.988658 -240.157404) (xy 187.936696 -240.169264) (xy 187.883546 -240.173248)
			(xy 187.830396 -240.169264) (xy 187.778434 -240.157404) (xy 187.72882 -240.137932) (xy 187.682662 -240.111283)
			(xy 187.640991 -240.078052) (xy 187.604739 -240.038981) (xy 187.574715 -239.994944) (xy 187.551589 -239.946923)
			(xy 187.535879 -239.895993) (xy 187.527936 -239.843289) (xy 173.151556 -239.843289) (xy 173.143613 -239.895993)
			(xy 173.127903 -239.946923) (xy 173.104777 -239.994944) (xy 173.074753 -240.038981) (xy 173.038501 -240.078052)
			(xy 172.99683 -240.111283) (xy 172.950672 -240.137932) (xy 172.901058 -240.157404) (xy 172.849096 -240.169264)
			(xy 172.795946 -240.173248) (xy 172.742796 -240.169264) (xy 172.690834 -240.157404) (xy 172.64122 -240.137932)
			(xy 172.595062 -240.111283) (xy 172.553391 -240.078052) (xy 172.517139 -240.038981) (xy 172.487115 -239.994944)
			(xy 172.463989 -239.946923) (xy 172.448279 -239.895993) (xy 172.440336 -239.843289) (xy 159.11576 -239.843289)
			(xy 159.11576 -240.693427) (xy 176.540404 -240.693427) (xy 176.540404 -240.640129) (xy 176.548347 -240.587425)
			(xy 176.564057 -240.536495) (xy 176.587183 -240.488474) (xy 176.617207 -240.444437) (xy 176.653459 -240.405366)
			(xy 176.69513 -240.372135) (xy 176.741288 -240.345486) (xy 176.790902 -240.326014) (xy 176.842864 -240.314154)
			(xy 176.896014 -240.310171) (xy 176.949164 -240.314154) (xy 177.001126 -240.326014) (xy 177.05074 -240.345486)
			(xy 177.096898 -240.372135) (xy 177.138569 -240.405366) (xy 177.174821 -240.444437) (xy 177.204845 -240.488474)
			(xy 177.227971 -240.536495) (xy 177.243681 -240.587425) (xy 177.251624 -240.640129) (xy 177.252122 -240.666778)
			(xy 177.251624 -240.693427) (xy 191.628004 -240.693427) (xy 191.628004 -240.640129) (xy 191.635947 -240.587425)
			(xy 191.651657 -240.536495) (xy 191.674783 -240.488474) (xy 191.704807 -240.444437) (xy 191.741059 -240.405366)
			(xy 191.78273 -240.372135) (xy 191.828888 -240.345486) (xy 191.878502 -240.326014) (xy 191.930464 -240.314154)
			(xy 191.983614 -240.310171) (xy 192.036764 -240.314154) (xy 192.088726 -240.326014) (xy 192.13834 -240.345486)
			(xy 192.184498 -240.372135) (xy 192.226169 -240.405366) (xy 192.262421 -240.444437) (xy 192.292445 -240.488474)
			(xy 192.315571 -240.536495) (xy 192.331281 -240.587425) (xy 192.339224 -240.640129) (xy 192.339722 -240.666778)
			(xy 192.339224 -240.693427) (xy 206.715604 -240.693427) (xy 206.715604 -240.640129) (xy 206.723547 -240.587425)
			(xy 206.739257 -240.536495) (xy 206.762383 -240.488474) (xy 206.792407 -240.444437) (xy 206.828659 -240.405366)
			(xy 206.87033 -240.372135) (xy 206.916488 -240.345486) (xy 206.966102 -240.326014) (xy 207.018064 -240.314154)
			(xy 207.071214 -240.310171) (xy 207.124364 -240.314154) (xy 207.176326 -240.326014) (xy 207.22594 -240.345486)
			(xy 207.272098 -240.372135) (xy 207.313769 -240.405366) (xy 207.350021 -240.444437) (xy 207.380045 -240.488474)
			(xy 207.403171 -240.536495) (xy 207.418881 -240.587425) (xy 207.426824 -240.640129) (xy 207.427322 -240.666778)
			(xy 207.426824 -240.693427) (xy 207.418881 -240.746131) (xy 207.403171 -240.797061) (xy 207.380045 -240.845082)
			(xy 207.350021 -240.889119) (xy 207.313769 -240.92819) (xy 207.272098 -240.961421) (xy 207.22594 -240.98807)
			(xy 207.176326 -241.007542) (xy 207.124364 -241.019402) (xy 207.071214 -241.023386) (xy 207.018064 -241.019402)
			(xy 206.966102 -241.007542) (xy 206.916488 -240.98807) (xy 206.87033 -240.961421) (xy 206.828659 -240.92819)
			(xy 206.792407 -240.889119) (xy 206.762383 -240.845082) (xy 206.739257 -240.797061) (xy 206.723547 -240.746131)
			(xy 206.715604 -240.693427) (xy 192.339224 -240.693427) (xy 192.331281 -240.746131) (xy 192.315571 -240.797061)
			(xy 192.292445 -240.845082) (xy 192.262421 -240.889119) (xy 192.226169 -240.92819) (xy 192.184498 -240.961421)
			(xy 192.13834 -240.98807) (xy 192.088726 -241.007542) (xy 192.036764 -241.019402) (xy 191.983614 -241.023386)
			(xy 191.930464 -241.019402) (xy 191.878502 -241.007542) (xy 191.828888 -240.98807) (xy 191.78273 -240.961421)
			(xy 191.741059 -240.92819) (xy 191.704807 -240.889119) (xy 191.674783 -240.845082) (xy 191.651657 -240.797061)
			(xy 191.635947 -240.746131) (xy 191.628004 -240.693427) (xy 177.251624 -240.693427) (xy 177.243681 -240.746131)
			(xy 177.227971 -240.797061) (xy 177.204845 -240.845082) (xy 177.174821 -240.889119) (xy 177.138569 -240.92819)
			(xy 177.096898 -240.961421) (xy 177.05074 -240.98807) (xy 177.001126 -241.007542) (xy 176.949164 -241.019402)
			(xy 176.896014 -241.023386) (xy 176.842864 -241.019402) (xy 176.790902 -241.007542) (xy 176.741288 -240.98807)
			(xy 176.69513 -240.961421) (xy 176.653459 -240.92819) (xy 176.617207 -240.889119) (xy 176.587183 -240.845082)
			(xy 176.564057 -240.797061) (xy 176.548347 -240.746131) (xy 176.540404 -240.693427) (xy 159.11576 -240.693427)
			(xy 159.11576 -241.543311) (xy 172.440336 -241.543311) (xy 172.440336 -241.490013) (xy 172.448279 -241.437309)
			(xy 172.463989 -241.386379) (xy 172.487115 -241.338358) (xy 172.517139 -241.294321) (xy 172.553391 -241.25525)
			(xy 172.595062 -241.222019) (xy 172.64122 -241.19537) (xy 172.690834 -241.175898) (xy 172.742796 -241.164038)
			(xy 172.795946 -241.160055) (xy 172.849096 -241.164038) (xy 172.901058 -241.175898) (xy 172.950672 -241.19537)
			(xy 172.99683 -241.222019) (xy 173.038501 -241.25525) (xy 173.074753 -241.294321) (xy 173.104777 -241.338358)
			(xy 173.127903 -241.386379) (xy 173.143613 -241.437309) (xy 173.151556 -241.490013) (xy 173.152054 -241.516662)
			(xy 173.151556 -241.543311) (xy 187.527936 -241.543311) (xy 187.527936 -241.490013) (xy 187.535879 -241.437309)
			(xy 187.551589 -241.386379) (xy 187.574715 -241.338358) (xy 187.604739 -241.294321) (xy 187.640991 -241.25525)
			(xy 187.682662 -241.222019) (xy 187.72882 -241.19537) (xy 187.778434 -241.175898) (xy 187.830396 -241.164038)
			(xy 187.883546 -241.160055) (xy 187.936696 -241.164038) (xy 187.988658 -241.175898) (xy 188.038272 -241.19537)
			(xy 188.08443 -241.222019) (xy 188.126101 -241.25525) (xy 188.162353 -241.294321) (xy 188.192377 -241.338358)
			(xy 188.215503 -241.386379) (xy 188.231213 -241.437309) (xy 188.239156 -241.490013) (xy 188.239654 -241.516662)
			(xy 188.239156 -241.543311) (xy 202.615536 -241.543311) (xy 202.615536 -241.490013) (xy 202.623479 -241.437309)
			(xy 202.639189 -241.386379) (xy 202.662315 -241.338358) (xy 202.692339 -241.294321) (xy 202.728591 -241.25525)
			(xy 202.770262 -241.222019) (xy 202.81642 -241.19537) (xy 202.866034 -241.175898) (xy 202.917996 -241.164038)
			(xy 202.971146 -241.160055) (xy 203.024296 -241.164038) (xy 203.076258 -241.175898) (xy 203.125872 -241.19537)
			(xy 203.17203 -241.222019) (xy 203.213701 -241.25525) (xy 203.249953 -241.294321) (xy 203.279977 -241.338358)
			(xy 203.303103 -241.386379) (xy 203.318813 -241.437309) (xy 203.326756 -241.490013) (xy 203.327254 -241.516662)
			(xy 203.326756 -241.543311) (xy 203.318813 -241.596015) (xy 203.303103 -241.646945) (xy 203.279977 -241.694966)
			(xy 203.249953 -241.739003) (xy 203.213701 -241.778074) (xy 203.17203 -241.811305) (xy 203.125872 -241.837954)
			(xy 203.076258 -241.857426) (xy 203.024296 -241.869286) (xy 202.971146 -241.87327) (xy 202.917996 -241.869286)
			(xy 202.866034 -241.857426) (xy 202.81642 -241.837954) (xy 202.770262 -241.811305) (xy 202.728591 -241.778074)
			(xy 202.692339 -241.739003) (xy 202.662315 -241.694966) (xy 202.639189 -241.646945) (xy 202.623479 -241.596015)
			(xy 202.615536 -241.543311) (xy 188.239156 -241.543311) (xy 188.231213 -241.596015) (xy 188.215503 -241.646945)
			(xy 188.192377 -241.694966) (xy 188.162353 -241.739003) (xy 188.126101 -241.778074) (xy 188.08443 -241.811305)
			(xy 188.038272 -241.837954) (xy 187.988658 -241.857426) (xy 187.936696 -241.869286) (xy 187.883546 -241.87327)
			(xy 187.830396 -241.869286) (xy 187.778434 -241.857426) (xy 187.72882 -241.837954) (xy 187.682662 -241.811305)
			(xy 187.640991 -241.778074) (xy 187.604739 -241.739003) (xy 187.574715 -241.694966) (xy 187.551589 -241.646945)
			(xy 187.535879 -241.596015) (xy 187.527936 -241.543311) (xy 173.151556 -241.543311) (xy 173.143613 -241.596015)
			(xy 173.127903 -241.646945) (xy 173.104777 -241.694966) (xy 173.074753 -241.739003) (xy 173.038501 -241.778074)
			(xy 172.99683 -241.811305) (xy 172.950672 -241.837954) (xy 172.901058 -241.857426) (xy 172.849096 -241.869286)
			(xy 172.795946 -241.87327) (xy 172.742796 -241.869286) (xy 172.690834 -241.857426) (xy 172.64122 -241.837954)
			(xy 172.595062 -241.811305) (xy 172.553391 -241.778074) (xy 172.517139 -241.739003) (xy 172.487115 -241.694966)
			(xy 172.463989 -241.646945) (xy 172.448279 -241.596015) (xy 172.440336 -241.543311) (xy 159.11576 -241.543311)
			(xy 159.11576 -242.393449) (xy 161.427404 -242.393449) (xy 161.427404 -242.340151) (xy 161.435347 -242.287447)
			(xy 161.451057 -242.236517) (xy 161.474183 -242.188496) (xy 161.504207 -242.144459) (xy 161.540459 -242.105388)
			(xy 161.58213 -242.072157) (xy 161.628288 -242.045508) (xy 161.677902 -242.026036) (xy 161.729864 -242.014176)
			(xy 161.783014 -242.010193) (xy 161.836164 -242.014176) (xy 161.888126 -242.026036) (xy 161.93774 -242.045508)
			(xy 161.983898 -242.072157) (xy 162.025569 -242.105388) (xy 162.061821 -242.144459) (xy 162.091845 -242.188496)
			(xy 162.114971 -242.236517) (xy 162.130681 -242.287447) (xy 162.138624 -242.340151) (xy 162.139122 -242.3668)
			(xy 162.138624 -242.393449) (xy 168.971204 -242.393449) (xy 168.971204 -242.340151) (xy 168.979147 -242.287447)
			(xy 168.994857 -242.236517) (xy 169.017983 -242.188496) (xy 169.048007 -242.144459) (xy 169.084259 -242.105388)
			(xy 169.12593 -242.072157) (xy 169.172088 -242.045508) (xy 169.221702 -242.026036) (xy 169.273664 -242.014176)
			(xy 169.326814 -242.010193) (xy 169.379964 -242.014176) (xy 169.431926 -242.026036) (xy 169.48154 -242.045508)
			(xy 169.527698 -242.072157) (xy 169.569369 -242.105388) (xy 169.605621 -242.144459) (xy 169.635645 -242.188496)
			(xy 169.658771 -242.236517) (xy 169.674481 -242.287447) (xy 169.682424 -242.340151) (xy 169.682922 -242.3668)
			(xy 169.682424 -242.393449) (xy 176.540404 -242.393449) (xy 176.540404 -242.340151) (xy 176.548347 -242.287447)
			(xy 176.564057 -242.236517) (xy 176.587183 -242.188496) (xy 176.617207 -242.144459) (xy 176.653459 -242.105388)
			(xy 176.69513 -242.072157) (xy 176.741288 -242.045508) (xy 176.790902 -242.026036) (xy 176.842864 -242.014176)
			(xy 176.896014 -242.010193) (xy 176.949164 -242.014176) (xy 177.001126 -242.026036) (xy 177.05074 -242.045508)
			(xy 177.096898 -242.072157) (xy 177.138569 -242.105388) (xy 177.174821 -242.144459) (xy 177.204845 -242.188496)
			(xy 177.227971 -242.236517) (xy 177.243681 -242.287447) (xy 177.251624 -242.340151) (xy 177.252122 -242.3668)
			(xy 177.251624 -242.393449) (xy 184.058804 -242.393449) (xy 184.058804 -242.340151) (xy 184.066747 -242.287447)
			(xy 184.082457 -242.236517) (xy 184.105583 -242.188496) (xy 184.135607 -242.144459) (xy 184.171859 -242.105388)
			(xy 184.21353 -242.072157) (xy 184.259688 -242.045508) (xy 184.309302 -242.026036) (xy 184.361264 -242.014176)
			(xy 184.414414 -242.010193) (xy 184.467564 -242.014176) (xy 184.519526 -242.026036) (xy 184.56914 -242.045508)
			(xy 184.615298 -242.072157) (xy 184.656969 -242.105388) (xy 184.693221 -242.144459) (xy 184.723245 -242.188496)
			(xy 184.746371 -242.236517) (xy 184.762081 -242.287447) (xy 184.770024 -242.340151) (xy 184.770522 -242.3668)
			(xy 184.770024 -242.393449) (xy 191.628004 -242.393449) (xy 191.628004 -242.340151) (xy 191.635947 -242.287447)
			(xy 191.651657 -242.236517) (xy 191.674783 -242.188496) (xy 191.704807 -242.144459) (xy 191.741059 -242.105388)
			(xy 191.78273 -242.072157) (xy 191.828888 -242.045508) (xy 191.878502 -242.026036) (xy 191.930464 -242.014176)
			(xy 191.983614 -242.010193) (xy 192.036764 -242.014176) (xy 192.088726 -242.026036) (xy 192.13834 -242.045508)
			(xy 192.184498 -242.072157) (xy 192.226169 -242.105388) (xy 192.262421 -242.144459) (xy 192.292445 -242.188496)
			(xy 192.315571 -242.236517) (xy 192.331281 -242.287447) (xy 192.339224 -242.340151) (xy 192.339722 -242.3668)
			(xy 192.339224 -242.393449) (xy 199.171804 -242.393449) (xy 199.171804 -242.340151) (xy 199.179747 -242.287447)
			(xy 199.195457 -242.236517) (xy 199.218583 -242.188496) (xy 199.248607 -242.144459) (xy 199.284859 -242.105388)
			(xy 199.32653 -242.072157) (xy 199.372688 -242.045508) (xy 199.422302 -242.026036) (xy 199.474264 -242.014176)
			(xy 199.527414 -242.010193) (xy 199.580564 -242.014176) (xy 199.632526 -242.026036) (xy 199.68214 -242.045508)
			(xy 199.728298 -242.072157) (xy 199.769969 -242.105388) (xy 199.806221 -242.144459) (xy 199.836245 -242.188496)
			(xy 199.859371 -242.236517) (xy 199.875081 -242.287447) (xy 199.883024 -242.340151) (xy 199.883522 -242.3668)
			(xy 199.883024 -242.393449) (xy 206.715604 -242.393449) (xy 206.715604 -242.340151) (xy 206.723547 -242.287447)
			(xy 206.739257 -242.236517) (xy 206.762383 -242.188496) (xy 206.792407 -242.144459) (xy 206.828659 -242.105388)
			(xy 206.87033 -242.072157) (xy 206.916488 -242.045508) (xy 206.966102 -242.026036) (xy 207.018064 -242.014176)
			(xy 207.071214 -242.010193) (xy 207.124364 -242.014176) (xy 207.176326 -242.026036) (xy 207.22594 -242.045508)
			(xy 207.272098 -242.072157) (xy 207.313769 -242.105388) (xy 207.350021 -242.144459) (xy 207.380045 -242.188496)
			(xy 207.403171 -242.236517) (xy 207.418881 -242.287447) (xy 207.426824 -242.340151) (xy 207.427322 -242.3668)
			(xy 207.426824 -242.393449) (xy 214.234004 -242.393449) (xy 214.234004 -242.340151) (xy 214.241947 -242.287447)
			(xy 214.257657 -242.236517) (xy 214.280783 -242.188496) (xy 214.310807 -242.144459) (xy 214.347059 -242.105388)
			(xy 214.38873 -242.072157) (xy 214.434888 -242.045508) (xy 214.484502 -242.026036) (xy 214.536464 -242.014176)
			(xy 214.589614 -242.010193) (xy 214.642764 -242.014176) (xy 214.694726 -242.026036) (xy 214.74434 -242.045508)
			(xy 214.790498 -242.072157) (xy 214.832169 -242.105388) (xy 214.868421 -242.144459) (xy 214.898445 -242.188496)
			(xy 214.921571 -242.236517) (xy 214.937281 -242.287447) (xy 214.945224 -242.340151) (xy 214.945722 -242.3668)
			(xy 214.945224 -242.393449) (xy 214.937281 -242.446153) (xy 214.921571 -242.497083) (xy 214.898445 -242.545104)
			(xy 214.868421 -242.589141) (xy 214.832169 -242.628212) (xy 214.790498 -242.661443) (xy 214.74434 -242.688092)
			(xy 214.694726 -242.707564) (xy 214.642764 -242.719424) (xy 214.589614 -242.723408) (xy 214.536464 -242.719424)
			(xy 214.484502 -242.707564) (xy 214.434888 -242.688092) (xy 214.38873 -242.661443) (xy 214.347059 -242.628212)
			(xy 214.310807 -242.589141) (xy 214.280783 -242.545104) (xy 214.257657 -242.497083) (xy 214.241947 -242.446153)
			(xy 214.234004 -242.393449) (xy 207.426824 -242.393449) (xy 207.418881 -242.446153) (xy 207.403171 -242.497083)
			(xy 207.380045 -242.545104) (xy 207.350021 -242.589141) (xy 207.313769 -242.628212) (xy 207.272098 -242.661443)
			(xy 207.22594 -242.688092) (xy 207.176326 -242.707564) (xy 207.124364 -242.719424) (xy 207.071214 -242.723408)
			(xy 207.018064 -242.719424) (xy 206.966102 -242.707564) (xy 206.916488 -242.688092) (xy 206.87033 -242.661443)
			(xy 206.828659 -242.628212) (xy 206.792407 -242.589141) (xy 206.762383 -242.545104) (xy 206.739257 -242.497083)
			(xy 206.723547 -242.446153) (xy 206.715604 -242.393449) (xy 199.883024 -242.393449) (xy 199.875081 -242.446153)
			(xy 199.859371 -242.497083) (xy 199.836245 -242.545104) (xy 199.806221 -242.589141) (xy 199.769969 -242.628212)
			(xy 199.728298 -242.661443) (xy 199.68214 -242.688092) (xy 199.632526 -242.707564) (xy 199.580564 -242.719424)
			(xy 199.527414 -242.723408) (xy 199.474264 -242.719424) (xy 199.422302 -242.707564) (xy 199.372688 -242.688092)
			(xy 199.32653 -242.661443) (xy 199.284859 -242.628212) (xy 199.248607 -242.589141) (xy 199.218583 -242.545104)
			(xy 199.195457 -242.497083) (xy 199.179747 -242.446153) (xy 199.171804 -242.393449) (xy 192.339224 -242.393449)
			(xy 192.331281 -242.446153) (xy 192.315571 -242.497083) (xy 192.292445 -242.545104) (xy 192.262421 -242.589141)
			(xy 192.226169 -242.628212) (xy 192.184498 -242.661443) (xy 192.13834 -242.688092) (xy 192.088726 -242.707564)
			(xy 192.036764 -242.719424) (xy 191.983614 -242.723408) (xy 191.930464 -242.719424) (xy 191.878502 -242.707564)
			(xy 191.828888 -242.688092) (xy 191.78273 -242.661443) (xy 191.741059 -242.628212) (xy 191.704807 -242.589141)
			(xy 191.674783 -242.545104) (xy 191.651657 -242.497083) (xy 191.635947 -242.446153) (xy 191.628004 -242.393449)
			(xy 184.770024 -242.393449) (xy 184.762081 -242.446153) (xy 184.746371 -242.497083) (xy 184.723245 -242.545104)
			(xy 184.693221 -242.589141) (xy 184.656969 -242.628212) (xy 184.615298 -242.661443) (xy 184.56914 -242.688092)
			(xy 184.519526 -242.707564) (xy 184.467564 -242.719424) (xy 184.414414 -242.723408) (xy 184.361264 -242.719424)
			(xy 184.309302 -242.707564) (xy 184.259688 -242.688092) (xy 184.21353 -242.661443) (xy 184.171859 -242.628212)
			(xy 184.135607 -242.589141) (xy 184.105583 -242.545104) (xy 184.082457 -242.497083) (xy 184.066747 -242.446153)
			(xy 184.058804 -242.393449) (xy 177.251624 -242.393449) (xy 177.243681 -242.446153) (xy 177.227971 -242.497083)
			(xy 177.204845 -242.545104) (xy 177.174821 -242.589141) (xy 177.138569 -242.628212) (xy 177.096898 -242.661443)
			(xy 177.05074 -242.688092) (xy 177.001126 -242.707564) (xy 176.949164 -242.719424) (xy 176.896014 -242.723408)
			(xy 176.842864 -242.719424) (xy 176.790902 -242.707564) (xy 176.741288 -242.688092) (xy 176.69513 -242.661443)
			(xy 176.653459 -242.628212) (xy 176.617207 -242.589141) (xy 176.587183 -242.545104) (xy 176.564057 -242.497083)
			(xy 176.548347 -242.446153) (xy 176.540404 -242.393449) (xy 169.682424 -242.393449) (xy 169.674481 -242.446153)
			(xy 169.658771 -242.497083) (xy 169.635645 -242.545104) (xy 169.605621 -242.589141) (xy 169.569369 -242.628212)
			(xy 169.527698 -242.661443) (xy 169.48154 -242.688092) (xy 169.431926 -242.707564) (xy 169.379964 -242.719424)
			(xy 169.326814 -242.723408) (xy 169.273664 -242.719424) (xy 169.221702 -242.707564) (xy 169.172088 -242.688092)
			(xy 169.12593 -242.661443) (xy 169.084259 -242.628212) (xy 169.048007 -242.589141) (xy 169.017983 -242.545104)
			(xy 168.994857 -242.497083) (xy 168.979147 -242.446153) (xy 168.971204 -242.393449) (xy 162.138624 -242.393449)
			(xy 162.130681 -242.446153) (xy 162.114971 -242.497083) (xy 162.091845 -242.545104) (xy 162.061821 -242.589141)
			(xy 162.025569 -242.628212) (xy 161.983898 -242.661443) (xy 161.93774 -242.688092) (xy 161.888126 -242.707564)
			(xy 161.836164 -242.719424) (xy 161.783014 -242.723408) (xy 161.729864 -242.719424) (xy 161.677902 -242.707564)
			(xy 161.628288 -242.688092) (xy 161.58213 -242.661443) (xy 161.540459 -242.628212) (xy 161.504207 -242.589141)
			(xy 161.474183 -242.545104) (xy 161.451057 -242.497083) (xy 161.435347 -242.446153) (xy 161.427404 -242.393449)
			(xy 159.11576 -242.393449) (xy 159.11576 -243.243333) (xy 161.427404 -243.243333) (xy 161.427404 -243.190035)
			(xy 161.435347 -243.137331) (xy 161.451057 -243.086401) (xy 161.474183 -243.03838) (xy 161.504207 -242.994343)
			(xy 161.540459 -242.955272) (xy 161.58213 -242.922041) (xy 161.628288 -242.895392) (xy 161.677902 -242.87592)
			(xy 161.729864 -242.86406) (xy 161.783014 -242.860077) (xy 161.836164 -242.86406) (xy 161.888126 -242.87592)
			(xy 161.93774 -242.895392) (xy 161.983898 -242.922041) (xy 162.025569 -242.955272) (xy 162.061821 -242.994343)
			(xy 162.091845 -243.03838) (xy 162.114971 -243.086401) (xy 162.130681 -243.137331) (xy 162.138624 -243.190035)
			(xy 162.139122 -243.216684) (xy 162.138624 -243.243333) (xy 164.871136 -243.243333) (xy 164.871136 -243.190035)
			(xy 164.879079 -243.137331) (xy 164.894789 -243.086401) (xy 164.917915 -243.03838) (xy 164.947939 -242.994343)
			(xy 164.984191 -242.955272) (xy 165.025862 -242.922041) (xy 165.07202 -242.895392) (xy 165.121634 -242.87592)
			(xy 165.173596 -242.86406) (xy 165.226746 -242.860077) (xy 165.279896 -242.86406) (xy 165.331858 -242.87592)
			(xy 165.381472 -242.895392) (xy 165.42763 -242.922041) (xy 165.469301 -242.955272) (xy 165.505553 -242.994343)
			(xy 165.535577 -243.03838) (xy 165.558703 -243.086401) (xy 165.574413 -243.137331) (xy 165.582356 -243.190035)
			(xy 165.582854 -243.216684) (xy 165.582356 -243.243333) (xy 168.971204 -243.243333) (xy 168.971204 -243.190035)
			(xy 168.979147 -243.137331) (xy 168.994857 -243.086401) (xy 169.017983 -243.03838) (xy 169.048007 -242.994343)
			(xy 169.084259 -242.955272) (xy 169.12593 -242.922041) (xy 169.172088 -242.895392) (xy 169.221702 -242.87592)
			(xy 169.273664 -242.86406) (xy 169.326814 -242.860077) (xy 169.379964 -242.86406) (xy 169.431926 -242.87592)
			(xy 169.48154 -242.895392) (xy 169.527698 -242.922041) (xy 169.569369 -242.955272) (xy 169.605621 -242.994343)
			(xy 169.635645 -243.03838) (xy 169.658771 -243.086401) (xy 169.674481 -243.137331) (xy 169.682424 -243.190035)
			(xy 169.682922 -243.216684) (xy 169.682424 -243.243333) (xy 172.440336 -243.243333) (xy 172.440336 -243.190035)
			(xy 172.448279 -243.137331) (xy 172.463989 -243.086401) (xy 172.487115 -243.03838) (xy 172.517139 -242.994343)
			(xy 172.553391 -242.955272) (xy 172.595062 -242.922041) (xy 172.64122 -242.895392) (xy 172.690834 -242.87592)
			(xy 172.742796 -242.86406) (xy 172.795946 -242.860077) (xy 172.849096 -242.86406) (xy 172.901058 -242.87592)
			(xy 172.950672 -242.895392) (xy 172.99683 -242.922041) (xy 173.038501 -242.955272) (xy 173.074753 -242.994343)
			(xy 173.104777 -243.03838) (xy 173.127903 -243.086401) (xy 173.143613 -243.137331) (xy 173.151556 -243.190035)
			(xy 173.152054 -243.216684) (xy 173.151556 -243.243333) (xy 176.540404 -243.243333) (xy 176.540404 -243.190035)
			(xy 176.548347 -243.137331) (xy 176.564057 -243.086401) (xy 176.587183 -243.03838) (xy 176.617207 -242.994343)
			(xy 176.653459 -242.955272) (xy 176.69513 -242.922041) (xy 176.741288 -242.895392) (xy 176.790902 -242.87592)
			(xy 176.842864 -242.86406) (xy 176.896014 -242.860077) (xy 176.949164 -242.86406) (xy 177.001126 -242.87592)
			(xy 177.05074 -242.895392) (xy 177.096898 -242.922041) (xy 177.138569 -242.955272) (xy 177.174821 -242.994343)
			(xy 177.204845 -243.03838) (xy 177.227971 -243.086401) (xy 177.243681 -243.137331) (xy 177.251624 -243.190035)
			(xy 177.252122 -243.216684) (xy 177.251624 -243.243333) (xy 179.958736 -243.243333) (xy 179.958736 -243.190035)
			(xy 179.966679 -243.137331) (xy 179.982389 -243.086401) (xy 180.005515 -243.03838) (xy 180.035539 -242.994343)
			(xy 180.071791 -242.955272) (xy 180.113462 -242.922041) (xy 180.15962 -242.895392) (xy 180.209234 -242.87592)
			(xy 180.261196 -242.86406) (xy 180.314346 -242.860077) (xy 180.367496 -242.86406) (xy 180.419458 -242.87592)
			(xy 180.469072 -242.895392) (xy 180.51523 -242.922041) (xy 180.556901 -242.955272) (xy 180.593153 -242.994343)
			(xy 180.623177 -243.03838) (xy 180.646303 -243.086401) (xy 180.662013 -243.137331) (xy 180.669956 -243.190035)
			(xy 180.670454 -243.216684) (xy 180.669956 -243.243333) (xy 184.058804 -243.243333) (xy 184.058804 -243.190035)
			(xy 184.066747 -243.137331) (xy 184.082457 -243.086401) (xy 184.105583 -243.03838) (xy 184.135607 -242.994343)
			(xy 184.171859 -242.955272) (xy 184.21353 -242.922041) (xy 184.259688 -242.895392) (xy 184.309302 -242.87592)
			(xy 184.361264 -242.86406) (xy 184.414414 -242.860077) (xy 184.467564 -242.86406) (xy 184.519526 -242.87592)
			(xy 184.56914 -242.895392) (xy 184.615298 -242.922041) (xy 184.656969 -242.955272) (xy 184.693221 -242.994343)
			(xy 184.723245 -243.03838) (xy 184.746371 -243.086401) (xy 184.762081 -243.137331) (xy 184.770024 -243.190035)
			(xy 184.770522 -243.216684) (xy 184.770024 -243.243333) (xy 187.527936 -243.243333) (xy 187.527936 -243.190035)
			(xy 187.535879 -243.137331) (xy 187.551589 -243.086401) (xy 187.574715 -243.03838) (xy 187.604739 -242.994343)
			(xy 187.640991 -242.955272) (xy 187.682662 -242.922041) (xy 187.72882 -242.895392) (xy 187.778434 -242.87592)
			(xy 187.830396 -242.86406) (xy 187.883546 -242.860077) (xy 187.936696 -242.86406) (xy 187.988658 -242.87592)
			(xy 188.038272 -242.895392) (xy 188.08443 -242.922041) (xy 188.126101 -242.955272) (xy 188.162353 -242.994343)
			(xy 188.192377 -243.03838) (xy 188.215503 -243.086401) (xy 188.231213 -243.137331) (xy 188.239156 -243.190035)
			(xy 188.239654 -243.216684) (xy 188.239156 -243.243333) (xy 191.628004 -243.243333) (xy 191.628004 -243.190035)
			(xy 191.635947 -243.137331) (xy 191.651657 -243.086401) (xy 191.674783 -243.03838) (xy 191.704807 -242.994343)
			(xy 191.741059 -242.955272) (xy 191.78273 -242.922041) (xy 191.828888 -242.895392) (xy 191.878502 -242.87592)
			(xy 191.930464 -242.86406) (xy 191.983614 -242.860077) (xy 192.036764 -242.86406) (xy 192.088726 -242.87592)
			(xy 192.13834 -242.895392) (xy 192.184498 -242.922041) (xy 192.226169 -242.955272) (xy 192.262421 -242.994343)
			(xy 192.292445 -243.03838) (xy 192.315571 -243.086401) (xy 192.331281 -243.137331) (xy 192.339224 -243.190035)
			(xy 192.339722 -243.216684) (xy 192.339224 -243.243333) (xy 195.071736 -243.243333) (xy 195.071736 -243.190035)
			(xy 195.079679 -243.137331) (xy 195.095389 -243.086401) (xy 195.118515 -243.03838) (xy 195.148539 -242.994343)
			(xy 195.184791 -242.955272) (xy 195.226462 -242.922041) (xy 195.27262 -242.895392) (xy 195.322234 -242.87592)
			(xy 195.374196 -242.86406) (xy 195.427346 -242.860077) (xy 195.480496 -242.86406) (xy 195.532458 -242.87592)
			(xy 195.582072 -242.895392) (xy 195.62823 -242.922041) (xy 195.669901 -242.955272) (xy 195.706153 -242.994343)
			(xy 195.736177 -243.03838) (xy 195.759303 -243.086401) (xy 195.775013 -243.137331) (xy 195.782956 -243.190035)
			(xy 195.783454 -243.216684) (xy 195.782956 -243.243333) (xy 199.171804 -243.243333) (xy 199.171804 -243.190035)
			(xy 199.179747 -243.137331) (xy 199.195457 -243.086401) (xy 199.218583 -243.03838) (xy 199.248607 -242.994343)
			(xy 199.284859 -242.955272) (xy 199.32653 -242.922041) (xy 199.372688 -242.895392) (xy 199.422302 -242.87592)
			(xy 199.474264 -242.86406) (xy 199.527414 -242.860077) (xy 199.580564 -242.86406) (xy 199.632526 -242.87592)
			(xy 199.68214 -242.895392) (xy 199.728298 -242.922041) (xy 199.769969 -242.955272) (xy 199.806221 -242.994343)
			(xy 199.836245 -243.03838) (xy 199.859371 -243.086401) (xy 199.875081 -243.137331) (xy 199.883024 -243.190035)
			(xy 199.883522 -243.216684) (xy 199.883024 -243.243333) (xy 202.615536 -243.243333) (xy 202.615536 -243.190035)
			(xy 202.623479 -243.137331) (xy 202.639189 -243.086401) (xy 202.662315 -243.03838) (xy 202.692339 -242.994343)
			(xy 202.728591 -242.955272) (xy 202.770262 -242.922041) (xy 202.81642 -242.895392) (xy 202.866034 -242.87592)
			(xy 202.917996 -242.86406) (xy 202.971146 -242.860077) (xy 203.024296 -242.86406) (xy 203.076258 -242.87592)
			(xy 203.125872 -242.895392) (xy 203.17203 -242.922041) (xy 203.213701 -242.955272) (xy 203.249953 -242.994343)
			(xy 203.279977 -243.03838) (xy 203.303103 -243.086401) (xy 203.318813 -243.137331) (xy 203.326756 -243.190035)
			(xy 203.327254 -243.216684) (xy 203.326756 -243.243333) (xy 206.715604 -243.243333) (xy 206.715604 -243.190035)
			(xy 206.723547 -243.137331) (xy 206.739257 -243.086401) (xy 206.762383 -243.03838) (xy 206.792407 -242.994343)
			(xy 206.828659 -242.955272) (xy 206.87033 -242.922041) (xy 206.916488 -242.895392) (xy 206.966102 -242.87592)
			(xy 207.018064 -242.86406) (xy 207.071214 -242.860077) (xy 207.124364 -242.86406) (xy 207.176326 -242.87592)
			(xy 207.22594 -242.895392) (xy 207.272098 -242.922041) (xy 207.313769 -242.955272) (xy 207.350021 -242.994343)
			(xy 207.380045 -243.03838) (xy 207.403171 -243.086401) (xy 207.418881 -243.137331) (xy 207.426824 -243.190035)
			(xy 207.427322 -243.216684) (xy 207.426824 -243.243333) (xy 210.159336 -243.243333) (xy 210.159336 -243.190035)
			(xy 210.167279 -243.137331) (xy 210.182989 -243.086401) (xy 210.206115 -243.03838) (xy 210.236139 -242.994343)
			(xy 210.272391 -242.955272) (xy 210.314062 -242.922041) (xy 210.36022 -242.895392) (xy 210.409834 -242.87592)
			(xy 210.461796 -242.86406) (xy 210.514946 -242.860077) (xy 210.568096 -242.86406) (xy 210.620058 -242.87592)
			(xy 210.669672 -242.895392) (xy 210.71583 -242.922041) (xy 210.757501 -242.955272) (xy 210.793753 -242.994343)
			(xy 210.823777 -243.03838) (xy 210.846903 -243.086401) (xy 210.862613 -243.137331) (xy 210.870556 -243.190035)
			(xy 210.871054 -243.216684) (xy 210.870556 -243.243333) (xy 214.234004 -243.243333) (xy 214.234004 -243.190035)
			(xy 214.241947 -243.137331) (xy 214.257657 -243.086401) (xy 214.280783 -243.03838) (xy 214.310807 -242.994343)
			(xy 214.347059 -242.955272) (xy 214.38873 -242.922041) (xy 214.434888 -242.895392) (xy 214.484502 -242.87592)
			(xy 214.536464 -242.86406) (xy 214.589614 -242.860077) (xy 214.642764 -242.86406) (xy 214.694726 -242.87592)
			(xy 214.74434 -242.895392) (xy 214.790498 -242.922041) (xy 214.832169 -242.955272) (xy 214.868421 -242.994343)
			(xy 214.898445 -243.03838) (xy 214.921571 -243.086401) (xy 214.937281 -243.137331) (xy 214.945224 -243.190035)
			(xy 214.945722 -243.216684) (xy 214.945224 -243.243333) (xy 214.937281 -243.296037) (xy 214.921571 -243.346967)
			(xy 214.898445 -243.394988) (xy 214.868421 -243.439025) (xy 214.832169 -243.478096) (xy 214.790498 -243.511327)
			(xy 214.74434 -243.537976) (xy 214.694726 -243.557448) (xy 214.642764 -243.569308) (xy 214.589614 -243.573292)
			(xy 214.536464 -243.569308) (xy 214.484502 -243.557448) (xy 214.434888 -243.537976) (xy 214.38873 -243.511327)
			(xy 214.347059 -243.478096) (xy 214.310807 -243.439025) (xy 214.280783 -243.394988) (xy 214.257657 -243.346967)
			(xy 214.241947 -243.296037) (xy 214.234004 -243.243333) (xy 210.870556 -243.243333) (xy 210.862613 -243.296037)
			(xy 210.846903 -243.346967) (xy 210.823777 -243.394988) (xy 210.793753 -243.439025) (xy 210.757501 -243.478096)
			(xy 210.71583 -243.511327) (xy 210.669672 -243.537976) (xy 210.620058 -243.557448) (xy 210.568096 -243.569308)
			(xy 210.514946 -243.573292) (xy 210.461796 -243.569308) (xy 210.409834 -243.557448) (xy 210.36022 -243.537976)
			(xy 210.314062 -243.511327) (xy 210.272391 -243.478096) (xy 210.236139 -243.439025) (xy 210.206115 -243.394988)
			(xy 210.182989 -243.346967) (xy 210.167279 -243.296037) (xy 210.159336 -243.243333) (xy 207.426824 -243.243333)
			(xy 207.418881 -243.296037) (xy 207.403171 -243.346967) (xy 207.380045 -243.394988) (xy 207.350021 -243.439025)
			(xy 207.313769 -243.478096) (xy 207.272098 -243.511327) (xy 207.22594 -243.537976) (xy 207.176326 -243.557448)
			(xy 207.124364 -243.569308) (xy 207.071214 -243.573292) (xy 207.018064 -243.569308) (xy 206.966102 -243.557448)
			(xy 206.916488 -243.537976) (xy 206.87033 -243.511327) (xy 206.828659 -243.478096) (xy 206.792407 -243.439025)
			(xy 206.762383 -243.394988) (xy 206.739257 -243.346967) (xy 206.723547 -243.296037) (xy 206.715604 -243.243333)
			(xy 203.326756 -243.243333) (xy 203.318813 -243.296037) (xy 203.303103 -243.346967) (xy 203.279977 -243.394988)
			(xy 203.249953 -243.439025) (xy 203.213701 -243.478096) (xy 203.17203 -243.511327) (xy 203.125872 -243.537976)
			(xy 203.076258 -243.557448) (xy 203.024296 -243.569308) (xy 202.971146 -243.573292) (xy 202.917996 -243.569308)
			(xy 202.866034 -243.557448) (xy 202.81642 -243.537976) (xy 202.770262 -243.511327) (xy 202.728591 -243.478096)
			(xy 202.692339 -243.439025) (xy 202.662315 -243.394988) (xy 202.639189 -243.346967) (xy 202.623479 -243.296037)
			(xy 202.615536 -243.243333) (xy 199.883024 -243.243333) (xy 199.875081 -243.296037) (xy 199.859371 -243.346967)
			(xy 199.836245 -243.394988) (xy 199.806221 -243.439025) (xy 199.769969 -243.478096) (xy 199.728298 -243.511327)
			(xy 199.68214 -243.537976) (xy 199.632526 -243.557448) (xy 199.580564 -243.569308) (xy 199.527414 -243.573292)
			(xy 199.474264 -243.569308) (xy 199.422302 -243.557448) (xy 199.372688 -243.537976) (xy 199.32653 -243.511327)
			(xy 199.284859 -243.478096) (xy 199.248607 -243.439025) (xy 199.218583 -243.394988) (xy 199.195457 -243.346967)
			(xy 199.179747 -243.296037) (xy 199.171804 -243.243333) (xy 195.782956 -243.243333) (xy 195.775013 -243.296037)
			(xy 195.759303 -243.346967) (xy 195.736177 -243.394988) (xy 195.706153 -243.439025) (xy 195.669901 -243.478096)
			(xy 195.62823 -243.511327) (xy 195.582072 -243.537976) (xy 195.532458 -243.557448) (xy 195.480496 -243.569308)
			(xy 195.427346 -243.573292) (xy 195.374196 -243.569308) (xy 195.322234 -243.557448) (xy 195.27262 -243.537976)
			(xy 195.226462 -243.511327) (xy 195.184791 -243.478096) (xy 195.148539 -243.439025) (xy 195.118515 -243.394988)
			(xy 195.095389 -243.346967) (xy 195.079679 -243.296037) (xy 195.071736 -243.243333) (xy 192.339224 -243.243333)
			(xy 192.331281 -243.296037) (xy 192.315571 -243.346967) (xy 192.292445 -243.394988) (xy 192.262421 -243.439025)
			(xy 192.226169 -243.478096) (xy 192.184498 -243.511327) (xy 192.13834 -243.537976) (xy 192.088726 -243.557448)
			(xy 192.036764 -243.569308) (xy 191.983614 -243.573292) (xy 191.930464 -243.569308) (xy 191.878502 -243.557448)
			(xy 191.828888 -243.537976) (xy 191.78273 -243.511327) (xy 191.741059 -243.478096) (xy 191.704807 -243.439025)
			(xy 191.674783 -243.394988) (xy 191.651657 -243.346967) (xy 191.635947 -243.296037) (xy 191.628004 -243.243333)
			(xy 188.239156 -243.243333) (xy 188.231213 -243.296037) (xy 188.215503 -243.346967) (xy 188.192377 -243.394988)
			(xy 188.162353 -243.439025) (xy 188.126101 -243.478096) (xy 188.08443 -243.511327) (xy 188.038272 -243.537976)
			(xy 187.988658 -243.557448) (xy 187.936696 -243.569308) (xy 187.883546 -243.573292) (xy 187.830396 -243.569308)
			(xy 187.778434 -243.557448) (xy 187.72882 -243.537976) (xy 187.682662 -243.511327) (xy 187.640991 -243.478096)
			(xy 187.604739 -243.439025) (xy 187.574715 -243.394988) (xy 187.551589 -243.346967) (xy 187.535879 -243.296037)
			(xy 187.527936 -243.243333) (xy 184.770024 -243.243333) (xy 184.762081 -243.296037) (xy 184.746371 -243.346967)
			(xy 184.723245 -243.394988) (xy 184.693221 -243.439025) (xy 184.656969 -243.478096) (xy 184.615298 -243.511327)
			(xy 184.56914 -243.537976) (xy 184.519526 -243.557448) (xy 184.467564 -243.569308) (xy 184.414414 -243.573292)
			(xy 184.361264 -243.569308) (xy 184.309302 -243.557448) (xy 184.259688 -243.537976) (xy 184.21353 -243.511327)
			(xy 184.171859 -243.478096) (xy 184.135607 -243.439025) (xy 184.105583 -243.394988) (xy 184.082457 -243.346967)
			(xy 184.066747 -243.296037) (xy 184.058804 -243.243333) (xy 180.669956 -243.243333) (xy 180.662013 -243.296037)
			(xy 180.646303 -243.346967) (xy 180.623177 -243.394988) (xy 180.593153 -243.439025) (xy 180.556901 -243.478096)
			(xy 180.51523 -243.511327) (xy 180.469072 -243.537976) (xy 180.419458 -243.557448) (xy 180.367496 -243.569308)
			(xy 180.314346 -243.573292) (xy 180.261196 -243.569308) (xy 180.209234 -243.557448) (xy 180.15962 -243.537976)
			(xy 180.113462 -243.511327) (xy 180.071791 -243.478096) (xy 180.035539 -243.439025) (xy 180.005515 -243.394988)
			(xy 179.982389 -243.346967) (xy 179.966679 -243.296037) (xy 179.958736 -243.243333) (xy 177.251624 -243.243333)
			(xy 177.243681 -243.296037) (xy 177.227971 -243.346967) (xy 177.204845 -243.394988) (xy 177.174821 -243.439025)
			(xy 177.138569 -243.478096) (xy 177.096898 -243.511327) (xy 177.05074 -243.537976) (xy 177.001126 -243.557448)
			(xy 176.949164 -243.569308) (xy 176.896014 -243.573292) (xy 176.842864 -243.569308) (xy 176.790902 -243.557448)
			(xy 176.741288 -243.537976) (xy 176.69513 -243.511327) (xy 176.653459 -243.478096) (xy 176.617207 -243.439025)
			(xy 176.587183 -243.394988) (xy 176.564057 -243.346967) (xy 176.548347 -243.296037) (xy 176.540404 -243.243333)
			(xy 173.151556 -243.243333) (xy 173.143613 -243.296037) (xy 173.127903 -243.346967) (xy 173.104777 -243.394988)
			(xy 173.074753 -243.439025) (xy 173.038501 -243.478096) (xy 172.99683 -243.511327) (xy 172.950672 -243.537976)
			(xy 172.901058 -243.557448) (xy 172.849096 -243.569308) (xy 172.795946 -243.573292) (xy 172.742796 -243.569308)
			(xy 172.690834 -243.557448) (xy 172.64122 -243.537976) (xy 172.595062 -243.511327) (xy 172.553391 -243.478096)
			(xy 172.517139 -243.439025) (xy 172.487115 -243.394988) (xy 172.463989 -243.346967) (xy 172.448279 -243.296037)
			(xy 172.440336 -243.243333) (xy 169.682424 -243.243333) (xy 169.674481 -243.296037) (xy 169.658771 -243.346967)
			(xy 169.635645 -243.394988) (xy 169.605621 -243.439025) (xy 169.569369 -243.478096) (xy 169.527698 -243.511327)
			(xy 169.48154 -243.537976) (xy 169.431926 -243.557448) (xy 169.379964 -243.569308) (xy 169.326814 -243.573292)
			(xy 169.273664 -243.569308) (xy 169.221702 -243.557448) (xy 169.172088 -243.537976) (xy 169.12593 -243.511327)
			(xy 169.084259 -243.478096) (xy 169.048007 -243.439025) (xy 169.017983 -243.394988) (xy 168.994857 -243.346967)
			(xy 168.979147 -243.296037) (xy 168.971204 -243.243333) (xy 165.582356 -243.243333) (xy 165.574413 -243.296037)
			(xy 165.558703 -243.346967) (xy 165.535577 -243.394988) (xy 165.505553 -243.439025) (xy 165.469301 -243.478096)
			(xy 165.42763 -243.511327) (xy 165.381472 -243.537976) (xy 165.331858 -243.557448) (xy 165.279896 -243.569308)
			(xy 165.226746 -243.573292) (xy 165.173596 -243.569308) (xy 165.121634 -243.557448) (xy 165.07202 -243.537976)
			(xy 165.025862 -243.511327) (xy 164.984191 -243.478096) (xy 164.947939 -243.439025) (xy 164.917915 -243.394988)
			(xy 164.894789 -243.346967) (xy 164.879079 -243.296037) (xy 164.871136 -243.243333) (xy 162.138624 -243.243333)
			(xy 162.130681 -243.296037) (xy 162.114971 -243.346967) (xy 162.091845 -243.394988) (xy 162.061821 -243.439025)
			(xy 162.025569 -243.478096) (xy 161.983898 -243.511327) (xy 161.93774 -243.537976) (xy 161.888126 -243.557448)
			(xy 161.836164 -243.569308) (xy 161.783014 -243.573292) (xy 161.729864 -243.569308) (xy 161.677902 -243.557448)
			(xy 161.628288 -243.537976) (xy 161.58213 -243.511327) (xy 161.540459 -243.478096) (xy 161.504207 -243.439025)
			(xy 161.474183 -243.394988) (xy 161.451057 -243.346967) (xy 161.435347 -243.296037) (xy 161.427404 -243.243333)
			(xy 159.11576 -243.243333) (xy 159.11576 -244.093217) (xy 164.871136 -244.093217) (xy 164.871136 -244.039919)
			(xy 164.879079 -243.987215) (xy 164.894789 -243.936285) (xy 164.917915 -243.888264) (xy 164.947939 -243.844227)
			(xy 164.984191 -243.805156) (xy 165.025862 -243.771925) (xy 165.07202 -243.745276) (xy 165.121634 -243.725804)
			(xy 165.173596 -243.713944) (xy 165.226746 -243.709961) (xy 165.279896 -243.713944) (xy 165.331858 -243.725804)
			(xy 165.381472 -243.745276) (xy 165.42763 -243.771925) (xy 165.469301 -243.805156) (xy 165.505553 -243.844227)
			(xy 165.535577 -243.888264) (xy 165.558703 -243.936285) (xy 165.574413 -243.987215) (xy 165.582356 -244.039919)
			(xy 165.582854 -244.066568) (xy 165.582356 -244.093217) (xy 172.440336 -244.093217) (xy 172.440336 -244.039919)
			(xy 172.448279 -243.987215) (xy 172.463989 -243.936285) (xy 172.487115 -243.888264) (xy 172.517139 -243.844227)
			(xy 172.553391 -243.805156) (xy 172.595062 -243.771925) (xy 172.64122 -243.745276) (xy 172.690834 -243.725804)
			(xy 172.742796 -243.713944) (xy 172.795946 -243.709961) (xy 172.849096 -243.713944) (xy 172.901058 -243.725804)
			(xy 172.950672 -243.745276) (xy 172.99683 -243.771925) (xy 173.038501 -243.805156) (xy 173.074753 -243.844227)
			(xy 173.104777 -243.888264) (xy 173.127903 -243.936285) (xy 173.143613 -243.987215) (xy 173.151556 -244.039919)
			(xy 173.152054 -244.066568) (xy 173.151556 -244.093217) (xy 179.958736 -244.093217) (xy 179.958736 -244.039919)
			(xy 179.966679 -243.987215) (xy 179.982389 -243.936285) (xy 180.005515 -243.888264) (xy 180.035539 -243.844227)
			(xy 180.071791 -243.805156) (xy 180.113462 -243.771925) (xy 180.15962 -243.745276) (xy 180.209234 -243.725804)
			(xy 180.261196 -243.713944) (xy 180.314346 -243.709961) (xy 180.367496 -243.713944) (xy 180.419458 -243.725804)
			(xy 180.469072 -243.745276) (xy 180.51523 -243.771925) (xy 180.556901 -243.805156) (xy 180.593153 -243.844227)
			(xy 180.623177 -243.888264) (xy 180.646303 -243.936285) (xy 180.662013 -243.987215) (xy 180.669956 -244.039919)
			(xy 180.670454 -244.066568) (xy 180.669956 -244.093217) (xy 187.527936 -244.093217) (xy 187.527936 -244.039919)
			(xy 187.535879 -243.987215) (xy 187.551589 -243.936285) (xy 187.574715 -243.888264) (xy 187.604739 -243.844227)
			(xy 187.640991 -243.805156) (xy 187.682662 -243.771925) (xy 187.72882 -243.745276) (xy 187.778434 -243.725804)
			(xy 187.830396 -243.713944) (xy 187.883546 -243.709961) (xy 187.936696 -243.713944) (xy 187.988658 -243.725804)
			(xy 188.038272 -243.745276) (xy 188.08443 -243.771925) (xy 188.126101 -243.805156) (xy 188.162353 -243.844227)
			(xy 188.192377 -243.888264) (xy 188.215503 -243.936285) (xy 188.231213 -243.987215) (xy 188.239156 -244.039919)
			(xy 188.239654 -244.066568) (xy 188.239156 -244.093217) (xy 195.071736 -244.093217) (xy 195.071736 -244.039919)
			(xy 195.079679 -243.987215) (xy 195.095389 -243.936285) (xy 195.118515 -243.888264) (xy 195.148539 -243.844227)
			(xy 195.184791 -243.805156) (xy 195.226462 -243.771925) (xy 195.27262 -243.745276) (xy 195.322234 -243.725804)
			(xy 195.374196 -243.713944) (xy 195.427346 -243.709961) (xy 195.480496 -243.713944) (xy 195.532458 -243.725804)
			(xy 195.582072 -243.745276) (xy 195.62823 -243.771925) (xy 195.669901 -243.805156) (xy 195.706153 -243.844227)
			(xy 195.736177 -243.888264) (xy 195.759303 -243.936285) (xy 195.775013 -243.987215) (xy 195.782956 -244.039919)
			(xy 195.783454 -244.066568) (xy 195.782956 -244.093217) (xy 202.615536 -244.093217) (xy 202.615536 -244.039919)
			(xy 202.623479 -243.987215) (xy 202.639189 -243.936285) (xy 202.662315 -243.888264) (xy 202.692339 -243.844227)
			(xy 202.728591 -243.805156) (xy 202.770262 -243.771925) (xy 202.81642 -243.745276) (xy 202.866034 -243.725804)
			(xy 202.917996 -243.713944) (xy 202.971146 -243.709961) (xy 203.024296 -243.713944) (xy 203.076258 -243.725804)
			(xy 203.125872 -243.745276) (xy 203.17203 -243.771925) (xy 203.213701 -243.805156) (xy 203.249953 -243.844227)
			(xy 203.279977 -243.888264) (xy 203.303103 -243.936285) (xy 203.318813 -243.987215) (xy 203.326756 -244.039919)
			(xy 203.327254 -244.066568) (xy 203.326756 -244.093217) (xy 210.159336 -244.093217) (xy 210.159336 -244.039919)
			(xy 210.167279 -243.987215) (xy 210.182989 -243.936285) (xy 210.206115 -243.888264) (xy 210.236139 -243.844227)
			(xy 210.272391 -243.805156) (xy 210.314062 -243.771925) (xy 210.36022 -243.745276) (xy 210.409834 -243.725804)
			(xy 210.461796 -243.713944) (xy 210.514946 -243.709961) (xy 210.568096 -243.713944) (xy 210.620058 -243.725804)
			(xy 210.669672 -243.745276) (xy 210.71583 -243.771925) (xy 210.757501 -243.805156) (xy 210.793753 -243.844227)
			(xy 210.823777 -243.888264) (xy 210.846903 -243.936285) (xy 210.862613 -243.987215) (xy 210.870556 -244.039919)
			(xy 210.871054 -244.066568) (xy 210.870556 -244.093217) (xy 210.862613 -244.145921) (xy 210.846903 -244.196851)
			(xy 210.823777 -244.244872) (xy 210.793753 -244.288909) (xy 210.757501 -244.32798) (xy 210.71583 -244.361211)
			(xy 210.669672 -244.38786) (xy 210.620058 -244.407332) (xy 210.568096 -244.419192) (xy 210.514946 -244.423176)
			(xy 210.461796 -244.419192) (xy 210.409834 -244.407332) (xy 210.36022 -244.38786) (xy 210.314062 -244.361211)
			(xy 210.272391 -244.32798) (xy 210.236139 -244.288909) (xy 210.206115 -244.244872) (xy 210.182989 -244.196851)
			(xy 210.167279 -244.145921) (xy 210.159336 -244.093217) (xy 203.326756 -244.093217) (xy 203.318813 -244.145921)
			(xy 203.303103 -244.196851) (xy 203.279977 -244.244872) (xy 203.249953 -244.288909) (xy 203.213701 -244.32798)
			(xy 203.17203 -244.361211) (xy 203.125872 -244.38786) (xy 203.076258 -244.407332) (xy 203.024296 -244.419192)
			(xy 202.971146 -244.423176) (xy 202.917996 -244.419192) (xy 202.866034 -244.407332) (xy 202.81642 -244.38786)
			(xy 202.770262 -244.361211) (xy 202.728591 -244.32798) (xy 202.692339 -244.288909) (xy 202.662315 -244.244872)
			(xy 202.639189 -244.196851) (xy 202.623479 -244.145921) (xy 202.615536 -244.093217) (xy 195.782956 -244.093217)
			(xy 195.775013 -244.145921) (xy 195.759303 -244.196851) (xy 195.736177 -244.244872) (xy 195.706153 -244.288909)
			(xy 195.669901 -244.32798) (xy 195.62823 -244.361211) (xy 195.582072 -244.38786) (xy 195.532458 -244.407332)
			(xy 195.480496 -244.419192) (xy 195.427346 -244.423176) (xy 195.374196 -244.419192) (xy 195.322234 -244.407332)
			(xy 195.27262 -244.38786) (xy 195.226462 -244.361211) (xy 195.184791 -244.32798) (xy 195.148539 -244.288909)
			(xy 195.118515 -244.244872) (xy 195.095389 -244.196851) (xy 195.079679 -244.145921) (xy 195.071736 -244.093217)
			(xy 188.239156 -244.093217) (xy 188.231213 -244.145921) (xy 188.215503 -244.196851) (xy 188.192377 -244.244872)
			(xy 188.162353 -244.288909) (xy 188.126101 -244.32798) (xy 188.08443 -244.361211) (xy 188.038272 -244.38786)
			(xy 187.988658 -244.407332) (xy 187.936696 -244.419192) (xy 187.883546 -244.423176) (xy 187.830396 -244.419192)
			(xy 187.778434 -244.407332) (xy 187.72882 -244.38786) (xy 187.682662 -244.361211) (xy 187.640991 -244.32798)
			(xy 187.604739 -244.288909) (xy 187.574715 -244.244872) (xy 187.551589 -244.196851) (xy 187.535879 -244.145921)
			(xy 187.527936 -244.093217) (xy 180.669956 -244.093217) (xy 180.662013 -244.145921) (xy 180.646303 -244.196851)
			(xy 180.623177 -244.244872) (xy 180.593153 -244.288909) (xy 180.556901 -244.32798) (xy 180.51523 -244.361211)
			(xy 180.469072 -244.38786) (xy 180.419458 -244.407332) (xy 180.367496 -244.419192) (xy 180.314346 -244.423176)
			(xy 180.261196 -244.419192) (xy 180.209234 -244.407332) (xy 180.15962 -244.38786) (xy 180.113462 -244.361211)
			(xy 180.071791 -244.32798) (xy 180.035539 -244.288909) (xy 180.005515 -244.244872) (xy 179.982389 -244.196851)
			(xy 179.966679 -244.145921) (xy 179.958736 -244.093217) (xy 173.151556 -244.093217) (xy 173.143613 -244.145921)
			(xy 173.127903 -244.196851) (xy 173.104777 -244.244872) (xy 173.074753 -244.288909) (xy 173.038501 -244.32798)
			(xy 172.99683 -244.361211) (xy 172.950672 -244.38786) (xy 172.901058 -244.407332) (xy 172.849096 -244.419192)
			(xy 172.795946 -244.423176) (xy 172.742796 -244.419192) (xy 172.690834 -244.407332) (xy 172.64122 -244.38786)
			(xy 172.595062 -244.361211) (xy 172.553391 -244.32798) (xy 172.517139 -244.288909) (xy 172.487115 -244.244872)
			(xy 172.463989 -244.196851) (xy 172.448279 -244.145921) (xy 172.440336 -244.093217) (xy 165.582356 -244.093217)
			(xy 165.574413 -244.145921) (xy 165.558703 -244.196851) (xy 165.535577 -244.244872) (xy 165.505553 -244.288909)
			(xy 165.469301 -244.32798) (xy 165.42763 -244.361211) (xy 165.381472 -244.38786) (xy 165.331858 -244.407332)
			(xy 165.279896 -244.419192) (xy 165.226746 -244.423176) (xy 165.173596 -244.419192) (xy 165.121634 -244.407332)
			(xy 165.07202 -244.38786) (xy 165.025862 -244.361211) (xy 164.984191 -244.32798) (xy 164.947939 -244.288909)
			(xy 164.917915 -244.244872) (xy 164.894789 -244.196851) (xy 164.879079 -244.145921) (xy 164.871136 -244.093217)
			(xy 159.11576 -244.093217) (xy 159.11576 -244.943355) (xy 176.540404 -244.943355) (xy 176.540404 -244.890057)
			(xy 176.548347 -244.837353) (xy 176.564057 -244.786423) (xy 176.587183 -244.738402) (xy 176.617207 -244.694365)
			(xy 176.653459 -244.655294) (xy 176.69513 -244.622063) (xy 176.741288 -244.595414) (xy 176.790902 -244.575942)
			(xy 176.842864 -244.564082) (xy 176.896014 -244.560099) (xy 176.949164 -244.564082) (xy 177.001126 -244.575942)
			(xy 177.05074 -244.595414) (xy 177.096898 -244.622063) (xy 177.138569 -244.655294) (xy 177.174821 -244.694365)
			(xy 177.204845 -244.738402) (xy 177.227971 -244.786423) (xy 177.243681 -244.837353) (xy 177.251624 -244.890057)
			(xy 177.252122 -244.916706) (xy 177.251624 -244.943355) (xy 184.084204 -244.943355) (xy 184.084204 -244.890057)
			(xy 184.092147 -244.837353) (xy 184.107857 -244.786423) (xy 184.130983 -244.738402) (xy 184.161007 -244.694365)
			(xy 184.197259 -244.655294) (xy 184.23893 -244.622063) (xy 184.285088 -244.595414) (xy 184.334702 -244.575942)
			(xy 184.386664 -244.564082) (xy 184.439814 -244.560099) (xy 184.492964 -244.564082) (xy 184.544926 -244.575942)
			(xy 184.59454 -244.595414) (xy 184.640698 -244.622063) (xy 184.682369 -244.655294) (xy 184.718621 -244.694365)
			(xy 184.748645 -244.738402) (xy 184.771771 -244.786423) (xy 184.787481 -244.837353) (xy 184.795424 -244.890057)
			(xy 184.795922 -244.916706) (xy 184.795424 -244.943355) (xy 191.628004 -244.943355) (xy 191.628004 -244.890057)
			(xy 191.635947 -244.837353) (xy 191.651657 -244.786423) (xy 191.674783 -244.738402) (xy 191.704807 -244.694365)
			(xy 191.741059 -244.655294) (xy 191.78273 -244.622063) (xy 191.828888 -244.595414) (xy 191.878502 -244.575942)
			(xy 191.930464 -244.564082) (xy 191.983614 -244.560099) (xy 192.036764 -244.564082) (xy 192.088726 -244.575942)
			(xy 192.13834 -244.595414) (xy 192.184498 -244.622063) (xy 192.226169 -244.655294) (xy 192.262421 -244.694365)
			(xy 192.292445 -244.738402) (xy 192.315571 -244.786423) (xy 192.331281 -244.837353) (xy 192.339224 -244.890057)
			(xy 192.339722 -244.916706) (xy 192.339224 -244.943355) (xy 199.171804 -244.943355) (xy 199.171804 -244.890057)
			(xy 199.179747 -244.837353) (xy 199.195457 -244.786423) (xy 199.218583 -244.738402) (xy 199.248607 -244.694365)
			(xy 199.284859 -244.655294) (xy 199.32653 -244.622063) (xy 199.372688 -244.595414) (xy 199.422302 -244.575942)
			(xy 199.474264 -244.564082) (xy 199.527414 -244.560099) (xy 199.580564 -244.564082) (xy 199.632526 -244.575942)
			(xy 199.68214 -244.595414) (xy 199.728298 -244.622063) (xy 199.769969 -244.655294) (xy 199.806221 -244.694365)
			(xy 199.836245 -244.738402) (xy 199.859371 -244.786423) (xy 199.875081 -244.837353) (xy 199.883024 -244.890057)
			(xy 199.883522 -244.916706) (xy 199.883024 -244.943355) (xy 206.715604 -244.943355) (xy 206.715604 -244.890057)
			(xy 206.723547 -244.837353) (xy 206.739257 -244.786423) (xy 206.762383 -244.738402) (xy 206.792407 -244.694365)
			(xy 206.828659 -244.655294) (xy 206.87033 -244.622063) (xy 206.916488 -244.595414) (xy 206.966102 -244.575942)
			(xy 207.018064 -244.564082) (xy 207.071214 -244.560099) (xy 207.124364 -244.564082) (xy 207.176326 -244.575942)
			(xy 207.22594 -244.595414) (xy 207.272098 -244.622063) (xy 207.313769 -244.655294) (xy 207.350021 -244.694365)
			(xy 207.380045 -244.738402) (xy 207.403171 -244.786423) (xy 207.418881 -244.837353) (xy 207.426824 -244.890057)
			(xy 207.427322 -244.916706) (xy 207.426824 -244.943355) (xy 214.259404 -244.943355) (xy 214.259404 -244.890057)
			(xy 214.267347 -244.837353) (xy 214.283057 -244.786423) (xy 214.306183 -244.738402) (xy 214.336207 -244.694365)
			(xy 214.372459 -244.655294) (xy 214.41413 -244.622063) (xy 214.460288 -244.595414) (xy 214.509902 -244.575942)
			(xy 214.561864 -244.564082) (xy 214.615014 -244.560099) (xy 214.668164 -244.564082) (xy 214.720126 -244.575942)
			(xy 214.76974 -244.595414) (xy 214.815898 -244.622063) (xy 214.857569 -244.655294) (xy 214.893821 -244.694365)
			(xy 214.923845 -244.738402) (xy 214.946971 -244.786423) (xy 214.962681 -244.837353) (xy 214.970624 -244.890057)
			(xy 214.971122 -244.916706) (xy 214.970624 -244.943355) (xy 214.962681 -244.996059) (xy 214.946971 -245.046989)
			(xy 214.923845 -245.09501) (xy 214.893821 -245.139047) (xy 214.857569 -245.178118) (xy 214.815898 -245.211349)
			(xy 214.76974 -245.237998) (xy 214.720126 -245.25747) (xy 214.668164 -245.26933) (xy 214.615014 -245.273314)
			(xy 214.561864 -245.26933) (xy 214.509902 -245.25747) (xy 214.460288 -245.237998) (xy 214.41413 -245.211349)
			(xy 214.372459 -245.178118) (xy 214.336207 -245.139047) (xy 214.306183 -245.09501) (xy 214.283057 -245.046989)
			(xy 214.267347 -244.996059) (xy 214.259404 -244.943355) (xy 207.426824 -244.943355) (xy 207.418881 -244.996059)
			(xy 207.403171 -245.046989) (xy 207.380045 -245.09501) (xy 207.350021 -245.139047) (xy 207.313769 -245.178118)
			(xy 207.272098 -245.211349) (xy 207.22594 -245.237998) (xy 207.176326 -245.25747) (xy 207.124364 -245.26933)
			(xy 207.071214 -245.273314) (xy 207.018064 -245.26933) (xy 206.966102 -245.25747) (xy 206.916488 -245.237998)
			(xy 206.87033 -245.211349) (xy 206.828659 -245.178118) (xy 206.792407 -245.139047) (xy 206.762383 -245.09501)
			(xy 206.739257 -245.046989) (xy 206.723547 -244.996059) (xy 206.715604 -244.943355) (xy 199.883024 -244.943355)
			(xy 199.875081 -244.996059) (xy 199.859371 -245.046989) (xy 199.836245 -245.09501) (xy 199.806221 -245.139047)
			(xy 199.769969 -245.178118) (xy 199.728298 -245.211349) (xy 199.68214 -245.237998) (xy 199.632526 -245.25747)
			(xy 199.580564 -245.26933) (xy 199.527414 -245.273314) (xy 199.474264 -245.26933) (xy 199.422302 -245.25747)
			(xy 199.372688 -245.237998) (xy 199.32653 -245.211349) (xy 199.284859 -245.178118) (xy 199.248607 -245.139047)
			(xy 199.218583 -245.09501) (xy 199.195457 -245.046989) (xy 199.179747 -244.996059) (xy 199.171804 -244.943355)
			(xy 192.339224 -244.943355) (xy 192.331281 -244.996059) (xy 192.315571 -245.046989) (xy 192.292445 -245.09501)
			(xy 192.262421 -245.139047) (xy 192.226169 -245.178118) (xy 192.184498 -245.211349) (xy 192.13834 -245.237998)
			(xy 192.088726 -245.25747) (xy 192.036764 -245.26933) (xy 191.983614 -245.273314) (xy 191.930464 -245.26933)
			(xy 191.878502 -245.25747) (xy 191.828888 -245.237998) (xy 191.78273 -245.211349) (xy 191.741059 -245.178118)
			(xy 191.704807 -245.139047) (xy 191.674783 -245.09501) (xy 191.651657 -245.046989) (xy 191.635947 -244.996059)
			(xy 191.628004 -244.943355) (xy 184.795424 -244.943355) (xy 184.787481 -244.996059) (xy 184.771771 -245.046989)
			(xy 184.748645 -245.09501) (xy 184.718621 -245.139047) (xy 184.682369 -245.178118) (xy 184.640698 -245.211349)
			(xy 184.59454 -245.237998) (xy 184.544926 -245.25747) (xy 184.492964 -245.26933) (xy 184.439814 -245.273314)
			(xy 184.386664 -245.26933) (xy 184.334702 -245.25747) (xy 184.285088 -245.237998) (xy 184.23893 -245.211349)
			(xy 184.197259 -245.178118) (xy 184.161007 -245.139047) (xy 184.130983 -245.09501) (xy 184.107857 -245.046989)
			(xy 184.092147 -244.996059) (xy 184.084204 -244.943355) (xy 177.251624 -244.943355) (xy 177.243681 -244.996059)
			(xy 177.227971 -245.046989) (xy 177.204845 -245.09501) (xy 177.174821 -245.139047) (xy 177.138569 -245.178118)
			(xy 177.096898 -245.211349) (xy 177.05074 -245.237998) (xy 177.001126 -245.25747) (xy 176.949164 -245.26933)
			(xy 176.896014 -245.273314) (xy 176.842864 -245.26933) (xy 176.790902 -245.25747) (xy 176.741288 -245.237998)
			(xy 176.69513 -245.211349) (xy 176.653459 -245.178118) (xy 176.617207 -245.139047) (xy 176.587183 -245.09501)
			(xy 176.564057 -245.046989) (xy 176.548347 -244.996059) (xy 176.540404 -244.943355) (xy 159.11576 -244.943355)
			(xy 159.11576 -245.793239) (xy 172.440336 -245.793239) (xy 172.440336 -245.739941) (xy 172.448279 -245.687237)
			(xy 172.463989 -245.636307) (xy 172.487115 -245.588286) (xy 172.517139 -245.544249) (xy 172.553391 -245.505178)
			(xy 172.595062 -245.471947) (xy 172.64122 -245.445298) (xy 172.690834 -245.425826) (xy 172.742796 -245.413966)
			(xy 172.795946 -245.409983) (xy 172.849096 -245.413966) (xy 172.901058 -245.425826) (xy 172.950672 -245.445298)
			(xy 172.99683 -245.471947) (xy 173.038501 -245.505178) (xy 173.074753 -245.544249) (xy 173.104777 -245.588286)
			(xy 173.127903 -245.636307) (xy 173.143613 -245.687237) (xy 173.151556 -245.739941) (xy 173.152054 -245.76659)
			(xy 173.151556 -245.793239) (xy 179.984136 -245.793239) (xy 179.984136 -245.739941) (xy 179.992079 -245.687237)
			(xy 180.007789 -245.636307) (xy 180.030915 -245.588286) (xy 180.060939 -245.544249) (xy 180.097191 -245.505178)
			(xy 180.138862 -245.471947) (xy 180.18502 -245.445298) (xy 180.234634 -245.425826) (xy 180.286596 -245.413966)
			(xy 180.339746 -245.409983) (xy 180.392896 -245.413966) (xy 180.444858 -245.425826) (xy 180.494472 -245.445298)
			(xy 180.54063 -245.471947) (xy 180.582301 -245.505178) (xy 180.618553 -245.544249) (xy 180.648577 -245.588286)
			(xy 180.671703 -245.636307) (xy 180.687413 -245.687237) (xy 180.695356 -245.739941) (xy 180.695854 -245.76659)
			(xy 180.695356 -245.793239) (xy 187.527936 -245.793239) (xy 187.527936 -245.739941) (xy 187.535879 -245.687237)
			(xy 187.551589 -245.636307) (xy 187.574715 -245.588286) (xy 187.604739 -245.544249) (xy 187.640991 -245.505178)
			(xy 187.682662 -245.471947) (xy 187.72882 -245.445298) (xy 187.778434 -245.425826) (xy 187.830396 -245.413966)
			(xy 187.883546 -245.409983) (xy 187.936696 -245.413966) (xy 187.988658 -245.425826) (xy 188.038272 -245.445298)
			(xy 188.08443 -245.471947) (xy 188.126101 -245.505178) (xy 188.162353 -245.544249) (xy 188.192377 -245.588286)
			(xy 188.215503 -245.636307) (xy 188.231213 -245.687237) (xy 188.239156 -245.739941) (xy 188.239654 -245.76659)
			(xy 188.239156 -245.793239) (xy 195.071736 -245.793239) (xy 195.071736 -245.739941) (xy 195.079679 -245.687237)
			(xy 195.095389 -245.636307) (xy 195.118515 -245.588286) (xy 195.148539 -245.544249) (xy 195.184791 -245.505178)
			(xy 195.226462 -245.471947) (xy 195.27262 -245.445298) (xy 195.322234 -245.425826) (xy 195.374196 -245.413966)
			(xy 195.427346 -245.409983) (xy 195.480496 -245.413966) (xy 195.532458 -245.425826) (xy 195.582072 -245.445298)
			(xy 195.62823 -245.471947) (xy 195.669901 -245.505178) (xy 195.706153 -245.544249) (xy 195.736177 -245.588286)
			(xy 195.759303 -245.636307) (xy 195.775013 -245.687237) (xy 195.782956 -245.739941) (xy 195.783454 -245.76659)
			(xy 195.782956 -245.793239) (xy 202.615536 -245.793239) (xy 202.615536 -245.739941) (xy 202.623479 -245.687237)
			(xy 202.639189 -245.636307) (xy 202.662315 -245.588286) (xy 202.692339 -245.544249) (xy 202.728591 -245.505178)
			(xy 202.770262 -245.471947) (xy 202.81642 -245.445298) (xy 202.866034 -245.425826) (xy 202.917996 -245.413966)
			(xy 202.971146 -245.409983) (xy 203.024296 -245.413966) (xy 203.076258 -245.425826) (xy 203.125872 -245.445298)
			(xy 203.17203 -245.471947) (xy 203.213701 -245.505178) (xy 203.249953 -245.544249) (xy 203.279977 -245.588286)
			(xy 203.303103 -245.636307) (xy 203.318813 -245.687237) (xy 203.326756 -245.739941) (xy 203.327254 -245.76659)
			(xy 203.326756 -245.793239) (xy 210.159336 -245.793239) (xy 210.159336 -245.739941) (xy 210.167279 -245.687237)
			(xy 210.182989 -245.636307) (xy 210.206115 -245.588286) (xy 210.236139 -245.544249) (xy 210.272391 -245.505178)
			(xy 210.314062 -245.471947) (xy 210.36022 -245.445298) (xy 210.409834 -245.425826) (xy 210.461796 -245.413966)
			(xy 210.514946 -245.409983) (xy 210.568096 -245.413966) (xy 210.620058 -245.425826) (xy 210.669672 -245.445298)
			(xy 210.71583 -245.471947) (xy 210.757501 -245.505178) (xy 210.793753 -245.544249) (xy 210.823777 -245.588286)
			(xy 210.846903 -245.636307) (xy 210.862613 -245.687237) (xy 210.870556 -245.739941) (xy 210.871054 -245.76659)
			(xy 210.870556 -245.793239) (xy 210.862613 -245.845943) (xy 210.846903 -245.896873) (xy 210.823777 -245.944894)
			(xy 210.793753 -245.988931) (xy 210.757501 -246.028002) (xy 210.71583 -246.061233) (xy 210.669672 -246.087882)
			(xy 210.620058 -246.107354) (xy 210.568096 -246.119214) (xy 210.514946 -246.123198) (xy 210.461796 -246.119214)
			(xy 210.409834 -246.107354) (xy 210.36022 -246.087882) (xy 210.314062 -246.061233) (xy 210.272391 -246.028002)
			(xy 210.236139 -245.988931) (xy 210.206115 -245.944894) (xy 210.182989 -245.896873) (xy 210.167279 -245.845943)
			(xy 210.159336 -245.793239) (xy 203.326756 -245.793239) (xy 203.318813 -245.845943) (xy 203.303103 -245.896873)
			(xy 203.279977 -245.944894) (xy 203.249953 -245.988931) (xy 203.213701 -246.028002) (xy 203.17203 -246.061233)
			(xy 203.125872 -246.087882) (xy 203.076258 -246.107354) (xy 203.024296 -246.119214) (xy 202.971146 -246.123198)
			(xy 202.917996 -246.119214) (xy 202.866034 -246.107354) (xy 202.81642 -246.087882) (xy 202.770262 -246.061233)
			(xy 202.728591 -246.028002) (xy 202.692339 -245.988931) (xy 202.662315 -245.944894) (xy 202.639189 -245.896873)
			(xy 202.623479 -245.845943) (xy 202.615536 -245.793239) (xy 195.782956 -245.793239) (xy 195.775013 -245.845943)
			(xy 195.759303 -245.896873) (xy 195.736177 -245.944894) (xy 195.706153 -245.988931) (xy 195.669901 -246.028002)
			(xy 195.62823 -246.061233) (xy 195.582072 -246.087882) (xy 195.532458 -246.107354) (xy 195.480496 -246.119214)
			(xy 195.427346 -246.123198) (xy 195.374196 -246.119214) (xy 195.322234 -246.107354) (xy 195.27262 -246.087882)
			(xy 195.226462 -246.061233) (xy 195.184791 -246.028002) (xy 195.148539 -245.988931) (xy 195.118515 -245.944894)
			(xy 195.095389 -245.896873) (xy 195.079679 -245.845943) (xy 195.071736 -245.793239) (xy 188.239156 -245.793239)
			(xy 188.231213 -245.845943) (xy 188.215503 -245.896873) (xy 188.192377 -245.944894) (xy 188.162353 -245.988931)
			(xy 188.126101 -246.028002) (xy 188.08443 -246.061233) (xy 188.038272 -246.087882) (xy 187.988658 -246.107354)
			(xy 187.936696 -246.119214) (xy 187.883546 -246.123198) (xy 187.830396 -246.119214) (xy 187.778434 -246.107354)
			(xy 187.72882 -246.087882) (xy 187.682662 -246.061233) (xy 187.640991 -246.028002) (xy 187.604739 -245.988931)
			(xy 187.574715 -245.944894) (xy 187.551589 -245.896873) (xy 187.535879 -245.845943) (xy 187.527936 -245.793239)
			(xy 180.695356 -245.793239) (xy 180.687413 -245.845943) (xy 180.671703 -245.896873) (xy 180.648577 -245.944894)
			(xy 180.618553 -245.988931) (xy 180.582301 -246.028002) (xy 180.54063 -246.061233) (xy 180.494472 -246.087882)
			(xy 180.444858 -246.107354) (xy 180.392896 -246.119214) (xy 180.339746 -246.123198) (xy 180.286596 -246.119214)
			(xy 180.234634 -246.107354) (xy 180.18502 -246.087882) (xy 180.138862 -246.061233) (xy 180.097191 -246.028002)
			(xy 180.060939 -245.988931) (xy 180.030915 -245.944894) (xy 180.007789 -245.896873) (xy 179.992079 -245.845943)
			(xy 179.984136 -245.793239) (xy 173.151556 -245.793239) (xy 173.143613 -245.845943) (xy 173.127903 -245.896873)
			(xy 173.104777 -245.944894) (xy 173.074753 -245.988931) (xy 173.038501 -246.028002) (xy 172.99683 -246.061233)
			(xy 172.950672 -246.087882) (xy 172.901058 -246.107354) (xy 172.849096 -246.119214) (xy 172.795946 -246.123198)
			(xy 172.742796 -246.119214) (xy 172.690834 -246.107354) (xy 172.64122 -246.087882) (xy 172.595062 -246.061233)
			(xy 172.553391 -246.028002) (xy 172.517139 -245.988931) (xy 172.487115 -245.944894) (xy 172.463989 -245.896873)
			(xy 172.448279 -245.845943) (xy 172.440336 -245.793239) (xy 159.11576 -245.793239) (xy 159.11576 -246.643377)
			(xy 176.540404 -246.643377) (xy 176.540404 -246.590079) (xy 176.548347 -246.537375) (xy 176.564057 -246.486445)
			(xy 176.587183 -246.438424) (xy 176.617207 -246.394387) (xy 176.653459 -246.355316) (xy 176.69513 -246.322085)
			(xy 176.741288 -246.295436) (xy 176.790902 -246.275964) (xy 176.842864 -246.264104) (xy 176.896014 -246.260121)
			(xy 176.949164 -246.264104) (xy 177.001126 -246.275964) (xy 177.05074 -246.295436) (xy 177.096898 -246.322085)
			(xy 177.138569 -246.355316) (xy 177.174821 -246.394387) (xy 177.204845 -246.438424) (xy 177.227971 -246.486445)
			(xy 177.243681 -246.537375) (xy 177.251624 -246.590079) (xy 177.252122 -246.616728) (xy 177.251624 -246.643377)
			(xy 191.602604 -246.643377) (xy 191.602604 -246.590079) (xy 191.610547 -246.537375) (xy 191.626257 -246.486445)
			(xy 191.649383 -246.438424) (xy 191.679407 -246.394387) (xy 191.715659 -246.355316) (xy 191.75733 -246.322085)
			(xy 191.803488 -246.295436) (xy 191.853102 -246.275964) (xy 191.905064 -246.264104) (xy 191.958214 -246.260121)
			(xy 192.011364 -246.264104) (xy 192.063326 -246.275964) (xy 192.11294 -246.295436) (xy 192.159098 -246.322085)
			(xy 192.200769 -246.355316) (xy 192.237021 -246.394387) (xy 192.267045 -246.438424) (xy 192.290171 -246.486445)
			(xy 192.305881 -246.537375) (xy 192.313824 -246.590079) (xy 192.314322 -246.616728) (xy 192.313824 -246.643377)
			(xy 206.715604 -246.643377) (xy 206.715604 -246.590079) (xy 206.723547 -246.537375) (xy 206.739257 -246.486445)
			(xy 206.762383 -246.438424) (xy 206.792407 -246.394387) (xy 206.828659 -246.355316) (xy 206.87033 -246.322085)
			(xy 206.916488 -246.295436) (xy 206.966102 -246.275964) (xy 207.018064 -246.264104) (xy 207.071214 -246.260121)
			(xy 207.124364 -246.264104) (xy 207.176326 -246.275964) (xy 207.22594 -246.295436) (xy 207.272098 -246.322085)
			(xy 207.313769 -246.355316) (xy 207.350021 -246.394387) (xy 207.380045 -246.438424) (xy 207.403171 -246.486445)
			(xy 207.418881 -246.537375) (xy 207.426824 -246.590079) (xy 207.427322 -246.616728) (xy 207.426824 -246.643377)
			(xy 207.418881 -246.696081) (xy 207.403171 -246.747011) (xy 207.380045 -246.795032) (xy 207.350021 -246.839069)
			(xy 207.313769 -246.87814) (xy 207.272098 -246.911371) (xy 207.22594 -246.93802) (xy 207.176326 -246.957492)
			(xy 207.124364 -246.969352) (xy 207.071214 -246.973336) (xy 207.018064 -246.969352) (xy 206.966102 -246.957492)
			(xy 206.916488 -246.93802) (xy 206.87033 -246.911371) (xy 206.828659 -246.87814) (xy 206.792407 -246.839069)
			(xy 206.762383 -246.795032) (xy 206.739257 -246.747011) (xy 206.723547 -246.696081) (xy 206.715604 -246.643377)
			(xy 192.313824 -246.643377) (xy 192.305881 -246.696081) (xy 192.290171 -246.747011) (xy 192.267045 -246.795032)
			(xy 192.237021 -246.839069) (xy 192.200769 -246.87814) (xy 192.159098 -246.911371) (xy 192.11294 -246.93802)
			(xy 192.063326 -246.957492) (xy 192.011364 -246.969352) (xy 191.958214 -246.973336) (xy 191.905064 -246.969352)
			(xy 191.853102 -246.957492) (xy 191.803488 -246.93802) (xy 191.75733 -246.911371) (xy 191.715659 -246.87814)
			(xy 191.679407 -246.839069) (xy 191.649383 -246.795032) (xy 191.626257 -246.747011) (xy 191.610547 -246.696081)
			(xy 191.602604 -246.643377) (xy 177.251624 -246.643377) (xy 177.243681 -246.696081) (xy 177.227971 -246.747011)
			(xy 177.204845 -246.795032) (xy 177.174821 -246.839069) (xy 177.138569 -246.87814) (xy 177.096898 -246.911371)
			(xy 177.05074 -246.93802) (xy 177.001126 -246.957492) (xy 176.949164 -246.969352) (xy 176.896014 -246.973336)
			(xy 176.842864 -246.969352) (xy 176.790902 -246.957492) (xy 176.741288 -246.93802) (xy 176.69513 -246.911371)
			(xy 176.653459 -246.87814) (xy 176.617207 -246.839069) (xy 176.587183 -246.795032) (xy 176.564057 -246.747011)
			(xy 176.548347 -246.696081) (xy 176.540404 -246.643377) (xy 159.11576 -246.643377) (xy 159.11576 -247.493261)
			(xy 172.440336 -247.493261) (xy 172.440336 -247.439963) (xy 172.448279 -247.387259) (xy 172.463989 -247.336329)
			(xy 172.487115 -247.288308) (xy 172.517139 -247.244271) (xy 172.553391 -247.2052) (xy 172.595062 -247.171969)
			(xy 172.64122 -247.14532) (xy 172.690834 -247.125848) (xy 172.742796 -247.113988) (xy 172.795946 -247.110005)
			(xy 172.849096 -247.113988) (xy 172.901058 -247.125848) (xy 172.950672 -247.14532) (xy 172.99683 -247.171969)
			(xy 173.038501 -247.2052) (xy 173.074753 -247.244271) (xy 173.104777 -247.288308) (xy 173.127903 -247.336329)
			(xy 173.143613 -247.387259) (xy 173.151556 -247.439963) (xy 173.152054 -247.466612) (xy 173.151556 -247.493261)
			(xy 187.527936 -247.493261) (xy 187.527936 -247.439963) (xy 187.535879 -247.387259) (xy 187.551589 -247.336329)
			(xy 187.574715 -247.288308) (xy 187.604739 -247.244271) (xy 187.640991 -247.2052) (xy 187.682662 -247.171969)
			(xy 187.72882 -247.14532) (xy 187.778434 -247.125848) (xy 187.830396 -247.113988) (xy 187.883546 -247.110005)
			(xy 187.936696 -247.113988) (xy 187.988658 -247.125848) (xy 188.038272 -247.14532) (xy 188.08443 -247.171969)
			(xy 188.126101 -247.2052) (xy 188.162353 -247.244271) (xy 188.192377 -247.288308) (xy 188.215503 -247.336329)
			(xy 188.231213 -247.387259) (xy 188.239156 -247.439963) (xy 188.239654 -247.466612) (xy 188.239156 -247.493261)
			(xy 202.615536 -247.493261) (xy 202.615536 -247.439963) (xy 202.623479 -247.387259) (xy 202.639189 -247.336329)
			(xy 202.662315 -247.288308) (xy 202.692339 -247.244271) (xy 202.728591 -247.2052) (xy 202.770262 -247.171969)
			(xy 202.81642 -247.14532) (xy 202.866034 -247.125848) (xy 202.917996 -247.113988) (xy 202.971146 -247.110005)
			(xy 203.024296 -247.113988) (xy 203.076258 -247.125848) (xy 203.125872 -247.14532) (xy 203.17203 -247.171969)
			(xy 203.213701 -247.2052) (xy 203.249953 -247.244271) (xy 203.279977 -247.288308) (xy 203.303103 -247.336329)
			(xy 203.318813 -247.387259) (xy 203.326756 -247.439963) (xy 203.327254 -247.466612) (xy 203.326756 -247.493261)
			(xy 203.318813 -247.545965) (xy 203.303103 -247.596895) (xy 203.279977 -247.644916) (xy 203.249953 -247.688953)
			(xy 203.213701 -247.728024) (xy 203.17203 -247.761255) (xy 203.125872 -247.787904) (xy 203.076258 -247.807376)
			(xy 203.024296 -247.819236) (xy 202.971146 -247.82322) (xy 202.917996 -247.819236) (xy 202.866034 -247.807376)
			(xy 202.81642 -247.787904) (xy 202.770262 -247.761255) (xy 202.728591 -247.728024) (xy 202.692339 -247.688953)
			(xy 202.662315 -247.644916) (xy 202.639189 -247.596895) (xy 202.623479 -247.545965) (xy 202.615536 -247.493261)
			(xy 188.239156 -247.493261) (xy 188.231213 -247.545965) (xy 188.215503 -247.596895) (xy 188.192377 -247.644916)
			(xy 188.162353 -247.688953) (xy 188.126101 -247.728024) (xy 188.08443 -247.761255) (xy 188.038272 -247.787904)
			(xy 187.988658 -247.807376) (xy 187.936696 -247.819236) (xy 187.883546 -247.82322) (xy 187.830396 -247.819236)
			(xy 187.778434 -247.807376) (xy 187.72882 -247.787904) (xy 187.682662 -247.761255) (xy 187.640991 -247.728024)
			(xy 187.604739 -247.688953) (xy 187.574715 -247.644916) (xy 187.551589 -247.596895) (xy 187.535879 -247.545965)
			(xy 187.527936 -247.493261) (xy 173.151556 -247.493261) (xy 173.143613 -247.545965) (xy 173.127903 -247.596895)
			(xy 173.104777 -247.644916) (xy 173.074753 -247.688953) (xy 173.038501 -247.728024) (xy 172.99683 -247.761255)
			(xy 172.950672 -247.787904) (xy 172.901058 -247.807376) (xy 172.849096 -247.819236) (xy 172.795946 -247.82322)
			(xy 172.742796 -247.819236) (xy 172.690834 -247.807376) (xy 172.64122 -247.787904) (xy 172.595062 -247.761255)
			(xy 172.553391 -247.728024) (xy 172.517139 -247.688953) (xy 172.487115 -247.644916) (xy 172.463989 -247.596895)
			(xy 172.448279 -247.545965) (xy 172.440336 -247.493261) (xy 159.11576 -247.493261) (xy 159.11576 -248.343399)
			(xy 176.540404 -248.343399) (xy 176.540404 -248.290101) (xy 176.548347 -248.237397) (xy 176.564057 -248.186467)
			(xy 176.587183 -248.138446) (xy 176.617207 -248.094409) (xy 176.653459 -248.055338) (xy 176.69513 -248.022107)
			(xy 176.741288 -247.995458) (xy 176.790902 -247.975986) (xy 176.842864 -247.964126) (xy 176.896014 -247.960143)
			(xy 176.949164 -247.964126) (xy 177.001126 -247.975986) (xy 177.05074 -247.995458) (xy 177.096898 -248.022107)
			(xy 177.138569 -248.055338) (xy 177.174821 -248.094409) (xy 177.204845 -248.138446) (xy 177.227971 -248.186467)
			(xy 177.243681 -248.237397) (xy 177.251624 -248.290101) (xy 177.252122 -248.31675) (xy 177.251624 -248.343399)
			(xy 191.628004 -248.343399) (xy 191.628004 -248.290101) (xy 191.635947 -248.237397) (xy 191.651657 -248.186467)
			(xy 191.674783 -248.138446) (xy 191.704807 -248.094409) (xy 191.741059 -248.055338) (xy 191.78273 -248.022107)
			(xy 191.828888 -247.995458) (xy 191.878502 -247.975986) (xy 191.930464 -247.964126) (xy 191.983614 -247.960143)
			(xy 192.036764 -247.964126) (xy 192.088726 -247.975986) (xy 192.13834 -247.995458) (xy 192.184498 -248.022107)
			(xy 192.226169 -248.055338) (xy 192.262421 -248.094409) (xy 192.292445 -248.138446) (xy 192.315571 -248.186467)
			(xy 192.331281 -248.237397) (xy 192.339224 -248.290101) (xy 192.339722 -248.31675) (xy 192.339224 -248.343399)
			(xy 206.715604 -248.343399) (xy 206.715604 -248.290101) (xy 206.723547 -248.237397) (xy 206.739257 -248.186467)
			(xy 206.762383 -248.138446) (xy 206.792407 -248.094409) (xy 206.828659 -248.055338) (xy 206.87033 -248.022107)
			(xy 206.916488 -247.995458) (xy 206.966102 -247.975986) (xy 207.018064 -247.964126) (xy 207.071214 -247.960143)
			(xy 207.124364 -247.964126) (xy 207.176326 -247.975986) (xy 207.22594 -247.995458) (xy 207.272098 -248.022107)
			(xy 207.313769 -248.055338) (xy 207.350021 -248.094409) (xy 207.380045 -248.138446) (xy 207.403171 -248.186467)
			(xy 207.418881 -248.237397) (xy 207.426824 -248.290101) (xy 207.427322 -248.31675) (xy 207.426824 -248.343399)
			(xy 207.418881 -248.396103) (xy 207.403171 -248.447033) (xy 207.380045 -248.495054) (xy 207.350021 -248.539091)
			(xy 207.313769 -248.578162) (xy 207.272098 -248.611393) (xy 207.22594 -248.638042) (xy 207.176326 -248.657514)
			(xy 207.124364 -248.669374) (xy 207.071214 -248.673358) (xy 207.018064 -248.669374) (xy 206.966102 -248.657514)
			(xy 206.916488 -248.638042) (xy 206.87033 -248.611393) (xy 206.828659 -248.578162) (xy 206.792407 -248.539091)
			(xy 206.762383 -248.495054) (xy 206.739257 -248.447033) (xy 206.723547 -248.396103) (xy 206.715604 -248.343399)
			(xy 192.339224 -248.343399) (xy 192.331281 -248.396103) (xy 192.315571 -248.447033) (xy 192.292445 -248.495054)
			(xy 192.262421 -248.539091) (xy 192.226169 -248.578162) (xy 192.184498 -248.611393) (xy 192.13834 -248.638042)
			(xy 192.088726 -248.657514) (xy 192.036764 -248.669374) (xy 191.983614 -248.673358) (xy 191.930464 -248.669374)
			(xy 191.878502 -248.657514) (xy 191.828888 -248.638042) (xy 191.78273 -248.611393) (xy 191.741059 -248.578162)
			(xy 191.704807 -248.539091) (xy 191.674783 -248.495054) (xy 191.651657 -248.447033) (xy 191.635947 -248.396103)
			(xy 191.628004 -248.343399) (xy 177.251624 -248.343399) (xy 177.243681 -248.396103) (xy 177.227971 -248.447033)
			(xy 177.204845 -248.495054) (xy 177.174821 -248.539091) (xy 177.138569 -248.578162) (xy 177.096898 -248.611393)
			(xy 177.05074 -248.638042) (xy 177.001126 -248.657514) (xy 176.949164 -248.669374) (xy 176.896014 -248.673358)
			(xy 176.842864 -248.669374) (xy 176.790902 -248.657514) (xy 176.741288 -248.638042) (xy 176.69513 -248.611393)
			(xy 176.653459 -248.578162) (xy 176.617207 -248.539091) (xy 176.587183 -248.495054) (xy 176.564057 -248.447033)
			(xy 176.548347 -248.396103) (xy 176.540404 -248.343399) (xy 159.11576 -248.343399) (xy 159.11576 -249.193283)
			(xy 172.440336 -249.193283) (xy 172.440336 -249.139985) (xy 172.448279 -249.087281) (xy 172.463989 -249.036351)
			(xy 172.487115 -248.98833) (xy 172.517139 -248.944293) (xy 172.553391 -248.905222) (xy 172.595062 -248.871991)
			(xy 172.64122 -248.845342) (xy 172.690834 -248.82587) (xy 172.742796 -248.81401) (xy 172.795946 -248.810027)
			(xy 172.849096 -248.81401) (xy 172.901058 -248.82587) (xy 172.950672 -248.845342) (xy 172.99683 -248.871991)
			(xy 173.038501 -248.905222) (xy 173.074753 -248.944293) (xy 173.104777 -248.98833) (xy 173.127903 -249.036351)
			(xy 173.143613 -249.087281) (xy 173.151556 -249.139985) (xy 173.152054 -249.166634) (xy 173.151556 -249.193283)
			(xy 187.527936 -249.193283) (xy 187.527936 -249.139985) (xy 187.535879 -249.087281) (xy 187.551589 -249.036351)
			(xy 187.574715 -248.98833) (xy 187.604739 -248.944293) (xy 187.640991 -248.905222) (xy 187.682662 -248.871991)
			(xy 187.72882 -248.845342) (xy 187.778434 -248.82587) (xy 187.830396 -248.81401) (xy 187.883546 -248.810027)
			(xy 187.936696 -248.81401) (xy 187.988658 -248.82587) (xy 188.038272 -248.845342) (xy 188.08443 -248.871991)
			(xy 188.126101 -248.905222) (xy 188.162353 -248.944293) (xy 188.192377 -248.98833) (xy 188.215503 -249.036351)
			(xy 188.231213 -249.087281) (xy 188.239156 -249.139985) (xy 188.239654 -249.166634) (xy 188.239156 -249.193283)
			(xy 202.615536 -249.193283) (xy 202.615536 -249.139985) (xy 202.623479 -249.087281) (xy 202.639189 -249.036351)
			(xy 202.662315 -248.98833) (xy 202.692339 -248.944293) (xy 202.728591 -248.905222) (xy 202.770262 -248.871991)
			(xy 202.81642 -248.845342) (xy 202.866034 -248.82587) (xy 202.917996 -248.81401) (xy 202.971146 -248.810027)
			(xy 203.024296 -248.81401) (xy 203.076258 -248.82587) (xy 203.125872 -248.845342) (xy 203.17203 -248.871991)
			(xy 203.213701 -248.905222) (xy 203.249953 -248.944293) (xy 203.279977 -248.98833) (xy 203.303103 -249.036351)
			(xy 203.318813 -249.087281) (xy 203.326756 -249.139985) (xy 203.327254 -249.166634) (xy 203.326756 -249.193283)
			(xy 203.318813 -249.245987) (xy 203.303103 -249.296917) (xy 203.279977 -249.344938) (xy 203.249953 -249.388975)
			(xy 203.213701 -249.428046) (xy 203.17203 -249.461277) (xy 203.125872 -249.487926) (xy 203.076258 -249.507398)
			(xy 203.024296 -249.519258) (xy 202.971146 -249.523242) (xy 202.917996 -249.519258) (xy 202.866034 -249.507398)
			(xy 202.81642 -249.487926) (xy 202.770262 -249.461277) (xy 202.728591 -249.428046) (xy 202.692339 -249.388975)
			(xy 202.662315 -249.344938) (xy 202.639189 -249.296917) (xy 202.623479 -249.245987) (xy 202.615536 -249.193283)
			(xy 188.239156 -249.193283) (xy 188.231213 -249.245987) (xy 188.215503 -249.296917) (xy 188.192377 -249.344938)
			(xy 188.162353 -249.388975) (xy 188.126101 -249.428046) (xy 188.08443 -249.461277) (xy 188.038272 -249.487926)
			(xy 187.988658 -249.507398) (xy 187.936696 -249.519258) (xy 187.883546 -249.523242) (xy 187.830396 -249.519258)
			(xy 187.778434 -249.507398) (xy 187.72882 -249.487926) (xy 187.682662 -249.461277) (xy 187.640991 -249.428046)
			(xy 187.604739 -249.388975) (xy 187.574715 -249.344938) (xy 187.551589 -249.296917) (xy 187.535879 -249.245987)
			(xy 187.527936 -249.193283) (xy 173.151556 -249.193283) (xy 173.143613 -249.245987) (xy 173.127903 -249.296917)
			(xy 173.104777 -249.344938) (xy 173.074753 -249.388975) (xy 173.038501 -249.428046) (xy 172.99683 -249.461277)
			(xy 172.950672 -249.487926) (xy 172.901058 -249.507398) (xy 172.849096 -249.519258) (xy 172.795946 -249.523242)
			(xy 172.742796 -249.519258) (xy 172.690834 -249.507398) (xy 172.64122 -249.487926) (xy 172.595062 -249.461277)
			(xy 172.553391 -249.428046) (xy 172.517139 -249.388975) (xy 172.487115 -249.344938) (xy 172.463989 -249.296917)
			(xy 172.448279 -249.245987) (xy 172.440336 -249.193283) (xy 159.11576 -249.193283) (xy 159.11576 -250.043421)
			(xy 176.540404 -250.043421) (xy 176.540404 -249.990123) (xy 176.548347 -249.937419) (xy 176.564057 -249.886489)
			(xy 176.587183 -249.838468) (xy 176.617207 -249.794431) (xy 176.653459 -249.75536) (xy 176.69513 -249.722129)
			(xy 176.741288 -249.69548) (xy 176.790902 -249.676008) (xy 176.842864 -249.664148) (xy 176.896014 -249.660165)
			(xy 176.949164 -249.664148) (xy 177.001126 -249.676008) (xy 177.05074 -249.69548) (xy 177.096898 -249.722129)
			(xy 177.138569 -249.75536) (xy 177.174821 -249.794431) (xy 177.204845 -249.838468) (xy 177.227971 -249.886489)
			(xy 177.243681 -249.937419) (xy 177.251624 -249.990123) (xy 177.252122 -250.016772) (xy 177.251624 -250.043421)
			(xy 191.628004 -250.043421) (xy 191.628004 -249.990123) (xy 191.635947 -249.937419) (xy 191.651657 -249.886489)
			(xy 191.674783 -249.838468) (xy 191.704807 -249.794431) (xy 191.741059 -249.75536) (xy 191.78273 -249.722129)
			(xy 191.828888 -249.69548) (xy 191.878502 -249.676008) (xy 191.930464 -249.664148) (xy 191.983614 -249.660165)
			(xy 192.036764 -249.664148) (xy 192.088726 -249.676008) (xy 192.13834 -249.69548) (xy 192.184498 -249.722129)
			(xy 192.226169 -249.75536) (xy 192.262421 -249.794431) (xy 192.292445 -249.838468) (xy 192.315571 -249.886489)
			(xy 192.331281 -249.937419) (xy 192.339224 -249.990123) (xy 192.339722 -250.016772) (xy 192.339224 -250.043421)
			(xy 206.715604 -250.043421) (xy 206.715604 -249.990123) (xy 206.723547 -249.937419) (xy 206.739257 -249.886489)
			(xy 206.762383 -249.838468) (xy 206.792407 -249.794431) (xy 206.828659 -249.75536) (xy 206.87033 -249.722129)
			(xy 206.916488 -249.69548) (xy 206.966102 -249.676008) (xy 207.018064 -249.664148) (xy 207.071214 -249.660165)
			(xy 207.124364 -249.664148) (xy 207.176326 -249.676008) (xy 207.22594 -249.69548) (xy 207.272098 -249.722129)
			(xy 207.313769 -249.75536) (xy 207.350021 -249.794431) (xy 207.380045 -249.838468) (xy 207.403171 -249.886489)
			(xy 207.418881 -249.937419) (xy 207.426824 -249.990123) (xy 207.427322 -250.016772) (xy 207.426824 -250.043421)
			(xy 207.418881 -250.096125) (xy 207.403171 -250.147055) (xy 207.380045 -250.195076) (xy 207.350021 -250.239113)
			(xy 207.313769 -250.278184) (xy 207.272098 -250.311415) (xy 207.22594 -250.338064) (xy 207.176326 -250.357536)
			(xy 207.124364 -250.369396) (xy 207.071214 -250.37338) (xy 207.018064 -250.369396) (xy 206.966102 -250.357536)
			(xy 206.916488 -250.338064) (xy 206.87033 -250.311415) (xy 206.828659 -250.278184) (xy 206.792407 -250.239113)
			(xy 206.762383 -250.195076) (xy 206.739257 -250.147055) (xy 206.723547 -250.096125) (xy 206.715604 -250.043421)
			(xy 192.339224 -250.043421) (xy 192.331281 -250.096125) (xy 192.315571 -250.147055) (xy 192.292445 -250.195076)
			(xy 192.262421 -250.239113) (xy 192.226169 -250.278184) (xy 192.184498 -250.311415) (xy 192.13834 -250.338064)
			(xy 192.088726 -250.357536) (xy 192.036764 -250.369396) (xy 191.983614 -250.37338) (xy 191.930464 -250.369396)
			(xy 191.878502 -250.357536) (xy 191.828888 -250.338064) (xy 191.78273 -250.311415) (xy 191.741059 -250.278184)
			(xy 191.704807 -250.239113) (xy 191.674783 -250.195076) (xy 191.651657 -250.147055) (xy 191.635947 -250.096125)
			(xy 191.628004 -250.043421) (xy 177.251624 -250.043421) (xy 177.243681 -250.096125) (xy 177.227971 -250.147055)
			(xy 177.204845 -250.195076) (xy 177.174821 -250.239113) (xy 177.138569 -250.278184) (xy 177.096898 -250.311415)
			(xy 177.05074 -250.338064) (xy 177.001126 -250.357536) (xy 176.949164 -250.369396) (xy 176.896014 -250.37338)
			(xy 176.842864 -250.369396) (xy 176.790902 -250.357536) (xy 176.741288 -250.338064) (xy 176.69513 -250.311415)
			(xy 176.653459 -250.278184) (xy 176.617207 -250.239113) (xy 176.587183 -250.195076) (xy 176.564057 -250.147055)
			(xy 176.548347 -250.096125) (xy 176.540404 -250.043421) (xy 159.11576 -250.043421) (xy 159.11576 -250.893305)
			(xy 172.440336 -250.893305) (xy 172.440336 -250.840007) (xy 172.448279 -250.787303) (xy 172.463989 -250.736373)
			(xy 172.487115 -250.688352) (xy 172.517139 -250.644315) (xy 172.553391 -250.605244) (xy 172.595062 -250.572013)
			(xy 172.64122 -250.545364) (xy 172.690834 -250.525892) (xy 172.742796 -250.514032) (xy 172.795946 -250.510049)
			(xy 172.849096 -250.514032) (xy 172.901058 -250.525892) (xy 172.950672 -250.545364) (xy 172.99683 -250.572013)
			(xy 173.038501 -250.605244) (xy 173.074753 -250.644315) (xy 173.104777 -250.688352) (xy 173.127903 -250.736373)
			(xy 173.143613 -250.787303) (xy 173.151556 -250.840007) (xy 173.152054 -250.866656) (xy 173.151556 -250.893305)
			(xy 187.527936 -250.893305) (xy 187.527936 -250.840007) (xy 187.535879 -250.787303) (xy 187.551589 -250.736373)
			(xy 187.574715 -250.688352) (xy 187.604739 -250.644315) (xy 187.640991 -250.605244) (xy 187.682662 -250.572013)
			(xy 187.72882 -250.545364) (xy 187.778434 -250.525892) (xy 187.830396 -250.514032) (xy 187.883546 -250.510049)
			(xy 187.936696 -250.514032) (xy 187.988658 -250.525892) (xy 188.038272 -250.545364) (xy 188.08443 -250.572013)
			(xy 188.126101 -250.605244) (xy 188.162353 -250.644315) (xy 188.192377 -250.688352) (xy 188.215503 -250.736373)
			(xy 188.231213 -250.787303) (xy 188.239156 -250.840007) (xy 188.239654 -250.866656) (xy 188.239156 -250.893305)
			(xy 202.615536 -250.893305) (xy 202.615536 -250.840007) (xy 202.623479 -250.787303) (xy 202.639189 -250.736373)
			(xy 202.662315 -250.688352) (xy 202.692339 -250.644315) (xy 202.728591 -250.605244) (xy 202.770262 -250.572013)
			(xy 202.81642 -250.545364) (xy 202.866034 -250.525892) (xy 202.917996 -250.514032) (xy 202.971146 -250.510049)
			(xy 203.024296 -250.514032) (xy 203.076258 -250.525892) (xy 203.125872 -250.545364) (xy 203.17203 -250.572013)
			(xy 203.213701 -250.605244) (xy 203.249953 -250.644315) (xy 203.279977 -250.688352) (xy 203.303103 -250.736373)
			(xy 203.318813 -250.787303) (xy 203.326756 -250.840007) (xy 203.327254 -250.866656) (xy 203.326756 -250.893305)
			(xy 203.318813 -250.946009) (xy 203.303103 -250.996939) (xy 203.279977 -251.04496) (xy 203.249953 -251.088997)
			(xy 203.213701 -251.128068) (xy 203.17203 -251.161299) (xy 203.125872 -251.187948) (xy 203.076258 -251.20742)
			(xy 203.024296 -251.21928) (xy 202.971146 -251.223264) (xy 202.917996 -251.21928) (xy 202.866034 -251.20742)
			(xy 202.81642 -251.187948) (xy 202.770262 -251.161299) (xy 202.728591 -251.128068) (xy 202.692339 -251.088997)
			(xy 202.662315 -251.04496) (xy 202.639189 -250.996939) (xy 202.623479 -250.946009) (xy 202.615536 -250.893305)
			(xy 188.239156 -250.893305) (xy 188.231213 -250.946009) (xy 188.215503 -250.996939) (xy 188.192377 -251.04496)
			(xy 188.162353 -251.088997) (xy 188.126101 -251.128068) (xy 188.08443 -251.161299) (xy 188.038272 -251.187948)
			(xy 187.988658 -251.20742) (xy 187.936696 -251.21928) (xy 187.883546 -251.223264) (xy 187.830396 -251.21928)
			(xy 187.778434 -251.20742) (xy 187.72882 -251.187948) (xy 187.682662 -251.161299) (xy 187.640991 -251.128068)
			(xy 187.604739 -251.088997) (xy 187.574715 -251.04496) (xy 187.551589 -250.996939) (xy 187.535879 -250.946009)
			(xy 187.527936 -250.893305) (xy 173.151556 -250.893305) (xy 173.143613 -250.946009) (xy 173.127903 -250.996939)
			(xy 173.104777 -251.04496) (xy 173.074753 -251.088997) (xy 173.038501 -251.128068) (xy 172.99683 -251.161299)
			(xy 172.950672 -251.187948) (xy 172.901058 -251.20742) (xy 172.849096 -251.21928) (xy 172.795946 -251.223264)
			(xy 172.742796 -251.21928) (xy 172.690834 -251.20742) (xy 172.64122 -251.187948) (xy 172.595062 -251.161299)
			(xy 172.553391 -251.128068) (xy 172.517139 -251.088997) (xy 172.487115 -251.04496) (xy 172.463989 -250.996939)
			(xy 172.448279 -250.946009) (xy 172.440336 -250.893305) (xy 159.11576 -250.893305) (xy 159.11576 -251.743443)
			(xy 176.540404 -251.743443) (xy 176.540404 -251.690145) (xy 176.548347 -251.637441) (xy 176.564057 -251.586511)
			(xy 176.587183 -251.53849) (xy 176.617207 -251.494453) (xy 176.653459 -251.455382) (xy 176.69513 -251.422151)
			(xy 176.741288 -251.395502) (xy 176.790902 -251.37603) (xy 176.842864 -251.36417) (xy 176.896014 -251.360187)
			(xy 176.949164 -251.36417) (xy 177.001126 -251.37603) (xy 177.05074 -251.395502) (xy 177.096898 -251.422151)
			(xy 177.138569 -251.455382) (xy 177.174821 -251.494453) (xy 177.204845 -251.53849) (xy 177.227971 -251.586511)
			(xy 177.243681 -251.637441) (xy 177.251624 -251.690145) (xy 177.252122 -251.716794) (xy 177.251624 -251.743443)
			(xy 191.628004 -251.743443) (xy 191.628004 -251.690145) (xy 191.635947 -251.637441) (xy 191.651657 -251.586511)
			(xy 191.674783 -251.53849) (xy 191.704807 -251.494453) (xy 191.741059 -251.455382) (xy 191.78273 -251.422151)
			(xy 191.828888 -251.395502) (xy 191.878502 -251.37603) (xy 191.930464 -251.36417) (xy 191.983614 -251.360187)
			(xy 192.036764 -251.36417) (xy 192.088726 -251.37603) (xy 192.13834 -251.395502) (xy 192.184498 -251.422151)
			(xy 192.226169 -251.455382) (xy 192.262421 -251.494453) (xy 192.292445 -251.53849) (xy 192.315571 -251.586511)
			(xy 192.331281 -251.637441) (xy 192.339224 -251.690145) (xy 192.339722 -251.716794) (xy 192.339224 -251.743443)
			(xy 206.715604 -251.743443) (xy 206.715604 -251.690145) (xy 206.723547 -251.637441) (xy 206.739257 -251.586511)
			(xy 206.762383 -251.53849) (xy 206.792407 -251.494453) (xy 206.828659 -251.455382) (xy 206.87033 -251.422151)
			(xy 206.916488 -251.395502) (xy 206.966102 -251.37603) (xy 207.018064 -251.36417) (xy 207.071214 -251.360187)
			(xy 207.124364 -251.36417) (xy 207.176326 -251.37603) (xy 207.22594 -251.395502) (xy 207.272098 -251.422151)
			(xy 207.313769 -251.455382) (xy 207.350021 -251.494453) (xy 207.380045 -251.53849) (xy 207.403171 -251.586511)
			(xy 207.418881 -251.637441) (xy 207.426824 -251.690145) (xy 207.427322 -251.716794) (xy 207.426824 -251.743443)
			(xy 207.418881 -251.796147) (xy 207.403171 -251.847077) (xy 207.380045 -251.895098) (xy 207.350021 -251.939135)
			(xy 207.313769 -251.978206) (xy 207.272098 -252.011437) (xy 207.22594 -252.038086) (xy 207.176326 -252.057558)
			(xy 207.124364 -252.069418) (xy 207.071214 -252.073402) (xy 207.018064 -252.069418) (xy 206.966102 -252.057558)
			(xy 206.916488 -252.038086) (xy 206.87033 -252.011437) (xy 206.828659 -251.978206) (xy 206.792407 -251.939135)
			(xy 206.762383 -251.895098) (xy 206.739257 -251.847077) (xy 206.723547 -251.796147) (xy 206.715604 -251.743443)
			(xy 192.339224 -251.743443) (xy 192.331281 -251.796147) (xy 192.315571 -251.847077) (xy 192.292445 -251.895098)
			(xy 192.262421 -251.939135) (xy 192.226169 -251.978206) (xy 192.184498 -252.011437) (xy 192.13834 -252.038086)
			(xy 192.088726 -252.057558) (xy 192.036764 -252.069418) (xy 191.983614 -252.073402) (xy 191.930464 -252.069418)
			(xy 191.878502 -252.057558) (xy 191.828888 -252.038086) (xy 191.78273 -252.011437) (xy 191.741059 -251.978206)
			(xy 191.704807 -251.939135) (xy 191.674783 -251.895098) (xy 191.651657 -251.847077) (xy 191.635947 -251.796147)
			(xy 191.628004 -251.743443) (xy 177.251624 -251.743443) (xy 177.243681 -251.796147) (xy 177.227971 -251.847077)
			(xy 177.204845 -251.895098) (xy 177.174821 -251.939135) (xy 177.138569 -251.978206) (xy 177.096898 -252.011437)
			(xy 177.05074 -252.038086) (xy 177.001126 -252.057558) (xy 176.949164 -252.069418) (xy 176.896014 -252.073402)
			(xy 176.842864 -252.069418) (xy 176.790902 -252.057558) (xy 176.741288 -252.038086) (xy 176.69513 -252.011437)
			(xy 176.653459 -251.978206) (xy 176.617207 -251.939135) (xy 176.587183 -251.895098) (xy 176.564057 -251.847077)
			(xy 176.548347 -251.796147) (xy 176.540404 -251.743443) (xy 159.11576 -251.743443) (xy 159.11576 -252.593327)
			(xy 172.440336 -252.593327) (xy 172.440336 -252.540029) (xy 172.448279 -252.487325) (xy 172.463989 -252.436395)
			(xy 172.487115 -252.388374) (xy 172.517139 -252.344337) (xy 172.553391 -252.305266) (xy 172.595062 -252.272035)
			(xy 172.64122 -252.245386) (xy 172.690834 -252.225914) (xy 172.742796 -252.214054) (xy 172.795946 -252.210071)
			(xy 172.849096 -252.214054) (xy 172.901058 -252.225914) (xy 172.950672 -252.245386) (xy 172.99683 -252.272035)
			(xy 173.038501 -252.305266) (xy 173.074753 -252.344337) (xy 173.104777 -252.388374) (xy 173.127903 -252.436395)
			(xy 173.143613 -252.487325) (xy 173.151556 -252.540029) (xy 173.152054 -252.566678) (xy 173.151556 -252.593327)
			(xy 176.540404 -252.593327) (xy 176.540404 -252.540029) (xy 176.548347 -252.487325) (xy 176.564057 -252.436395)
			(xy 176.587183 -252.388374) (xy 176.617207 -252.344337) (xy 176.653459 -252.305266) (xy 176.69513 -252.272035)
			(xy 176.741288 -252.245386) (xy 176.790902 -252.225914) (xy 176.842864 -252.214054) (xy 176.896014 -252.210071)
			(xy 176.949164 -252.214054) (xy 177.001126 -252.225914) (xy 177.05074 -252.245386) (xy 177.096898 -252.272035)
			(xy 177.138569 -252.305266) (xy 177.174821 -252.344337) (xy 177.204845 -252.388374) (xy 177.227971 -252.436395)
			(xy 177.243681 -252.487325) (xy 177.251624 -252.540029) (xy 177.252122 -252.566678) (xy 177.251624 -252.593327)
			(xy 184.058804 -252.593327) (xy 184.058804 -252.540029) (xy 184.066747 -252.487325) (xy 184.082457 -252.436395)
			(xy 184.105583 -252.388374) (xy 184.135607 -252.344337) (xy 184.171859 -252.305266) (xy 184.21353 -252.272035)
			(xy 184.259688 -252.245386) (xy 184.309302 -252.225914) (xy 184.361264 -252.214054) (xy 184.414414 -252.210071)
			(xy 184.467564 -252.214054) (xy 184.519526 -252.225914) (xy 184.56914 -252.245386) (xy 184.615298 -252.272035)
			(xy 184.656969 -252.305266) (xy 184.693221 -252.344337) (xy 184.723245 -252.388374) (xy 184.746371 -252.436395)
			(xy 184.762081 -252.487325) (xy 184.770024 -252.540029) (xy 184.770522 -252.566678) (xy 184.770024 -252.593327)
			(xy 187.527936 -252.593327) (xy 187.527936 -252.540029) (xy 187.535879 -252.487325) (xy 187.551589 -252.436395)
			(xy 187.574715 -252.388374) (xy 187.604739 -252.344337) (xy 187.640991 -252.305266) (xy 187.682662 -252.272035)
			(xy 187.72882 -252.245386) (xy 187.778434 -252.225914) (xy 187.830396 -252.214054) (xy 187.883546 -252.210071)
			(xy 187.936696 -252.214054) (xy 187.988658 -252.225914) (xy 188.038272 -252.245386) (xy 188.08443 -252.272035)
			(xy 188.126101 -252.305266) (xy 188.162353 -252.344337) (xy 188.192377 -252.388374) (xy 188.215503 -252.436395)
			(xy 188.231213 -252.487325) (xy 188.239156 -252.540029) (xy 188.239654 -252.566678) (xy 188.239156 -252.593327)
			(xy 191.628004 -252.593327) (xy 191.628004 -252.540029) (xy 191.635947 -252.487325) (xy 191.651657 -252.436395)
			(xy 191.674783 -252.388374) (xy 191.704807 -252.344337) (xy 191.741059 -252.305266) (xy 191.78273 -252.272035)
			(xy 191.828888 -252.245386) (xy 191.878502 -252.225914) (xy 191.930464 -252.214054) (xy 191.983614 -252.210071)
			(xy 192.036764 -252.214054) (xy 192.088726 -252.225914) (xy 192.13834 -252.245386) (xy 192.184498 -252.272035)
			(xy 192.226169 -252.305266) (xy 192.262421 -252.344337) (xy 192.292445 -252.388374) (xy 192.315571 -252.436395)
			(xy 192.331281 -252.487325) (xy 192.339224 -252.540029) (xy 192.339722 -252.566678) (xy 192.339224 -252.593327)
			(xy 199.171804 -252.593327) (xy 199.171804 -252.540029) (xy 199.179747 -252.487325) (xy 199.195457 -252.436395)
			(xy 199.218583 -252.388374) (xy 199.248607 -252.344337) (xy 199.284859 -252.305266) (xy 199.32653 -252.272035)
			(xy 199.372688 -252.245386) (xy 199.422302 -252.225914) (xy 199.474264 -252.214054) (xy 199.527414 -252.210071)
			(xy 199.580564 -252.214054) (xy 199.632526 -252.225914) (xy 199.68214 -252.245386) (xy 199.728298 -252.272035)
			(xy 199.769969 -252.305266) (xy 199.806221 -252.344337) (xy 199.836245 -252.388374) (xy 199.859371 -252.436395)
			(xy 199.875081 -252.487325) (xy 199.883024 -252.540029) (xy 199.883522 -252.566678) (xy 199.883024 -252.593327)
			(xy 202.615536 -252.593327) (xy 202.615536 -252.540029) (xy 202.623479 -252.487325) (xy 202.639189 -252.436395)
			(xy 202.662315 -252.388374) (xy 202.692339 -252.344337) (xy 202.728591 -252.305266) (xy 202.770262 -252.272035)
			(xy 202.81642 -252.245386) (xy 202.866034 -252.225914) (xy 202.917996 -252.214054) (xy 202.971146 -252.210071)
			(xy 203.024296 -252.214054) (xy 203.076258 -252.225914) (xy 203.125872 -252.245386) (xy 203.17203 -252.272035)
			(xy 203.213701 -252.305266) (xy 203.249953 -252.344337) (xy 203.279977 -252.388374) (xy 203.303103 -252.436395)
			(xy 203.318813 -252.487325) (xy 203.326756 -252.540029) (xy 203.327254 -252.566678) (xy 203.326756 -252.593327)
			(xy 206.715604 -252.593327) (xy 206.715604 -252.540029) (xy 206.723547 -252.487325) (xy 206.739257 -252.436395)
			(xy 206.762383 -252.388374) (xy 206.792407 -252.344337) (xy 206.828659 -252.305266) (xy 206.87033 -252.272035)
			(xy 206.916488 -252.245386) (xy 206.966102 -252.225914) (xy 207.018064 -252.214054) (xy 207.071214 -252.210071)
			(xy 207.124364 -252.214054) (xy 207.176326 -252.225914) (xy 207.22594 -252.245386) (xy 207.272098 -252.272035)
			(xy 207.313769 -252.305266) (xy 207.350021 -252.344337) (xy 207.380045 -252.388374) (xy 207.403171 -252.436395)
			(xy 207.418881 -252.487325) (xy 207.426824 -252.540029) (xy 207.427322 -252.566678) (xy 207.426824 -252.593327)
			(xy 214.234004 -252.593327) (xy 214.234004 -252.540029) (xy 214.241947 -252.487325) (xy 214.257657 -252.436395)
			(xy 214.280783 -252.388374) (xy 214.310807 -252.344337) (xy 214.347059 -252.305266) (xy 214.38873 -252.272035)
			(xy 214.434888 -252.245386) (xy 214.484502 -252.225914) (xy 214.536464 -252.214054) (xy 214.589614 -252.210071)
			(xy 214.642764 -252.214054) (xy 214.694726 -252.225914) (xy 214.74434 -252.245386) (xy 214.790498 -252.272035)
			(xy 214.832169 -252.305266) (xy 214.868421 -252.344337) (xy 214.898445 -252.388374) (xy 214.921571 -252.436395)
			(xy 214.937281 -252.487325) (xy 214.945224 -252.540029) (xy 214.945722 -252.566678) (xy 214.945224 -252.593327)
			(xy 214.937281 -252.646031) (xy 214.921571 -252.696961) (xy 214.898445 -252.744982) (xy 214.868421 -252.789019)
			(xy 214.832169 -252.82809) (xy 214.790498 -252.861321) (xy 214.74434 -252.88797) (xy 214.694726 -252.907442)
			(xy 214.642764 -252.919302) (xy 214.589614 -252.923286) (xy 214.536464 -252.919302) (xy 214.484502 -252.907442)
			(xy 214.434888 -252.88797) (xy 214.38873 -252.861321) (xy 214.347059 -252.82809) (xy 214.310807 -252.789019)
			(xy 214.280783 -252.744982) (xy 214.257657 -252.696961) (xy 214.241947 -252.646031) (xy 214.234004 -252.593327)
			(xy 207.426824 -252.593327) (xy 207.418881 -252.646031) (xy 207.403171 -252.696961) (xy 207.380045 -252.744982)
			(xy 207.350021 -252.789019) (xy 207.313769 -252.82809) (xy 207.272098 -252.861321) (xy 207.22594 -252.88797)
			(xy 207.176326 -252.907442) (xy 207.124364 -252.919302) (xy 207.071214 -252.923286) (xy 207.018064 -252.919302)
			(xy 206.966102 -252.907442) (xy 206.916488 -252.88797) (xy 206.87033 -252.861321) (xy 206.828659 -252.82809)
			(xy 206.792407 -252.789019) (xy 206.762383 -252.744982) (xy 206.739257 -252.696961) (xy 206.723547 -252.646031)
			(xy 206.715604 -252.593327) (xy 203.326756 -252.593327) (xy 203.318813 -252.646031) (xy 203.303103 -252.696961)
			(xy 203.279977 -252.744982) (xy 203.249953 -252.789019) (xy 203.213701 -252.82809) (xy 203.17203 -252.861321)
			(xy 203.125872 -252.88797) (xy 203.076258 -252.907442) (xy 203.024296 -252.919302) (xy 202.971146 -252.923286)
			(xy 202.917996 -252.919302) (xy 202.866034 -252.907442) (xy 202.81642 -252.88797) (xy 202.770262 -252.861321)
			(xy 202.728591 -252.82809) (xy 202.692339 -252.789019) (xy 202.662315 -252.744982) (xy 202.639189 -252.696961)
			(xy 202.623479 -252.646031) (xy 202.615536 -252.593327) (xy 199.883024 -252.593327) (xy 199.875081 -252.646031)
			(xy 199.859371 -252.696961) (xy 199.836245 -252.744982) (xy 199.806221 -252.789019) (xy 199.769969 -252.82809)
			(xy 199.728298 -252.861321) (xy 199.68214 -252.88797) (xy 199.632526 -252.907442) (xy 199.580564 -252.919302)
			(xy 199.527414 -252.923286) (xy 199.474264 -252.919302) (xy 199.422302 -252.907442) (xy 199.372688 -252.88797)
			(xy 199.32653 -252.861321) (xy 199.284859 -252.82809) (xy 199.248607 -252.789019) (xy 199.218583 -252.744982)
			(xy 199.195457 -252.696961) (xy 199.179747 -252.646031) (xy 199.171804 -252.593327) (xy 192.339224 -252.593327)
			(xy 192.331281 -252.646031) (xy 192.315571 -252.696961) (xy 192.292445 -252.744982) (xy 192.262421 -252.789019)
			(xy 192.226169 -252.82809) (xy 192.184498 -252.861321) (xy 192.13834 -252.88797) (xy 192.088726 -252.907442)
			(xy 192.036764 -252.919302) (xy 191.983614 -252.923286) (xy 191.930464 -252.919302) (xy 191.878502 -252.907442)
			(xy 191.828888 -252.88797) (xy 191.78273 -252.861321) (xy 191.741059 -252.82809) (xy 191.704807 -252.789019)
			(xy 191.674783 -252.744982) (xy 191.651657 -252.696961) (xy 191.635947 -252.646031) (xy 191.628004 -252.593327)
			(xy 188.239156 -252.593327) (xy 188.231213 -252.646031) (xy 188.215503 -252.696961) (xy 188.192377 -252.744982)
			(xy 188.162353 -252.789019) (xy 188.126101 -252.82809) (xy 188.08443 -252.861321) (xy 188.038272 -252.88797)
			(xy 187.988658 -252.907442) (xy 187.936696 -252.919302) (xy 187.883546 -252.923286) (xy 187.830396 -252.919302)
			(xy 187.778434 -252.907442) (xy 187.72882 -252.88797) (xy 187.682662 -252.861321) (xy 187.640991 -252.82809)
			(xy 187.604739 -252.789019) (xy 187.574715 -252.744982) (xy 187.551589 -252.696961) (xy 187.535879 -252.646031)
			(xy 187.527936 -252.593327) (xy 184.770024 -252.593327) (xy 184.762081 -252.646031) (xy 184.746371 -252.696961)
			(xy 184.723245 -252.744982) (xy 184.693221 -252.789019) (xy 184.656969 -252.82809) (xy 184.615298 -252.861321)
			(xy 184.56914 -252.88797) (xy 184.519526 -252.907442) (xy 184.467564 -252.919302) (xy 184.414414 -252.923286)
			(xy 184.361264 -252.919302) (xy 184.309302 -252.907442) (xy 184.259688 -252.88797) (xy 184.21353 -252.861321)
			(xy 184.171859 -252.82809) (xy 184.135607 -252.789019) (xy 184.105583 -252.744982) (xy 184.082457 -252.696961)
			(xy 184.066747 -252.646031) (xy 184.058804 -252.593327) (xy 177.251624 -252.593327) (xy 177.243681 -252.646031)
			(xy 177.227971 -252.696961) (xy 177.204845 -252.744982) (xy 177.174821 -252.789019) (xy 177.138569 -252.82809)
			(xy 177.096898 -252.861321) (xy 177.05074 -252.88797) (xy 177.001126 -252.907442) (xy 176.949164 -252.919302)
			(xy 176.896014 -252.923286) (xy 176.842864 -252.919302) (xy 176.790902 -252.907442) (xy 176.741288 -252.88797)
			(xy 176.69513 -252.861321) (xy 176.653459 -252.82809) (xy 176.617207 -252.789019) (xy 176.587183 -252.744982)
			(xy 176.564057 -252.696961) (xy 176.548347 -252.646031) (xy 176.540404 -252.593327) (xy 173.151556 -252.593327)
			(xy 173.143613 -252.646031) (xy 173.127903 -252.696961) (xy 173.104777 -252.744982) (xy 173.074753 -252.789019)
			(xy 173.038501 -252.82809) (xy 172.99683 -252.861321) (xy 172.950672 -252.88797) (xy 172.901058 -252.907442)
			(xy 172.849096 -252.919302) (xy 172.795946 -252.923286) (xy 172.742796 -252.919302) (xy 172.690834 -252.907442)
			(xy 172.64122 -252.88797) (xy 172.595062 -252.861321) (xy 172.553391 -252.82809) (xy 172.517139 -252.789019)
			(xy 172.487115 -252.744982) (xy 172.463989 -252.696961) (xy 172.448279 -252.646031) (xy 172.440336 -252.593327)
			(xy 159.11576 -252.593327) (xy 159.11576 -253.736094) (xy 159.139785 -253.749494) (xy 159.183758 -253.782545)
			(xy 159.222126 -253.821964) (xy 159.253977 -253.866815) (xy 159.278553 -253.916029) (xy 159.295269 -253.968437)
			(xy 159.303728 -254.022792) (xy 159.303728 -254.077801) (xy 159.29527 -254.132156) (xy 159.278556 -254.184564)
			(xy 159.253981 -254.233779) (xy 159.222131 -254.27863) (xy 159.183764 -254.31805) (xy 159.139792 -254.351102)
			(xy 159.11576 -254.36449) (xy 159.11576 -254.79629) (xy 162.28695 -254.79629) (xy 162.287463 -254.7682)
			(xy 162.296307 -254.712722) (xy 162.313757 -254.659321) (xy 162.339381 -254.609326) (xy 162.372542 -254.563977)
			(xy 162.392106 -254.543814) (xy 162.402266 -254.532941) (xy 162.416416 -254.50678) (xy 162.422445 -254.477654)
			(xy 162.419841 -254.448025) (xy 162.408827 -254.420397) (xy 162.39998 -254.408432) (xy 162.381811 -254.384627)
			(xy 162.352886 -254.332197) (xy 162.333138 -254.275667) (xy 162.323124 -254.21663) (xy 162.32251 -254.18669)
			(xy 162.323008 -254.160041) (xy 162.330951 -254.107337) (xy 162.346661 -254.056407) (xy 162.369787 -254.008386)
			(xy 162.399811 -253.964349) (xy 162.436063 -253.925278) (xy 162.477734 -253.892047) (xy 162.523892 -253.865398)
			(xy 162.573506 -253.845926) (xy 162.625468 -253.834066) (xy 162.678618 -253.830083) (xy 162.731768 -253.834066)
			(xy 162.78373 -253.845926) (xy 162.833344 -253.865398) (xy 162.879502 -253.892047) (xy 162.921173 -253.925278)
			(xy 162.957425 -253.964349) (xy 162.987449 -254.008386) (xy 163.010575 -254.056407) (xy 163.018639 -254.08255)
			(xy 163.28517 -254.08255) (xy 163.285695 -254.054567) (xy 163.294457 -253.99929) (xy 163.311757 -253.946064)
			(xy 163.337169 -253.896199) (xy 163.370068 -253.850923) (xy 163.409644 -253.81135) (xy 163.454923 -253.778454)
			(xy 163.50479 -253.753046) (xy 163.558017 -253.73575) (xy 163.613295 -253.726993) (xy 163.641278 -253.726442)
			(xy 163.666737 -253.726852) (xy 163.717134 -253.734114) (xy 163.765984 -253.748478) (xy 163.812291 -253.769652)
			(xy 163.85511 -253.797204) (xy 163.89357 -253.830572) (xy 163.926886 -253.869077) (xy 163.940998 -253.890272)
			(xy 163.948609 -253.901422) (xy 163.96864 -253.91951) (xy 163.992708 -253.931722) (xy 164.019134 -253.937206)
			(xy 164.046074 -253.935579) (xy 164.071649 -253.926955) (xy 164.094073 -253.911936) (xy 164.111782 -253.891569)
			(xy 164.118036 -253.879604) (xy 164.130976 -253.854157) (xy 164.163662 -253.807357) (xy 164.203393 -253.766369)
			(xy 164.249151 -253.732241) (xy 164.299767 -253.705848) (xy 164.353944 -253.687864) (xy 164.410296 -253.678751)
			(xy 164.438838 -253.678182) (xy 164.466822 -253.678706) (xy 164.469794 -253.679177) (xy 170.348392 -253.679177)
			(xy 170.348392 -253.625879) (xy 170.356335 -253.573175) (xy 170.372045 -253.522245) (xy 170.395171 -253.474224)
			(xy 170.425195 -253.430187) (xy 170.461447 -253.391116) (xy 170.503118 -253.357885) (xy 170.549276 -253.331236)
			(xy 170.59889 -253.311764) (xy 170.650852 -253.299904) (xy 170.704002 -253.295921) (xy 170.757152 -253.299904)
			(xy 170.809114 -253.311764) (xy 170.858728 -253.331236) (xy 170.904886 -253.357885) (xy 170.946557 -253.391116)
			(xy 170.982809 -253.430187) (xy 171.012833 -253.474224) (xy 171.035959 -253.522245) (xy 171.051669 -253.573175)
			(xy 171.059612 -253.625879) (xy 171.06011 -253.652528) (xy 171.059612 -253.679177) (xy 171.051669 -253.731881)
			(xy 171.035959 -253.782811) (xy 171.012833 -253.830832) (xy 170.982809 -253.874869) (xy 170.946557 -253.91394)
			(xy 170.904886 -253.947171) (xy 170.858728 -253.97382) (xy 170.809114 -253.993292) (xy 170.757152 -254.005152)
			(xy 170.704002 -254.009136) (xy 170.650852 -254.005152) (xy 170.59889 -253.993292) (xy 170.549276 -253.97382)
			(xy 170.503118 -253.947171) (xy 170.461447 -253.91394) (xy 170.425195 -253.874869) (xy 170.395171 -253.830832)
			(xy 170.372045 -253.782811) (xy 170.356335 -253.731881) (xy 170.348392 -253.679177) (xy 164.469794 -253.679177)
			(xy 164.522099 -253.687466) (xy 164.575326 -253.704765) (xy 164.625192 -253.730177) (xy 164.670468 -253.763077)
			(xy 164.710042 -253.802653) (xy 164.742937 -253.847932) (xy 164.768345 -253.8978) (xy 164.78564 -253.951028)
			(xy 164.794396 -254.006306) (xy 164.794946 -254.03429) (xy 164.794528 -254.059268) (xy 164.787531 -254.108732)
			(xy 164.773686 -254.156732) (xy 164.753266 -254.202324) (xy 164.726671 -254.244614) (xy 164.694425 -254.282769)
			(xy 164.676074 -254.29972) (xy 164.665535 -254.309817) (xy 164.650164 -254.334611) (xy 164.642426 -254.362737)
			(xy 164.642951 -254.391905) (xy 164.651697 -254.419735) (xy 164.667951 -254.443959) (xy 164.678868 -254.453644)
			(xy 164.687275 -254.460691) (xy 164.703288 -254.47569) (xy 164.710872 -254.483616) (xy 164.720912 -254.493477)
			(xy 164.745077 -254.507871) (xy 164.77225 -254.515133) (xy 164.800374 -254.514713) (xy 164.827319 -254.506642)
			(xy 164.851043 -254.491533) (xy 164.860732 -254.48133) (xy 164.877677 -254.462806) (xy 164.915924 -254.430286)
			(xy 164.95836 -254.403462) (xy 165.004145 -254.382868) (xy 165.052369 -254.36891) (xy 165.102076 -254.361867)
			(xy 165.127178 -254.361442) (xy 165.157427 -254.362086) (xy 165.217058 -254.372298) (xy 165.245796 -254.381762)
			(xy 165.260356 -254.386374) (xy 165.290859 -254.387641) (xy 165.320375 -254.379844) (xy 165.346274 -254.363681)
			(xy 165.366246 -254.340592) (xy 165.37851 -254.312635) (xy 165.381974 -254.282304) (xy 165.379654 -254.267208)
			(xy 165.376564 -254.249783) (xy 165.37326 -254.214546) (xy 165.37305 -254.19685) (xy 165.373501 -254.169592)
			(xy 165.381253 -254.11563) (xy 165.396606 -254.063321) (xy 165.419247 -254.013729) (xy 165.448716 -253.967865)
			(xy 165.484412 -253.926661) (xy 165.525609 -253.890958) (xy 165.571468 -253.86148) (xy 165.621056 -253.83883)
			(xy 165.673362 -253.823468) (xy 165.727323 -253.815706) (xy 165.781839 -253.815704) (xy 165.8358 -253.82346)
			(xy 165.888108 -253.838817) (xy 165.937698 -253.861462) (xy 165.98356 -253.890934) (xy 166.02476 -253.926634)
			(xy 166.060461 -253.967834) (xy 166.089934 -254.013695) (xy 166.112581 -254.063285) (xy 166.127939 -254.115592)
			(xy 166.135696 -254.169553) (xy 166.135694 -254.224069) (xy 166.127934 -254.27803) (xy 166.112573 -254.330336)
			(xy 166.089923 -254.379924) (xy 166.060447 -254.425784) (xy 166.024744 -254.466982) (xy 165.983542 -254.502679)
			(xy 165.937678 -254.532149) (xy 165.888086 -254.554791) (xy 165.835777 -254.570145) (xy 165.781816 -254.577898)
			(xy 165.754558 -254.578358) (xy 165.730941 -254.578033) (xy 165.684067 -254.572225) (xy 165.638268 -254.560676)
			(xy 165.616128 -254.55245) (xy 165.601727 -254.547476) (xy 165.571353 -254.545324) (xy 165.541693 -254.552218)
			(xy 165.515381 -254.567545) (xy 165.494753 -254.589944) (xy 165.481641 -254.617426) (xy 165.477208 -254.647552)
			(xy 165.478968 -254.662686) (xy 165.480977 -254.676313) (xy 165.483135 -254.703776) (xy 165.483286 -254.71755)
			(xy 165.482805 -254.745536) (xy 165.474042 -254.800817) (xy 165.456739 -254.854046) (xy 165.431323 -254.903914)
			(xy 165.398419 -254.949192) (xy 165.358837 -254.988766) (xy 165.313553 -255.021661) (xy 165.26368 -255.047067)
			(xy 165.210446 -255.064359) (xy 165.155164 -255.073111) (xy 165.127178 -255.073658) (xy 165.098111 -255.073111)
			(xy 165.040748 -255.063677) (xy 164.98568 -255.045049) (xy 164.93437 -255.01772) (xy 164.888183 -254.982418)
			(xy 164.867844 -254.961644) (xy 164.85788 -254.951701) (xy 164.833692 -254.937318) (xy 164.806499 -254.93007)
			(xy 164.778361 -254.930506) (xy 164.751406 -254.938593) (xy 164.727675 -254.953719) (xy 164.717984 -254.96393)
			(xy 164.701023 -254.982438) (xy 164.66278 -255.014961) (xy 164.620347 -255.041788) (xy 164.574566 -255.062386)
			(xy 164.526344 -255.076346) (xy 164.476639 -255.083392) (xy 164.451538 -255.083818) (xy 164.423174 -255.083258)
			(xy 164.367159 -255.074288) (xy 164.313275 -255.056554) (xy 164.262882 -255.030503) (xy 164.217256 -254.996794)
			(xy 164.177549 -254.95628) (xy 164.160708 -254.93345) (xy 164.151561 -254.921343) (xy 164.127572 -254.902783)
			(xy 164.099187 -254.892092) (xy 164.068914 -254.890214) (xy 164.039426 -254.897314) (xy 164.013326 -254.912766)
			(xy 163.992919 -254.935206) (xy 163.985956 -254.94869) (xy 163.974834 -254.971228) (xy 163.947158 -255.013179)
			(xy 163.913856 -255.050821) (xy 163.875592 -255.083405) (xy 163.833125 -255.110283) (xy 163.7873 -255.130922)
			(xy 163.739027 -255.14491) (xy 163.689267 -255.15197) (xy 163.664138 -255.152398) (xy 163.636153 -255.151852)
			(xy 163.580872 -255.143102) (xy 163.52764 -255.125811) (xy 163.47777 -255.100404) (xy 163.432487 -255.067509)
			(xy 163.39291 -255.027934) (xy 163.36001 -254.982654) (xy 163.3346 -254.932786) (xy 163.317305 -254.879555)
			(xy 163.30855 -254.824275) (xy 163.30803 -254.79629) (xy 163.308456 -254.770676) (xy 163.315786 -254.719976)
			(xy 163.330308 -254.67085) (xy 163.351722 -254.624313) (xy 163.379585 -254.581325) (xy 163.413322 -254.542776)
			(xy 163.43249 -254.52578) (xy 163.443696 -254.51551) (xy 163.459946 -254.489839) (xy 163.467935 -254.460525)
			(xy 163.466956 -254.430159) (xy 163.457095 -254.401421) (xy 163.439225 -254.37685) (xy 163.42741 -254.367284)
			(xy 163.405739 -254.350328) (xy 163.36735 -254.310912) (xy 163.335479 -254.266061) (xy 163.310886 -254.216842)
			(xy 163.294156 -254.164426) (xy 163.285686 -254.110061) (xy 163.28517 -254.08255) (xy 163.018639 -254.08255)
			(xy 163.026285 -254.107337) (xy 163.034228 -254.160041) (xy 163.034726 -254.18669) (xy 163.034207 -254.214779)
			(xy 163.025366 -254.270258) (xy 163.007917 -254.323659) (xy 162.982294 -254.373654) (xy 162.949134 -254.419003)
			(xy 162.92957 -254.439166) (xy 162.919427 -254.450055) (xy 162.905265 -254.476209) (xy 162.899229 -254.505332)
			(xy 162.90183 -254.53496) (xy 162.912847 -254.562586) (xy 162.921696 -254.574548) (xy 162.939853 -254.598362)
			(xy 162.968781 -254.650789) (xy 162.988532 -254.707316) (xy 162.99855 -254.766351) (xy 162.999166 -254.79629)
			(xy 162.998668 -254.822939) (xy 162.990725 -254.875643) (xy 162.975015 -254.926573) (xy 162.951889 -254.974594)
			(xy 162.921865 -255.018631) (xy 162.885613 -255.057702) (xy 162.843942 -255.090933) (xy 162.797784 -255.117582)
			(xy 162.74817 -255.137054) (xy 162.696208 -255.148914) (xy 162.643058 -255.152898) (xy 162.589908 -255.148914)
			(xy 162.537946 -255.137054) (xy 162.488332 -255.117582) (xy 162.442174 -255.090933) (xy 162.400503 -255.057702)
			(xy 162.364251 -255.018631) (xy 162.334227 -254.974594) (xy 162.311101 -254.926573) (xy 162.295391 -254.875643)
			(xy 162.287448 -254.822939) (xy 162.28695 -254.79629) (xy 159.11576 -254.79629) (xy 159.11576 -256.24663)
			(xy 206.828388 -256.24663) (xy 206.832459 -256.191008) (xy 206.844585 -256.136571) (xy 206.864508 -256.08448)
			(xy 206.891804 -256.035845) (xy 206.92589 -255.991702) (xy 206.966039 -255.952993) (xy 207.011397 -255.920542)
			(xy 207.060997 -255.895041) (xy 207.113781 -255.877034) (xy 207.168624 -255.866904) (xy 207.224358 -255.864867)
			(xy 207.279795 -255.870967) (xy 207.333752 -255.885073) (xy 207.385081 -255.906885) (xy 207.432687 -255.935939)
			(xy 207.475555 -255.971614) (xy 207.512772 -256.013151) (xy 207.543545 -256.059664) (xy 207.567217 -256.110161)
			(xy 207.583285 -256.163568) (xy 207.591405 -256.218744) (xy 207.591914 -256.24663) (xy 207.591405 -256.274516)
			(xy 207.583285 -256.329692) (xy 207.567217 -256.383099) (xy 207.543545 -256.433596) (xy 207.512772 -256.480109)
			(xy 207.475555 -256.521646) (xy 207.432687 -256.557321) (xy 207.385081 -256.586375) (xy 207.333752 -256.608187)
			(xy 207.279795 -256.622293) (xy 207.224358 -256.628393) (xy 207.168624 -256.626356) (xy 207.113781 -256.616226)
			(xy 207.060997 -256.598219) (xy 207.011397 -256.572718) (xy 206.966039 -256.540267) (xy 206.92589 -256.501558)
			(xy 206.891804 -256.457415) (xy 206.864508 -256.40878) (xy 206.844585 -256.356689) (xy 206.832459 -256.302252)
			(xy 206.828388 -256.24663) (xy 159.11576 -256.24663) (xy 159.11576 -259.393415) (xy 172.440336 -259.393415)
			(xy 172.440336 -259.340117) (xy 172.448279 -259.287413) (xy 172.463989 -259.236483) (xy 172.487115 -259.188462)
			(xy 172.517139 -259.144425) (xy 172.553391 -259.105354) (xy 172.595062 -259.072123) (xy 172.64122 -259.045474)
			(xy 172.690834 -259.026002) (xy 172.742796 -259.014142) (xy 172.795946 -259.010159) (xy 172.849096 -259.014142)
			(xy 172.901058 -259.026002) (xy 172.950672 -259.045474) (xy 172.99683 -259.072123) (xy 173.038501 -259.105354)
			(xy 173.074753 -259.144425) (xy 173.104777 -259.188462) (xy 173.127903 -259.236483) (xy 173.143613 -259.287413)
			(xy 173.151556 -259.340117) (xy 173.152054 -259.366766) (xy 173.151556 -259.393415) (xy 176.540404 -259.393415)
			(xy 176.540404 -259.340117) (xy 176.548347 -259.287413) (xy 176.564057 -259.236483) (xy 176.587183 -259.188462)
			(xy 176.617207 -259.144425) (xy 176.653459 -259.105354) (xy 176.69513 -259.072123) (xy 176.741288 -259.045474)
			(xy 176.790902 -259.026002) (xy 176.842864 -259.014142) (xy 176.896014 -259.010159) (xy 176.949164 -259.014142)
			(xy 177.001126 -259.026002) (xy 177.05074 -259.045474) (xy 177.096898 -259.072123) (xy 177.138569 -259.105354)
			(xy 177.174821 -259.144425) (xy 177.204845 -259.188462) (xy 177.227971 -259.236483) (xy 177.243681 -259.287413)
			(xy 177.251624 -259.340117) (xy 177.252122 -259.366766) (xy 177.251624 -259.393415) (xy 184.084204 -259.393415)
			(xy 184.084204 -259.340117) (xy 184.092147 -259.287413) (xy 184.107857 -259.236483) (xy 184.130983 -259.188462)
			(xy 184.161007 -259.144425) (xy 184.197259 -259.105354) (xy 184.23893 -259.072123) (xy 184.285088 -259.045474)
			(xy 184.334702 -259.026002) (xy 184.386664 -259.014142) (xy 184.439814 -259.010159) (xy 184.492964 -259.014142)
			(xy 184.544926 -259.026002) (xy 184.59454 -259.045474) (xy 184.640698 -259.072123) (xy 184.682369 -259.105354)
			(xy 184.718621 -259.144425) (xy 184.748645 -259.188462) (xy 184.771771 -259.236483) (xy 184.787481 -259.287413)
			(xy 184.795424 -259.340117) (xy 184.795922 -259.366766) (xy 184.795424 -259.393415) (xy 187.527936 -259.393415)
			(xy 187.527936 -259.340117) (xy 187.535879 -259.287413) (xy 187.551589 -259.236483) (xy 187.574715 -259.188462)
			(xy 187.604739 -259.144425) (xy 187.640991 -259.105354) (xy 187.682662 -259.072123) (xy 187.72882 -259.045474)
			(xy 187.778434 -259.026002) (xy 187.830396 -259.014142) (xy 187.883546 -259.010159) (xy 187.936696 -259.014142)
			(xy 187.988658 -259.026002) (xy 188.038272 -259.045474) (xy 188.08443 -259.072123) (xy 188.126101 -259.105354)
			(xy 188.162353 -259.144425) (xy 188.192377 -259.188462) (xy 188.215503 -259.236483) (xy 188.231213 -259.287413)
			(xy 188.239156 -259.340117) (xy 188.239654 -259.366766) (xy 188.239156 -259.393415) (xy 191.628004 -259.393415)
			(xy 191.628004 -259.340117) (xy 191.635947 -259.287413) (xy 191.651657 -259.236483) (xy 191.674783 -259.188462)
			(xy 191.704807 -259.144425) (xy 191.741059 -259.105354) (xy 191.78273 -259.072123) (xy 191.828888 -259.045474)
			(xy 191.878502 -259.026002) (xy 191.930464 -259.014142) (xy 191.983614 -259.010159) (xy 192.036764 -259.014142)
			(xy 192.088726 -259.026002) (xy 192.13834 -259.045474) (xy 192.184498 -259.072123) (xy 192.226169 -259.105354)
			(xy 192.262421 -259.144425) (xy 192.292445 -259.188462) (xy 192.315571 -259.236483) (xy 192.331281 -259.287413)
			(xy 192.339224 -259.340117) (xy 192.339722 -259.366766) (xy 192.339224 -259.393415) (xy 199.171804 -259.393415)
			(xy 199.171804 -259.340117) (xy 199.179747 -259.287413) (xy 199.195457 -259.236483) (xy 199.218583 -259.188462)
			(xy 199.248607 -259.144425) (xy 199.284859 -259.105354) (xy 199.32653 -259.072123) (xy 199.372688 -259.045474)
			(xy 199.422302 -259.026002) (xy 199.474264 -259.014142) (xy 199.527414 -259.010159) (xy 199.580564 -259.014142)
			(xy 199.632526 -259.026002) (xy 199.68214 -259.045474) (xy 199.728298 -259.072123) (xy 199.769969 -259.105354)
			(xy 199.806221 -259.144425) (xy 199.836245 -259.188462) (xy 199.859371 -259.236483) (xy 199.875081 -259.287413)
			(xy 199.883024 -259.340117) (xy 199.883522 -259.366766) (xy 199.883024 -259.393415) (xy 202.615536 -259.393415)
			(xy 202.615536 -259.340117) (xy 202.623479 -259.287413) (xy 202.639189 -259.236483) (xy 202.662315 -259.188462)
			(xy 202.692339 -259.144425) (xy 202.728591 -259.105354) (xy 202.770262 -259.072123) (xy 202.81642 -259.045474)
			(xy 202.866034 -259.026002) (xy 202.917996 -259.014142) (xy 202.971146 -259.010159) (xy 203.024296 -259.014142)
			(xy 203.076258 -259.026002) (xy 203.125872 -259.045474) (xy 203.17203 -259.072123) (xy 203.213701 -259.105354)
			(xy 203.249953 -259.144425) (xy 203.279977 -259.188462) (xy 203.303103 -259.236483) (xy 203.318813 -259.287413)
			(xy 203.326756 -259.340117) (xy 203.327254 -259.366766) (xy 203.326756 -259.393415) (xy 206.715604 -259.393415)
			(xy 206.715604 -259.340117) (xy 206.723547 -259.287413) (xy 206.739257 -259.236483) (xy 206.762383 -259.188462)
			(xy 206.792407 -259.144425) (xy 206.828659 -259.105354) (xy 206.87033 -259.072123) (xy 206.916488 -259.045474)
			(xy 206.966102 -259.026002) (xy 207.018064 -259.014142) (xy 207.071214 -259.010159) (xy 207.124364 -259.014142)
			(xy 207.176326 -259.026002) (xy 207.22594 -259.045474) (xy 207.272098 -259.072123) (xy 207.313769 -259.105354)
			(xy 207.350021 -259.144425) (xy 207.380045 -259.188462) (xy 207.403171 -259.236483) (xy 207.418881 -259.287413)
			(xy 207.426824 -259.340117) (xy 207.427322 -259.366766) (xy 207.426824 -259.393415) (xy 214.259404 -259.393415)
			(xy 214.259404 -259.340117) (xy 214.267347 -259.287413) (xy 214.283057 -259.236483) (xy 214.306183 -259.188462)
			(xy 214.336207 -259.144425) (xy 214.372459 -259.105354) (xy 214.41413 -259.072123) (xy 214.460288 -259.045474)
			(xy 214.509902 -259.026002) (xy 214.561864 -259.014142) (xy 214.615014 -259.010159) (xy 214.668164 -259.014142)
			(xy 214.720126 -259.026002) (xy 214.76974 -259.045474) (xy 214.815898 -259.072123) (xy 214.857569 -259.105354)
			(xy 214.893821 -259.144425) (xy 214.923845 -259.188462) (xy 214.946971 -259.236483) (xy 214.962681 -259.287413)
			(xy 214.970624 -259.340117) (xy 214.971122 -259.366766) (xy 214.970624 -259.393415) (xy 214.962681 -259.446119)
			(xy 214.946971 -259.497049) (xy 214.923845 -259.54507) (xy 214.893821 -259.589107) (xy 214.857569 -259.628178)
			(xy 214.815898 -259.661409) (xy 214.76974 -259.688058) (xy 214.720126 -259.70753) (xy 214.668164 -259.71939)
			(xy 214.615014 -259.723374) (xy 214.561864 -259.71939) (xy 214.509902 -259.70753) (xy 214.460288 -259.688058)
			(xy 214.41413 -259.661409) (xy 214.372459 -259.628178) (xy 214.336207 -259.589107) (xy 214.306183 -259.54507)
			(xy 214.283057 -259.497049) (xy 214.267347 -259.446119) (xy 214.259404 -259.393415) (xy 207.426824 -259.393415)
			(xy 207.418881 -259.446119) (xy 207.403171 -259.497049) (xy 207.380045 -259.54507) (xy 207.350021 -259.589107)
			(xy 207.313769 -259.628178) (xy 207.272098 -259.661409) (xy 207.22594 -259.688058) (xy 207.176326 -259.70753)
			(xy 207.124364 -259.71939) (xy 207.071214 -259.723374) (xy 207.018064 -259.71939) (xy 206.966102 -259.70753)
			(xy 206.916488 -259.688058) (xy 206.87033 -259.661409) (xy 206.828659 -259.628178) (xy 206.792407 -259.589107)
			(xy 206.762383 -259.54507) (xy 206.739257 -259.497049) (xy 206.723547 -259.446119) (xy 206.715604 -259.393415)
			(xy 203.326756 -259.393415) (xy 203.318813 -259.446119) (xy 203.303103 -259.497049) (xy 203.279977 -259.54507)
			(xy 203.249953 -259.589107) (xy 203.213701 -259.628178) (xy 203.17203 -259.661409) (xy 203.125872 -259.688058)
			(xy 203.076258 -259.70753) (xy 203.024296 -259.71939) (xy 202.971146 -259.723374) (xy 202.917996 -259.71939)
			(xy 202.866034 -259.70753) (xy 202.81642 -259.688058) (xy 202.770262 -259.661409) (xy 202.728591 -259.628178)
			(xy 202.692339 -259.589107) (xy 202.662315 -259.54507) (xy 202.639189 -259.497049) (xy 202.623479 -259.446119)
			(xy 202.615536 -259.393415) (xy 199.883024 -259.393415) (xy 199.875081 -259.446119) (xy 199.859371 -259.497049)
			(xy 199.836245 -259.54507) (xy 199.806221 -259.589107) (xy 199.769969 -259.628178) (xy 199.728298 -259.661409)
			(xy 199.68214 -259.688058) (xy 199.632526 -259.70753) (xy 199.580564 -259.71939) (xy 199.527414 -259.723374)
			(xy 199.474264 -259.71939) (xy 199.422302 -259.70753) (xy 199.372688 -259.688058) (xy 199.32653 -259.661409)
			(xy 199.284859 -259.628178) (xy 199.248607 -259.589107) (xy 199.218583 -259.54507) (xy 199.195457 -259.497049)
			(xy 199.179747 -259.446119) (xy 199.171804 -259.393415) (xy 192.339224 -259.393415) (xy 192.331281 -259.446119)
			(xy 192.315571 -259.497049) (xy 192.292445 -259.54507) (xy 192.262421 -259.589107) (xy 192.226169 -259.628178)
			(xy 192.184498 -259.661409) (xy 192.13834 -259.688058) (xy 192.088726 -259.70753) (xy 192.036764 -259.71939)
			(xy 191.983614 -259.723374) (xy 191.930464 -259.71939) (xy 191.878502 -259.70753) (xy 191.828888 -259.688058)
			(xy 191.78273 -259.661409) (xy 191.741059 -259.628178) (xy 191.704807 -259.589107) (xy 191.674783 -259.54507)
			(xy 191.651657 -259.497049) (xy 191.635947 -259.446119) (xy 191.628004 -259.393415) (xy 188.239156 -259.393415)
			(xy 188.231213 -259.446119) (xy 188.215503 -259.497049) (xy 188.192377 -259.54507) (xy 188.162353 -259.589107)
			(xy 188.126101 -259.628178) (xy 188.08443 -259.661409) (xy 188.038272 -259.688058) (xy 187.988658 -259.70753)
			(xy 187.936696 -259.71939) (xy 187.883546 -259.723374) (xy 187.830396 -259.71939) (xy 187.778434 -259.70753)
			(xy 187.72882 -259.688058) (xy 187.682662 -259.661409) (xy 187.640991 -259.628178) (xy 187.604739 -259.589107)
			(xy 187.574715 -259.54507) (xy 187.551589 -259.497049) (xy 187.535879 -259.446119) (xy 187.527936 -259.393415)
			(xy 184.795424 -259.393415) (xy 184.787481 -259.446119) (xy 184.771771 -259.497049) (xy 184.748645 -259.54507)
			(xy 184.718621 -259.589107) (xy 184.682369 -259.628178) (xy 184.640698 -259.661409) (xy 184.59454 -259.688058)
			(xy 184.544926 -259.70753) (xy 184.492964 -259.71939) (xy 184.439814 -259.723374) (xy 184.386664 -259.71939)
			(xy 184.334702 -259.70753) (xy 184.285088 -259.688058) (xy 184.23893 -259.661409) (xy 184.197259 -259.628178)
			(xy 184.161007 -259.589107) (xy 184.130983 -259.54507) (xy 184.107857 -259.497049) (xy 184.092147 -259.446119)
			(xy 184.084204 -259.393415) (xy 177.251624 -259.393415) (xy 177.243681 -259.446119) (xy 177.227971 -259.497049)
			(xy 177.204845 -259.54507) (xy 177.174821 -259.589107) (xy 177.138569 -259.628178) (xy 177.096898 -259.661409)
			(xy 177.05074 -259.688058) (xy 177.001126 -259.70753) (xy 176.949164 -259.71939) (xy 176.896014 -259.723374)
			(xy 176.842864 -259.71939) (xy 176.790902 -259.70753) (xy 176.741288 -259.688058) (xy 176.69513 -259.661409)
			(xy 176.653459 -259.628178) (xy 176.617207 -259.589107) (xy 176.587183 -259.54507) (xy 176.564057 -259.497049)
			(xy 176.548347 -259.446119) (xy 176.540404 -259.393415) (xy 173.151556 -259.393415) (xy 173.143613 -259.446119)
			(xy 173.127903 -259.497049) (xy 173.104777 -259.54507) (xy 173.074753 -259.589107) (xy 173.038501 -259.628178)
			(xy 172.99683 -259.661409) (xy 172.950672 -259.688058) (xy 172.901058 -259.70753) (xy 172.849096 -259.71939)
			(xy 172.795946 -259.723374) (xy 172.742796 -259.71939) (xy 172.690834 -259.70753) (xy 172.64122 -259.688058)
			(xy 172.595062 -259.661409) (xy 172.553391 -259.628178) (xy 172.517139 -259.589107) (xy 172.487115 -259.54507)
			(xy 172.463989 -259.497049) (xy 172.448279 -259.446119) (xy 172.440336 -259.393415) (xy 159.11576 -259.393415)
			(xy 159.11576 -260.243299) (xy 176.540404 -260.243299) (xy 176.540404 -260.190001) (xy 176.548347 -260.137297)
			(xy 176.564057 -260.086367) (xy 176.587183 -260.038346) (xy 176.617207 -259.994309) (xy 176.653459 -259.955238)
			(xy 176.69513 -259.922007) (xy 176.741288 -259.895358) (xy 176.790902 -259.875886) (xy 176.842864 -259.864026)
			(xy 176.896014 -259.860043) (xy 176.949164 -259.864026) (xy 177.001126 -259.875886) (xy 177.05074 -259.895358)
			(xy 177.096898 -259.922007) (xy 177.138569 -259.955238) (xy 177.174821 -259.994309) (xy 177.204845 -260.038346)
			(xy 177.227971 -260.086367) (xy 177.243681 -260.137297) (xy 177.251624 -260.190001) (xy 177.252122 -260.21665)
			(xy 177.251624 -260.243299) (xy 184.084204 -260.243299) (xy 184.084204 -260.190001) (xy 184.092147 -260.137297)
			(xy 184.107857 -260.086367) (xy 184.130983 -260.038346) (xy 184.161007 -259.994309) (xy 184.197259 -259.955238)
			(xy 184.23893 -259.922007) (xy 184.285088 -259.895358) (xy 184.334702 -259.875886) (xy 184.386664 -259.864026)
			(xy 184.439814 -259.860043) (xy 184.492964 -259.864026) (xy 184.544926 -259.875886) (xy 184.59454 -259.895358)
			(xy 184.640698 -259.922007) (xy 184.682369 -259.955238) (xy 184.718621 -259.994309) (xy 184.748645 -260.038346)
			(xy 184.771771 -260.086367) (xy 184.787481 -260.137297) (xy 184.795424 -260.190001) (xy 184.795922 -260.21665)
			(xy 184.795424 -260.243299) (xy 191.628004 -260.243299) (xy 191.628004 -260.190001) (xy 191.635947 -260.137297)
			(xy 191.651657 -260.086367) (xy 191.674783 -260.038346) (xy 191.704807 -259.994309) (xy 191.741059 -259.955238)
			(xy 191.78273 -259.922007) (xy 191.828888 -259.895358) (xy 191.878502 -259.875886) (xy 191.930464 -259.864026)
			(xy 191.983614 -259.860043) (xy 192.036764 -259.864026) (xy 192.088726 -259.875886) (xy 192.13834 -259.895358)
			(xy 192.184498 -259.922007) (xy 192.226169 -259.955238) (xy 192.262421 -259.994309) (xy 192.292445 -260.038346)
			(xy 192.315571 -260.086367) (xy 192.331281 -260.137297) (xy 192.339224 -260.190001) (xy 192.339722 -260.21665)
			(xy 192.339224 -260.243299) (xy 199.171804 -260.243299) (xy 199.171804 -260.190001) (xy 199.179747 -260.137297)
			(xy 199.195457 -260.086367) (xy 199.218583 -260.038346) (xy 199.248607 -259.994309) (xy 199.284859 -259.955238)
			(xy 199.32653 -259.922007) (xy 199.372688 -259.895358) (xy 199.422302 -259.875886) (xy 199.474264 -259.864026)
			(xy 199.527414 -259.860043) (xy 199.580564 -259.864026) (xy 199.632526 -259.875886) (xy 199.68214 -259.895358)
			(xy 199.728298 -259.922007) (xy 199.769969 -259.955238) (xy 199.806221 -259.994309) (xy 199.836245 -260.038346)
			(xy 199.859371 -260.086367) (xy 199.875081 -260.137297) (xy 199.883024 -260.190001) (xy 199.883522 -260.21665)
			(xy 199.883024 -260.243299) (xy 206.715604 -260.243299) (xy 206.715604 -260.190001) (xy 206.723547 -260.137297)
			(xy 206.739257 -260.086367) (xy 206.762383 -260.038346) (xy 206.792407 -259.994309) (xy 206.828659 -259.955238)
			(xy 206.87033 -259.922007) (xy 206.916488 -259.895358) (xy 206.966102 -259.875886) (xy 207.018064 -259.864026)
			(xy 207.071214 -259.860043) (xy 207.124364 -259.864026) (xy 207.176326 -259.875886) (xy 207.22594 -259.895358)
			(xy 207.272098 -259.922007) (xy 207.313769 -259.955238) (xy 207.350021 -259.994309) (xy 207.380045 -260.038346)
			(xy 207.403171 -260.086367) (xy 207.418881 -260.137297) (xy 207.426824 -260.190001) (xy 207.427322 -260.21665)
			(xy 207.426824 -260.243299) (xy 214.259404 -260.243299) (xy 214.259404 -260.190001) (xy 214.267347 -260.137297)
			(xy 214.283057 -260.086367) (xy 214.306183 -260.038346) (xy 214.336207 -259.994309) (xy 214.372459 -259.955238)
			(xy 214.41413 -259.922007) (xy 214.460288 -259.895358) (xy 214.509902 -259.875886) (xy 214.561864 -259.864026)
			(xy 214.615014 -259.860043) (xy 214.668164 -259.864026) (xy 214.720126 -259.875886) (xy 214.76974 -259.895358)
			(xy 214.815898 -259.922007) (xy 214.857569 -259.955238) (xy 214.893821 -259.994309) (xy 214.923845 -260.038346)
			(xy 214.946971 -260.086367) (xy 214.962681 -260.137297) (xy 214.970624 -260.190001) (xy 214.971122 -260.21665)
			(xy 214.970624 -260.243299) (xy 214.962681 -260.296003) (xy 214.946971 -260.346933) (xy 214.923845 -260.394954)
			(xy 214.893821 -260.438991) (xy 214.857569 -260.478062) (xy 214.815898 -260.511293) (xy 214.76974 -260.537942)
			(xy 214.720126 -260.557414) (xy 214.668164 -260.569274) (xy 214.615014 -260.573258) (xy 214.561864 -260.569274)
			(xy 214.509902 -260.557414) (xy 214.460288 -260.537942) (xy 214.41413 -260.511293) (xy 214.372459 -260.478062)
			(xy 214.336207 -260.438991) (xy 214.306183 -260.394954) (xy 214.283057 -260.346933) (xy 214.267347 -260.296003)
			(xy 214.259404 -260.243299) (xy 207.426824 -260.243299) (xy 207.418881 -260.296003) (xy 207.403171 -260.346933)
			(xy 207.380045 -260.394954) (xy 207.350021 -260.438991) (xy 207.313769 -260.478062) (xy 207.272098 -260.511293)
			(xy 207.22594 -260.537942) (xy 207.176326 -260.557414) (xy 207.124364 -260.569274) (xy 207.071214 -260.573258)
			(xy 207.018064 -260.569274) (xy 206.966102 -260.557414) (xy 206.916488 -260.537942) (xy 206.87033 -260.511293)
			(xy 206.828659 -260.478062) (xy 206.792407 -260.438991) (xy 206.762383 -260.394954) (xy 206.739257 -260.346933)
			(xy 206.723547 -260.296003) (xy 206.715604 -260.243299) (xy 199.883024 -260.243299) (xy 199.875081 -260.296003)
			(xy 199.859371 -260.346933) (xy 199.836245 -260.394954) (xy 199.806221 -260.438991) (xy 199.769969 -260.478062)
			(xy 199.728298 -260.511293) (xy 199.68214 -260.537942) (xy 199.632526 -260.557414) (xy 199.580564 -260.569274)
			(xy 199.527414 -260.573258) (xy 199.474264 -260.569274) (xy 199.422302 -260.557414) (xy 199.372688 -260.537942)
			(xy 199.32653 -260.511293) (xy 199.284859 -260.478062) (xy 199.248607 -260.438991) (xy 199.218583 -260.394954)
			(xy 199.195457 -260.346933) (xy 199.179747 -260.296003) (xy 199.171804 -260.243299) (xy 192.339224 -260.243299)
			(xy 192.331281 -260.296003) (xy 192.315571 -260.346933) (xy 192.292445 -260.394954) (xy 192.262421 -260.438991)
			(xy 192.226169 -260.478062) (xy 192.184498 -260.511293) (xy 192.13834 -260.537942) (xy 192.088726 -260.557414)
			(xy 192.036764 -260.569274) (xy 191.983614 -260.573258) (xy 191.930464 -260.569274) (xy 191.878502 -260.557414)
			(xy 191.828888 -260.537942) (xy 191.78273 -260.511293) (xy 191.741059 -260.478062) (xy 191.704807 -260.438991)
			(xy 191.674783 -260.394954) (xy 191.651657 -260.346933) (xy 191.635947 -260.296003) (xy 191.628004 -260.243299)
			(xy 184.795424 -260.243299) (xy 184.787481 -260.296003) (xy 184.771771 -260.346933) (xy 184.748645 -260.394954)
			(xy 184.718621 -260.438991) (xy 184.682369 -260.478062) (xy 184.640698 -260.511293) (xy 184.59454 -260.537942)
			(xy 184.544926 -260.557414) (xy 184.492964 -260.569274) (xy 184.439814 -260.573258) (xy 184.386664 -260.569274)
			(xy 184.334702 -260.557414) (xy 184.285088 -260.537942) (xy 184.23893 -260.511293) (xy 184.197259 -260.478062)
			(xy 184.161007 -260.438991) (xy 184.130983 -260.394954) (xy 184.107857 -260.346933) (xy 184.092147 -260.296003)
			(xy 184.084204 -260.243299) (xy 177.251624 -260.243299) (xy 177.243681 -260.296003) (xy 177.227971 -260.346933)
			(xy 177.204845 -260.394954) (xy 177.174821 -260.438991) (xy 177.138569 -260.478062) (xy 177.096898 -260.511293)
			(xy 177.05074 -260.537942) (xy 177.001126 -260.557414) (xy 176.949164 -260.569274) (xy 176.896014 -260.573258)
			(xy 176.842864 -260.569274) (xy 176.790902 -260.557414) (xy 176.741288 -260.537942) (xy 176.69513 -260.511293)
			(xy 176.653459 -260.478062) (xy 176.617207 -260.438991) (xy 176.587183 -260.394954) (xy 176.564057 -260.346933)
			(xy 176.548347 -260.296003) (xy 176.540404 -260.243299) (xy 159.11576 -260.243299) (xy 159.11576 -261.093437)
			(xy 172.364136 -261.093437) (xy 172.364136 -261.040139) (xy 172.372079 -260.987435) (xy 172.387789 -260.936505)
			(xy 172.410915 -260.888484) (xy 172.440939 -260.844447) (xy 172.477191 -260.805376) (xy 172.518862 -260.772145)
			(xy 172.56502 -260.745496) (xy 172.614634 -260.726024) (xy 172.666596 -260.714164) (xy 172.719746 -260.710181)
			(xy 172.772896 -260.714164) (xy 172.824858 -260.726024) (xy 172.874472 -260.745496) (xy 172.92063 -260.772145)
			(xy 172.962301 -260.805376) (xy 172.998553 -260.844447) (xy 173.028577 -260.888484) (xy 173.051703 -260.936505)
			(xy 173.067413 -260.987435) (xy 173.075356 -261.040139) (xy 173.075854 -261.066788) (xy 173.075356 -261.093437)
			(xy 187.527936 -261.093437) (xy 187.527936 -261.040139) (xy 187.535879 -260.987435) (xy 187.551589 -260.936505)
			(xy 187.574715 -260.888484) (xy 187.604739 -260.844447) (xy 187.640991 -260.805376) (xy 187.682662 -260.772145)
			(xy 187.72882 -260.745496) (xy 187.778434 -260.726024) (xy 187.830396 -260.714164) (xy 187.883546 -260.710181)
			(xy 187.936696 -260.714164) (xy 187.988658 -260.726024) (xy 188.038272 -260.745496) (xy 188.08443 -260.772145)
			(xy 188.126101 -260.805376) (xy 188.162353 -260.844447) (xy 188.192377 -260.888484) (xy 188.215503 -260.936505)
			(xy 188.231213 -260.987435) (xy 188.239156 -261.040139) (xy 188.239654 -261.066788) (xy 188.239156 -261.093437)
			(xy 202.615536 -261.093437) (xy 202.615536 -261.040139) (xy 202.623479 -260.987435) (xy 202.639189 -260.936505)
			(xy 202.662315 -260.888484) (xy 202.692339 -260.844447) (xy 202.728591 -260.805376) (xy 202.770262 -260.772145)
			(xy 202.81642 -260.745496) (xy 202.866034 -260.726024) (xy 202.917996 -260.714164) (xy 202.971146 -260.710181)
			(xy 203.024296 -260.714164) (xy 203.076258 -260.726024) (xy 203.125872 -260.745496) (xy 203.17203 -260.772145)
			(xy 203.213701 -260.805376) (xy 203.249953 -260.844447) (xy 203.279977 -260.888484) (xy 203.303103 -260.936505)
			(xy 203.318813 -260.987435) (xy 203.326756 -261.040139) (xy 203.327254 -261.066788) (xy 203.326756 -261.093437)
			(xy 203.318813 -261.146141) (xy 203.303103 -261.197071) (xy 203.279977 -261.245092) (xy 203.249953 -261.289129)
			(xy 203.213701 -261.3282) (xy 203.17203 -261.361431) (xy 203.125872 -261.38808) (xy 203.076258 -261.407552)
			(xy 203.024296 -261.419412) (xy 202.971146 -261.423396) (xy 202.917996 -261.419412) (xy 202.866034 -261.407552)
			(xy 202.81642 -261.38808) (xy 202.770262 -261.361431) (xy 202.728591 -261.3282) (xy 202.692339 -261.289129)
			(xy 202.662315 -261.245092) (xy 202.639189 -261.197071) (xy 202.623479 -261.146141) (xy 202.615536 -261.093437)
			(xy 188.239156 -261.093437) (xy 188.231213 -261.146141) (xy 188.215503 -261.197071) (xy 188.192377 -261.245092)
			(xy 188.162353 -261.289129) (xy 188.126101 -261.3282) (xy 188.08443 -261.361431) (xy 188.038272 -261.38808)
			(xy 187.988658 -261.407552) (xy 187.936696 -261.419412) (xy 187.883546 -261.423396) (xy 187.830396 -261.419412)
			(xy 187.778434 -261.407552) (xy 187.72882 -261.38808) (xy 187.682662 -261.361431) (xy 187.640991 -261.3282)
			(xy 187.604739 -261.289129) (xy 187.574715 -261.245092) (xy 187.551589 -261.197071) (xy 187.535879 -261.146141)
			(xy 187.527936 -261.093437) (xy 173.075356 -261.093437) (xy 173.067413 -261.146141) (xy 173.051703 -261.197071)
			(xy 173.028577 -261.245092) (xy 172.998553 -261.289129) (xy 172.962301 -261.3282) (xy 172.92063 -261.361431)
			(xy 172.874472 -261.38808) (xy 172.824858 -261.407552) (xy 172.772896 -261.419412) (xy 172.719746 -261.423396)
			(xy 172.666596 -261.419412) (xy 172.614634 -261.407552) (xy 172.56502 -261.38808) (xy 172.518862 -261.361431)
			(xy 172.477191 -261.3282) (xy 172.440939 -261.289129) (xy 172.410915 -261.245092) (xy 172.387789 -261.197071)
			(xy 172.372079 -261.146141) (xy 172.364136 -261.093437) (xy 159.11576 -261.093437) (xy 159.11576 -261.943321)
			(xy 176.540404 -261.943321) (xy 176.540404 -261.890023) (xy 176.548347 -261.837319) (xy 176.564057 -261.786389)
			(xy 176.587183 -261.738368) (xy 176.617207 -261.694331) (xy 176.653459 -261.65526) (xy 176.69513 -261.622029)
			(xy 176.741288 -261.59538) (xy 176.790902 -261.575908) (xy 176.842864 -261.564048) (xy 176.896014 -261.560065)
			(xy 176.949164 -261.564048) (xy 177.001126 -261.575908) (xy 177.05074 -261.59538) (xy 177.096898 -261.622029)
			(xy 177.138569 -261.65526) (xy 177.174821 -261.694331) (xy 177.204845 -261.738368) (xy 177.227971 -261.786389)
			(xy 177.243681 -261.837319) (xy 177.251624 -261.890023) (xy 177.252122 -261.916672) (xy 177.251624 -261.943321)
			(xy 191.628004 -261.943321) (xy 191.628004 -261.890023) (xy 191.635947 -261.837319) (xy 191.651657 -261.786389)
			(xy 191.674783 -261.738368) (xy 191.704807 -261.694331) (xy 191.741059 -261.65526) (xy 191.78273 -261.622029)
			(xy 191.828888 -261.59538) (xy 191.878502 -261.575908) (xy 191.930464 -261.564048) (xy 191.983614 -261.560065)
			(xy 192.036764 -261.564048) (xy 192.088726 -261.575908) (xy 192.13834 -261.59538) (xy 192.184498 -261.622029)
			(xy 192.226169 -261.65526) (xy 192.262421 -261.694331) (xy 192.292445 -261.738368) (xy 192.315571 -261.786389)
			(xy 192.331281 -261.837319) (xy 192.339224 -261.890023) (xy 192.339722 -261.916672) (xy 192.339224 -261.943321)
			(xy 206.715604 -261.943321) (xy 206.715604 -261.890023) (xy 206.723547 -261.837319) (xy 206.739257 -261.786389)
			(xy 206.762383 -261.738368) (xy 206.792407 -261.694331) (xy 206.828659 -261.65526) (xy 206.87033 -261.622029)
			(xy 206.916488 -261.59538) (xy 206.966102 -261.575908) (xy 207.018064 -261.564048) (xy 207.071214 -261.560065)
			(xy 207.124364 -261.564048) (xy 207.176326 -261.575908) (xy 207.22594 -261.59538) (xy 207.272098 -261.622029)
			(xy 207.313769 -261.65526) (xy 207.350021 -261.694331) (xy 207.380045 -261.738368) (xy 207.403171 -261.786389)
			(xy 207.418881 -261.837319) (xy 207.426824 -261.890023) (xy 207.427322 -261.916672) (xy 207.426824 -261.943321)
			(xy 207.418881 -261.996025) (xy 207.403171 -262.046955) (xy 207.380045 -262.094976) (xy 207.350021 -262.139013)
			(xy 207.313769 -262.178084) (xy 207.272098 -262.211315) (xy 207.22594 -262.237964) (xy 207.176326 -262.257436)
			(xy 207.124364 -262.269296) (xy 207.071214 -262.27328) (xy 207.018064 -262.269296) (xy 206.966102 -262.257436)
			(xy 206.916488 -262.237964) (xy 206.87033 -262.211315) (xy 206.828659 -262.178084) (xy 206.792407 -262.139013)
			(xy 206.762383 -262.094976) (xy 206.739257 -262.046955) (xy 206.723547 -261.996025) (xy 206.715604 -261.943321)
			(xy 192.339224 -261.943321) (xy 192.331281 -261.996025) (xy 192.315571 -262.046955) (xy 192.292445 -262.094976)
			(xy 192.262421 -262.139013) (xy 192.226169 -262.178084) (xy 192.184498 -262.211315) (xy 192.13834 -262.237964)
			(xy 192.088726 -262.257436) (xy 192.036764 -262.269296) (xy 191.983614 -262.27328) (xy 191.930464 -262.269296)
			(xy 191.878502 -262.257436) (xy 191.828888 -262.237964) (xy 191.78273 -262.211315) (xy 191.741059 -262.178084)
			(xy 191.704807 -262.139013) (xy 191.674783 -262.094976) (xy 191.651657 -262.046955) (xy 191.635947 -261.996025)
			(xy 191.628004 -261.943321) (xy 177.251624 -261.943321) (xy 177.243681 -261.996025) (xy 177.227971 -262.046955)
			(xy 177.204845 -262.094976) (xy 177.174821 -262.139013) (xy 177.138569 -262.178084) (xy 177.096898 -262.211315)
			(xy 177.05074 -262.237964) (xy 177.001126 -262.257436) (xy 176.949164 -262.269296) (xy 176.896014 -262.27328)
			(xy 176.842864 -262.269296) (xy 176.790902 -262.257436) (xy 176.741288 -262.237964) (xy 176.69513 -262.211315)
			(xy 176.653459 -262.178084) (xy 176.617207 -262.139013) (xy 176.587183 -262.094976) (xy 176.564057 -262.046955)
			(xy 176.548347 -261.996025) (xy 176.540404 -261.943321) (xy 159.11576 -261.943321) (xy 159.11576 -262.793205)
			(xy 172.364136 -262.793205) (xy 172.364136 -262.739907) (xy 172.372079 -262.687203) (xy 172.387789 -262.636273)
			(xy 172.410915 -262.588252) (xy 172.440939 -262.544215) (xy 172.477191 -262.505144) (xy 172.518862 -262.471913)
			(xy 172.56502 -262.445264) (xy 172.614634 -262.425792) (xy 172.666596 -262.413932) (xy 172.719746 -262.409949)
			(xy 172.772896 -262.413932) (xy 172.824858 -262.425792) (xy 172.874472 -262.445264) (xy 172.92063 -262.471913)
			(xy 172.962301 -262.505144) (xy 172.998553 -262.544215) (xy 173.028577 -262.588252) (xy 173.051703 -262.636273)
			(xy 173.067413 -262.687203) (xy 173.075356 -262.739907) (xy 173.075854 -262.766556) (xy 173.075356 -262.793205)
			(xy 187.527936 -262.793205) (xy 187.527936 -262.739907) (xy 187.535879 -262.687203) (xy 187.551589 -262.636273)
			(xy 187.574715 -262.588252) (xy 187.604739 -262.544215) (xy 187.640991 -262.505144) (xy 187.682662 -262.471913)
			(xy 187.72882 -262.445264) (xy 187.778434 -262.425792) (xy 187.830396 -262.413932) (xy 187.883546 -262.409949)
			(xy 187.936696 -262.413932) (xy 187.988658 -262.425792) (xy 188.038272 -262.445264) (xy 188.08443 -262.471913)
			(xy 188.126101 -262.505144) (xy 188.162353 -262.544215) (xy 188.192377 -262.588252) (xy 188.215503 -262.636273)
			(xy 188.231213 -262.687203) (xy 188.239156 -262.739907) (xy 188.239654 -262.766556) (xy 188.239156 -262.793205)
			(xy 188.239118 -262.793459) (xy 202.615536 -262.793459) (xy 202.615536 -262.740161) (xy 202.623479 -262.687457)
			(xy 202.639189 -262.636527) (xy 202.662315 -262.588506) (xy 202.692339 -262.544469) (xy 202.728591 -262.505398)
			(xy 202.770262 -262.472167) (xy 202.81642 -262.445518) (xy 202.866034 -262.426046) (xy 202.917996 -262.414186)
			(xy 202.971146 -262.410203) (xy 203.024296 -262.414186) (xy 203.076258 -262.426046) (xy 203.125872 -262.445518)
			(xy 203.17203 -262.472167) (xy 203.213701 -262.505398) (xy 203.249953 -262.544469) (xy 203.279977 -262.588506)
			(xy 203.303103 -262.636527) (xy 203.318813 -262.687457) (xy 203.326756 -262.740161) (xy 203.327254 -262.76681)
			(xy 203.326756 -262.793459) (xy 203.318813 -262.846163) (xy 203.303103 -262.897093) (xy 203.279977 -262.945114)
			(xy 203.249953 -262.989151) (xy 203.213701 -263.028222) (xy 203.17203 -263.061453) (xy 203.125872 -263.088102)
			(xy 203.076258 -263.107574) (xy 203.024296 -263.119434) (xy 202.971146 -263.123418) (xy 202.917996 -263.119434)
			(xy 202.866034 -263.107574) (xy 202.81642 -263.088102) (xy 202.770262 -263.061453) (xy 202.728591 -263.028222)
			(xy 202.692339 -262.989151) (xy 202.662315 -262.945114) (xy 202.639189 -262.897093) (xy 202.623479 -262.846163)
			(xy 202.615536 -262.793459) (xy 188.239118 -262.793459) (xy 188.231213 -262.845909) (xy 188.215503 -262.896839)
			(xy 188.192377 -262.94486) (xy 188.162353 -262.988897) (xy 188.126101 -263.027968) (xy 188.08443 -263.061199)
			(xy 188.038272 -263.087848) (xy 187.988658 -263.10732) (xy 187.936696 -263.11918) (xy 187.883546 -263.123164)
			(xy 187.830396 -263.11918) (xy 187.778434 -263.10732) (xy 187.72882 -263.087848) (xy 187.682662 -263.061199)
			(xy 187.640991 -263.027968) (xy 187.604739 -262.988897) (xy 187.574715 -262.94486) (xy 187.551589 -262.896839)
			(xy 187.535879 -262.845909) (xy 187.527936 -262.793205) (xy 173.075356 -262.793205) (xy 173.067413 -262.845909)
			(xy 173.051703 -262.896839) (xy 173.028577 -262.94486) (xy 172.998553 -262.988897) (xy 172.962301 -263.027968)
			(xy 172.92063 -263.061199) (xy 172.874472 -263.087848) (xy 172.824858 -263.10732) (xy 172.772896 -263.11918)
			(xy 172.719746 -263.123164) (xy 172.666596 -263.11918) (xy 172.614634 -263.10732) (xy 172.56502 -263.087848)
			(xy 172.518862 -263.061199) (xy 172.477191 -263.027968) (xy 172.440939 -262.988897) (xy 172.410915 -262.94486)
			(xy 172.387789 -262.896839) (xy 172.372079 -262.845909) (xy 172.364136 -262.793205) (xy 159.11576 -262.793205)
			(xy 159.11576 -263.643343) (xy 176.464204 -263.643343) (xy 176.464204 -263.590045) (xy 176.472147 -263.537341)
			(xy 176.487857 -263.486411) (xy 176.510983 -263.43839) (xy 176.541007 -263.394353) (xy 176.577259 -263.355282)
			(xy 176.61893 -263.322051) (xy 176.665088 -263.295402) (xy 176.714702 -263.27593) (xy 176.766664 -263.26407)
			(xy 176.819814 -263.260087) (xy 176.872964 -263.26407) (xy 176.924926 -263.27593) (xy 176.97454 -263.295402)
			(xy 177.020698 -263.322051) (xy 177.062369 -263.355282) (xy 177.098621 -263.394353) (xy 177.128645 -263.43839)
			(xy 177.151771 -263.486411) (xy 177.167481 -263.537341) (xy 177.175424 -263.590045) (xy 177.175922 -263.616694)
			(xy 177.175424 -263.643343) (xy 191.551804 -263.643343) (xy 191.551804 -263.590045) (xy 191.559747 -263.537341)
			(xy 191.575457 -263.486411) (xy 191.598583 -263.43839) (xy 191.628607 -263.394353) (xy 191.664859 -263.355282)
			(xy 191.70653 -263.322051) (xy 191.752688 -263.295402) (xy 191.802302 -263.27593) (xy 191.854264 -263.26407)
			(xy 191.907414 -263.260087) (xy 191.960564 -263.26407) (xy 192.012526 -263.27593) (xy 192.06214 -263.295402)
			(xy 192.108298 -263.322051) (xy 192.149969 -263.355282) (xy 192.186221 -263.394353) (xy 192.216245 -263.43839)
			(xy 192.239371 -263.486411) (xy 192.255081 -263.537341) (xy 192.263024 -263.590045) (xy 192.263522 -263.616694)
			(xy 192.263024 -263.643343) (xy 206.715604 -263.643343) (xy 206.715604 -263.590045) (xy 206.723547 -263.537341)
			(xy 206.739257 -263.486411) (xy 206.762383 -263.43839) (xy 206.792407 -263.394353) (xy 206.828659 -263.355282)
			(xy 206.87033 -263.322051) (xy 206.916488 -263.295402) (xy 206.966102 -263.27593) (xy 207.018064 -263.26407)
			(xy 207.071214 -263.260087) (xy 207.124364 -263.26407) (xy 207.176326 -263.27593) (xy 207.22594 -263.295402)
			(xy 207.272098 -263.322051) (xy 207.313769 -263.355282) (xy 207.350021 -263.394353) (xy 207.380045 -263.43839)
			(xy 207.403171 -263.486411) (xy 207.418881 -263.537341) (xy 207.426824 -263.590045) (xy 207.427322 -263.616694)
			(xy 207.426824 -263.643343) (xy 207.418881 -263.696047) (xy 207.403171 -263.746977) (xy 207.380045 -263.794998)
			(xy 207.350021 -263.839035) (xy 207.313769 -263.878106) (xy 207.272098 -263.911337) (xy 207.22594 -263.937986)
			(xy 207.176326 -263.957458) (xy 207.124364 -263.969318) (xy 207.071214 -263.973302) (xy 207.018064 -263.969318)
			(xy 206.966102 -263.957458) (xy 206.916488 -263.937986) (xy 206.87033 -263.911337) (xy 206.828659 -263.878106)
			(xy 206.792407 -263.839035) (xy 206.762383 -263.794998) (xy 206.739257 -263.746977) (xy 206.723547 -263.696047)
			(xy 206.715604 -263.643343) (xy 192.263024 -263.643343) (xy 192.255081 -263.696047) (xy 192.239371 -263.746977)
			(xy 192.216245 -263.794998) (xy 192.186221 -263.839035) (xy 192.149969 -263.878106) (xy 192.108298 -263.911337)
			(xy 192.06214 -263.937986) (xy 192.012526 -263.957458) (xy 191.960564 -263.969318) (xy 191.907414 -263.973302)
			(xy 191.854264 -263.969318) (xy 191.802302 -263.957458) (xy 191.752688 -263.937986) (xy 191.70653 -263.911337)
			(xy 191.664859 -263.878106) (xy 191.628607 -263.839035) (xy 191.598583 -263.794998) (xy 191.575457 -263.746977)
			(xy 191.559747 -263.696047) (xy 191.551804 -263.643343) (xy 177.175424 -263.643343) (xy 177.167481 -263.696047)
			(xy 177.151771 -263.746977) (xy 177.128645 -263.794998) (xy 177.098621 -263.839035) (xy 177.062369 -263.878106)
			(xy 177.020698 -263.911337) (xy 176.97454 -263.937986) (xy 176.924926 -263.957458) (xy 176.872964 -263.969318)
			(xy 176.819814 -263.973302) (xy 176.766664 -263.969318) (xy 176.714702 -263.957458) (xy 176.665088 -263.937986)
			(xy 176.61893 -263.911337) (xy 176.577259 -263.878106) (xy 176.541007 -263.839035) (xy 176.510983 -263.794998)
			(xy 176.487857 -263.746977) (xy 176.472147 -263.696047) (xy 176.464204 -263.643343) (xy 159.11576 -263.643343)
			(xy 159.11576 -264.493227) (xy 172.364136 -264.493227) (xy 172.364136 -264.439929) (xy 172.372079 -264.387225)
			(xy 172.387789 -264.336295) (xy 172.410915 -264.288274) (xy 172.440939 -264.244237) (xy 172.477191 -264.205166)
			(xy 172.518862 -264.171935) (xy 172.56502 -264.145286) (xy 172.614634 -264.125814) (xy 172.666596 -264.113954)
			(xy 172.719746 -264.109971) (xy 172.772896 -264.113954) (xy 172.824858 -264.125814) (xy 172.874472 -264.145286)
			(xy 172.92063 -264.171935) (xy 172.962301 -264.205166) (xy 172.998553 -264.244237) (xy 173.028577 -264.288274)
			(xy 173.051703 -264.336295) (xy 173.067413 -264.387225) (xy 173.075356 -264.439929) (xy 173.075854 -264.466578)
			(xy 173.075356 -264.493227) (xy 187.527936 -264.493227) (xy 187.527936 -264.439929) (xy 187.535879 -264.387225)
			(xy 187.551589 -264.336295) (xy 187.574715 -264.288274) (xy 187.604739 -264.244237) (xy 187.640991 -264.205166)
			(xy 187.682662 -264.171935) (xy 187.72882 -264.145286) (xy 187.778434 -264.125814) (xy 187.830396 -264.113954)
			(xy 187.883546 -264.109971) (xy 187.936696 -264.113954) (xy 187.988658 -264.125814) (xy 188.038272 -264.145286)
			(xy 188.08443 -264.171935) (xy 188.126101 -264.205166) (xy 188.162353 -264.244237) (xy 188.192377 -264.288274)
			(xy 188.215503 -264.336295) (xy 188.231213 -264.387225) (xy 188.239156 -264.439929) (xy 188.239654 -264.466578)
			(xy 188.239156 -264.493227) (xy 202.615536 -264.493227) (xy 202.615536 -264.439929) (xy 202.623479 -264.387225)
			(xy 202.639189 -264.336295) (xy 202.662315 -264.288274) (xy 202.692339 -264.244237) (xy 202.728591 -264.205166)
			(xy 202.770262 -264.171935) (xy 202.81642 -264.145286) (xy 202.866034 -264.125814) (xy 202.917996 -264.113954)
			(xy 202.971146 -264.109971) (xy 203.024296 -264.113954) (xy 203.076258 -264.125814) (xy 203.125872 -264.145286)
			(xy 203.17203 -264.171935) (xy 203.213701 -264.205166) (xy 203.249953 -264.244237) (xy 203.279977 -264.288274)
			(xy 203.303103 -264.336295) (xy 203.318813 -264.387225) (xy 203.326756 -264.439929) (xy 203.327254 -264.466578)
			(xy 203.326756 -264.493227) (xy 203.318813 -264.545931) (xy 203.303103 -264.596861) (xy 203.279977 -264.644882)
			(xy 203.249953 -264.688919) (xy 203.213701 -264.72799) (xy 203.17203 -264.761221) (xy 203.125872 -264.78787)
			(xy 203.076258 -264.807342) (xy 203.024296 -264.819202) (xy 202.971146 -264.823186) (xy 202.917996 -264.819202)
			(xy 202.866034 -264.807342) (xy 202.81642 -264.78787) (xy 202.770262 -264.761221) (xy 202.728591 -264.72799)
			(xy 202.692339 -264.688919) (xy 202.662315 -264.644882) (xy 202.639189 -264.596861) (xy 202.623479 -264.545931)
			(xy 202.615536 -264.493227) (xy 188.239156 -264.493227) (xy 188.231213 -264.545931) (xy 188.215503 -264.596861)
			(xy 188.192377 -264.644882) (xy 188.162353 -264.688919) (xy 188.126101 -264.72799) (xy 188.08443 -264.761221)
			(xy 188.038272 -264.78787) (xy 187.988658 -264.807342) (xy 187.936696 -264.819202) (xy 187.883546 -264.823186)
			(xy 187.830396 -264.819202) (xy 187.778434 -264.807342) (xy 187.72882 -264.78787) (xy 187.682662 -264.761221)
			(xy 187.640991 -264.72799) (xy 187.604739 -264.688919) (xy 187.574715 -264.644882) (xy 187.551589 -264.596861)
			(xy 187.535879 -264.545931) (xy 187.527936 -264.493227) (xy 173.075356 -264.493227) (xy 173.067413 -264.545931)
			(xy 173.051703 -264.596861) (xy 173.028577 -264.644882) (xy 172.998553 -264.688919) (xy 172.962301 -264.72799)
			(xy 172.92063 -264.761221) (xy 172.874472 -264.78787) (xy 172.824858 -264.807342) (xy 172.772896 -264.819202)
			(xy 172.719746 -264.823186) (xy 172.666596 -264.819202) (xy 172.614634 -264.807342) (xy 172.56502 -264.78787)
			(xy 172.518862 -264.761221) (xy 172.477191 -264.72799) (xy 172.440939 -264.688919) (xy 172.410915 -264.644882)
			(xy 172.387789 -264.596861) (xy 172.372079 -264.545931) (xy 172.364136 -264.493227) (xy 159.11576 -264.493227)
			(xy 159.11576 -265.343365) (xy 176.464204 -265.343365) (xy 176.464204 -265.290067) (xy 176.472147 -265.237363)
			(xy 176.487857 -265.186433) (xy 176.510983 -265.138412) (xy 176.541007 -265.094375) (xy 176.577259 -265.055304)
			(xy 176.61893 -265.022073) (xy 176.665088 -264.995424) (xy 176.714702 -264.975952) (xy 176.766664 -264.964092)
			(xy 176.819814 -264.960109) (xy 176.872964 -264.964092) (xy 176.924926 -264.975952) (xy 176.97454 -264.995424)
			(xy 177.020698 -265.022073) (xy 177.062369 -265.055304) (xy 177.098621 -265.094375) (xy 177.128645 -265.138412)
			(xy 177.151771 -265.186433) (xy 177.167481 -265.237363) (xy 177.175424 -265.290067) (xy 177.175922 -265.316716)
			(xy 177.175424 -265.343365) (xy 191.551804 -265.343365) (xy 191.551804 -265.290067) (xy 191.559747 -265.237363)
			(xy 191.575457 -265.186433) (xy 191.598583 -265.138412) (xy 191.628607 -265.094375) (xy 191.664859 -265.055304)
			(xy 191.70653 -265.022073) (xy 191.752688 -264.995424) (xy 191.802302 -264.975952) (xy 191.854264 -264.964092)
			(xy 191.907414 -264.960109) (xy 191.960564 -264.964092) (xy 192.012526 -264.975952) (xy 192.06214 -264.995424)
			(xy 192.108298 -265.022073) (xy 192.149969 -265.055304) (xy 192.186221 -265.094375) (xy 192.216245 -265.138412)
			(xy 192.239371 -265.186433) (xy 192.255081 -265.237363) (xy 192.263024 -265.290067) (xy 192.263522 -265.316716)
			(xy 192.263024 -265.343365) (xy 206.715604 -265.343365) (xy 206.715604 -265.290067) (xy 206.723547 -265.237363)
			(xy 206.739257 -265.186433) (xy 206.762383 -265.138412) (xy 206.792407 -265.094375) (xy 206.828659 -265.055304)
			(xy 206.87033 -265.022073) (xy 206.916488 -264.995424) (xy 206.966102 -264.975952) (xy 207.018064 -264.964092)
			(xy 207.071214 -264.960109) (xy 207.124364 -264.964092) (xy 207.176326 -264.975952) (xy 207.22594 -264.995424)
			(xy 207.272098 -265.022073) (xy 207.313769 -265.055304) (xy 207.350021 -265.094375) (xy 207.380045 -265.138412)
			(xy 207.403171 -265.186433) (xy 207.418881 -265.237363) (xy 207.426824 -265.290067) (xy 207.427322 -265.316716)
			(xy 207.426824 -265.343365) (xy 207.418881 -265.396069) (xy 207.403171 -265.446999) (xy 207.380045 -265.49502)
			(xy 207.350021 -265.539057) (xy 207.313769 -265.578128) (xy 207.272098 -265.611359) (xy 207.22594 -265.638008)
			(xy 207.176326 -265.65748) (xy 207.124364 -265.66934) (xy 207.071214 -265.673324) (xy 207.018064 -265.66934)
			(xy 206.966102 -265.65748) (xy 206.916488 -265.638008) (xy 206.87033 -265.611359) (xy 206.828659 -265.578128)
			(xy 206.792407 -265.539057) (xy 206.762383 -265.49502) (xy 206.739257 -265.446999) (xy 206.723547 -265.396069)
			(xy 206.715604 -265.343365) (xy 192.263024 -265.343365) (xy 192.255081 -265.396069) (xy 192.239371 -265.446999)
			(xy 192.216245 -265.49502) (xy 192.186221 -265.539057) (xy 192.149969 -265.578128) (xy 192.108298 -265.611359)
			(xy 192.06214 -265.638008) (xy 192.012526 -265.65748) (xy 191.960564 -265.66934) (xy 191.907414 -265.673324)
			(xy 191.854264 -265.66934) (xy 191.802302 -265.65748) (xy 191.752688 -265.638008) (xy 191.70653 -265.611359)
			(xy 191.664859 -265.578128) (xy 191.628607 -265.539057) (xy 191.598583 -265.49502) (xy 191.575457 -265.446999)
			(xy 191.559747 -265.396069) (xy 191.551804 -265.343365) (xy 177.175424 -265.343365) (xy 177.167481 -265.396069)
			(xy 177.151771 -265.446999) (xy 177.128645 -265.49502) (xy 177.098621 -265.539057) (xy 177.062369 -265.578128)
			(xy 177.020698 -265.611359) (xy 176.97454 -265.638008) (xy 176.924926 -265.65748) (xy 176.872964 -265.66934)
			(xy 176.819814 -265.673324) (xy 176.766664 -265.66934) (xy 176.714702 -265.65748) (xy 176.665088 -265.638008)
			(xy 176.61893 -265.611359) (xy 176.577259 -265.578128) (xy 176.541007 -265.539057) (xy 176.510983 -265.49502)
			(xy 176.487857 -265.446999) (xy 176.472147 -265.396069) (xy 176.464204 -265.343365) (xy 159.11576 -265.343365)
			(xy 159.11576 -266.193249) (xy 172.364136 -266.193249) (xy 172.364136 -266.139951) (xy 172.372079 -266.087247)
			(xy 172.387789 -266.036317) (xy 172.410915 -265.988296) (xy 172.440939 -265.944259) (xy 172.477191 -265.905188)
			(xy 172.518862 -265.871957) (xy 172.56502 -265.845308) (xy 172.614634 -265.825836) (xy 172.666596 -265.813976)
			(xy 172.719746 -265.809993) (xy 172.772896 -265.813976) (xy 172.824858 -265.825836) (xy 172.874472 -265.845308)
			(xy 172.92063 -265.871957) (xy 172.962301 -265.905188) (xy 172.998553 -265.944259) (xy 173.028577 -265.988296)
			(xy 173.051703 -266.036317) (xy 173.067413 -266.087247) (xy 173.075356 -266.139951) (xy 173.075854 -266.1666)
			(xy 173.075356 -266.193249) (xy 187.527936 -266.193249) (xy 187.527936 -266.139951) (xy 187.535879 -266.087247)
			(xy 187.551589 -266.036317) (xy 187.574715 -265.988296) (xy 187.604739 -265.944259) (xy 187.640991 -265.905188)
			(xy 187.682662 -265.871957) (xy 187.72882 -265.845308) (xy 187.778434 -265.825836) (xy 187.830396 -265.813976)
			(xy 187.883546 -265.809993) (xy 187.936696 -265.813976) (xy 187.988658 -265.825836) (xy 188.038272 -265.845308)
			(xy 188.08443 -265.871957) (xy 188.126101 -265.905188) (xy 188.162353 -265.944259) (xy 188.192377 -265.988296)
			(xy 188.215503 -266.036317) (xy 188.231213 -266.087247) (xy 188.239156 -266.139951) (xy 188.239654 -266.1666)
			(xy 188.239156 -266.193249) (xy 202.615536 -266.193249) (xy 202.615536 -266.139951) (xy 202.623479 -266.087247)
			(xy 202.639189 -266.036317) (xy 202.662315 -265.988296) (xy 202.692339 -265.944259) (xy 202.728591 -265.905188)
			(xy 202.770262 -265.871957) (xy 202.81642 -265.845308) (xy 202.866034 -265.825836) (xy 202.917996 -265.813976)
			(xy 202.971146 -265.809993) (xy 203.024296 -265.813976) (xy 203.076258 -265.825836) (xy 203.125872 -265.845308)
			(xy 203.17203 -265.871957) (xy 203.213701 -265.905188) (xy 203.249953 -265.944259) (xy 203.279977 -265.988296)
			(xy 203.303103 -266.036317) (xy 203.318813 -266.087247) (xy 203.326756 -266.139951) (xy 203.327254 -266.1666)
			(xy 203.326756 -266.193249) (xy 203.318813 -266.245953) (xy 203.303103 -266.296883) (xy 203.279977 -266.344904)
			(xy 203.249953 -266.388941) (xy 203.213701 -266.428012) (xy 203.17203 -266.461243) (xy 203.125872 -266.487892)
			(xy 203.076258 -266.507364) (xy 203.024296 -266.519224) (xy 202.971146 -266.523208) (xy 202.917996 -266.519224)
			(xy 202.866034 -266.507364) (xy 202.81642 -266.487892) (xy 202.770262 -266.461243) (xy 202.728591 -266.428012)
			(xy 202.692339 -266.388941) (xy 202.662315 -266.344904) (xy 202.639189 -266.296883) (xy 202.623479 -266.245953)
			(xy 202.615536 -266.193249) (xy 188.239156 -266.193249) (xy 188.231213 -266.245953) (xy 188.215503 -266.296883)
			(xy 188.192377 -266.344904) (xy 188.162353 -266.388941) (xy 188.126101 -266.428012) (xy 188.08443 -266.461243)
			(xy 188.038272 -266.487892) (xy 187.988658 -266.507364) (xy 187.936696 -266.519224) (xy 187.883546 -266.523208)
			(xy 187.830396 -266.519224) (xy 187.778434 -266.507364) (xy 187.72882 -266.487892) (xy 187.682662 -266.461243)
			(xy 187.640991 -266.428012) (xy 187.604739 -266.388941) (xy 187.574715 -266.344904) (xy 187.551589 -266.296883)
			(xy 187.535879 -266.245953) (xy 187.527936 -266.193249) (xy 173.075356 -266.193249) (xy 173.067413 -266.245953)
			(xy 173.051703 -266.296883) (xy 173.028577 -266.344904) (xy 172.998553 -266.388941) (xy 172.962301 -266.428012)
			(xy 172.92063 -266.461243) (xy 172.874472 -266.487892) (xy 172.824858 -266.507364) (xy 172.772896 -266.519224)
			(xy 172.719746 -266.523208) (xy 172.666596 -266.519224) (xy 172.614634 -266.507364) (xy 172.56502 -266.487892)
			(xy 172.518862 -266.461243) (xy 172.477191 -266.428012) (xy 172.440939 -266.388941) (xy 172.410915 -266.344904)
			(xy 172.387789 -266.296883) (xy 172.372079 -266.245953) (xy 172.364136 -266.193249) (xy 159.11576 -266.193249)
			(xy 159.11576 -267.043387) (xy 176.540404 -267.043387) (xy 176.540404 -266.990089) (xy 176.548347 -266.937385)
			(xy 176.564057 -266.886455) (xy 176.587183 -266.838434) (xy 176.617207 -266.794397) (xy 176.653459 -266.755326)
			(xy 176.69513 -266.722095) (xy 176.741288 -266.695446) (xy 176.790902 -266.675974) (xy 176.842864 -266.664114)
			(xy 176.896014 -266.660131) (xy 176.949164 -266.664114) (xy 177.001126 -266.675974) (xy 177.05074 -266.695446)
			(xy 177.096898 -266.722095) (xy 177.138569 -266.755326) (xy 177.174821 -266.794397) (xy 177.204845 -266.838434)
			(xy 177.227971 -266.886455) (xy 177.243681 -266.937385) (xy 177.251624 -266.990089) (xy 177.252122 -267.016738)
			(xy 177.251624 -267.043387) (xy 184.084204 -267.043387) (xy 184.084204 -266.990089) (xy 184.092147 -266.937385)
			(xy 184.107857 -266.886455) (xy 184.130983 -266.838434) (xy 184.161007 -266.794397) (xy 184.197259 -266.755326)
			(xy 184.23893 -266.722095) (xy 184.285088 -266.695446) (xy 184.334702 -266.675974) (xy 184.386664 -266.664114)
			(xy 184.439814 -266.660131) (xy 184.492964 -266.664114) (xy 184.544926 -266.675974) (xy 184.59454 -266.695446)
			(xy 184.640698 -266.722095) (xy 184.682369 -266.755326) (xy 184.718621 -266.794397) (xy 184.748645 -266.838434)
			(xy 184.771771 -266.886455) (xy 184.787481 -266.937385) (xy 184.795424 -266.990089) (xy 184.795922 -267.016738)
			(xy 184.795424 -267.043387) (xy 191.628004 -267.043387) (xy 191.628004 -266.990089) (xy 191.635947 -266.937385)
			(xy 191.651657 -266.886455) (xy 191.674783 -266.838434) (xy 191.704807 -266.794397) (xy 191.741059 -266.755326)
			(xy 191.78273 -266.722095) (xy 191.828888 -266.695446) (xy 191.878502 -266.675974) (xy 191.930464 -266.664114)
			(xy 191.983614 -266.660131) (xy 192.036764 -266.664114) (xy 192.088726 -266.675974) (xy 192.13834 -266.695446)
			(xy 192.184498 -266.722095) (xy 192.226169 -266.755326) (xy 192.262421 -266.794397) (xy 192.292445 -266.838434)
			(xy 192.315571 -266.886455) (xy 192.331281 -266.937385) (xy 192.339224 -266.990089) (xy 192.339722 -267.016738)
			(xy 192.339224 -267.043387) (xy 199.171804 -267.043387) (xy 199.171804 -266.990089) (xy 199.179747 -266.937385)
			(xy 199.195457 -266.886455) (xy 199.218583 -266.838434) (xy 199.248607 -266.794397) (xy 199.284859 -266.755326)
			(xy 199.32653 -266.722095) (xy 199.372688 -266.695446) (xy 199.422302 -266.675974) (xy 199.474264 -266.664114)
			(xy 199.527414 -266.660131) (xy 199.580564 -266.664114) (xy 199.632526 -266.675974) (xy 199.68214 -266.695446)
			(xy 199.728298 -266.722095) (xy 199.769969 -266.755326) (xy 199.806221 -266.794397) (xy 199.836245 -266.838434)
			(xy 199.859371 -266.886455) (xy 199.875081 -266.937385) (xy 199.883024 -266.990089) (xy 199.883522 -267.016738)
			(xy 199.883024 -267.043387) (xy 206.639404 -267.043387) (xy 206.639404 -266.990089) (xy 206.647347 -266.937385)
			(xy 206.663057 -266.886455) (xy 206.686183 -266.838434) (xy 206.716207 -266.794397) (xy 206.752459 -266.755326)
			(xy 206.79413 -266.722095) (xy 206.840288 -266.695446) (xy 206.889902 -266.675974) (xy 206.941864 -266.664114)
			(xy 206.995014 -266.660131) (xy 207.048164 -266.664114) (xy 207.100126 -266.675974) (xy 207.14974 -266.695446)
			(xy 207.195898 -266.722095) (xy 207.237569 -266.755326) (xy 207.273821 -266.794397) (xy 207.303845 -266.838434)
			(xy 207.326971 -266.886455) (xy 207.342681 -266.937385) (xy 207.350624 -266.990089) (xy 207.351122 -267.016738)
			(xy 207.350624 -267.043387) (xy 214.259404 -267.043387) (xy 214.259404 -266.990089) (xy 214.267347 -266.937385)
			(xy 214.283057 -266.886455) (xy 214.306183 -266.838434) (xy 214.336207 -266.794397) (xy 214.372459 -266.755326)
			(xy 214.41413 -266.722095) (xy 214.460288 -266.695446) (xy 214.509902 -266.675974) (xy 214.561864 -266.664114)
			(xy 214.615014 -266.660131) (xy 214.668164 -266.664114) (xy 214.720126 -266.675974) (xy 214.76974 -266.695446)
			(xy 214.815898 -266.722095) (xy 214.857569 -266.755326) (xy 214.893821 -266.794397) (xy 214.923845 -266.838434)
			(xy 214.946971 -266.886455) (xy 214.962681 -266.937385) (xy 214.970624 -266.990089) (xy 214.971122 -267.016738)
			(xy 214.970624 -267.043387) (xy 214.962681 -267.096091) (xy 214.946971 -267.147021) (xy 214.923845 -267.195042)
			(xy 214.893821 -267.239079) (xy 214.857569 -267.27815) (xy 214.815898 -267.311381) (xy 214.76974 -267.33803)
			(xy 214.720126 -267.357502) (xy 214.668164 -267.369362) (xy 214.615014 -267.373346) (xy 214.561864 -267.369362)
			(xy 214.509902 -267.357502) (xy 214.460288 -267.33803) (xy 214.41413 -267.311381) (xy 214.372459 -267.27815)
			(xy 214.336207 -267.239079) (xy 214.306183 -267.195042) (xy 214.283057 -267.147021) (xy 214.267347 -267.096091)
			(xy 214.259404 -267.043387) (xy 207.350624 -267.043387) (xy 207.342681 -267.096091) (xy 207.326971 -267.147021)
			(xy 207.303845 -267.195042) (xy 207.273821 -267.239079) (xy 207.237569 -267.27815) (xy 207.195898 -267.311381)
			(xy 207.14974 -267.33803) (xy 207.100126 -267.357502) (xy 207.048164 -267.369362) (xy 206.995014 -267.373346)
			(xy 206.941864 -267.369362) (xy 206.889902 -267.357502) (xy 206.840288 -267.33803) (xy 206.79413 -267.311381)
			(xy 206.752459 -267.27815) (xy 206.716207 -267.239079) (xy 206.686183 -267.195042) (xy 206.663057 -267.147021)
			(xy 206.647347 -267.096091) (xy 206.639404 -267.043387) (xy 199.883024 -267.043387) (xy 199.875081 -267.096091)
			(xy 199.859371 -267.147021) (xy 199.836245 -267.195042) (xy 199.806221 -267.239079) (xy 199.769969 -267.27815)
			(xy 199.728298 -267.311381) (xy 199.68214 -267.33803) (xy 199.632526 -267.357502) (xy 199.580564 -267.369362)
			(xy 199.527414 -267.373346) (xy 199.474264 -267.369362) (xy 199.422302 -267.357502) (xy 199.372688 -267.33803)
			(xy 199.32653 -267.311381) (xy 199.284859 -267.27815) (xy 199.248607 -267.239079) (xy 199.218583 -267.195042)
			(xy 199.195457 -267.147021) (xy 199.179747 -267.096091) (xy 199.171804 -267.043387) (xy 192.339224 -267.043387)
			(xy 192.331281 -267.096091) (xy 192.315571 -267.147021) (xy 192.292445 -267.195042) (xy 192.262421 -267.239079)
			(xy 192.226169 -267.27815) (xy 192.184498 -267.311381) (xy 192.13834 -267.33803) (xy 192.088726 -267.357502)
			(xy 192.036764 -267.369362) (xy 191.983614 -267.373346) (xy 191.930464 -267.369362) (xy 191.878502 -267.357502)
			(xy 191.828888 -267.33803) (xy 191.78273 -267.311381) (xy 191.741059 -267.27815) (xy 191.704807 -267.239079)
			(xy 191.674783 -267.195042) (xy 191.651657 -267.147021) (xy 191.635947 -267.096091) (xy 191.628004 -267.043387)
			(xy 184.795424 -267.043387) (xy 184.787481 -267.096091) (xy 184.771771 -267.147021) (xy 184.748645 -267.195042)
			(xy 184.718621 -267.239079) (xy 184.682369 -267.27815) (xy 184.640698 -267.311381) (xy 184.59454 -267.33803)
			(xy 184.544926 -267.357502) (xy 184.492964 -267.369362) (xy 184.439814 -267.373346) (xy 184.386664 -267.369362)
			(xy 184.334702 -267.357502) (xy 184.285088 -267.33803) (xy 184.23893 -267.311381) (xy 184.197259 -267.27815)
			(xy 184.161007 -267.239079) (xy 184.130983 -267.195042) (xy 184.107857 -267.147021) (xy 184.092147 -267.096091)
			(xy 184.084204 -267.043387) (xy 177.251624 -267.043387) (xy 177.243681 -267.096091) (xy 177.227971 -267.147021)
			(xy 177.204845 -267.195042) (xy 177.174821 -267.239079) (xy 177.138569 -267.27815) (xy 177.096898 -267.311381)
			(xy 177.05074 -267.33803) (xy 177.001126 -267.357502) (xy 176.949164 -267.369362) (xy 176.896014 -267.373346)
			(xy 176.842864 -267.369362) (xy 176.790902 -267.357502) (xy 176.741288 -267.33803) (xy 176.69513 -267.311381)
			(xy 176.653459 -267.27815) (xy 176.617207 -267.239079) (xy 176.587183 -267.195042) (xy 176.564057 -267.147021)
			(xy 176.548347 -267.096091) (xy 176.540404 -267.043387) (xy 159.11576 -267.043387) (xy 159.11576 -267.893271)
			(xy 172.364136 -267.893271) (xy 172.364136 -267.839973) (xy 172.372079 -267.787269) (xy 172.387789 -267.736339)
			(xy 172.410915 -267.688318) (xy 172.440939 -267.644281) (xy 172.477191 -267.60521) (xy 172.518862 -267.571979)
			(xy 172.56502 -267.54533) (xy 172.614634 -267.525858) (xy 172.666596 -267.513998) (xy 172.719746 -267.510015)
			(xy 172.772896 -267.513998) (xy 172.824858 -267.525858) (xy 172.874472 -267.54533) (xy 172.92063 -267.571979)
			(xy 172.962301 -267.60521) (xy 172.998553 -267.644281) (xy 173.028577 -267.688318) (xy 173.051703 -267.736339)
			(xy 173.067413 -267.787269) (xy 173.075356 -267.839973) (xy 173.075854 -267.866622) (xy 173.075356 -267.893271)
			(xy 179.984136 -267.893271) (xy 179.984136 -267.839973) (xy 179.992079 -267.787269) (xy 180.007789 -267.736339)
			(xy 180.030915 -267.688318) (xy 180.060939 -267.644281) (xy 180.097191 -267.60521) (xy 180.138862 -267.571979)
			(xy 180.18502 -267.54533) (xy 180.234634 -267.525858) (xy 180.286596 -267.513998) (xy 180.339746 -267.510015)
			(xy 180.392896 -267.513998) (xy 180.444858 -267.525858) (xy 180.494472 -267.54533) (xy 180.54063 -267.571979)
			(xy 180.582301 -267.60521) (xy 180.618553 -267.644281) (xy 180.648577 -267.688318) (xy 180.671703 -267.736339)
			(xy 180.687413 -267.787269) (xy 180.695356 -267.839973) (xy 180.695854 -267.866622) (xy 180.695356 -267.893271)
			(xy 187.527936 -267.893271) (xy 187.527936 -267.839973) (xy 187.535879 -267.787269) (xy 187.551589 -267.736339)
			(xy 187.574715 -267.688318) (xy 187.604739 -267.644281) (xy 187.640991 -267.60521) (xy 187.682662 -267.571979)
			(xy 187.72882 -267.54533) (xy 187.778434 -267.525858) (xy 187.830396 -267.513998) (xy 187.883546 -267.510015)
			(xy 187.936696 -267.513998) (xy 187.988658 -267.525858) (xy 188.038272 -267.54533) (xy 188.08443 -267.571979)
			(xy 188.126101 -267.60521) (xy 188.162353 -267.644281) (xy 188.192377 -267.688318) (xy 188.215503 -267.736339)
			(xy 188.231213 -267.787269) (xy 188.239156 -267.839973) (xy 188.239654 -267.866622) (xy 188.239156 -267.893271)
			(xy 195.071736 -267.893271) (xy 195.071736 -267.839973) (xy 195.079679 -267.787269) (xy 195.095389 -267.736339)
			(xy 195.118515 -267.688318) (xy 195.148539 -267.644281) (xy 195.184791 -267.60521) (xy 195.226462 -267.571979)
			(xy 195.27262 -267.54533) (xy 195.322234 -267.525858) (xy 195.374196 -267.513998) (xy 195.427346 -267.510015)
			(xy 195.480496 -267.513998) (xy 195.532458 -267.525858) (xy 195.582072 -267.54533) (xy 195.62823 -267.571979)
			(xy 195.669901 -267.60521) (xy 195.706153 -267.644281) (xy 195.736177 -267.688318) (xy 195.759303 -267.736339)
			(xy 195.775013 -267.787269) (xy 195.782956 -267.839973) (xy 195.783454 -267.866622) (xy 195.782956 -267.893271)
			(xy 202.615536 -267.893271) (xy 202.615536 -267.839973) (xy 202.623479 -267.787269) (xy 202.639189 -267.736339)
			(xy 202.662315 -267.688318) (xy 202.692339 -267.644281) (xy 202.728591 -267.60521) (xy 202.770262 -267.571979)
			(xy 202.81642 -267.54533) (xy 202.866034 -267.525858) (xy 202.917996 -267.513998) (xy 202.971146 -267.510015)
			(xy 203.024296 -267.513998) (xy 203.076258 -267.525858) (xy 203.125872 -267.54533) (xy 203.17203 -267.571979)
			(xy 203.213701 -267.60521) (xy 203.249953 -267.644281) (xy 203.279977 -267.688318) (xy 203.303103 -267.736339)
			(xy 203.318813 -267.787269) (xy 203.326756 -267.839973) (xy 203.327254 -267.866622) (xy 203.326756 -267.893271)
			(xy 210.159336 -267.893271) (xy 210.159336 -267.839973) (xy 210.167279 -267.787269) (xy 210.182989 -267.736339)
			(xy 210.206115 -267.688318) (xy 210.236139 -267.644281) (xy 210.272391 -267.60521) (xy 210.314062 -267.571979)
			(xy 210.36022 -267.54533) (xy 210.409834 -267.525858) (xy 210.461796 -267.513998) (xy 210.514946 -267.510015)
			(xy 210.568096 -267.513998) (xy 210.620058 -267.525858) (xy 210.669672 -267.54533) (xy 210.71583 -267.571979)
			(xy 210.757501 -267.60521) (xy 210.793753 -267.644281) (xy 210.823777 -267.688318) (xy 210.846903 -267.736339)
			(xy 210.862613 -267.787269) (xy 210.870556 -267.839973) (xy 210.871054 -267.866622) (xy 210.870556 -267.893271)
			(xy 210.862613 -267.945975) (xy 210.846903 -267.996905) (xy 210.823777 -268.044926) (xy 210.793753 -268.088963)
			(xy 210.757501 -268.128034) (xy 210.71583 -268.161265) (xy 210.669672 -268.187914) (xy 210.620058 -268.207386)
			(xy 210.568096 -268.219246) (xy 210.514946 -268.22323) (xy 210.461796 -268.219246) (xy 210.409834 -268.207386)
			(xy 210.36022 -268.187914) (xy 210.314062 -268.161265) (xy 210.272391 -268.128034) (xy 210.236139 -268.088963)
			(xy 210.206115 -268.044926) (xy 210.182989 -267.996905) (xy 210.167279 -267.945975) (xy 210.159336 -267.893271)
			(xy 203.326756 -267.893271) (xy 203.318813 -267.945975) (xy 203.303103 -267.996905) (xy 203.279977 -268.044926)
			(xy 203.249953 -268.088963) (xy 203.213701 -268.128034) (xy 203.17203 -268.161265) (xy 203.125872 -268.187914)
			(xy 203.076258 -268.207386) (xy 203.024296 -268.219246) (xy 202.971146 -268.22323) (xy 202.917996 -268.219246)
			(xy 202.866034 -268.207386) (xy 202.81642 -268.187914) (xy 202.770262 -268.161265) (xy 202.728591 -268.128034)
			(xy 202.692339 -268.088963) (xy 202.662315 -268.044926) (xy 202.639189 -267.996905) (xy 202.623479 -267.945975)
			(xy 202.615536 -267.893271) (xy 195.782956 -267.893271) (xy 195.775013 -267.945975) (xy 195.759303 -267.996905)
			(xy 195.736177 -268.044926) (xy 195.706153 -268.088963) (xy 195.669901 -268.128034) (xy 195.62823 -268.161265)
			(xy 195.582072 -268.187914) (xy 195.532458 -268.207386) (xy 195.480496 -268.219246) (xy 195.427346 -268.22323)
			(xy 195.374196 -268.219246) (xy 195.322234 -268.207386) (xy 195.27262 -268.187914) (xy 195.226462 -268.161265)
			(xy 195.184791 -268.128034) (xy 195.148539 -268.088963) (xy 195.118515 -268.044926) (xy 195.095389 -267.996905)
			(xy 195.079679 -267.945975) (xy 195.071736 -267.893271) (xy 188.239156 -267.893271) (xy 188.231213 -267.945975)
			(xy 188.215503 -267.996905) (xy 188.192377 -268.044926) (xy 188.162353 -268.088963) (xy 188.126101 -268.128034)
			(xy 188.08443 -268.161265) (xy 188.038272 -268.187914) (xy 187.988658 -268.207386) (xy 187.936696 -268.219246)
			(xy 187.883546 -268.22323) (xy 187.830396 -268.219246) (xy 187.778434 -268.207386) (xy 187.72882 -268.187914)
			(xy 187.682662 -268.161265) (xy 187.640991 -268.128034) (xy 187.604739 -268.088963) (xy 187.574715 -268.044926)
			(xy 187.551589 -267.996905) (xy 187.535879 -267.945975) (xy 187.527936 -267.893271) (xy 180.695356 -267.893271)
			(xy 180.687413 -267.945975) (xy 180.671703 -267.996905) (xy 180.648577 -268.044926) (xy 180.618553 -268.088963)
			(xy 180.582301 -268.128034) (xy 180.54063 -268.161265) (xy 180.494472 -268.187914) (xy 180.444858 -268.207386)
			(xy 180.392896 -268.219246) (xy 180.339746 -268.22323) (xy 180.286596 -268.219246) (xy 180.234634 -268.207386)
			(xy 180.18502 -268.187914) (xy 180.138862 -268.161265) (xy 180.097191 -268.128034) (xy 180.060939 -268.088963)
			(xy 180.030915 -268.044926) (xy 180.007789 -267.996905) (xy 179.992079 -267.945975) (xy 179.984136 -267.893271)
			(xy 173.075356 -267.893271) (xy 173.067413 -267.945975) (xy 173.051703 -267.996905) (xy 173.028577 -268.044926)
			(xy 172.998553 -268.088963) (xy 172.962301 -268.128034) (xy 172.92063 -268.161265) (xy 172.874472 -268.187914)
			(xy 172.824858 -268.207386) (xy 172.772896 -268.219246) (xy 172.719746 -268.22323) (xy 172.666596 -268.219246)
			(xy 172.614634 -268.207386) (xy 172.56502 -268.187914) (xy 172.518862 -268.161265) (xy 172.477191 -268.128034)
			(xy 172.440939 -268.088963) (xy 172.410915 -268.044926) (xy 172.387789 -267.996905) (xy 172.372079 -267.945975)
			(xy 172.364136 -267.893271) (xy 159.11576 -267.893271) (xy 159.11576 -268.743409) (xy 184.084204 -268.743409)
			(xy 184.084204 -268.690111) (xy 184.092147 -268.637407) (xy 184.107857 -268.586477) (xy 184.130983 -268.538456)
			(xy 184.161007 -268.494419) (xy 184.197259 -268.455348) (xy 184.23893 -268.422117) (xy 184.285088 -268.395468)
			(xy 184.334702 -268.375996) (xy 184.386664 -268.364136) (xy 184.439814 -268.360153) (xy 184.492964 -268.364136)
			(xy 184.544926 -268.375996) (xy 184.59454 -268.395468) (xy 184.640698 -268.422117) (xy 184.682369 -268.455348)
			(xy 184.718621 -268.494419) (xy 184.748645 -268.538456) (xy 184.771771 -268.586477) (xy 184.787481 -268.637407)
			(xy 184.795424 -268.690111) (xy 184.795922 -268.71676) (xy 184.795424 -268.743409) (xy 191.551804 -268.743409)
			(xy 191.551804 -268.690111) (xy 191.559747 -268.637407) (xy 191.575457 -268.586477) (xy 191.598583 -268.538456)
			(xy 191.628607 -268.494419) (xy 191.664859 -268.455348) (xy 191.70653 -268.422117) (xy 191.752688 -268.395468)
			(xy 191.802302 -268.375996) (xy 191.854264 -268.364136) (xy 191.907414 -268.360153) (xy 191.960564 -268.364136)
			(xy 192.012526 -268.375996) (xy 192.06214 -268.395468) (xy 192.108298 -268.422117) (xy 192.149969 -268.455348)
			(xy 192.186221 -268.494419) (xy 192.216245 -268.538456) (xy 192.239371 -268.586477) (xy 192.255081 -268.637407)
			(xy 192.263024 -268.690111) (xy 192.263522 -268.71676) (xy 192.263024 -268.743409) (xy 192.255081 -268.796113)
			(xy 192.239371 -268.847043) (xy 192.216245 -268.895064) (xy 192.186221 -268.939101) (xy 192.149969 -268.978172)
			(xy 192.108298 -269.011403) (xy 192.06214 -269.038052) (xy 192.012526 -269.057524) (xy 191.960564 -269.069384)
			(xy 191.907414 -269.073368) (xy 191.854264 -269.069384) (xy 191.802302 -269.057524) (xy 191.752688 -269.038052)
			(xy 191.70653 -269.011403) (xy 191.664859 -268.978172) (xy 191.628607 -268.939101) (xy 191.598583 -268.895064)
			(xy 191.575457 -268.847043) (xy 191.559747 -268.796113) (xy 191.551804 -268.743409) (xy 184.795424 -268.743409)
			(xy 184.787481 -268.796113) (xy 184.771771 -268.847043) (xy 184.748645 -268.895064) (xy 184.718621 -268.939101)
			(xy 184.682369 -268.978172) (xy 184.640698 -269.011403) (xy 184.59454 -269.038052) (xy 184.544926 -269.057524)
			(xy 184.492964 -269.069384) (xy 184.439814 -269.073368) (xy 184.386664 -269.069384) (xy 184.334702 -269.057524)
			(xy 184.285088 -269.038052) (xy 184.23893 -269.011403) (xy 184.197259 -268.978172) (xy 184.161007 -268.939101)
			(xy 184.130983 -268.895064) (xy 184.107857 -268.847043) (xy 184.092147 -268.796113) (xy 184.084204 -268.743409)
			(xy 159.11576 -268.743409) (xy 159.11576 -269.593293) (xy 172.440336 -269.593293) (xy 172.440336 -269.539995)
			(xy 172.448279 -269.487291) (xy 172.463989 -269.436361) (xy 172.487115 -269.38834) (xy 172.517139 -269.344303)
			(xy 172.553391 -269.305232) (xy 172.595062 -269.272001) (xy 172.64122 -269.245352) (xy 172.690834 -269.22588)
			(xy 172.742796 -269.21402) (xy 172.795946 -269.210037) (xy 172.849096 -269.21402) (xy 172.901058 -269.22588)
			(xy 172.950672 -269.245352) (xy 172.99683 -269.272001) (xy 173.038501 -269.305232) (xy 173.074753 -269.344303)
			(xy 173.104777 -269.38834) (xy 173.127903 -269.436361) (xy 173.143613 -269.487291) (xy 173.151556 -269.539995)
			(xy 173.152054 -269.566644) (xy 173.151556 -269.593293) (xy 187.527936 -269.593293) (xy 187.527936 -269.539995)
			(xy 187.535879 -269.487291) (xy 187.551589 -269.436361) (xy 187.574715 -269.38834) (xy 187.604739 -269.344303)
			(xy 187.640991 -269.305232) (xy 187.682662 -269.272001) (xy 187.72882 -269.245352) (xy 187.778434 -269.22588)
			(xy 187.830396 -269.21402) (xy 187.883546 -269.210037) (xy 187.936696 -269.21402) (xy 187.988658 -269.22588)
			(xy 188.038272 -269.245352) (xy 188.08443 -269.272001) (xy 188.126101 -269.305232) (xy 188.162353 -269.344303)
			(xy 188.192377 -269.38834) (xy 188.215503 -269.436361) (xy 188.231213 -269.487291) (xy 188.239156 -269.539995)
			(xy 188.239654 -269.566644) (xy 188.239156 -269.593293) (xy 202.615536 -269.593293) (xy 202.615536 -269.539995)
			(xy 202.623479 -269.487291) (xy 202.639189 -269.436361) (xy 202.662315 -269.38834) (xy 202.692339 -269.344303)
			(xy 202.728591 -269.305232) (xy 202.770262 -269.272001) (xy 202.81642 -269.245352) (xy 202.866034 -269.22588)
			(xy 202.917996 -269.21402) (xy 202.971146 -269.210037) (xy 203.024296 -269.21402) (xy 203.076258 -269.22588)
			(xy 203.125872 -269.245352) (xy 203.17203 -269.272001) (xy 203.213701 -269.305232) (xy 203.249953 -269.344303)
			(xy 203.279977 -269.38834) (xy 203.303103 -269.436361) (xy 203.318813 -269.487291) (xy 203.326756 -269.539995)
			(xy 203.327254 -269.566644) (xy 203.326756 -269.593293) (xy 203.318813 -269.645997) (xy 203.303103 -269.696927)
			(xy 203.279977 -269.744948) (xy 203.249953 -269.788985) (xy 203.213701 -269.828056) (xy 203.17203 -269.861287)
			(xy 203.125872 -269.887936) (xy 203.076258 -269.907408) (xy 203.024296 -269.919268) (xy 202.971146 -269.923252)
			(xy 202.917996 -269.919268) (xy 202.866034 -269.907408) (xy 202.81642 -269.887936) (xy 202.770262 -269.861287)
			(xy 202.728591 -269.828056) (xy 202.692339 -269.788985) (xy 202.662315 -269.744948) (xy 202.639189 -269.696927)
			(xy 202.623479 -269.645997) (xy 202.615536 -269.593293) (xy 188.239156 -269.593293) (xy 188.231213 -269.645997)
			(xy 188.215503 -269.696927) (xy 188.192377 -269.744948) (xy 188.162353 -269.788985) (xy 188.126101 -269.828056)
			(xy 188.08443 -269.861287) (xy 188.038272 -269.887936) (xy 187.988658 -269.907408) (xy 187.936696 -269.919268)
			(xy 187.883546 -269.923252) (xy 187.830396 -269.919268) (xy 187.778434 -269.907408) (xy 187.72882 -269.887936)
			(xy 187.682662 -269.861287) (xy 187.640991 -269.828056) (xy 187.604739 -269.788985) (xy 187.574715 -269.744948)
			(xy 187.551589 -269.696927) (xy 187.535879 -269.645997) (xy 187.527936 -269.593293) (xy 173.151556 -269.593293)
			(xy 173.143613 -269.645997) (xy 173.127903 -269.696927) (xy 173.104777 -269.744948) (xy 173.074753 -269.788985)
			(xy 173.038501 -269.828056) (xy 172.99683 -269.861287) (xy 172.950672 -269.887936) (xy 172.901058 -269.907408)
			(xy 172.849096 -269.919268) (xy 172.795946 -269.923252) (xy 172.742796 -269.919268) (xy 172.690834 -269.907408)
			(xy 172.64122 -269.887936) (xy 172.595062 -269.861287) (xy 172.553391 -269.828056) (xy 172.517139 -269.788985)
			(xy 172.487115 -269.744948) (xy 172.463989 -269.696927) (xy 172.448279 -269.645997) (xy 172.440336 -269.593293)
			(xy 159.11576 -269.593293) (xy 159.11576 -270.443431) (xy 176.540404 -270.443431) (xy 176.540404 -270.390133)
			(xy 176.548347 -270.337429) (xy 176.564057 -270.286499) (xy 176.587183 -270.238478) (xy 176.617207 -270.194441)
			(xy 176.653459 -270.15537) (xy 176.69513 -270.122139) (xy 176.741288 -270.09549) (xy 176.790902 -270.076018)
			(xy 176.842864 -270.064158) (xy 176.896014 -270.060175) (xy 176.949164 -270.064158) (xy 177.001126 -270.076018)
			(xy 177.05074 -270.09549) (xy 177.096898 -270.122139) (xy 177.138569 -270.15537) (xy 177.174821 -270.194441)
			(xy 177.204845 -270.238478) (xy 177.227971 -270.286499) (xy 177.243681 -270.337429) (xy 177.251624 -270.390133)
			(xy 177.252122 -270.416782) (xy 177.251624 -270.443431) (xy 191.602604 -270.443431) (xy 191.602604 -270.390133)
			(xy 191.610547 -270.337429) (xy 191.626257 -270.286499) (xy 191.649383 -270.238478) (xy 191.679407 -270.194441)
			(xy 191.715659 -270.15537) (xy 191.75733 -270.122139) (xy 191.803488 -270.09549) (xy 191.853102 -270.076018)
			(xy 191.905064 -270.064158) (xy 191.958214 -270.060175) (xy 192.011364 -270.064158) (xy 192.063326 -270.076018)
			(xy 192.11294 -270.09549) (xy 192.159098 -270.122139) (xy 192.200769 -270.15537) (xy 192.237021 -270.194441)
			(xy 192.267045 -270.238478) (xy 192.290171 -270.286499) (xy 192.305881 -270.337429) (xy 192.313824 -270.390133)
			(xy 192.314322 -270.416782) (xy 192.313824 -270.443431) (xy 206.715604 -270.443431) (xy 206.715604 -270.390133)
			(xy 206.723547 -270.337429) (xy 206.739257 -270.286499) (xy 206.762383 -270.238478) (xy 206.792407 -270.194441)
			(xy 206.828659 -270.15537) (xy 206.87033 -270.122139) (xy 206.916488 -270.09549) (xy 206.966102 -270.076018)
			(xy 207.018064 -270.064158) (xy 207.071214 -270.060175) (xy 207.124364 -270.064158) (xy 207.176326 -270.076018)
			(xy 207.22594 -270.09549) (xy 207.272098 -270.122139) (xy 207.313769 -270.15537) (xy 207.350021 -270.194441)
			(xy 207.380045 -270.238478) (xy 207.403171 -270.286499) (xy 207.418881 -270.337429) (xy 207.426824 -270.390133)
			(xy 207.427322 -270.416782) (xy 207.426824 -270.443431) (xy 207.418881 -270.496135) (xy 207.403171 -270.547065)
			(xy 207.380045 -270.595086) (xy 207.350021 -270.639123) (xy 207.313769 -270.678194) (xy 207.272098 -270.711425)
			(xy 207.22594 -270.738074) (xy 207.176326 -270.757546) (xy 207.124364 -270.769406) (xy 207.071214 -270.77339)
			(xy 207.018064 -270.769406) (xy 206.966102 -270.757546) (xy 206.916488 -270.738074) (xy 206.87033 -270.711425)
			(xy 206.828659 -270.678194) (xy 206.792407 -270.639123) (xy 206.762383 -270.595086) (xy 206.739257 -270.547065)
			(xy 206.723547 -270.496135) (xy 206.715604 -270.443431) (xy 192.313824 -270.443431) (xy 192.305881 -270.496135)
			(xy 192.290171 -270.547065) (xy 192.267045 -270.595086) (xy 192.237021 -270.639123) (xy 192.200769 -270.678194)
			(xy 192.159098 -270.711425) (xy 192.11294 -270.738074) (xy 192.063326 -270.757546) (xy 192.011364 -270.769406)
			(xy 191.958214 -270.77339) (xy 191.905064 -270.769406) (xy 191.853102 -270.757546) (xy 191.803488 -270.738074)
			(xy 191.75733 -270.711425) (xy 191.715659 -270.678194) (xy 191.679407 -270.639123) (xy 191.649383 -270.595086)
			(xy 191.626257 -270.547065) (xy 191.610547 -270.496135) (xy 191.602604 -270.443431) (xy 177.251624 -270.443431)
			(xy 177.243681 -270.496135) (xy 177.227971 -270.547065) (xy 177.204845 -270.595086) (xy 177.174821 -270.639123)
			(xy 177.138569 -270.678194) (xy 177.096898 -270.711425) (xy 177.05074 -270.738074) (xy 177.001126 -270.757546)
			(xy 176.949164 -270.769406) (xy 176.896014 -270.77339) (xy 176.842864 -270.769406) (xy 176.790902 -270.757546)
			(xy 176.741288 -270.738074) (xy 176.69513 -270.711425) (xy 176.653459 -270.678194) (xy 176.617207 -270.639123)
			(xy 176.587183 -270.595086) (xy 176.564057 -270.547065) (xy 176.548347 -270.496135) (xy 176.540404 -270.443431)
			(xy 159.11576 -270.443431) (xy 159.11576 -271.293315) (xy 172.440336 -271.293315) (xy 172.440336 -271.240017)
			(xy 172.448279 -271.187313) (xy 172.463989 -271.136383) (xy 172.487115 -271.088362) (xy 172.517139 -271.044325)
			(xy 172.553391 -271.005254) (xy 172.595062 -270.972023) (xy 172.64122 -270.945374) (xy 172.690834 -270.925902)
			(xy 172.742796 -270.914042) (xy 172.795946 -270.910059) (xy 172.849096 -270.914042) (xy 172.901058 -270.925902)
			(xy 172.950672 -270.945374) (xy 172.99683 -270.972023) (xy 173.038501 -271.005254) (xy 173.074753 -271.044325)
			(xy 173.104777 -271.088362) (xy 173.127903 -271.136383) (xy 173.143613 -271.187313) (xy 173.151556 -271.240017)
			(xy 173.152054 -271.266666) (xy 173.151556 -271.293315) (xy 187.527936 -271.293315) (xy 187.527936 -271.240017)
			(xy 187.535879 -271.187313) (xy 187.551589 -271.136383) (xy 187.574715 -271.088362) (xy 187.604739 -271.044325)
			(xy 187.640991 -271.005254) (xy 187.682662 -270.972023) (xy 187.72882 -270.945374) (xy 187.778434 -270.925902)
			(xy 187.830396 -270.914042) (xy 187.883546 -270.910059) (xy 187.936696 -270.914042) (xy 187.988658 -270.925902)
			(xy 188.038272 -270.945374) (xy 188.08443 -270.972023) (xy 188.126101 -271.005254) (xy 188.162353 -271.044325)
			(xy 188.192377 -271.088362) (xy 188.215503 -271.136383) (xy 188.231213 -271.187313) (xy 188.239156 -271.240017)
			(xy 188.239654 -271.266666) (xy 188.239156 -271.293315) (xy 202.615536 -271.293315) (xy 202.615536 -271.240017)
			(xy 202.623479 -271.187313) (xy 202.639189 -271.136383) (xy 202.662315 -271.088362) (xy 202.692339 -271.044325)
			(xy 202.728591 -271.005254) (xy 202.770262 -270.972023) (xy 202.81642 -270.945374) (xy 202.866034 -270.925902)
			(xy 202.917996 -270.914042) (xy 202.971146 -270.910059) (xy 203.024296 -270.914042) (xy 203.076258 -270.925902)
			(xy 203.125872 -270.945374) (xy 203.17203 -270.972023) (xy 203.213701 -271.005254) (xy 203.249953 -271.044325)
			(xy 203.279977 -271.088362) (xy 203.303103 -271.136383) (xy 203.318813 -271.187313) (xy 203.326756 -271.240017)
			(xy 203.327254 -271.266666) (xy 203.326756 -271.293315) (xy 203.318813 -271.346019) (xy 203.303103 -271.396949)
			(xy 203.279977 -271.44497) (xy 203.249953 -271.489007) (xy 203.213701 -271.528078) (xy 203.17203 -271.561309)
			(xy 203.125872 -271.587958) (xy 203.076258 -271.60743) (xy 203.024296 -271.61929) (xy 202.971146 -271.623274)
			(xy 202.917996 -271.61929) (xy 202.866034 -271.60743) (xy 202.81642 -271.587958) (xy 202.770262 -271.561309)
			(xy 202.728591 -271.528078) (xy 202.692339 -271.489007) (xy 202.662315 -271.44497) (xy 202.639189 -271.396949)
			(xy 202.623479 -271.346019) (xy 202.615536 -271.293315) (xy 188.239156 -271.293315) (xy 188.231213 -271.346019)
			(xy 188.215503 -271.396949) (xy 188.192377 -271.44497) (xy 188.162353 -271.489007) (xy 188.126101 -271.528078)
			(xy 188.08443 -271.561309) (xy 188.038272 -271.587958) (xy 187.988658 -271.60743) (xy 187.936696 -271.61929)
			(xy 187.883546 -271.623274) (xy 187.830396 -271.61929) (xy 187.778434 -271.60743) (xy 187.72882 -271.587958)
			(xy 187.682662 -271.561309) (xy 187.640991 -271.528078) (xy 187.604739 -271.489007) (xy 187.574715 -271.44497)
			(xy 187.551589 -271.396949) (xy 187.535879 -271.346019) (xy 187.527936 -271.293315) (xy 173.151556 -271.293315)
			(xy 173.143613 -271.346019) (xy 173.127903 -271.396949) (xy 173.104777 -271.44497) (xy 173.074753 -271.489007)
			(xy 173.038501 -271.528078) (xy 172.99683 -271.561309) (xy 172.950672 -271.587958) (xy 172.901058 -271.60743)
			(xy 172.849096 -271.61929) (xy 172.795946 -271.623274) (xy 172.742796 -271.61929) (xy 172.690834 -271.60743)
			(xy 172.64122 -271.587958) (xy 172.595062 -271.561309) (xy 172.553391 -271.528078) (xy 172.517139 -271.489007)
			(xy 172.487115 -271.44497) (xy 172.463989 -271.396949) (xy 172.448279 -271.346019) (xy 172.440336 -271.293315)
			(xy 159.11576 -271.293315) (xy 159.11576 -272.143199) (xy 176.540404 -272.143199) (xy 176.540404 -272.089901)
			(xy 176.548347 -272.037197) (xy 176.564057 -271.986267) (xy 176.587183 -271.938246) (xy 176.617207 -271.894209)
			(xy 176.653459 -271.855138) (xy 176.69513 -271.821907) (xy 176.741288 -271.795258) (xy 176.790902 -271.775786)
			(xy 176.842864 -271.763926) (xy 176.896014 -271.759943) (xy 176.949164 -271.763926) (xy 177.001126 -271.775786)
			(xy 177.05074 -271.795258) (xy 177.096898 -271.821907) (xy 177.138569 -271.855138) (xy 177.174821 -271.894209)
			(xy 177.204845 -271.938246) (xy 177.227971 -271.986267) (xy 177.243681 -272.037197) (xy 177.251624 -272.089901)
			(xy 177.252122 -272.11655) (xy 177.251624 -272.143199) (xy 177.251586 -272.143453) (xy 191.586094 -272.143453)
			(xy 191.586094 -272.090155) (xy 191.594037 -272.037451) (xy 191.609747 -271.986521) (xy 191.632873 -271.9385)
			(xy 191.662897 -271.894463) (xy 191.699149 -271.855392) (xy 191.74082 -271.822161) (xy 191.786978 -271.795512)
			(xy 191.836592 -271.77604) (xy 191.888554 -271.76418) (xy 191.941704 -271.760197) (xy 191.994854 -271.76418)
			(xy 192.046816 -271.77604) (xy 192.09643 -271.795512) (xy 192.142588 -271.822161) (xy 192.184259 -271.855392)
			(xy 192.220511 -271.894463) (xy 192.250535 -271.9385) (xy 192.273661 -271.986521) (xy 192.289371 -272.037451)
			(xy 192.297314 -272.090155) (xy 192.297812 -272.116804) (xy 192.297319 -272.143199) (xy 206.715604 -272.143199)
			(xy 206.715604 -272.089901) (xy 206.723547 -272.037197) (xy 206.739257 -271.986267) (xy 206.762383 -271.938246)
			(xy 206.792407 -271.894209) (xy 206.828659 -271.855138) (xy 206.87033 -271.821907) (xy 206.916488 -271.795258)
			(xy 206.966102 -271.775786) (xy 207.018064 -271.763926) (xy 207.071214 -271.759943) (xy 207.124364 -271.763926)
			(xy 207.176326 -271.775786) (xy 207.22594 -271.795258) (xy 207.272098 -271.821907) (xy 207.313769 -271.855138)
			(xy 207.350021 -271.894209) (xy 207.380045 -271.938246) (xy 207.403171 -271.986267) (xy 207.418881 -272.037197)
			(xy 207.426824 -272.089901) (xy 207.427322 -272.11655) (xy 207.426824 -272.143199) (xy 207.418881 -272.195903)
			(xy 207.403171 -272.246833) (xy 207.380045 -272.294854) (xy 207.350021 -272.338891) (xy 207.313769 -272.377962)
			(xy 207.272098 -272.411193) (xy 207.22594 -272.437842) (xy 207.176326 -272.457314) (xy 207.124364 -272.469174)
			(xy 207.071214 -272.473158) (xy 207.018064 -272.469174) (xy 206.966102 -272.457314) (xy 206.916488 -272.437842)
			(xy 206.87033 -272.411193) (xy 206.828659 -272.377962) (xy 206.792407 -272.338891) (xy 206.762383 -272.294854)
			(xy 206.739257 -272.246833) (xy 206.723547 -272.195903) (xy 206.715604 -272.143199) (xy 192.297319 -272.143199)
			(xy 192.297314 -272.143453) (xy 192.289371 -272.196157) (xy 192.273661 -272.247087) (xy 192.250535 -272.295108)
			(xy 192.220511 -272.339145) (xy 192.184259 -272.378216) (xy 192.142588 -272.411447) (xy 192.09643 -272.438096)
			(xy 192.046816 -272.457568) (xy 191.994854 -272.469428) (xy 191.941704 -272.473412) (xy 191.888554 -272.469428)
			(xy 191.836592 -272.457568) (xy 191.786978 -272.438096) (xy 191.74082 -272.411447) (xy 191.699149 -272.378216)
			(xy 191.662897 -272.339145) (xy 191.632873 -272.295108) (xy 191.609747 -272.247087) (xy 191.594037 -272.196157)
			(xy 191.586094 -272.143453) (xy 177.251586 -272.143453) (xy 177.243681 -272.195903) (xy 177.227971 -272.246833)
			(xy 177.204845 -272.294854) (xy 177.174821 -272.338891) (xy 177.138569 -272.377962) (xy 177.096898 -272.411193)
			(xy 177.05074 -272.437842) (xy 177.001126 -272.457314) (xy 176.949164 -272.469174) (xy 176.896014 -272.473158)
			(xy 176.842864 -272.469174) (xy 176.790902 -272.457314) (xy 176.741288 -272.437842) (xy 176.69513 -272.411193)
			(xy 176.653459 -272.377962) (xy 176.617207 -272.338891) (xy 176.587183 -272.294854) (xy 176.564057 -272.246833)
			(xy 176.548347 -272.195903) (xy 176.540404 -272.143199) (xy 159.11576 -272.143199) (xy 159.11576 -272.993337)
			(xy 172.440336 -272.993337) (xy 172.440336 -272.940039) (xy 172.448279 -272.887335) (xy 172.463989 -272.836405)
			(xy 172.487115 -272.788384) (xy 172.517139 -272.744347) (xy 172.553391 -272.705276) (xy 172.595062 -272.672045)
			(xy 172.64122 -272.645396) (xy 172.690834 -272.625924) (xy 172.742796 -272.614064) (xy 172.795946 -272.610081)
			(xy 172.849096 -272.614064) (xy 172.901058 -272.625924) (xy 172.950672 -272.645396) (xy 172.99683 -272.672045)
			(xy 173.038501 -272.705276) (xy 173.074753 -272.744347) (xy 173.104777 -272.788384) (xy 173.127903 -272.836405)
			(xy 173.143613 -272.887335) (xy 173.151556 -272.940039) (xy 173.152054 -272.966688) (xy 173.151556 -272.993337)
			(xy 187.527936 -272.993337) (xy 187.527936 -272.940039) (xy 187.535879 -272.887335) (xy 187.551589 -272.836405)
			(xy 187.574715 -272.788384) (xy 187.604739 -272.744347) (xy 187.640991 -272.705276) (xy 187.682662 -272.672045)
			(xy 187.72882 -272.645396) (xy 187.778434 -272.625924) (xy 187.830396 -272.614064) (xy 187.883546 -272.610081)
			(xy 187.936696 -272.614064) (xy 187.988658 -272.625924) (xy 188.038272 -272.645396) (xy 188.08443 -272.672045)
			(xy 188.126101 -272.705276) (xy 188.162353 -272.744347) (xy 188.192377 -272.788384) (xy 188.215503 -272.836405)
			(xy 188.231213 -272.887335) (xy 188.239156 -272.940039) (xy 188.239654 -272.966688) (xy 188.239156 -272.993337)
			(xy 202.615536 -272.993337) (xy 202.615536 -272.940039) (xy 202.623479 -272.887335) (xy 202.639189 -272.836405)
			(xy 202.662315 -272.788384) (xy 202.692339 -272.744347) (xy 202.728591 -272.705276) (xy 202.770262 -272.672045)
			(xy 202.81642 -272.645396) (xy 202.866034 -272.625924) (xy 202.917996 -272.614064) (xy 202.971146 -272.610081)
			(xy 203.024296 -272.614064) (xy 203.076258 -272.625924) (xy 203.125872 -272.645396) (xy 203.17203 -272.672045)
			(xy 203.213701 -272.705276) (xy 203.249953 -272.744347) (xy 203.279977 -272.788384) (xy 203.303103 -272.836405)
			(xy 203.318813 -272.887335) (xy 203.326756 -272.940039) (xy 203.327254 -272.966688) (xy 203.326756 -272.993337)
			(xy 203.318813 -273.046041) (xy 203.303103 -273.096971) (xy 203.279977 -273.144992) (xy 203.249953 -273.189029)
			(xy 203.213701 -273.2281) (xy 203.17203 -273.261331) (xy 203.125872 -273.28798) (xy 203.076258 -273.307452)
			(xy 203.024296 -273.319312) (xy 202.971146 -273.323296) (xy 202.917996 -273.319312) (xy 202.866034 -273.307452)
			(xy 202.81642 -273.28798) (xy 202.770262 -273.261331) (xy 202.728591 -273.2281) (xy 202.692339 -273.189029)
			(xy 202.662315 -273.144992) (xy 202.639189 -273.096971) (xy 202.623479 -273.046041) (xy 202.615536 -272.993337)
			(xy 188.239156 -272.993337) (xy 188.231213 -273.046041) (xy 188.215503 -273.096971) (xy 188.192377 -273.144992)
			(xy 188.162353 -273.189029) (xy 188.126101 -273.2281) (xy 188.08443 -273.261331) (xy 188.038272 -273.28798)
			(xy 187.988658 -273.307452) (xy 187.936696 -273.319312) (xy 187.883546 -273.323296) (xy 187.830396 -273.319312)
			(xy 187.778434 -273.307452) (xy 187.72882 -273.28798) (xy 187.682662 -273.261331) (xy 187.640991 -273.2281)
			(xy 187.604739 -273.189029) (xy 187.574715 -273.144992) (xy 187.551589 -273.096971) (xy 187.535879 -273.046041)
			(xy 187.527936 -272.993337) (xy 173.151556 -272.993337) (xy 173.143613 -273.046041) (xy 173.127903 -273.096971)
			(xy 173.104777 -273.144992) (xy 173.074753 -273.189029) (xy 173.038501 -273.2281) (xy 172.99683 -273.261331)
			(xy 172.950672 -273.28798) (xy 172.901058 -273.307452) (xy 172.849096 -273.319312) (xy 172.795946 -273.323296)
			(xy 172.742796 -273.319312) (xy 172.690834 -273.307452) (xy 172.64122 -273.28798) (xy 172.595062 -273.261331)
			(xy 172.553391 -273.2281) (xy 172.517139 -273.189029) (xy 172.487115 -273.144992) (xy 172.463989 -273.096971)
			(xy 172.448279 -273.046041) (xy 172.440336 -272.993337) (xy 159.11576 -272.993337) (xy 159.11576 -273.843221)
			(xy 176.540404 -273.843221) (xy 176.540404 -273.789923) (xy 176.548347 -273.737219) (xy 176.564057 -273.686289)
			(xy 176.587183 -273.638268) (xy 176.617207 -273.594231) (xy 176.653459 -273.55516) (xy 176.69513 -273.521929)
			(xy 176.741288 -273.49528) (xy 176.790902 -273.475808) (xy 176.842864 -273.463948) (xy 176.896014 -273.459965)
			(xy 176.949164 -273.463948) (xy 177.001126 -273.475808) (xy 177.05074 -273.49528) (xy 177.096898 -273.521929)
			(xy 177.138569 -273.55516) (xy 177.174821 -273.594231) (xy 177.204845 -273.638268) (xy 177.227971 -273.686289)
			(xy 177.243681 -273.737219) (xy 177.251624 -273.789923) (xy 177.252122 -273.816572) (xy 177.251624 -273.843221)
			(xy 191.628004 -273.843221) (xy 191.628004 -273.789923) (xy 191.635947 -273.737219) (xy 191.651657 -273.686289)
			(xy 191.674783 -273.638268) (xy 191.704807 -273.594231) (xy 191.741059 -273.55516) (xy 191.78273 -273.521929)
			(xy 191.828888 -273.49528) (xy 191.878502 -273.475808) (xy 191.930464 -273.463948) (xy 191.983614 -273.459965)
			(xy 192.036764 -273.463948) (xy 192.088726 -273.475808) (xy 192.13834 -273.49528) (xy 192.184498 -273.521929)
			(xy 192.226169 -273.55516) (xy 192.262421 -273.594231) (xy 192.292445 -273.638268) (xy 192.315571 -273.686289)
			(xy 192.331281 -273.737219) (xy 192.339224 -273.789923) (xy 192.339722 -273.816572) (xy 192.339224 -273.843221)
			(xy 206.715604 -273.843221) (xy 206.715604 -273.789923) (xy 206.723547 -273.737219) (xy 206.739257 -273.686289)
			(xy 206.762383 -273.638268) (xy 206.792407 -273.594231) (xy 206.828659 -273.55516) (xy 206.87033 -273.521929)
			(xy 206.916488 -273.49528) (xy 206.966102 -273.475808) (xy 207.018064 -273.463948) (xy 207.071214 -273.459965)
			(xy 207.124364 -273.463948) (xy 207.176326 -273.475808) (xy 207.22594 -273.49528) (xy 207.272098 -273.521929)
			(xy 207.313769 -273.55516) (xy 207.350021 -273.594231) (xy 207.380045 -273.638268) (xy 207.403171 -273.686289)
			(xy 207.418881 -273.737219) (xy 207.426824 -273.789923) (xy 207.427322 -273.816572) (xy 207.426824 -273.843221)
			(xy 207.418881 -273.895925) (xy 207.403171 -273.946855) (xy 207.380045 -273.994876) (xy 207.350021 -274.038913)
			(xy 207.313769 -274.077984) (xy 207.272098 -274.111215) (xy 207.22594 -274.137864) (xy 207.176326 -274.157336)
			(xy 207.124364 -274.169196) (xy 207.071214 -274.17318) (xy 207.018064 -274.169196) (xy 206.966102 -274.157336)
			(xy 206.916488 -274.137864) (xy 206.87033 -274.111215) (xy 206.828659 -274.077984) (xy 206.792407 -274.038913)
			(xy 206.762383 -273.994876) (xy 206.739257 -273.946855) (xy 206.723547 -273.895925) (xy 206.715604 -273.843221)
			(xy 192.339224 -273.843221) (xy 192.331281 -273.895925) (xy 192.315571 -273.946855) (xy 192.292445 -273.994876)
			(xy 192.262421 -274.038913) (xy 192.226169 -274.077984) (xy 192.184498 -274.111215) (xy 192.13834 -274.137864)
			(xy 192.088726 -274.157336) (xy 192.036764 -274.169196) (xy 191.983614 -274.17318) (xy 191.930464 -274.169196)
			(xy 191.878502 -274.157336) (xy 191.828888 -274.137864) (xy 191.78273 -274.111215) (xy 191.741059 -274.077984)
			(xy 191.704807 -274.038913) (xy 191.674783 -273.994876) (xy 191.651657 -273.946855) (xy 191.635947 -273.895925)
			(xy 191.628004 -273.843221) (xy 177.251624 -273.843221) (xy 177.243681 -273.895925) (xy 177.227971 -273.946855)
			(xy 177.204845 -273.994876) (xy 177.174821 -274.038913) (xy 177.138569 -274.077984) (xy 177.096898 -274.111215)
			(xy 177.05074 -274.137864) (xy 177.001126 -274.157336) (xy 176.949164 -274.169196) (xy 176.896014 -274.17318)
			(xy 176.842864 -274.169196) (xy 176.790902 -274.157336) (xy 176.741288 -274.137864) (xy 176.69513 -274.111215)
			(xy 176.653459 -274.077984) (xy 176.617207 -274.038913) (xy 176.587183 -273.994876) (xy 176.564057 -273.946855)
			(xy 176.548347 -273.895925) (xy 176.540404 -273.843221) (xy 159.11576 -273.843221) (xy 159.11576 -274.693359)
			(xy 172.440336 -274.693359) (xy 172.440336 -274.640061) (xy 172.448279 -274.587357) (xy 172.463989 -274.536427)
			(xy 172.487115 -274.488406) (xy 172.517139 -274.444369) (xy 172.553391 -274.405298) (xy 172.595062 -274.372067)
			(xy 172.64122 -274.345418) (xy 172.690834 -274.325946) (xy 172.742796 -274.314086) (xy 172.795946 -274.310103)
			(xy 172.849096 -274.314086) (xy 172.901058 -274.325946) (xy 172.950672 -274.345418) (xy 172.99683 -274.372067)
			(xy 173.038501 -274.405298) (xy 173.074753 -274.444369) (xy 173.104777 -274.488406) (xy 173.127903 -274.536427)
			(xy 173.143613 -274.587357) (xy 173.151556 -274.640061) (xy 173.152054 -274.66671) (xy 173.151556 -274.693359)
			(xy 176.540404 -274.693359) (xy 176.540404 -274.640061) (xy 176.548347 -274.587357) (xy 176.564057 -274.536427)
			(xy 176.587183 -274.488406) (xy 176.617207 -274.444369) (xy 176.653459 -274.405298) (xy 176.69513 -274.372067)
			(xy 176.741288 -274.345418) (xy 176.790902 -274.325946) (xy 176.842864 -274.314086) (xy 176.896014 -274.310103)
			(xy 176.949164 -274.314086) (xy 177.001126 -274.325946) (xy 177.05074 -274.345418) (xy 177.096898 -274.372067)
			(xy 177.138569 -274.405298) (xy 177.174821 -274.444369) (xy 177.204845 -274.488406) (xy 177.227971 -274.536427)
			(xy 177.243681 -274.587357) (xy 177.251624 -274.640061) (xy 177.252122 -274.66671) (xy 177.251624 -274.693359)
			(xy 187.527936 -274.693359) (xy 187.527936 -274.640061) (xy 187.535879 -274.587357) (xy 187.551589 -274.536427)
			(xy 187.574715 -274.488406) (xy 187.604739 -274.444369) (xy 187.640991 -274.405298) (xy 187.682662 -274.372067)
			(xy 187.72882 -274.345418) (xy 187.778434 -274.325946) (xy 187.830396 -274.314086) (xy 187.883546 -274.310103)
			(xy 187.936696 -274.314086) (xy 187.988658 -274.325946) (xy 188.038272 -274.345418) (xy 188.08443 -274.372067)
			(xy 188.126101 -274.405298) (xy 188.162353 -274.444369) (xy 188.192377 -274.488406) (xy 188.215503 -274.536427)
			(xy 188.231213 -274.587357) (xy 188.239156 -274.640061) (xy 188.239654 -274.66671) (xy 188.239156 -274.693359)
			(xy 191.628004 -274.693359) (xy 191.628004 -274.640061) (xy 191.635947 -274.587357) (xy 191.651657 -274.536427)
			(xy 191.674783 -274.488406) (xy 191.704807 -274.444369) (xy 191.741059 -274.405298) (xy 191.78273 -274.372067)
			(xy 191.828888 -274.345418) (xy 191.878502 -274.325946) (xy 191.930464 -274.314086) (xy 191.983614 -274.310103)
			(xy 192.036764 -274.314086) (xy 192.088726 -274.325946) (xy 192.13834 -274.345418) (xy 192.184498 -274.372067)
			(xy 192.226169 -274.405298) (xy 192.262421 -274.444369) (xy 192.292445 -274.488406) (xy 192.315571 -274.536427)
			(xy 192.331281 -274.587357) (xy 192.339224 -274.640061) (xy 192.339722 -274.66671) (xy 192.339224 -274.693359)
			(xy 202.615536 -274.693359) (xy 202.615536 -274.640061) (xy 202.623479 -274.587357) (xy 202.639189 -274.536427)
			(xy 202.662315 -274.488406) (xy 202.692339 -274.444369) (xy 202.728591 -274.405298) (xy 202.770262 -274.372067)
			(xy 202.81642 -274.345418) (xy 202.866034 -274.325946) (xy 202.917996 -274.314086) (xy 202.971146 -274.310103)
			(xy 203.024296 -274.314086) (xy 203.076258 -274.325946) (xy 203.125872 -274.345418) (xy 203.17203 -274.372067)
			(xy 203.213701 -274.405298) (xy 203.249953 -274.444369) (xy 203.279977 -274.488406) (xy 203.303103 -274.536427)
			(xy 203.318813 -274.587357) (xy 203.326756 -274.640061) (xy 203.327254 -274.66671) (xy 203.326756 -274.693359)
			(xy 206.715604 -274.693359) (xy 206.715604 -274.640061) (xy 206.723547 -274.587357) (xy 206.739257 -274.536427)
			(xy 206.762383 -274.488406) (xy 206.792407 -274.444369) (xy 206.828659 -274.405298) (xy 206.87033 -274.372067)
			(xy 206.916488 -274.345418) (xy 206.966102 -274.325946) (xy 207.018064 -274.314086) (xy 207.071214 -274.310103)
			(xy 207.124364 -274.314086) (xy 207.176326 -274.325946) (xy 207.22594 -274.345418) (xy 207.272098 -274.372067)
			(xy 207.313769 -274.405298) (xy 207.350021 -274.444369) (xy 207.380045 -274.488406) (xy 207.403171 -274.536427)
			(xy 207.418881 -274.587357) (xy 207.426824 -274.640061) (xy 207.427322 -274.66671) (xy 207.426824 -274.693359)
			(xy 207.418881 -274.746063) (xy 207.403171 -274.796993) (xy 207.380045 -274.845014) (xy 207.350021 -274.889051)
			(xy 207.313769 -274.928122) (xy 207.272098 -274.961353) (xy 207.22594 -274.988002) (xy 207.176326 -275.007474)
			(xy 207.124364 -275.019334) (xy 207.071214 -275.023318) (xy 207.018064 -275.019334) (xy 206.966102 -275.007474)
			(xy 206.916488 -274.988002) (xy 206.87033 -274.961353) (xy 206.828659 -274.928122) (xy 206.792407 -274.889051)
			(xy 206.762383 -274.845014) (xy 206.739257 -274.796993) (xy 206.723547 -274.746063) (xy 206.715604 -274.693359)
			(xy 203.326756 -274.693359) (xy 203.318813 -274.746063) (xy 203.303103 -274.796993) (xy 203.279977 -274.845014)
			(xy 203.249953 -274.889051) (xy 203.213701 -274.928122) (xy 203.17203 -274.961353) (xy 203.125872 -274.988002)
			(xy 203.076258 -275.007474) (xy 203.024296 -275.019334) (xy 202.971146 -275.023318) (xy 202.917996 -275.019334)
			(xy 202.866034 -275.007474) (xy 202.81642 -274.988002) (xy 202.770262 -274.961353) (xy 202.728591 -274.928122)
			(xy 202.692339 -274.889051) (xy 202.662315 -274.845014) (xy 202.639189 -274.796993) (xy 202.623479 -274.746063)
			(xy 202.615536 -274.693359) (xy 192.339224 -274.693359) (xy 192.331281 -274.746063) (xy 192.315571 -274.796993)
			(xy 192.292445 -274.845014) (xy 192.262421 -274.889051) (xy 192.226169 -274.928122) (xy 192.184498 -274.961353)
			(xy 192.13834 -274.988002) (xy 192.088726 -275.007474) (xy 192.036764 -275.019334) (xy 191.983614 -275.023318)
			(xy 191.930464 -275.019334) (xy 191.878502 -275.007474) (xy 191.828888 -274.988002) (xy 191.78273 -274.961353)
			(xy 191.741059 -274.928122) (xy 191.704807 -274.889051) (xy 191.674783 -274.845014) (xy 191.651657 -274.796993)
			(xy 191.635947 -274.746063) (xy 191.628004 -274.693359) (xy 188.239156 -274.693359) (xy 188.231213 -274.746063)
			(xy 188.215503 -274.796993) (xy 188.192377 -274.845014) (xy 188.162353 -274.889051) (xy 188.126101 -274.928122)
			(xy 188.08443 -274.961353) (xy 188.038272 -274.988002) (xy 187.988658 -275.007474) (xy 187.936696 -275.019334)
			(xy 187.883546 -275.023318) (xy 187.830396 -275.019334) (xy 187.778434 -275.007474) (xy 187.72882 -274.988002)
			(xy 187.682662 -274.961353) (xy 187.640991 -274.928122) (xy 187.604739 -274.889051) (xy 187.574715 -274.845014)
			(xy 187.551589 -274.796993) (xy 187.535879 -274.746063) (xy 187.527936 -274.693359) (xy 177.251624 -274.693359)
			(xy 177.243681 -274.746063) (xy 177.227971 -274.796993) (xy 177.204845 -274.845014) (xy 177.174821 -274.889051)
			(xy 177.138569 -274.928122) (xy 177.096898 -274.961353) (xy 177.05074 -274.988002) (xy 177.001126 -275.007474)
			(xy 176.949164 -275.019334) (xy 176.896014 -275.023318) (xy 176.842864 -275.019334) (xy 176.790902 -275.007474)
			(xy 176.741288 -274.988002) (xy 176.69513 -274.961353) (xy 176.653459 -274.928122) (xy 176.617207 -274.889051)
			(xy 176.587183 -274.845014) (xy 176.564057 -274.796993) (xy 176.548347 -274.746063) (xy 176.540404 -274.693359)
			(xy 173.151556 -274.693359) (xy 173.143613 -274.746063) (xy 173.127903 -274.796993) (xy 173.104777 -274.845014)
			(xy 173.074753 -274.889051) (xy 173.038501 -274.928122) (xy 172.99683 -274.961353) (xy 172.950672 -274.988002)
			(xy 172.901058 -275.007474) (xy 172.849096 -275.019334) (xy 172.795946 -275.023318) (xy 172.742796 -275.019334)
			(xy 172.690834 -275.007474) (xy 172.64122 -274.988002) (xy 172.595062 -274.961353) (xy 172.553391 -274.928122)
			(xy 172.517139 -274.889051) (xy 172.487115 -274.845014) (xy 172.463989 -274.796993) (xy 172.448279 -274.746063)
			(xy 172.440336 -274.693359) (xy 159.11576 -274.693359) (xy 159.11576 -275.543243) (xy 172.440336 -275.543243)
			(xy 172.440336 -275.489945) (xy 172.448279 -275.437241) (xy 172.463989 -275.386311) (xy 172.487115 -275.33829)
			(xy 172.517139 -275.294253) (xy 172.553391 -275.255182) (xy 172.595062 -275.221951) (xy 172.64122 -275.195302)
			(xy 172.690834 -275.17583) (xy 172.742796 -275.16397) (xy 172.795946 -275.159987) (xy 172.849096 -275.16397)
			(xy 172.901058 -275.17583) (xy 172.950672 -275.195302) (xy 172.99683 -275.221951) (xy 173.038501 -275.255182)
			(xy 173.074753 -275.294253) (xy 173.104777 -275.33829) (xy 173.127903 -275.386311) (xy 173.143613 -275.437241)
			(xy 173.151556 -275.489945) (xy 173.152054 -275.516594) (xy 173.151556 -275.543243) (xy 187.527936 -275.543243)
			(xy 187.527936 -275.489945) (xy 187.535879 -275.437241) (xy 187.551589 -275.386311) (xy 187.574715 -275.33829)
			(xy 187.604739 -275.294253) (xy 187.640991 -275.255182) (xy 187.682662 -275.221951) (xy 187.72882 -275.195302)
			(xy 187.778434 -275.17583) (xy 187.830396 -275.16397) (xy 187.883546 -275.159987) (xy 187.936696 -275.16397)
			(xy 187.988658 -275.17583) (xy 188.038272 -275.195302) (xy 188.08443 -275.221951) (xy 188.126101 -275.255182)
			(xy 188.162353 -275.294253) (xy 188.192377 -275.33829) (xy 188.215503 -275.386311) (xy 188.231213 -275.437241)
			(xy 188.239156 -275.489945) (xy 188.239654 -275.516594) (xy 188.239156 -275.543243) (xy 202.615536 -275.543243)
			(xy 202.615536 -275.489945) (xy 202.623479 -275.437241) (xy 202.639189 -275.386311) (xy 202.662315 -275.33829)
			(xy 202.692339 -275.294253) (xy 202.728591 -275.255182) (xy 202.770262 -275.221951) (xy 202.81642 -275.195302)
			(xy 202.866034 -275.17583) (xy 202.917996 -275.16397) (xy 202.971146 -275.159987) (xy 203.024296 -275.16397)
			(xy 203.076258 -275.17583) (xy 203.125872 -275.195302) (xy 203.17203 -275.221951) (xy 203.213701 -275.255182)
			(xy 203.249953 -275.294253) (xy 203.279977 -275.33829) (xy 203.303103 -275.386311) (xy 203.318813 -275.437241)
			(xy 203.326756 -275.489945) (xy 203.327254 -275.516594) (xy 203.326756 -275.543243) (xy 203.318813 -275.595947)
			(xy 203.303103 -275.646877) (xy 203.279977 -275.694898) (xy 203.249953 -275.738935) (xy 203.213701 -275.778006)
			(xy 203.17203 -275.811237) (xy 203.125872 -275.837886) (xy 203.076258 -275.857358) (xy 203.024296 -275.869218)
			(xy 202.971146 -275.873202) (xy 202.917996 -275.869218) (xy 202.866034 -275.857358) (xy 202.81642 -275.837886)
			(xy 202.770262 -275.811237) (xy 202.728591 -275.778006) (xy 202.692339 -275.738935) (xy 202.662315 -275.694898)
			(xy 202.639189 -275.646877) (xy 202.623479 -275.595947) (xy 202.615536 -275.543243) (xy 188.239156 -275.543243)
			(xy 188.231213 -275.595947) (xy 188.215503 -275.646877) (xy 188.192377 -275.694898) (xy 188.162353 -275.738935)
			(xy 188.126101 -275.778006) (xy 188.08443 -275.811237) (xy 188.038272 -275.837886) (xy 187.988658 -275.857358)
			(xy 187.936696 -275.869218) (xy 187.883546 -275.873202) (xy 187.830396 -275.869218) (xy 187.778434 -275.857358)
			(xy 187.72882 -275.837886) (xy 187.682662 -275.811237) (xy 187.640991 -275.778006) (xy 187.604739 -275.738935)
			(xy 187.574715 -275.694898) (xy 187.551589 -275.646877) (xy 187.535879 -275.595947) (xy 187.527936 -275.543243)
			(xy 173.151556 -275.543243) (xy 173.143613 -275.595947) (xy 173.127903 -275.646877) (xy 173.104777 -275.694898)
			(xy 173.074753 -275.738935) (xy 173.038501 -275.778006) (xy 172.99683 -275.811237) (xy 172.950672 -275.837886)
			(xy 172.901058 -275.857358) (xy 172.849096 -275.869218) (xy 172.795946 -275.873202) (xy 172.742796 -275.869218)
			(xy 172.690834 -275.857358) (xy 172.64122 -275.837886) (xy 172.595062 -275.811237) (xy 172.553391 -275.778006)
			(xy 172.517139 -275.738935) (xy 172.487115 -275.694898) (xy 172.463989 -275.646877) (xy 172.448279 -275.595947)
			(xy 172.440336 -275.543243) (xy 159.11576 -275.543243) (xy 159.11576 -276.393381) (xy 176.540404 -276.393381)
			(xy 176.540404 -276.340083) (xy 176.548347 -276.287379) (xy 176.564057 -276.236449) (xy 176.587183 -276.188428)
			(xy 176.617207 -276.144391) (xy 176.653459 -276.10532) (xy 176.69513 -276.072089) (xy 176.741288 -276.04544)
			(xy 176.790902 -276.025968) (xy 176.842864 -276.014108) (xy 176.896014 -276.010125) (xy 176.949164 -276.014108)
			(xy 177.001126 -276.025968) (xy 177.05074 -276.04544) (xy 177.096898 -276.072089) (xy 177.138569 -276.10532)
			(xy 177.174821 -276.144391) (xy 177.204845 -276.188428) (xy 177.227971 -276.236449) (xy 177.243681 -276.287379)
			(xy 177.251624 -276.340083) (xy 177.252122 -276.366732) (xy 177.251624 -276.393381) (xy 191.628004 -276.393381)
			(xy 191.628004 -276.340083) (xy 191.635947 -276.287379) (xy 191.651657 -276.236449) (xy 191.674783 -276.188428)
			(xy 191.704807 -276.144391) (xy 191.741059 -276.10532) (xy 191.78273 -276.072089) (xy 191.828888 -276.04544)
			(xy 191.878502 -276.025968) (xy 191.930464 -276.014108) (xy 191.983614 -276.010125) (xy 192.036764 -276.014108)
			(xy 192.088726 -276.025968) (xy 192.13834 -276.04544) (xy 192.184498 -276.072089) (xy 192.226169 -276.10532)
			(xy 192.262421 -276.144391) (xy 192.292445 -276.188428) (xy 192.315571 -276.236449) (xy 192.331281 -276.287379)
			(xy 192.339224 -276.340083) (xy 192.339722 -276.366732) (xy 192.339224 -276.393381) (xy 206.715604 -276.393381)
			(xy 206.715604 -276.340083) (xy 206.723547 -276.287379) (xy 206.739257 -276.236449) (xy 206.762383 -276.188428)
			(xy 206.792407 -276.144391) (xy 206.828659 -276.10532) (xy 206.87033 -276.072089) (xy 206.916488 -276.04544)
			(xy 206.966102 -276.025968) (xy 207.018064 -276.014108) (xy 207.071214 -276.010125) (xy 207.124364 -276.014108)
			(xy 207.176326 -276.025968) (xy 207.22594 -276.04544) (xy 207.272098 -276.072089) (xy 207.313769 -276.10532)
			(xy 207.350021 -276.144391) (xy 207.380045 -276.188428) (xy 207.403171 -276.236449) (xy 207.418881 -276.287379)
			(xy 207.426824 -276.340083) (xy 207.427322 -276.366732) (xy 207.426824 -276.393381) (xy 207.418881 -276.446085)
			(xy 207.403171 -276.497015) (xy 207.380045 -276.545036) (xy 207.350021 -276.589073) (xy 207.313769 -276.628144)
			(xy 207.272098 -276.661375) (xy 207.22594 -276.688024) (xy 207.176326 -276.707496) (xy 207.124364 -276.719356)
			(xy 207.071214 -276.72334) (xy 207.018064 -276.719356) (xy 206.966102 -276.707496) (xy 206.916488 -276.688024)
			(xy 206.87033 -276.661375) (xy 206.828659 -276.628144) (xy 206.792407 -276.589073) (xy 206.762383 -276.545036)
			(xy 206.739257 -276.497015) (xy 206.723547 -276.446085) (xy 206.715604 -276.393381) (xy 192.339224 -276.393381)
			(xy 192.331281 -276.446085) (xy 192.315571 -276.497015) (xy 192.292445 -276.545036) (xy 192.262421 -276.589073)
			(xy 192.226169 -276.628144) (xy 192.184498 -276.661375) (xy 192.13834 -276.688024) (xy 192.088726 -276.707496)
			(xy 192.036764 -276.719356) (xy 191.983614 -276.72334) (xy 191.930464 -276.719356) (xy 191.878502 -276.707496)
			(xy 191.828888 -276.688024) (xy 191.78273 -276.661375) (xy 191.741059 -276.628144) (xy 191.704807 -276.589073)
			(xy 191.674783 -276.545036) (xy 191.651657 -276.497015) (xy 191.635947 -276.446085) (xy 191.628004 -276.393381)
			(xy 177.251624 -276.393381) (xy 177.243681 -276.446085) (xy 177.227971 -276.497015) (xy 177.204845 -276.545036)
			(xy 177.174821 -276.589073) (xy 177.138569 -276.628144) (xy 177.096898 -276.661375) (xy 177.05074 -276.688024)
			(xy 177.001126 -276.707496) (xy 176.949164 -276.719356) (xy 176.896014 -276.72334) (xy 176.842864 -276.719356)
			(xy 176.790902 -276.707496) (xy 176.741288 -276.688024) (xy 176.69513 -276.661375) (xy 176.653459 -276.628144)
			(xy 176.617207 -276.589073) (xy 176.587183 -276.545036) (xy 176.564057 -276.497015) (xy 176.548347 -276.446085)
			(xy 176.540404 -276.393381) (xy 159.11576 -276.393381) (xy 159.11576 -277.243265) (xy 172.440336 -277.243265)
			(xy 172.440336 -277.189967) (xy 172.448279 -277.137263) (xy 172.463989 -277.086333) (xy 172.487115 -277.038312)
			(xy 172.517139 -276.994275) (xy 172.553391 -276.955204) (xy 172.595062 -276.921973) (xy 172.64122 -276.895324)
			(xy 172.690834 -276.875852) (xy 172.742796 -276.863992) (xy 172.795946 -276.860009) (xy 172.849096 -276.863992)
			(xy 172.901058 -276.875852) (xy 172.950672 -276.895324) (xy 172.99683 -276.921973) (xy 173.038501 -276.955204)
			(xy 173.074753 -276.994275) (xy 173.104777 -277.038312) (xy 173.127903 -277.086333) (xy 173.143613 -277.137263)
			(xy 173.151556 -277.189967) (xy 173.152054 -277.216616) (xy 173.151556 -277.243265) (xy 187.527936 -277.243265)
			(xy 187.527936 -277.189967) (xy 187.535879 -277.137263) (xy 187.551589 -277.086333) (xy 187.574715 -277.038312)
			(xy 187.604739 -276.994275) (xy 187.640991 -276.955204) (xy 187.682662 -276.921973) (xy 187.72882 -276.895324)
			(xy 187.778434 -276.875852) (xy 187.830396 -276.863992) (xy 187.883546 -276.860009) (xy 187.936696 -276.863992)
			(xy 187.988658 -276.875852) (xy 188.038272 -276.895324) (xy 188.08443 -276.921973) (xy 188.126101 -276.955204)
			(xy 188.162353 -276.994275) (xy 188.192377 -277.038312) (xy 188.215503 -277.086333) (xy 188.231213 -277.137263)
			(xy 188.239156 -277.189967) (xy 188.239654 -277.216616) (xy 188.239156 -277.243265) (xy 202.615536 -277.243265)
			(xy 202.615536 -277.189967) (xy 202.623479 -277.137263) (xy 202.639189 -277.086333) (xy 202.662315 -277.038312)
			(xy 202.692339 -276.994275) (xy 202.728591 -276.955204) (xy 202.770262 -276.921973) (xy 202.81642 -276.895324)
			(xy 202.866034 -276.875852) (xy 202.917996 -276.863992) (xy 202.971146 -276.860009) (xy 203.024296 -276.863992)
			(xy 203.076258 -276.875852) (xy 203.125872 -276.895324) (xy 203.17203 -276.921973) (xy 203.213701 -276.955204)
			(xy 203.249953 -276.994275) (xy 203.279977 -277.038312) (xy 203.303103 -277.086333) (xy 203.318813 -277.137263)
			(xy 203.326756 -277.189967) (xy 203.327254 -277.216616) (xy 203.326756 -277.243265) (xy 203.318813 -277.295969)
			(xy 203.303103 -277.346899) (xy 203.279977 -277.39492) (xy 203.249953 -277.438957) (xy 203.213701 -277.478028)
			(xy 203.17203 -277.511259) (xy 203.125872 -277.537908) (xy 203.076258 -277.55738) (xy 203.024296 -277.56924)
			(xy 202.971146 -277.573224) (xy 202.917996 -277.56924) (xy 202.866034 -277.55738) (xy 202.81642 -277.537908)
			(xy 202.770262 -277.511259) (xy 202.728591 -277.478028) (xy 202.692339 -277.438957) (xy 202.662315 -277.39492)
			(xy 202.639189 -277.346899) (xy 202.623479 -277.295969) (xy 202.615536 -277.243265) (xy 188.239156 -277.243265)
			(xy 188.231213 -277.295969) (xy 188.215503 -277.346899) (xy 188.192377 -277.39492) (xy 188.162353 -277.438957)
			(xy 188.126101 -277.478028) (xy 188.08443 -277.511259) (xy 188.038272 -277.537908) (xy 187.988658 -277.55738)
			(xy 187.936696 -277.56924) (xy 187.883546 -277.573224) (xy 187.830396 -277.56924) (xy 187.778434 -277.55738)
			(xy 187.72882 -277.537908) (xy 187.682662 -277.511259) (xy 187.640991 -277.478028) (xy 187.604739 -277.438957)
			(xy 187.574715 -277.39492) (xy 187.551589 -277.346899) (xy 187.535879 -277.295969) (xy 187.527936 -277.243265)
			(xy 173.151556 -277.243265) (xy 173.143613 -277.295969) (xy 173.127903 -277.346899) (xy 173.104777 -277.39492)
			(xy 173.074753 -277.438957) (xy 173.038501 -277.478028) (xy 172.99683 -277.511259) (xy 172.950672 -277.537908)
			(xy 172.901058 -277.55738) (xy 172.849096 -277.56924) (xy 172.795946 -277.573224) (xy 172.742796 -277.56924)
			(xy 172.690834 -277.55738) (xy 172.64122 -277.537908) (xy 172.595062 -277.511259) (xy 172.553391 -277.478028)
			(xy 172.517139 -277.438957) (xy 172.487115 -277.39492) (xy 172.463989 -277.346899) (xy 172.448279 -277.295969)
			(xy 172.440336 -277.243265) (xy 159.11576 -277.243265) (xy 159.11576 -278.093403) (xy 176.540404 -278.093403)
			(xy 176.540404 -278.040105) (xy 176.548347 -277.987401) (xy 176.564057 -277.936471) (xy 176.587183 -277.88845)
			(xy 176.617207 -277.844413) (xy 176.653459 -277.805342) (xy 176.69513 -277.772111) (xy 176.741288 -277.745462)
			(xy 176.790902 -277.72599) (xy 176.842864 -277.71413) (xy 176.896014 -277.710147) (xy 176.949164 -277.71413)
			(xy 177.001126 -277.72599) (xy 177.05074 -277.745462) (xy 177.096898 -277.772111) (xy 177.138569 -277.805342)
			(xy 177.174821 -277.844413) (xy 177.204845 -277.88845) (xy 177.227971 -277.936471) (xy 177.243681 -277.987401)
			(xy 177.251624 -278.040105) (xy 177.252122 -278.066754) (xy 177.251624 -278.093403) (xy 191.628004 -278.093403)
			(xy 191.628004 -278.040105) (xy 191.635947 -277.987401) (xy 191.651657 -277.936471) (xy 191.674783 -277.88845)
			(xy 191.704807 -277.844413) (xy 191.741059 -277.805342) (xy 191.78273 -277.772111) (xy 191.828888 -277.745462)
			(xy 191.878502 -277.72599) (xy 191.930464 -277.71413) (xy 191.983614 -277.710147) (xy 192.036764 -277.71413)
			(xy 192.088726 -277.72599) (xy 192.13834 -277.745462) (xy 192.184498 -277.772111) (xy 192.226169 -277.805342)
			(xy 192.262421 -277.844413) (xy 192.292445 -277.88845) (xy 192.315571 -277.936471) (xy 192.331281 -277.987401)
			(xy 192.339224 -278.040105) (xy 192.339722 -278.066754) (xy 192.339224 -278.093403) (xy 206.715604 -278.093403)
			(xy 206.715604 -278.040105) (xy 206.723547 -277.987401) (xy 206.739257 -277.936471) (xy 206.762383 -277.88845)
			(xy 206.792407 -277.844413) (xy 206.828659 -277.805342) (xy 206.87033 -277.772111) (xy 206.916488 -277.745462)
			(xy 206.966102 -277.72599) (xy 207.018064 -277.71413) (xy 207.071214 -277.710147) (xy 207.124364 -277.71413)
			(xy 207.176326 -277.72599) (xy 207.22594 -277.745462) (xy 207.272098 -277.772111) (xy 207.313769 -277.805342)
			(xy 207.350021 -277.844413) (xy 207.380045 -277.88845) (xy 207.403171 -277.936471) (xy 207.418881 -277.987401)
			(xy 207.426824 -278.040105) (xy 207.427322 -278.066754) (xy 207.426824 -278.093403) (xy 207.418881 -278.146107)
			(xy 207.403171 -278.197037) (xy 207.380045 -278.245058) (xy 207.350021 -278.289095) (xy 207.313769 -278.328166)
			(xy 207.272098 -278.361397) (xy 207.22594 -278.388046) (xy 207.176326 -278.407518) (xy 207.124364 -278.419378)
			(xy 207.071214 -278.423362) (xy 207.018064 -278.419378) (xy 206.966102 -278.407518) (xy 206.916488 -278.388046)
			(xy 206.87033 -278.361397) (xy 206.828659 -278.328166) (xy 206.792407 -278.289095) (xy 206.762383 -278.245058)
			(xy 206.739257 -278.197037) (xy 206.723547 -278.146107) (xy 206.715604 -278.093403) (xy 192.339224 -278.093403)
			(xy 192.331281 -278.146107) (xy 192.315571 -278.197037) (xy 192.292445 -278.245058) (xy 192.262421 -278.289095)
			(xy 192.226169 -278.328166) (xy 192.184498 -278.361397) (xy 192.13834 -278.388046) (xy 192.088726 -278.407518)
			(xy 192.036764 -278.419378) (xy 191.983614 -278.423362) (xy 191.930464 -278.419378) (xy 191.878502 -278.407518)
			(xy 191.828888 -278.388046) (xy 191.78273 -278.361397) (xy 191.741059 -278.328166) (xy 191.704807 -278.289095)
			(xy 191.674783 -278.245058) (xy 191.651657 -278.197037) (xy 191.635947 -278.146107) (xy 191.628004 -278.093403)
			(xy 177.251624 -278.093403) (xy 177.243681 -278.146107) (xy 177.227971 -278.197037) (xy 177.204845 -278.245058)
			(xy 177.174821 -278.289095) (xy 177.138569 -278.328166) (xy 177.096898 -278.361397) (xy 177.05074 -278.388046)
			(xy 177.001126 -278.407518) (xy 176.949164 -278.419378) (xy 176.896014 -278.423362) (xy 176.842864 -278.419378)
			(xy 176.790902 -278.407518) (xy 176.741288 -278.388046) (xy 176.69513 -278.361397) (xy 176.653459 -278.328166)
			(xy 176.617207 -278.289095) (xy 176.587183 -278.245058) (xy 176.564057 -278.197037) (xy 176.548347 -278.146107)
			(xy 176.540404 -278.093403) (xy 159.11576 -278.093403) (xy 159.11576 -278.943287) (xy 172.440336 -278.943287)
			(xy 172.440336 -278.889989) (xy 172.448279 -278.837285) (xy 172.463989 -278.786355) (xy 172.487115 -278.738334)
			(xy 172.517139 -278.694297) (xy 172.553391 -278.655226) (xy 172.595062 -278.621995) (xy 172.64122 -278.595346)
			(xy 172.690834 -278.575874) (xy 172.742796 -278.564014) (xy 172.795946 -278.560031) (xy 172.849096 -278.564014)
			(xy 172.901058 -278.575874) (xy 172.950672 -278.595346) (xy 172.99683 -278.621995) (xy 173.038501 -278.655226)
			(xy 173.074753 -278.694297) (xy 173.104777 -278.738334) (xy 173.127903 -278.786355) (xy 173.143613 -278.837285)
			(xy 173.151556 -278.889989) (xy 173.152054 -278.916638) (xy 173.151556 -278.943287) (xy 187.527936 -278.943287)
			(xy 187.527936 -278.889989) (xy 187.535879 -278.837285) (xy 187.551589 -278.786355) (xy 187.574715 -278.738334)
			(xy 187.604739 -278.694297) (xy 187.640991 -278.655226) (xy 187.682662 -278.621995) (xy 187.72882 -278.595346)
			(xy 187.778434 -278.575874) (xy 187.830396 -278.564014) (xy 187.883546 -278.560031) (xy 187.936696 -278.564014)
			(xy 187.988658 -278.575874) (xy 188.038272 -278.595346) (xy 188.08443 -278.621995) (xy 188.126101 -278.655226)
			(xy 188.162353 -278.694297) (xy 188.192377 -278.738334) (xy 188.215503 -278.786355) (xy 188.231213 -278.837285)
			(xy 188.239156 -278.889989) (xy 188.239654 -278.916638) (xy 188.239156 -278.943287) (xy 202.615536 -278.943287)
			(xy 202.615536 -278.889989) (xy 202.623479 -278.837285) (xy 202.639189 -278.786355) (xy 202.662315 -278.738334)
			(xy 202.692339 -278.694297) (xy 202.728591 -278.655226) (xy 202.770262 -278.621995) (xy 202.81642 -278.595346)
			(xy 202.866034 -278.575874) (xy 202.917996 -278.564014) (xy 202.971146 -278.560031) (xy 203.024296 -278.564014)
			(xy 203.076258 -278.575874) (xy 203.125872 -278.595346) (xy 203.17203 -278.621995) (xy 203.213701 -278.655226)
			(xy 203.249953 -278.694297) (xy 203.279977 -278.738334) (xy 203.303103 -278.786355) (xy 203.318813 -278.837285)
			(xy 203.326756 -278.889989) (xy 203.327254 -278.916638) (xy 203.326756 -278.943287) (xy 203.318813 -278.995991)
			(xy 203.303103 -279.046921) (xy 203.279977 -279.094942) (xy 203.249953 -279.138979) (xy 203.213701 -279.17805)
			(xy 203.17203 -279.211281) (xy 203.125872 -279.23793) (xy 203.076258 -279.257402) (xy 203.024296 -279.269262)
			(xy 202.971146 -279.273246) (xy 202.917996 -279.269262) (xy 202.866034 -279.257402) (xy 202.81642 -279.23793)
			(xy 202.770262 -279.211281) (xy 202.728591 -279.17805) (xy 202.692339 -279.138979) (xy 202.662315 -279.094942)
			(xy 202.639189 -279.046921) (xy 202.623479 -278.995991) (xy 202.615536 -278.943287) (xy 188.239156 -278.943287)
			(xy 188.231213 -278.995991) (xy 188.215503 -279.046921) (xy 188.192377 -279.094942) (xy 188.162353 -279.138979)
			(xy 188.126101 -279.17805) (xy 188.08443 -279.211281) (xy 188.038272 -279.23793) (xy 187.988658 -279.257402)
			(xy 187.936696 -279.269262) (xy 187.883546 -279.273246) (xy 187.830396 -279.269262) (xy 187.778434 -279.257402)
			(xy 187.72882 -279.23793) (xy 187.682662 -279.211281) (xy 187.640991 -279.17805) (xy 187.604739 -279.138979)
			(xy 187.574715 -279.094942) (xy 187.551589 -279.046921) (xy 187.535879 -278.995991) (xy 187.527936 -278.943287)
			(xy 173.151556 -278.943287) (xy 173.143613 -278.995991) (xy 173.127903 -279.046921) (xy 173.104777 -279.094942)
			(xy 173.074753 -279.138979) (xy 173.038501 -279.17805) (xy 172.99683 -279.211281) (xy 172.950672 -279.23793)
			(xy 172.901058 -279.257402) (xy 172.849096 -279.269262) (xy 172.795946 -279.273246) (xy 172.742796 -279.269262)
			(xy 172.690834 -279.257402) (xy 172.64122 -279.23793) (xy 172.595062 -279.211281) (xy 172.553391 -279.17805)
			(xy 172.517139 -279.138979) (xy 172.487115 -279.094942) (xy 172.463989 -279.046921) (xy 172.448279 -278.995991)
			(xy 172.440336 -278.943287) (xy 159.11576 -278.943287) (xy 159.11576 -279.793425) (xy 176.540404 -279.793425)
			(xy 176.540404 -279.740127) (xy 176.548347 -279.687423) (xy 176.564057 -279.636493) (xy 176.587183 -279.588472)
			(xy 176.617207 -279.544435) (xy 176.653459 -279.505364) (xy 176.69513 -279.472133) (xy 176.741288 -279.445484)
			(xy 176.790902 -279.426012) (xy 176.842864 -279.414152) (xy 176.896014 -279.410169) (xy 176.949164 -279.414152)
			(xy 177.001126 -279.426012) (xy 177.05074 -279.445484) (xy 177.096898 -279.472133) (xy 177.138569 -279.505364)
			(xy 177.174821 -279.544435) (xy 177.204845 -279.588472) (xy 177.227971 -279.636493) (xy 177.243681 -279.687423)
			(xy 177.251624 -279.740127) (xy 177.252122 -279.766776) (xy 177.251624 -279.793425) (xy 191.628004 -279.793425)
			(xy 191.628004 -279.740127) (xy 191.635947 -279.687423) (xy 191.651657 -279.636493) (xy 191.674783 -279.588472)
			(xy 191.704807 -279.544435) (xy 191.741059 -279.505364) (xy 191.78273 -279.472133) (xy 191.828888 -279.445484)
			(xy 191.878502 -279.426012) (xy 191.930464 -279.414152) (xy 191.983614 -279.410169) (xy 192.036764 -279.414152)
			(xy 192.088726 -279.426012) (xy 192.13834 -279.445484) (xy 192.184498 -279.472133) (xy 192.226169 -279.505364)
			(xy 192.262421 -279.544435) (xy 192.292445 -279.588472) (xy 192.315571 -279.636493) (xy 192.331281 -279.687423)
			(xy 192.339224 -279.740127) (xy 192.339722 -279.766776) (xy 192.339224 -279.793425) (xy 206.715604 -279.793425)
			(xy 206.715604 -279.740127) (xy 206.723547 -279.687423) (xy 206.739257 -279.636493) (xy 206.762383 -279.588472)
			(xy 206.792407 -279.544435) (xy 206.828659 -279.505364) (xy 206.87033 -279.472133) (xy 206.916488 -279.445484)
			(xy 206.966102 -279.426012) (xy 207.018064 -279.414152) (xy 207.071214 -279.410169) (xy 207.124364 -279.414152)
			(xy 207.176326 -279.426012) (xy 207.22594 -279.445484) (xy 207.272098 -279.472133) (xy 207.313769 -279.505364)
			(xy 207.350021 -279.544435) (xy 207.380045 -279.588472) (xy 207.403171 -279.636493) (xy 207.418881 -279.687423)
			(xy 207.426824 -279.740127) (xy 207.427322 -279.766776) (xy 207.426824 -279.793425) (xy 207.418881 -279.846129)
			(xy 207.403171 -279.897059) (xy 207.380045 -279.94508) (xy 207.350021 -279.989117) (xy 207.313769 -280.028188)
			(xy 207.272098 -280.061419) (xy 207.22594 -280.088068) (xy 207.176326 -280.10754) (xy 207.124364 -280.1194)
			(xy 207.071214 -280.123384) (xy 207.018064 -280.1194) (xy 206.966102 -280.10754) (xy 206.916488 -280.088068)
			(xy 206.87033 -280.061419) (xy 206.828659 -280.028188) (xy 206.792407 -279.989117) (xy 206.762383 -279.94508)
			(xy 206.739257 -279.897059) (xy 206.723547 -279.846129) (xy 206.715604 -279.793425) (xy 192.339224 -279.793425)
			(xy 192.331281 -279.846129) (xy 192.315571 -279.897059) (xy 192.292445 -279.94508) (xy 192.262421 -279.989117)
			(xy 192.226169 -280.028188) (xy 192.184498 -280.061419) (xy 192.13834 -280.088068) (xy 192.088726 -280.10754)
			(xy 192.036764 -280.1194) (xy 191.983614 -280.123384) (xy 191.930464 -280.1194) (xy 191.878502 -280.10754)
			(xy 191.828888 -280.088068) (xy 191.78273 -280.061419) (xy 191.741059 -280.028188) (xy 191.704807 -279.989117)
			(xy 191.674783 -279.94508) (xy 191.651657 -279.897059) (xy 191.635947 -279.846129) (xy 191.628004 -279.793425)
			(xy 177.251624 -279.793425) (xy 177.243681 -279.846129) (xy 177.227971 -279.897059) (xy 177.204845 -279.94508)
			(xy 177.174821 -279.989117) (xy 177.138569 -280.028188) (xy 177.096898 -280.061419) (xy 177.05074 -280.088068)
			(xy 177.001126 -280.10754) (xy 176.949164 -280.1194) (xy 176.896014 -280.123384) (xy 176.842864 -280.1194)
			(xy 176.790902 -280.10754) (xy 176.741288 -280.088068) (xy 176.69513 -280.061419) (xy 176.653459 -280.028188)
			(xy 176.617207 -279.989117) (xy 176.587183 -279.94508) (xy 176.564057 -279.897059) (xy 176.548347 -279.846129)
			(xy 176.540404 -279.793425) (xy 159.11576 -279.793425) (xy 159.11576 -280.643309) (xy 172.440336 -280.643309)
			(xy 172.440336 -280.590011) (xy 172.448279 -280.537307) (xy 172.463989 -280.486377) (xy 172.487115 -280.438356)
			(xy 172.517139 -280.394319) (xy 172.553391 -280.355248) (xy 172.595062 -280.322017) (xy 172.64122 -280.295368)
			(xy 172.690834 -280.275896) (xy 172.742796 -280.264036) (xy 172.795946 -280.260053) (xy 172.849096 -280.264036)
			(xy 172.901058 -280.275896) (xy 172.950672 -280.295368) (xy 172.99683 -280.322017) (xy 173.038501 -280.355248)
			(xy 173.074753 -280.394319) (xy 173.104777 -280.438356) (xy 173.127903 -280.486377) (xy 173.143613 -280.537307)
			(xy 173.151556 -280.590011) (xy 173.152054 -280.61666) (xy 173.151556 -280.643309) (xy 187.527936 -280.643309)
			(xy 187.527936 -280.590011) (xy 187.535879 -280.537307) (xy 187.551589 -280.486377) (xy 187.574715 -280.438356)
			(xy 187.604739 -280.394319) (xy 187.640991 -280.355248) (xy 187.682662 -280.322017) (xy 187.72882 -280.295368)
			(xy 187.778434 -280.275896) (xy 187.830396 -280.264036) (xy 187.883546 -280.260053) (xy 187.936696 -280.264036)
			(xy 187.988658 -280.275896) (xy 188.038272 -280.295368) (xy 188.08443 -280.322017) (xy 188.126101 -280.355248)
			(xy 188.162353 -280.394319) (xy 188.192377 -280.438356) (xy 188.215503 -280.486377) (xy 188.231213 -280.537307)
			(xy 188.239156 -280.590011) (xy 188.239654 -280.61666) (xy 188.239156 -280.643309) (xy 202.615536 -280.643309)
			(xy 202.615536 -280.590011) (xy 202.623479 -280.537307) (xy 202.639189 -280.486377) (xy 202.662315 -280.438356)
			(xy 202.692339 -280.394319) (xy 202.728591 -280.355248) (xy 202.770262 -280.322017) (xy 202.81642 -280.295368)
			(xy 202.866034 -280.275896) (xy 202.917996 -280.264036) (xy 202.971146 -280.260053) (xy 203.024296 -280.264036)
			(xy 203.076258 -280.275896) (xy 203.125872 -280.295368) (xy 203.17203 -280.322017) (xy 203.213701 -280.355248)
			(xy 203.249953 -280.394319) (xy 203.279977 -280.438356) (xy 203.303103 -280.486377) (xy 203.318813 -280.537307)
			(xy 203.326756 -280.590011) (xy 203.327254 -280.61666) (xy 203.326756 -280.643309) (xy 203.318813 -280.696013)
			(xy 203.303103 -280.746943) (xy 203.279977 -280.794964) (xy 203.249953 -280.839001) (xy 203.213701 -280.878072)
			(xy 203.17203 -280.911303) (xy 203.125872 -280.937952) (xy 203.076258 -280.957424) (xy 203.024296 -280.969284)
			(xy 202.971146 -280.973268) (xy 202.917996 -280.969284) (xy 202.866034 -280.957424) (xy 202.81642 -280.937952)
			(xy 202.770262 -280.911303) (xy 202.728591 -280.878072) (xy 202.692339 -280.839001) (xy 202.662315 -280.794964)
			(xy 202.639189 -280.746943) (xy 202.623479 -280.696013) (xy 202.615536 -280.643309) (xy 188.239156 -280.643309)
			(xy 188.231213 -280.696013) (xy 188.215503 -280.746943) (xy 188.192377 -280.794964) (xy 188.162353 -280.839001)
			(xy 188.126101 -280.878072) (xy 188.08443 -280.911303) (xy 188.038272 -280.937952) (xy 187.988658 -280.957424)
			(xy 187.936696 -280.969284) (xy 187.883546 -280.973268) (xy 187.830396 -280.969284) (xy 187.778434 -280.957424)
			(xy 187.72882 -280.937952) (xy 187.682662 -280.911303) (xy 187.640991 -280.878072) (xy 187.604739 -280.839001)
			(xy 187.574715 -280.794964) (xy 187.551589 -280.746943) (xy 187.535879 -280.696013) (xy 187.527936 -280.643309)
			(xy 173.151556 -280.643309) (xy 173.143613 -280.696013) (xy 173.127903 -280.746943) (xy 173.104777 -280.794964)
			(xy 173.074753 -280.839001) (xy 173.038501 -280.878072) (xy 172.99683 -280.911303) (xy 172.950672 -280.937952)
			(xy 172.901058 -280.957424) (xy 172.849096 -280.969284) (xy 172.795946 -280.973268) (xy 172.742796 -280.969284)
			(xy 172.690834 -280.957424) (xy 172.64122 -280.937952) (xy 172.595062 -280.911303) (xy 172.553391 -280.878072)
			(xy 172.517139 -280.839001) (xy 172.487115 -280.794964) (xy 172.463989 -280.746943) (xy 172.448279 -280.696013)
			(xy 172.440336 -280.643309) (xy 159.11576 -280.643309) (xy 159.11576 -281.493193) (xy 176.540404 -281.493193)
			(xy 176.540404 -281.439895) (xy 176.548347 -281.387191) (xy 176.564057 -281.336261) (xy 176.587183 -281.28824)
			(xy 176.617207 -281.244203) (xy 176.653459 -281.205132) (xy 176.69513 -281.171901) (xy 176.741288 -281.145252)
			(xy 176.790902 -281.12578) (xy 176.842864 -281.11392) (xy 176.896014 -281.109937) (xy 176.949164 -281.11392)
			(xy 177.001126 -281.12578) (xy 177.05074 -281.145252) (xy 177.096898 -281.171901) (xy 177.138569 -281.205132)
			(xy 177.174821 -281.244203) (xy 177.204845 -281.28824) (xy 177.227971 -281.336261) (xy 177.243681 -281.387191)
			(xy 177.251624 -281.439895) (xy 177.252122 -281.466544) (xy 177.251624 -281.493193) (xy 177.251586 -281.493447)
			(xy 191.586094 -281.493447) (xy 191.586094 -281.440149) (xy 191.594037 -281.387445) (xy 191.609747 -281.336515)
			(xy 191.632873 -281.288494) (xy 191.662897 -281.244457) (xy 191.699149 -281.205386) (xy 191.74082 -281.172155)
			(xy 191.786978 -281.145506) (xy 191.836592 -281.126034) (xy 191.888554 -281.114174) (xy 191.941704 -281.110191)
			(xy 191.994854 -281.114174) (xy 192.046816 -281.126034) (xy 192.09643 -281.145506) (xy 192.142588 -281.172155)
			(xy 192.184259 -281.205386) (xy 192.220511 -281.244457) (xy 192.250535 -281.288494) (xy 192.273661 -281.336515)
			(xy 192.289371 -281.387445) (xy 192.297314 -281.440149) (xy 192.297812 -281.466798) (xy 192.297319 -281.493193)
			(xy 206.715604 -281.493193) (xy 206.715604 -281.439895) (xy 206.723547 -281.387191) (xy 206.739257 -281.336261)
			(xy 206.762383 -281.28824) (xy 206.792407 -281.244203) (xy 206.828659 -281.205132) (xy 206.87033 -281.171901)
			(xy 206.916488 -281.145252) (xy 206.966102 -281.12578) (xy 207.018064 -281.11392) (xy 207.071214 -281.109937)
			(xy 207.124364 -281.11392) (xy 207.176326 -281.12578) (xy 207.22594 -281.145252) (xy 207.272098 -281.171901)
			(xy 207.313769 -281.205132) (xy 207.350021 -281.244203) (xy 207.380045 -281.28824) (xy 207.403171 -281.336261)
			(xy 207.418881 -281.387191) (xy 207.426824 -281.439895) (xy 207.427322 -281.466544) (xy 207.426824 -281.493193)
			(xy 207.418881 -281.545897) (xy 207.403171 -281.596827) (xy 207.380045 -281.644848) (xy 207.350021 -281.688885)
			(xy 207.313769 -281.727956) (xy 207.272098 -281.761187) (xy 207.22594 -281.787836) (xy 207.176326 -281.807308)
			(xy 207.124364 -281.819168) (xy 207.071214 -281.823152) (xy 207.018064 -281.819168) (xy 206.966102 -281.807308)
			(xy 206.916488 -281.787836) (xy 206.87033 -281.761187) (xy 206.828659 -281.727956) (xy 206.792407 -281.688885)
			(xy 206.762383 -281.644848) (xy 206.739257 -281.596827) (xy 206.723547 -281.545897) (xy 206.715604 -281.493193)
			(xy 192.297319 -281.493193) (xy 192.297314 -281.493447) (xy 192.289371 -281.546151) (xy 192.273661 -281.597081)
			(xy 192.250535 -281.645102) (xy 192.220511 -281.689139) (xy 192.184259 -281.72821) (xy 192.142588 -281.761441)
			(xy 192.09643 -281.78809) (xy 192.046816 -281.807562) (xy 191.994854 -281.819422) (xy 191.941704 -281.823406)
			(xy 191.888554 -281.819422) (xy 191.836592 -281.807562) (xy 191.786978 -281.78809) (xy 191.74082 -281.761441)
			(xy 191.699149 -281.72821) (xy 191.662897 -281.689139) (xy 191.632873 -281.645102) (xy 191.609747 -281.597081)
			(xy 191.594037 -281.546151) (xy 191.586094 -281.493447) (xy 177.251586 -281.493447) (xy 177.243681 -281.545897)
			(xy 177.227971 -281.596827) (xy 177.204845 -281.644848) (xy 177.174821 -281.688885) (xy 177.138569 -281.727956)
			(xy 177.096898 -281.761187) (xy 177.05074 -281.787836) (xy 177.001126 -281.807308) (xy 176.949164 -281.819168)
			(xy 176.896014 -281.823152) (xy 176.842864 -281.819168) (xy 176.790902 -281.807308) (xy 176.741288 -281.787836)
			(xy 176.69513 -281.761187) (xy 176.653459 -281.727956) (xy 176.617207 -281.688885) (xy 176.587183 -281.644848)
			(xy 176.564057 -281.596827) (xy 176.548347 -281.545897) (xy 176.540404 -281.493193) (xy 159.11576 -281.493193)
			(xy 159.11576 -282.343331) (xy 172.440336 -282.343331) (xy 172.440336 -282.290033) (xy 172.448279 -282.237329)
			(xy 172.463989 -282.186399) (xy 172.487115 -282.138378) (xy 172.517139 -282.094341) (xy 172.553391 -282.05527)
			(xy 172.595062 -282.022039) (xy 172.64122 -281.99539) (xy 172.690834 -281.975918) (xy 172.742796 -281.964058)
			(xy 172.795946 -281.960075) (xy 172.849096 -281.964058) (xy 172.901058 -281.975918) (xy 172.950672 -281.99539)
			(xy 172.99683 -282.022039) (xy 173.038501 -282.05527) (xy 173.074753 -282.094341) (xy 173.104777 -282.138378)
			(xy 173.127903 -282.186399) (xy 173.143613 -282.237329) (xy 173.151556 -282.290033) (xy 173.152054 -282.316682)
			(xy 173.151556 -282.343331) (xy 187.527936 -282.343331) (xy 187.527936 -282.290033) (xy 187.535879 -282.237329)
			(xy 187.551589 -282.186399) (xy 187.574715 -282.138378) (xy 187.604739 -282.094341) (xy 187.640991 -282.05527)
			(xy 187.682662 -282.022039) (xy 187.72882 -281.99539) (xy 187.778434 -281.975918) (xy 187.830396 -281.964058)
			(xy 187.883546 -281.960075) (xy 187.936696 -281.964058) (xy 187.988658 -281.975918) (xy 188.038272 -281.99539)
			(xy 188.08443 -282.022039) (xy 188.126101 -282.05527) (xy 188.162353 -282.094341) (xy 188.192377 -282.138378)
			(xy 188.215503 -282.186399) (xy 188.231213 -282.237329) (xy 188.239156 -282.290033) (xy 188.239654 -282.316682)
			(xy 188.239156 -282.343331) (xy 202.615536 -282.343331) (xy 202.615536 -282.290033) (xy 202.623479 -282.237329)
			(xy 202.639189 -282.186399) (xy 202.662315 -282.138378) (xy 202.692339 -282.094341) (xy 202.728591 -282.05527)
			(xy 202.770262 -282.022039) (xy 202.81642 -281.99539) (xy 202.866034 -281.975918) (xy 202.917996 -281.964058)
			(xy 202.971146 -281.960075) (xy 203.024296 -281.964058) (xy 203.076258 -281.975918) (xy 203.125872 -281.99539)
			(xy 203.17203 -282.022039) (xy 203.213701 -282.05527) (xy 203.249953 -282.094341) (xy 203.279977 -282.138378)
			(xy 203.303103 -282.186399) (xy 203.318813 -282.237329) (xy 203.326756 -282.290033) (xy 203.327254 -282.316682)
			(xy 203.326756 -282.343331) (xy 203.318813 -282.396035) (xy 203.303103 -282.446965) (xy 203.279977 -282.494986)
			(xy 203.249953 -282.539023) (xy 203.213701 -282.578094) (xy 203.17203 -282.611325) (xy 203.125872 -282.637974)
			(xy 203.076258 -282.657446) (xy 203.024296 -282.669306) (xy 202.971146 -282.67329) (xy 202.917996 -282.669306)
			(xy 202.866034 -282.657446) (xy 202.81642 -282.637974) (xy 202.770262 -282.611325) (xy 202.728591 -282.578094)
			(xy 202.692339 -282.539023) (xy 202.662315 -282.494986) (xy 202.639189 -282.446965) (xy 202.623479 -282.396035)
			(xy 202.615536 -282.343331) (xy 188.239156 -282.343331) (xy 188.231213 -282.396035) (xy 188.215503 -282.446965)
			(xy 188.192377 -282.494986) (xy 188.162353 -282.539023) (xy 188.126101 -282.578094) (xy 188.08443 -282.611325)
			(xy 188.038272 -282.637974) (xy 187.988658 -282.657446) (xy 187.936696 -282.669306) (xy 187.883546 -282.67329)
			(xy 187.830396 -282.669306) (xy 187.778434 -282.657446) (xy 187.72882 -282.637974) (xy 187.682662 -282.611325)
			(xy 187.640991 -282.578094) (xy 187.604739 -282.539023) (xy 187.574715 -282.494986) (xy 187.551589 -282.446965)
			(xy 187.535879 -282.396035) (xy 187.527936 -282.343331) (xy 173.151556 -282.343331) (xy 173.143613 -282.396035)
			(xy 173.127903 -282.446965) (xy 173.104777 -282.494986) (xy 173.074753 -282.539023) (xy 173.038501 -282.578094)
			(xy 172.99683 -282.611325) (xy 172.950672 -282.637974) (xy 172.901058 -282.657446) (xy 172.849096 -282.669306)
			(xy 172.795946 -282.67329) (xy 172.742796 -282.669306) (xy 172.690834 -282.657446) (xy 172.64122 -282.637974)
			(xy 172.595062 -282.611325) (xy 172.553391 -282.578094) (xy 172.517139 -282.539023) (xy 172.487115 -282.494986)
			(xy 172.463989 -282.446965) (xy 172.448279 -282.396035) (xy 172.440336 -282.343331) (xy 159.11576 -282.343331)
			(xy 159.11576 -283.193215) (xy 176.540404 -283.193215) (xy 176.540404 -283.139917) (xy 176.548347 -283.087213)
			(xy 176.564057 -283.036283) (xy 176.587183 -282.988262) (xy 176.617207 -282.944225) (xy 176.653459 -282.905154)
			(xy 176.69513 -282.871923) (xy 176.741288 -282.845274) (xy 176.790902 -282.825802) (xy 176.842864 -282.813942)
			(xy 176.896014 -282.809959) (xy 176.949164 -282.813942) (xy 177.001126 -282.825802) (xy 177.05074 -282.845274)
			(xy 177.096898 -282.871923) (xy 177.138569 -282.905154) (xy 177.174821 -282.944225) (xy 177.204845 -282.988262)
			(xy 177.227971 -283.036283) (xy 177.243681 -283.087213) (xy 177.251624 -283.139917) (xy 177.252122 -283.166566)
			(xy 177.251624 -283.193215) (xy 191.628004 -283.193215) (xy 191.628004 -283.139917) (xy 191.635947 -283.087213)
			(xy 191.651657 -283.036283) (xy 191.674783 -282.988262) (xy 191.704807 -282.944225) (xy 191.741059 -282.905154)
			(xy 191.78273 -282.871923) (xy 191.828888 -282.845274) (xy 191.878502 -282.825802) (xy 191.930464 -282.813942)
			(xy 191.983614 -282.809959) (xy 192.036764 -282.813942) (xy 192.088726 -282.825802) (xy 192.13834 -282.845274)
			(xy 192.184498 -282.871923) (xy 192.226169 -282.905154) (xy 192.262421 -282.944225) (xy 192.292445 -282.988262)
			(xy 192.315571 -283.036283) (xy 192.331281 -283.087213) (xy 192.339224 -283.139917) (xy 192.339722 -283.166566)
			(xy 192.339224 -283.193215) (xy 206.715604 -283.193215) (xy 206.715604 -283.139917) (xy 206.723547 -283.087213)
			(xy 206.739257 -283.036283) (xy 206.762383 -282.988262) (xy 206.792407 -282.944225) (xy 206.828659 -282.905154)
			(xy 206.87033 -282.871923) (xy 206.916488 -282.845274) (xy 206.966102 -282.825802) (xy 207.018064 -282.813942)
			(xy 207.071214 -282.809959) (xy 207.124364 -282.813942) (xy 207.176326 -282.825802) (xy 207.22594 -282.845274)
			(xy 207.272098 -282.871923) (xy 207.313769 -282.905154) (xy 207.350021 -282.944225) (xy 207.380045 -282.988262)
			(xy 207.403171 -283.036283) (xy 207.418881 -283.087213) (xy 207.426824 -283.139917) (xy 207.427322 -283.166566)
			(xy 207.426824 -283.193215) (xy 207.418881 -283.245919) (xy 207.403171 -283.296849) (xy 207.380045 -283.34487)
			(xy 207.350021 -283.388907) (xy 207.313769 -283.427978) (xy 207.272098 -283.461209) (xy 207.22594 -283.487858)
			(xy 207.176326 -283.50733) (xy 207.124364 -283.51919) (xy 207.071214 -283.523174) (xy 207.018064 -283.51919)
			(xy 206.966102 -283.50733) (xy 206.916488 -283.487858) (xy 206.87033 -283.461209) (xy 206.828659 -283.427978)
			(xy 206.792407 -283.388907) (xy 206.762383 -283.34487) (xy 206.739257 -283.296849) (xy 206.723547 -283.245919)
			(xy 206.715604 -283.193215) (xy 192.339224 -283.193215) (xy 192.331281 -283.245919) (xy 192.315571 -283.296849)
			(xy 192.292445 -283.34487) (xy 192.262421 -283.388907) (xy 192.226169 -283.427978) (xy 192.184498 -283.461209)
			(xy 192.13834 -283.487858) (xy 192.088726 -283.50733) (xy 192.036764 -283.51919) (xy 191.983614 -283.523174)
			(xy 191.930464 -283.51919) (xy 191.878502 -283.50733) (xy 191.828888 -283.487858) (xy 191.78273 -283.461209)
			(xy 191.741059 -283.427978) (xy 191.704807 -283.388907) (xy 191.674783 -283.34487) (xy 191.651657 -283.296849)
			(xy 191.635947 -283.245919) (xy 191.628004 -283.193215) (xy 177.251624 -283.193215) (xy 177.243681 -283.245919)
			(xy 177.227971 -283.296849) (xy 177.204845 -283.34487) (xy 177.174821 -283.388907) (xy 177.138569 -283.427978)
			(xy 177.096898 -283.461209) (xy 177.05074 -283.487858) (xy 177.001126 -283.50733) (xy 176.949164 -283.51919)
			(xy 176.896014 -283.523174) (xy 176.842864 -283.51919) (xy 176.790902 -283.50733) (xy 176.741288 -283.487858)
			(xy 176.69513 -283.461209) (xy 176.653459 -283.427978) (xy 176.617207 -283.388907) (xy 176.587183 -283.34487)
			(xy 176.564057 -283.296849) (xy 176.548347 -283.245919) (xy 176.540404 -283.193215) (xy 159.11576 -283.193215)
			(xy 159.11576 -284.043353) (xy 172.440336 -284.043353) (xy 172.440336 -283.990055) (xy 172.448279 -283.937351)
			(xy 172.463989 -283.886421) (xy 172.487115 -283.8384) (xy 172.517139 -283.794363) (xy 172.553391 -283.755292)
			(xy 172.595062 -283.722061) (xy 172.64122 -283.695412) (xy 172.690834 -283.67594) (xy 172.742796 -283.66408)
			(xy 172.795946 -283.660097) (xy 172.849096 -283.66408) (xy 172.901058 -283.67594) (xy 172.950672 -283.695412)
			(xy 172.99683 -283.722061) (xy 173.038501 -283.755292) (xy 173.074753 -283.794363) (xy 173.104777 -283.8384)
			(xy 173.127903 -283.886421) (xy 173.143613 -283.937351) (xy 173.151556 -283.990055) (xy 173.152054 -284.016704)
			(xy 173.151556 -284.043353) (xy 176.540404 -284.043353) (xy 176.540404 -283.990055) (xy 176.548347 -283.937351)
			(xy 176.564057 -283.886421) (xy 176.587183 -283.8384) (xy 176.617207 -283.794363) (xy 176.653459 -283.755292)
			(xy 176.69513 -283.722061) (xy 176.741288 -283.695412) (xy 176.790902 -283.67594) (xy 176.842864 -283.66408)
			(xy 176.896014 -283.660097) (xy 176.949164 -283.66408) (xy 177.001126 -283.67594) (xy 177.05074 -283.695412)
			(xy 177.096898 -283.722061) (xy 177.138569 -283.755292) (xy 177.174821 -283.794363) (xy 177.204845 -283.8384)
			(xy 177.227971 -283.886421) (xy 177.243681 -283.937351) (xy 177.251624 -283.990055) (xy 177.252122 -284.016704)
			(xy 177.251624 -284.043353) (xy 187.527936 -284.043353) (xy 187.527936 -283.990055) (xy 187.535879 -283.937351)
			(xy 187.551589 -283.886421) (xy 187.574715 -283.8384) (xy 187.604739 -283.794363) (xy 187.640991 -283.755292)
			(xy 187.682662 -283.722061) (xy 187.72882 -283.695412) (xy 187.778434 -283.67594) (xy 187.830396 -283.66408)
			(xy 187.883546 -283.660097) (xy 187.936696 -283.66408) (xy 187.988658 -283.67594) (xy 188.038272 -283.695412)
			(xy 188.08443 -283.722061) (xy 188.126101 -283.755292) (xy 188.162353 -283.794363) (xy 188.192377 -283.8384)
			(xy 188.215503 -283.886421) (xy 188.231213 -283.937351) (xy 188.239156 -283.990055) (xy 188.239654 -284.016704)
			(xy 188.239156 -284.043353) (xy 191.628004 -284.043353) (xy 191.628004 -283.990055) (xy 191.635947 -283.937351)
			(xy 191.651657 -283.886421) (xy 191.674783 -283.8384) (xy 191.704807 -283.794363) (xy 191.741059 -283.755292)
			(xy 191.78273 -283.722061) (xy 191.828888 -283.695412) (xy 191.878502 -283.67594) (xy 191.930464 -283.66408)
			(xy 191.983614 -283.660097) (xy 192.036764 -283.66408) (xy 192.088726 -283.67594) (xy 192.13834 -283.695412)
			(xy 192.184498 -283.722061) (xy 192.226169 -283.755292) (xy 192.262421 -283.794363) (xy 192.292445 -283.8384)
			(xy 192.315571 -283.886421) (xy 192.331281 -283.937351) (xy 192.339224 -283.990055) (xy 192.339722 -284.016704)
			(xy 192.339224 -284.043353) (xy 202.615536 -284.043353) (xy 202.615536 -283.990055) (xy 202.623479 -283.937351)
			(xy 202.639189 -283.886421) (xy 202.662315 -283.8384) (xy 202.692339 -283.794363) (xy 202.728591 -283.755292)
			(xy 202.770262 -283.722061) (xy 202.81642 -283.695412) (xy 202.866034 -283.67594) (xy 202.917996 -283.66408)
			(xy 202.971146 -283.660097) (xy 203.024296 -283.66408) (xy 203.076258 -283.67594) (xy 203.125872 -283.695412)
			(xy 203.17203 -283.722061) (xy 203.213701 -283.755292) (xy 203.249953 -283.794363) (xy 203.279977 -283.8384)
			(xy 203.303103 -283.886421) (xy 203.318813 -283.937351) (xy 203.326756 -283.990055) (xy 203.327254 -284.016704)
			(xy 203.326756 -284.043353) (xy 206.715604 -284.043353) (xy 206.715604 -283.990055) (xy 206.723547 -283.937351)
			(xy 206.739257 -283.886421) (xy 206.762383 -283.8384) (xy 206.792407 -283.794363) (xy 206.828659 -283.755292)
			(xy 206.87033 -283.722061) (xy 206.916488 -283.695412) (xy 206.966102 -283.67594) (xy 207.018064 -283.66408)
			(xy 207.071214 -283.660097) (xy 207.124364 -283.66408) (xy 207.176326 -283.67594) (xy 207.22594 -283.695412)
			(xy 207.272098 -283.722061) (xy 207.313769 -283.755292) (xy 207.350021 -283.794363) (xy 207.380045 -283.8384)
			(xy 207.403171 -283.886421) (xy 207.418881 -283.937351) (xy 207.426824 -283.990055) (xy 207.427322 -284.016704)
			(xy 207.426824 -284.043353) (xy 207.418881 -284.096057) (xy 207.403171 -284.146987) (xy 207.380045 -284.195008)
			(xy 207.350021 -284.239045) (xy 207.313769 -284.278116) (xy 207.272098 -284.311347) (xy 207.22594 -284.337996)
			(xy 207.176326 -284.357468) (xy 207.124364 -284.369328) (xy 207.071214 -284.373312) (xy 207.018064 -284.369328)
			(xy 206.966102 -284.357468) (xy 206.916488 -284.337996) (xy 206.87033 -284.311347) (xy 206.828659 -284.278116)
			(xy 206.792407 -284.239045) (xy 206.762383 -284.195008) (xy 206.739257 -284.146987) (xy 206.723547 -284.096057)
			(xy 206.715604 -284.043353) (xy 203.326756 -284.043353) (xy 203.318813 -284.096057) (xy 203.303103 -284.146987)
			(xy 203.279977 -284.195008) (xy 203.249953 -284.239045) (xy 203.213701 -284.278116) (xy 203.17203 -284.311347)
			(xy 203.125872 -284.337996) (xy 203.076258 -284.357468) (xy 203.024296 -284.369328) (xy 202.971146 -284.373312)
			(xy 202.917996 -284.369328) (xy 202.866034 -284.357468) (xy 202.81642 -284.337996) (xy 202.770262 -284.311347)
			(xy 202.728591 -284.278116) (xy 202.692339 -284.239045) (xy 202.662315 -284.195008) (xy 202.639189 -284.146987)
			(xy 202.623479 -284.096057) (xy 202.615536 -284.043353) (xy 192.339224 -284.043353) (xy 192.331281 -284.096057)
			(xy 192.315571 -284.146987) (xy 192.292445 -284.195008) (xy 192.262421 -284.239045) (xy 192.226169 -284.278116)
			(xy 192.184498 -284.311347) (xy 192.13834 -284.337996) (xy 192.088726 -284.357468) (xy 192.036764 -284.369328)
			(xy 191.983614 -284.373312) (xy 191.930464 -284.369328) (xy 191.878502 -284.357468) (xy 191.828888 -284.337996)
			(xy 191.78273 -284.311347) (xy 191.741059 -284.278116) (xy 191.704807 -284.239045) (xy 191.674783 -284.195008)
			(xy 191.651657 -284.146987) (xy 191.635947 -284.096057) (xy 191.628004 -284.043353) (xy 188.239156 -284.043353)
			(xy 188.231213 -284.096057) (xy 188.215503 -284.146987) (xy 188.192377 -284.195008) (xy 188.162353 -284.239045)
			(xy 188.126101 -284.278116) (xy 188.08443 -284.311347) (xy 188.038272 -284.337996) (xy 187.988658 -284.357468)
			(xy 187.936696 -284.369328) (xy 187.883546 -284.373312) (xy 187.830396 -284.369328) (xy 187.778434 -284.357468)
			(xy 187.72882 -284.337996) (xy 187.682662 -284.311347) (xy 187.640991 -284.278116) (xy 187.604739 -284.239045)
			(xy 187.574715 -284.195008) (xy 187.551589 -284.146987) (xy 187.535879 -284.096057) (xy 187.527936 -284.043353)
			(xy 177.251624 -284.043353) (xy 177.243681 -284.096057) (xy 177.227971 -284.146987) (xy 177.204845 -284.195008)
			(xy 177.174821 -284.239045) (xy 177.138569 -284.278116) (xy 177.096898 -284.311347) (xy 177.05074 -284.337996)
			(xy 177.001126 -284.357468) (xy 176.949164 -284.369328) (xy 176.896014 -284.373312) (xy 176.842864 -284.369328)
			(xy 176.790902 -284.357468) (xy 176.741288 -284.337996) (xy 176.69513 -284.311347) (xy 176.653459 -284.278116)
			(xy 176.617207 -284.239045) (xy 176.587183 -284.195008) (xy 176.564057 -284.146987) (xy 176.548347 -284.096057)
			(xy 176.540404 -284.043353) (xy 173.151556 -284.043353) (xy 173.143613 -284.096057) (xy 173.127903 -284.146987)
			(xy 173.104777 -284.195008) (xy 173.074753 -284.239045) (xy 173.038501 -284.278116) (xy 172.99683 -284.311347)
			(xy 172.950672 -284.337996) (xy 172.901058 -284.357468) (xy 172.849096 -284.369328) (xy 172.795946 -284.373312)
			(xy 172.742796 -284.369328) (xy 172.690834 -284.357468) (xy 172.64122 -284.337996) (xy 172.595062 -284.311347)
			(xy 172.553391 -284.278116) (xy 172.517139 -284.239045) (xy 172.487115 -284.195008) (xy 172.463989 -284.146987)
			(xy 172.448279 -284.096057) (xy 172.440336 -284.043353) (xy 159.11576 -284.043353) (xy 159.11576 -284.893237)
			(xy 172.440336 -284.893237) (xy 172.440336 -284.839939) (xy 172.448279 -284.787235) (xy 172.463989 -284.736305)
			(xy 172.487115 -284.688284) (xy 172.517139 -284.644247) (xy 172.553391 -284.605176) (xy 172.595062 -284.571945)
			(xy 172.64122 -284.545296) (xy 172.690834 -284.525824) (xy 172.742796 -284.513964) (xy 172.795946 -284.509981)
			(xy 172.849096 -284.513964) (xy 172.901058 -284.525824) (xy 172.950672 -284.545296) (xy 172.99683 -284.571945)
			(xy 173.038501 -284.605176) (xy 173.074753 -284.644247) (xy 173.104777 -284.688284) (xy 173.127903 -284.736305)
			(xy 173.143613 -284.787235) (xy 173.151556 -284.839939) (xy 173.152054 -284.866588) (xy 173.151556 -284.893237)
			(xy 187.527936 -284.893237) (xy 187.527936 -284.839939) (xy 187.535879 -284.787235) (xy 187.551589 -284.736305)
			(xy 187.574715 -284.688284) (xy 187.604739 -284.644247) (xy 187.640991 -284.605176) (xy 187.682662 -284.571945)
			(xy 187.72882 -284.545296) (xy 187.778434 -284.525824) (xy 187.830396 -284.513964) (xy 187.883546 -284.509981)
			(xy 187.936696 -284.513964) (xy 187.988658 -284.525824) (xy 188.038272 -284.545296) (xy 188.08443 -284.571945)
			(xy 188.126101 -284.605176) (xy 188.162353 -284.644247) (xy 188.192377 -284.688284) (xy 188.215503 -284.736305)
			(xy 188.231213 -284.787235) (xy 188.239156 -284.839939) (xy 188.239654 -284.866588) (xy 188.239156 -284.893237)
			(xy 202.615536 -284.893237) (xy 202.615536 -284.839939) (xy 202.623479 -284.787235) (xy 202.639189 -284.736305)
			(xy 202.662315 -284.688284) (xy 202.692339 -284.644247) (xy 202.728591 -284.605176) (xy 202.770262 -284.571945)
			(xy 202.81642 -284.545296) (xy 202.866034 -284.525824) (xy 202.917996 -284.513964) (xy 202.971146 -284.509981)
			(xy 203.024296 -284.513964) (xy 203.076258 -284.525824) (xy 203.125872 -284.545296) (xy 203.17203 -284.571945)
			(xy 203.213701 -284.605176) (xy 203.249953 -284.644247) (xy 203.279977 -284.688284) (xy 203.303103 -284.736305)
			(xy 203.318813 -284.787235) (xy 203.326756 -284.839939) (xy 203.327254 -284.866588) (xy 203.326756 -284.893237)
			(xy 203.318813 -284.945941) (xy 203.303103 -284.996871) (xy 203.279977 -285.044892) (xy 203.249953 -285.088929)
			(xy 203.213701 -285.128) (xy 203.17203 -285.161231) (xy 203.125872 -285.18788) (xy 203.076258 -285.207352)
			(xy 203.024296 -285.219212) (xy 202.971146 -285.223196) (xy 202.917996 -285.219212) (xy 202.866034 -285.207352)
			(xy 202.81642 -285.18788) (xy 202.770262 -285.161231) (xy 202.728591 -285.128) (xy 202.692339 -285.088929)
			(xy 202.662315 -285.044892) (xy 202.639189 -284.996871) (xy 202.623479 -284.945941) (xy 202.615536 -284.893237)
			(xy 188.239156 -284.893237) (xy 188.231213 -284.945941) (xy 188.215503 -284.996871) (xy 188.192377 -285.044892)
			(xy 188.162353 -285.088929) (xy 188.126101 -285.128) (xy 188.08443 -285.161231) (xy 188.038272 -285.18788)
			(xy 187.988658 -285.207352) (xy 187.936696 -285.219212) (xy 187.883546 -285.223196) (xy 187.830396 -285.219212)
			(xy 187.778434 -285.207352) (xy 187.72882 -285.18788) (xy 187.682662 -285.161231) (xy 187.640991 -285.128)
			(xy 187.604739 -285.088929) (xy 187.574715 -285.044892) (xy 187.551589 -284.996871) (xy 187.535879 -284.945941)
			(xy 187.527936 -284.893237) (xy 173.151556 -284.893237) (xy 173.143613 -284.945941) (xy 173.127903 -284.996871)
			(xy 173.104777 -285.044892) (xy 173.074753 -285.088929) (xy 173.038501 -285.128) (xy 172.99683 -285.161231)
			(xy 172.950672 -285.18788) (xy 172.901058 -285.207352) (xy 172.849096 -285.219212) (xy 172.795946 -285.223196)
			(xy 172.742796 -285.219212) (xy 172.690834 -285.207352) (xy 172.64122 -285.18788) (xy 172.595062 -285.161231)
			(xy 172.553391 -285.128) (xy 172.517139 -285.088929) (xy 172.487115 -285.044892) (xy 172.463989 -284.996871)
			(xy 172.448279 -284.945941) (xy 172.440336 -284.893237) (xy 159.11576 -284.893237) (xy 159.11576 -285.743375)
			(xy 176.540404 -285.743375) (xy 176.540404 -285.690077) (xy 176.548347 -285.637373) (xy 176.564057 -285.586443)
			(xy 176.587183 -285.538422) (xy 176.617207 -285.494385) (xy 176.653459 -285.455314) (xy 176.69513 -285.422083)
			(xy 176.741288 -285.395434) (xy 176.790902 -285.375962) (xy 176.842864 -285.364102) (xy 176.896014 -285.360119)
			(xy 176.949164 -285.364102) (xy 177.001126 -285.375962) (xy 177.05074 -285.395434) (xy 177.096898 -285.422083)
			(xy 177.138569 -285.455314) (xy 177.174821 -285.494385) (xy 177.204845 -285.538422) (xy 177.227971 -285.586443)
			(xy 177.243681 -285.637373) (xy 177.251624 -285.690077) (xy 177.252122 -285.716726) (xy 177.251624 -285.743375)
			(xy 191.628004 -285.743375) (xy 191.628004 -285.690077) (xy 191.635947 -285.637373) (xy 191.651657 -285.586443)
			(xy 191.674783 -285.538422) (xy 191.704807 -285.494385) (xy 191.741059 -285.455314) (xy 191.78273 -285.422083)
			(xy 191.828888 -285.395434) (xy 191.878502 -285.375962) (xy 191.930464 -285.364102) (xy 191.983614 -285.360119)
			(xy 192.036764 -285.364102) (xy 192.088726 -285.375962) (xy 192.13834 -285.395434) (xy 192.184498 -285.422083)
			(xy 192.226169 -285.455314) (xy 192.262421 -285.494385) (xy 192.292445 -285.538422) (xy 192.315571 -285.586443)
			(xy 192.331281 -285.637373) (xy 192.339224 -285.690077) (xy 192.339722 -285.716726) (xy 192.339224 -285.743375)
			(xy 206.715604 -285.743375) (xy 206.715604 -285.690077) (xy 206.723547 -285.637373) (xy 206.739257 -285.586443)
			(xy 206.762383 -285.538422) (xy 206.792407 -285.494385) (xy 206.828659 -285.455314) (xy 206.87033 -285.422083)
			(xy 206.916488 -285.395434) (xy 206.966102 -285.375962) (xy 207.018064 -285.364102) (xy 207.071214 -285.360119)
			(xy 207.124364 -285.364102) (xy 207.176326 -285.375962) (xy 207.22594 -285.395434) (xy 207.272098 -285.422083)
			(xy 207.313769 -285.455314) (xy 207.350021 -285.494385) (xy 207.380045 -285.538422) (xy 207.403171 -285.586443)
			(xy 207.418881 -285.637373) (xy 207.426824 -285.690077) (xy 207.427322 -285.716726) (xy 207.426824 -285.743375)
			(xy 207.418881 -285.796079) (xy 207.403171 -285.847009) (xy 207.380045 -285.89503) (xy 207.350021 -285.939067)
			(xy 207.313769 -285.978138) (xy 207.272098 -286.011369) (xy 207.22594 -286.038018) (xy 207.176326 -286.05749)
			(xy 207.124364 -286.06935) (xy 207.071214 -286.073334) (xy 207.018064 -286.06935) (xy 206.966102 -286.05749)
			(xy 206.916488 -286.038018) (xy 206.87033 -286.011369) (xy 206.828659 -285.978138) (xy 206.792407 -285.939067)
			(xy 206.762383 -285.89503) (xy 206.739257 -285.847009) (xy 206.723547 -285.796079) (xy 206.715604 -285.743375)
			(xy 192.339224 -285.743375) (xy 192.331281 -285.796079) (xy 192.315571 -285.847009) (xy 192.292445 -285.89503)
			(xy 192.262421 -285.939067) (xy 192.226169 -285.978138) (xy 192.184498 -286.011369) (xy 192.13834 -286.038018)
			(xy 192.088726 -286.05749) (xy 192.036764 -286.06935) (xy 191.983614 -286.073334) (xy 191.930464 -286.06935)
			(xy 191.878502 -286.05749) (xy 191.828888 -286.038018) (xy 191.78273 -286.011369) (xy 191.741059 -285.978138)
			(xy 191.704807 -285.939067) (xy 191.674783 -285.89503) (xy 191.651657 -285.847009) (xy 191.635947 -285.796079)
			(xy 191.628004 -285.743375) (xy 177.251624 -285.743375) (xy 177.243681 -285.796079) (xy 177.227971 -285.847009)
			(xy 177.204845 -285.89503) (xy 177.174821 -285.939067) (xy 177.138569 -285.978138) (xy 177.096898 -286.011369)
			(xy 177.05074 -286.038018) (xy 177.001126 -286.05749) (xy 176.949164 -286.06935) (xy 176.896014 -286.073334)
			(xy 176.842864 -286.06935) (xy 176.790902 -286.05749) (xy 176.741288 -286.038018) (xy 176.69513 -286.011369)
			(xy 176.653459 -285.978138) (xy 176.617207 -285.939067) (xy 176.587183 -285.89503) (xy 176.564057 -285.847009)
			(xy 176.548347 -285.796079) (xy 176.540404 -285.743375) (xy 159.11576 -285.743375) (xy 159.11576 -286.593259)
			(xy 172.440336 -286.593259) (xy 172.440336 -286.539961) (xy 172.448279 -286.487257) (xy 172.463989 -286.436327)
			(xy 172.487115 -286.388306) (xy 172.517139 -286.344269) (xy 172.553391 -286.305198) (xy 172.595062 -286.271967)
			(xy 172.64122 -286.245318) (xy 172.690834 -286.225846) (xy 172.742796 -286.213986) (xy 172.795946 -286.210003)
			(xy 172.849096 -286.213986) (xy 172.901058 -286.225846) (xy 172.950672 -286.245318) (xy 172.99683 -286.271967)
			(xy 173.038501 -286.305198) (xy 173.074753 -286.344269) (xy 173.104777 -286.388306) (xy 173.127903 -286.436327)
			(xy 173.143613 -286.487257) (xy 173.151556 -286.539961) (xy 173.152054 -286.56661) (xy 173.151556 -286.593259)
			(xy 187.527936 -286.593259) (xy 187.527936 -286.539961) (xy 187.535879 -286.487257) (xy 187.551589 -286.436327)
			(xy 187.574715 -286.388306) (xy 187.604739 -286.344269) (xy 187.640991 -286.305198) (xy 187.682662 -286.271967)
			(xy 187.72882 -286.245318) (xy 187.778434 -286.225846) (xy 187.830396 -286.213986) (xy 187.883546 -286.210003)
			(xy 187.936696 -286.213986) (xy 187.988658 -286.225846) (xy 188.038272 -286.245318) (xy 188.08443 -286.271967)
			(xy 188.126101 -286.305198) (xy 188.162353 -286.344269) (xy 188.192377 -286.388306) (xy 188.215503 -286.436327)
			(xy 188.231213 -286.487257) (xy 188.239156 -286.539961) (xy 188.239654 -286.56661) (xy 188.239156 -286.593259)
			(xy 202.615536 -286.593259) (xy 202.615536 -286.539961) (xy 202.623479 -286.487257) (xy 202.639189 -286.436327)
			(xy 202.662315 -286.388306) (xy 202.692339 -286.344269) (xy 202.728591 -286.305198) (xy 202.770262 -286.271967)
			(xy 202.81642 -286.245318) (xy 202.866034 -286.225846) (xy 202.917996 -286.213986) (xy 202.971146 -286.210003)
			(xy 203.024296 -286.213986) (xy 203.076258 -286.225846) (xy 203.125872 -286.245318) (xy 203.17203 -286.271967)
			(xy 203.213701 -286.305198) (xy 203.249953 -286.344269) (xy 203.279977 -286.388306) (xy 203.303103 -286.436327)
			(xy 203.318813 -286.487257) (xy 203.326756 -286.539961) (xy 203.327254 -286.56661) (xy 203.326756 -286.593259)
			(xy 203.318813 -286.645963) (xy 203.303103 -286.696893) (xy 203.279977 -286.744914) (xy 203.249953 -286.788951)
			(xy 203.213701 -286.828022) (xy 203.17203 -286.861253) (xy 203.125872 -286.887902) (xy 203.076258 -286.907374)
			(xy 203.024296 -286.919234) (xy 202.971146 -286.923218) (xy 202.917996 -286.919234) (xy 202.866034 -286.907374)
			(xy 202.81642 -286.887902) (xy 202.770262 -286.861253) (xy 202.728591 -286.828022) (xy 202.692339 -286.788951)
			(xy 202.662315 -286.744914) (xy 202.639189 -286.696893) (xy 202.623479 -286.645963) (xy 202.615536 -286.593259)
			(xy 188.239156 -286.593259) (xy 188.231213 -286.645963) (xy 188.215503 -286.696893) (xy 188.192377 -286.744914)
			(xy 188.162353 -286.788951) (xy 188.126101 -286.828022) (xy 188.08443 -286.861253) (xy 188.038272 -286.887902)
			(xy 187.988658 -286.907374) (xy 187.936696 -286.919234) (xy 187.883546 -286.923218) (xy 187.830396 -286.919234)
			(xy 187.778434 -286.907374) (xy 187.72882 -286.887902) (xy 187.682662 -286.861253) (xy 187.640991 -286.828022)
			(xy 187.604739 -286.788951) (xy 187.574715 -286.744914) (xy 187.551589 -286.696893) (xy 187.535879 -286.645963)
			(xy 187.527936 -286.593259) (xy 173.151556 -286.593259) (xy 173.143613 -286.645963) (xy 173.127903 -286.696893)
			(xy 173.104777 -286.744914) (xy 173.074753 -286.788951) (xy 173.038501 -286.828022) (xy 172.99683 -286.861253)
			(xy 172.950672 -286.887902) (xy 172.901058 -286.907374) (xy 172.849096 -286.919234) (xy 172.795946 -286.923218)
			(xy 172.742796 -286.919234) (xy 172.690834 -286.907374) (xy 172.64122 -286.887902) (xy 172.595062 -286.861253)
			(xy 172.553391 -286.828022) (xy 172.517139 -286.788951) (xy 172.487115 -286.744914) (xy 172.463989 -286.696893)
			(xy 172.448279 -286.645963) (xy 172.440336 -286.593259) (xy 159.11576 -286.593259) (xy 159.11576 -287.443397)
			(xy 176.540404 -287.443397) (xy 176.540404 -287.390099) (xy 176.548347 -287.337395) (xy 176.564057 -287.286465)
			(xy 176.587183 -287.238444) (xy 176.617207 -287.194407) (xy 176.653459 -287.155336) (xy 176.69513 -287.122105)
			(xy 176.741288 -287.095456) (xy 176.790902 -287.075984) (xy 176.842864 -287.064124) (xy 176.896014 -287.060141)
			(xy 176.949164 -287.064124) (xy 177.001126 -287.075984) (xy 177.05074 -287.095456) (xy 177.096898 -287.122105)
			(xy 177.138569 -287.155336) (xy 177.174821 -287.194407) (xy 177.204845 -287.238444) (xy 177.227971 -287.286465)
			(xy 177.243681 -287.337395) (xy 177.251624 -287.390099) (xy 177.252122 -287.416748) (xy 177.251624 -287.443397)
			(xy 191.628004 -287.443397) (xy 191.628004 -287.390099) (xy 191.635947 -287.337395) (xy 191.651657 -287.286465)
			(xy 191.674783 -287.238444) (xy 191.704807 -287.194407) (xy 191.741059 -287.155336) (xy 191.78273 -287.122105)
			(xy 191.828888 -287.095456) (xy 191.878502 -287.075984) (xy 191.930464 -287.064124) (xy 191.983614 -287.060141)
			(xy 192.036764 -287.064124) (xy 192.088726 -287.075984) (xy 192.13834 -287.095456) (xy 192.184498 -287.122105)
			(xy 192.226169 -287.155336) (xy 192.262421 -287.194407) (xy 192.292445 -287.238444) (xy 192.315571 -287.286465)
			(xy 192.331281 -287.337395) (xy 192.339224 -287.390099) (xy 192.339722 -287.416748) (xy 192.339224 -287.443397)
			(xy 206.715604 -287.443397) (xy 206.715604 -287.390099) (xy 206.723547 -287.337395) (xy 206.739257 -287.286465)
			(xy 206.762383 -287.238444) (xy 206.792407 -287.194407) (xy 206.828659 -287.155336) (xy 206.87033 -287.122105)
			(xy 206.916488 -287.095456) (xy 206.966102 -287.075984) (xy 207.018064 -287.064124) (xy 207.071214 -287.060141)
			(xy 207.124364 -287.064124) (xy 207.176326 -287.075984) (xy 207.22594 -287.095456) (xy 207.272098 -287.122105)
			(xy 207.313769 -287.155336) (xy 207.350021 -287.194407) (xy 207.380045 -287.238444) (xy 207.403171 -287.286465)
			(xy 207.418881 -287.337395) (xy 207.426824 -287.390099) (xy 207.427322 -287.416748) (xy 207.426824 -287.443397)
			(xy 207.418881 -287.496101) (xy 207.403171 -287.547031) (xy 207.380045 -287.595052) (xy 207.350021 -287.639089)
			(xy 207.313769 -287.67816) (xy 207.272098 -287.711391) (xy 207.22594 -287.73804) (xy 207.176326 -287.757512)
			(xy 207.124364 -287.769372) (xy 207.071214 -287.773356) (xy 207.018064 -287.769372) (xy 206.966102 -287.757512)
			(xy 206.916488 -287.73804) (xy 206.87033 -287.711391) (xy 206.828659 -287.67816) (xy 206.792407 -287.639089)
			(xy 206.762383 -287.595052) (xy 206.739257 -287.547031) (xy 206.723547 -287.496101) (xy 206.715604 -287.443397)
			(xy 192.339224 -287.443397) (xy 192.331281 -287.496101) (xy 192.315571 -287.547031) (xy 192.292445 -287.595052)
			(xy 192.262421 -287.639089) (xy 192.226169 -287.67816) (xy 192.184498 -287.711391) (xy 192.13834 -287.73804)
			(xy 192.088726 -287.757512) (xy 192.036764 -287.769372) (xy 191.983614 -287.773356) (xy 191.930464 -287.769372)
			(xy 191.878502 -287.757512) (xy 191.828888 -287.73804) (xy 191.78273 -287.711391) (xy 191.741059 -287.67816)
			(xy 191.704807 -287.639089) (xy 191.674783 -287.595052) (xy 191.651657 -287.547031) (xy 191.635947 -287.496101)
			(xy 191.628004 -287.443397) (xy 177.251624 -287.443397) (xy 177.243681 -287.496101) (xy 177.227971 -287.547031)
			(xy 177.204845 -287.595052) (xy 177.174821 -287.639089) (xy 177.138569 -287.67816) (xy 177.096898 -287.711391)
			(xy 177.05074 -287.73804) (xy 177.001126 -287.757512) (xy 176.949164 -287.769372) (xy 176.896014 -287.773356)
			(xy 176.842864 -287.769372) (xy 176.790902 -287.757512) (xy 176.741288 -287.73804) (xy 176.69513 -287.711391)
			(xy 176.653459 -287.67816) (xy 176.617207 -287.639089) (xy 176.587183 -287.595052) (xy 176.564057 -287.547031)
			(xy 176.548347 -287.496101) (xy 176.540404 -287.443397) (xy 159.11576 -287.443397) (xy 159.11576 -288.293281)
			(xy 172.440336 -288.293281) (xy 172.440336 -288.239983) (xy 172.448279 -288.187279) (xy 172.463989 -288.136349)
			(xy 172.487115 -288.088328) (xy 172.517139 -288.044291) (xy 172.553391 -288.00522) (xy 172.595062 -287.971989)
			(xy 172.64122 -287.94534) (xy 172.690834 -287.925868) (xy 172.742796 -287.914008) (xy 172.795946 -287.910025)
			(xy 172.849096 -287.914008) (xy 172.901058 -287.925868) (xy 172.950672 -287.94534) (xy 172.99683 -287.971989)
			(xy 173.038501 -288.00522) (xy 173.074753 -288.044291) (xy 173.104777 -288.088328) (xy 173.127903 -288.136349)
			(xy 173.143613 -288.187279) (xy 173.151556 -288.239983) (xy 173.152054 -288.266632) (xy 173.151556 -288.293281)
			(xy 187.527936 -288.293281) (xy 187.527936 -288.239983) (xy 187.535879 -288.187279) (xy 187.551589 -288.136349)
			(xy 187.574715 -288.088328) (xy 187.604739 -288.044291) (xy 187.640991 -288.00522) (xy 187.682662 -287.971989)
			(xy 187.72882 -287.94534) (xy 187.778434 -287.925868) (xy 187.830396 -287.914008) (xy 187.883546 -287.910025)
			(xy 187.936696 -287.914008) (xy 187.988658 -287.925868) (xy 188.038272 -287.94534) (xy 188.08443 -287.971989)
			(xy 188.126101 -288.00522) (xy 188.162353 -288.044291) (xy 188.192377 -288.088328) (xy 188.215503 -288.136349)
			(xy 188.231213 -288.187279) (xy 188.239156 -288.239983) (xy 188.239654 -288.266632) (xy 188.239156 -288.293281)
			(xy 202.615536 -288.293281) (xy 202.615536 -288.239983) (xy 202.623479 -288.187279) (xy 202.639189 -288.136349)
			(xy 202.662315 -288.088328) (xy 202.692339 -288.044291) (xy 202.728591 -288.00522) (xy 202.770262 -287.971989)
			(xy 202.81642 -287.94534) (xy 202.866034 -287.925868) (xy 202.917996 -287.914008) (xy 202.971146 -287.910025)
			(xy 203.024296 -287.914008) (xy 203.076258 -287.925868) (xy 203.125872 -287.94534) (xy 203.17203 -287.971989)
			(xy 203.213701 -288.00522) (xy 203.249953 -288.044291) (xy 203.279977 -288.088328) (xy 203.303103 -288.136349)
			(xy 203.318813 -288.187279) (xy 203.326756 -288.239983) (xy 203.327254 -288.266632) (xy 203.326756 -288.293281)
			(xy 203.318813 -288.345985) (xy 203.303103 -288.396915) (xy 203.279977 -288.444936) (xy 203.249953 -288.488973)
			(xy 203.213701 -288.528044) (xy 203.17203 -288.561275) (xy 203.125872 -288.587924) (xy 203.076258 -288.607396)
			(xy 203.024296 -288.619256) (xy 202.971146 -288.62324) (xy 202.917996 -288.619256) (xy 202.866034 -288.607396)
			(xy 202.81642 -288.587924) (xy 202.770262 -288.561275) (xy 202.728591 -288.528044) (xy 202.692339 -288.488973)
			(xy 202.662315 -288.444936) (xy 202.639189 -288.396915) (xy 202.623479 -288.345985) (xy 202.615536 -288.293281)
			(xy 188.239156 -288.293281) (xy 188.231213 -288.345985) (xy 188.215503 -288.396915) (xy 188.192377 -288.444936)
			(xy 188.162353 -288.488973) (xy 188.126101 -288.528044) (xy 188.08443 -288.561275) (xy 188.038272 -288.587924)
			(xy 187.988658 -288.607396) (xy 187.936696 -288.619256) (xy 187.883546 -288.62324) (xy 187.830396 -288.619256)
			(xy 187.778434 -288.607396) (xy 187.72882 -288.587924) (xy 187.682662 -288.561275) (xy 187.640991 -288.528044)
			(xy 187.604739 -288.488973) (xy 187.574715 -288.444936) (xy 187.551589 -288.396915) (xy 187.535879 -288.345985)
			(xy 187.527936 -288.293281) (xy 173.151556 -288.293281) (xy 173.143613 -288.345985) (xy 173.127903 -288.396915)
			(xy 173.104777 -288.444936) (xy 173.074753 -288.488973) (xy 173.038501 -288.528044) (xy 172.99683 -288.561275)
			(xy 172.950672 -288.587924) (xy 172.901058 -288.607396) (xy 172.849096 -288.619256) (xy 172.795946 -288.62324)
			(xy 172.742796 -288.619256) (xy 172.690834 -288.607396) (xy 172.64122 -288.587924) (xy 172.595062 -288.561275)
			(xy 172.553391 -288.528044) (xy 172.517139 -288.488973) (xy 172.487115 -288.444936) (xy 172.463989 -288.396915)
			(xy 172.448279 -288.345985) (xy 172.440336 -288.293281) (xy 159.11576 -288.293281) (xy 159.11576 -289.143419)
			(xy 176.540404 -289.143419) (xy 176.540404 -289.090121) (xy 176.548347 -289.037417) (xy 176.564057 -288.986487)
			(xy 176.587183 -288.938466) (xy 176.617207 -288.894429) (xy 176.653459 -288.855358) (xy 176.69513 -288.822127)
			(xy 176.741288 -288.795478) (xy 176.790902 -288.776006) (xy 176.842864 -288.764146) (xy 176.896014 -288.760163)
			(xy 176.949164 -288.764146) (xy 177.001126 -288.776006) (xy 177.05074 -288.795478) (xy 177.096898 -288.822127)
			(xy 177.138569 -288.855358) (xy 177.174821 -288.894429) (xy 177.204845 -288.938466) (xy 177.227971 -288.986487)
			(xy 177.243681 -289.037417) (xy 177.251624 -289.090121) (xy 177.252122 -289.11677) (xy 177.251624 -289.143419)
			(xy 191.628004 -289.143419) (xy 191.628004 -289.090121) (xy 191.635947 -289.037417) (xy 191.651657 -288.986487)
			(xy 191.674783 -288.938466) (xy 191.704807 -288.894429) (xy 191.741059 -288.855358) (xy 191.78273 -288.822127)
			(xy 191.828888 -288.795478) (xy 191.878502 -288.776006) (xy 191.930464 -288.764146) (xy 191.983614 -288.760163)
			(xy 192.036764 -288.764146) (xy 192.088726 -288.776006) (xy 192.13834 -288.795478) (xy 192.184498 -288.822127)
			(xy 192.226169 -288.855358) (xy 192.262421 -288.894429) (xy 192.292445 -288.938466) (xy 192.315571 -288.986487)
			(xy 192.331281 -289.037417) (xy 192.339224 -289.090121) (xy 192.339722 -289.11677) (xy 192.339224 -289.143419)
			(xy 206.715604 -289.143419) (xy 206.715604 -289.090121) (xy 206.723547 -289.037417) (xy 206.739257 -288.986487)
			(xy 206.762383 -288.938466) (xy 206.792407 -288.894429) (xy 206.828659 -288.855358) (xy 206.87033 -288.822127)
			(xy 206.916488 -288.795478) (xy 206.966102 -288.776006) (xy 207.018064 -288.764146) (xy 207.071214 -288.760163)
			(xy 207.124364 -288.764146) (xy 207.176326 -288.776006) (xy 207.22594 -288.795478) (xy 207.272098 -288.822127)
			(xy 207.313769 -288.855358) (xy 207.350021 -288.894429) (xy 207.380045 -288.938466) (xy 207.403171 -288.986487)
			(xy 207.418881 -289.037417) (xy 207.426824 -289.090121) (xy 207.427322 -289.11677) (xy 207.426824 -289.143419)
			(xy 207.418881 -289.196123) (xy 207.403171 -289.247053) (xy 207.380045 -289.295074) (xy 207.350021 -289.339111)
			(xy 207.313769 -289.378182) (xy 207.272098 -289.411413) (xy 207.22594 -289.438062) (xy 207.176326 -289.457534)
			(xy 207.124364 -289.469394) (xy 207.071214 -289.473378) (xy 207.018064 -289.469394) (xy 206.966102 -289.457534)
			(xy 206.916488 -289.438062) (xy 206.87033 -289.411413) (xy 206.828659 -289.378182) (xy 206.792407 -289.339111)
			(xy 206.762383 -289.295074) (xy 206.739257 -289.247053) (xy 206.723547 -289.196123) (xy 206.715604 -289.143419)
			(xy 192.339224 -289.143419) (xy 192.331281 -289.196123) (xy 192.315571 -289.247053) (xy 192.292445 -289.295074)
			(xy 192.262421 -289.339111) (xy 192.226169 -289.378182) (xy 192.184498 -289.411413) (xy 192.13834 -289.438062)
			(xy 192.088726 -289.457534) (xy 192.036764 -289.469394) (xy 191.983614 -289.473378) (xy 191.930464 -289.469394)
			(xy 191.878502 -289.457534) (xy 191.828888 -289.438062) (xy 191.78273 -289.411413) (xy 191.741059 -289.378182)
			(xy 191.704807 -289.339111) (xy 191.674783 -289.295074) (xy 191.651657 -289.247053) (xy 191.635947 -289.196123)
			(xy 191.628004 -289.143419) (xy 177.251624 -289.143419) (xy 177.243681 -289.196123) (xy 177.227971 -289.247053)
			(xy 177.204845 -289.295074) (xy 177.174821 -289.339111) (xy 177.138569 -289.378182) (xy 177.096898 -289.411413)
			(xy 177.05074 -289.438062) (xy 177.001126 -289.457534) (xy 176.949164 -289.469394) (xy 176.896014 -289.473378)
			(xy 176.842864 -289.469394) (xy 176.790902 -289.457534) (xy 176.741288 -289.438062) (xy 176.69513 -289.411413)
			(xy 176.653459 -289.378182) (xy 176.617207 -289.339111) (xy 176.587183 -289.295074) (xy 176.564057 -289.247053)
			(xy 176.548347 -289.196123) (xy 176.540404 -289.143419) (xy 159.11576 -289.143419) (xy 159.11576 -289.993303)
			(xy 172.440336 -289.993303) (xy 172.440336 -289.940005) (xy 172.448279 -289.887301) (xy 172.463989 -289.836371)
			(xy 172.487115 -289.78835) (xy 172.517139 -289.744313) (xy 172.553391 -289.705242) (xy 172.595062 -289.672011)
			(xy 172.64122 -289.645362) (xy 172.690834 -289.62589) (xy 172.742796 -289.61403) (xy 172.795946 -289.610047)
			(xy 172.849096 -289.61403) (xy 172.901058 -289.62589) (xy 172.950672 -289.645362) (xy 172.99683 -289.672011)
			(xy 173.038501 -289.705242) (xy 173.074753 -289.744313) (xy 173.104777 -289.78835) (xy 173.127903 -289.836371)
			(xy 173.143613 -289.887301) (xy 173.151556 -289.940005) (xy 173.152054 -289.966654) (xy 173.151556 -289.993303)
			(xy 187.527936 -289.993303) (xy 187.527936 -289.940005) (xy 187.535879 -289.887301) (xy 187.551589 -289.836371)
			(xy 187.574715 -289.78835) (xy 187.604739 -289.744313) (xy 187.640991 -289.705242) (xy 187.682662 -289.672011)
			(xy 187.72882 -289.645362) (xy 187.778434 -289.62589) (xy 187.830396 -289.61403) (xy 187.883546 -289.610047)
			(xy 187.936696 -289.61403) (xy 187.988658 -289.62589) (xy 188.038272 -289.645362) (xy 188.08443 -289.672011)
			(xy 188.126101 -289.705242) (xy 188.162353 -289.744313) (xy 188.192377 -289.78835) (xy 188.215503 -289.836371)
			(xy 188.231213 -289.887301) (xy 188.239156 -289.940005) (xy 188.239654 -289.966654) (xy 188.239156 -289.993303)
			(xy 202.615536 -289.993303) (xy 202.615536 -289.940005) (xy 202.623479 -289.887301) (xy 202.639189 -289.836371)
			(xy 202.662315 -289.78835) (xy 202.692339 -289.744313) (xy 202.728591 -289.705242) (xy 202.770262 -289.672011)
			(xy 202.81642 -289.645362) (xy 202.866034 -289.62589) (xy 202.917996 -289.61403) (xy 202.971146 -289.610047)
			(xy 203.024296 -289.61403) (xy 203.076258 -289.62589) (xy 203.125872 -289.645362) (xy 203.17203 -289.672011)
			(xy 203.213701 -289.705242) (xy 203.249953 -289.744313) (xy 203.279977 -289.78835) (xy 203.303103 -289.836371)
			(xy 203.318813 -289.887301) (xy 203.326756 -289.940005) (xy 203.327254 -289.966654) (xy 203.326756 -289.993303)
			(xy 203.318813 -290.046007) (xy 203.303103 -290.096937) (xy 203.279977 -290.144958) (xy 203.249953 -290.188995)
			(xy 203.213701 -290.228066) (xy 203.17203 -290.261297) (xy 203.125872 -290.287946) (xy 203.076258 -290.307418)
			(xy 203.024296 -290.319278) (xy 202.971146 -290.323262) (xy 202.917996 -290.319278) (xy 202.866034 -290.307418)
			(xy 202.81642 -290.287946) (xy 202.770262 -290.261297) (xy 202.728591 -290.228066) (xy 202.692339 -290.188995)
			(xy 202.662315 -290.144958) (xy 202.639189 -290.096937) (xy 202.623479 -290.046007) (xy 202.615536 -289.993303)
			(xy 188.239156 -289.993303) (xy 188.231213 -290.046007) (xy 188.215503 -290.096937) (xy 188.192377 -290.144958)
			(xy 188.162353 -290.188995) (xy 188.126101 -290.228066) (xy 188.08443 -290.261297) (xy 188.038272 -290.287946)
			(xy 187.988658 -290.307418) (xy 187.936696 -290.319278) (xy 187.883546 -290.323262) (xy 187.830396 -290.319278)
			(xy 187.778434 -290.307418) (xy 187.72882 -290.287946) (xy 187.682662 -290.261297) (xy 187.640991 -290.228066)
			(xy 187.604739 -290.188995) (xy 187.574715 -290.144958) (xy 187.551589 -290.096937) (xy 187.535879 -290.046007)
			(xy 187.527936 -289.993303) (xy 173.151556 -289.993303) (xy 173.143613 -290.046007) (xy 173.127903 -290.096937)
			(xy 173.104777 -290.144958) (xy 173.074753 -290.188995) (xy 173.038501 -290.228066) (xy 172.99683 -290.261297)
			(xy 172.950672 -290.287946) (xy 172.901058 -290.307418) (xy 172.849096 -290.319278) (xy 172.795946 -290.323262)
			(xy 172.742796 -290.319278) (xy 172.690834 -290.307418) (xy 172.64122 -290.287946) (xy 172.595062 -290.261297)
			(xy 172.553391 -290.228066) (xy 172.517139 -290.188995) (xy 172.487115 -290.144958) (xy 172.463989 -290.096937)
			(xy 172.448279 -290.046007) (xy 172.440336 -289.993303) (xy 159.11576 -289.993303) (xy 159.11576 -290.843187)
			(xy 176.540404 -290.843187) (xy 176.540404 -290.789889) (xy 176.548347 -290.737185) (xy 176.564057 -290.686255)
			(xy 176.587183 -290.638234) (xy 176.617207 -290.594197) (xy 176.653459 -290.555126) (xy 176.69513 -290.521895)
			(xy 176.741288 -290.495246) (xy 176.790902 -290.475774) (xy 176.842864 -290.463914) (xy 176.896014 -290.459931)
			(xy 176.949164 -290.463914) (xy 177.001126 -290.475774) (xy 177.05074 -290.495246) (xy 177.096898 -290.521895)
			(xy 177.138569 -290.555126) (xy 177.174821 -290.594197) (xy 177.204845 -290.638234) (xy 177.227971 -290.686255)
			(xy 177.243681 -290.737185) (xy 177.251624 -290.789889) (xy 177.252122 -290.816538) (xy 177.251624 -290.843187)
			(xy 191.628004 -290.843187) (xy 191.628004 -290.789889) (xy 191.635947 -290.737185) (xy 191.651657 -290.686255)
			(xy 191.674783 -290.638234) (xy 191.704807 -290.594197) (xy 191.741059 -290.555126) (xy 191.78273 -290.521895)
			(xy 191.828888 -290.495246) (xy 191.878502 -290.475774) (xy 191.930464 -290.463914) (xy 191.983614 -290.459931)
			(xy 192.036764 -290.463914) (xy 192.088726 -290.475774) (xy 192.13834 -290.495246) (xy 192.184498 -290.521895)
			(xy 192.226169 -290.555126) (xy 192.262421 -290.594197) (xy 192.292445 -290.638234) (xy 192.315571 -290.686255)
			(xy 192.331281 -290.737185) (xy 192.339224 -290.789889) (xy 192.339722 -290.816538) (xy 192.339224 -290.843187)
			(xy 206.715604 -290.843187) (xy 206.715604 -290.789889) (xy 206.723547 -290.737185) (xy 206.739257 -290.686255)
			(xy 206.762383 -290.638234) (xy 206.792407 -290.594197) (xy 206.828659 -290.555126) (xy 206.87033 -290.521895)
			(xy 206.916488 -290.495246) (xy 206.966102 -290.475774) (xy 207.018064 -290.463914) (xy 207.071214 -290.459931)
			(xy 207.124364 -290.463914) (xy 207.176326 -290.475774) (xy 207.22594 -290.495246) (xy 207.272098 -290.521895)
			(xy 207.313769 -290.555126) (xy 207.350021 -290.594197) (xy 207.380045 -290.638234) (xy 207.403171 -290.686255)
			(xy 207.418881 -290.737185) (xy 207.426824 -290.789889) (xy 207.427322 -290.816538) (xy 207.426824 -290.843187)
			(xy 207.418881 -290.895891) (xy 207.403171 -290.946821) (xy 207.380045 -290.994842) (xy 207.350021 -291.038879)
			(xy 207.313769 -291.07795) (xy 207.272098 -291.111181) (xy 207.22594 -291.13783) (xy 207.176326 -291.157302)
			(xy 207.124364 -291.169162) (xy 207.071214 -291.173146) (xy 207.018064 -291.169162) (xy 206.966102 -291.157302)
			(xy 206.916488 -291.13783) (xy 206.87033 -291.111181) (xy 206.828659 -291.07795) (xy 206.792407 -291.038879)
			(xy 206.762383 -290.994842) (xy 206.739257 -290.946821) (xy 206.723547 -290.895891) (xy 206.715604 -290.843187)
			(xy 192.339224 -290.843187) (xy 192.331281 -290.895891) (xy 192.315571 -290.946821) (xy 192.292445 -290.994842)
			(xy 192.262421 -291.038879) (xy 192.226169 -291.07795) (xy 192.184498 -291.111181) (xy 192.13834 -291.13783)
			(xy 192.088726 -291.157302) (xy 192.036764 -291.169162) (xy 191.983614 -291.173146) (xy 191.930464 -291.169162)
			(xy 191.878502 -291.157302) (xy 191.828888 -291.13783) (xy 191.78273 -291.111181) (xy 191.741059 -291.07795)
			(xy 191.704807 -291.038879) (xy 191.674783 -290.994842) (xy 191.651657 -290.946821) (xy 191.635947 -290.895891)
			(xy 191.628004 -290.843187) (xy 177.251624 -290.843187) (xy 177.243681 -290.895891) (xy 177.227971 -290.946821)
			(xy 177.204845 -290.994842) (xy 177.174821 -291.038879) (xy 177.138569 -291.07795) (xy 177.096898 -291.111181)
			(xy 177.05074 -291.13783) (xy 177.001126 -291.157302) (xy 176.949164 -291.169162) (xy 176.896014 -291.173146)
			(xy 176.842864 -291.169162) (xy 176.790902 -291.157302) (xy 176.741288 -291.13783) (xy 176.69513 -291.111181)
			(xy 176.653459 -291.07795) (xy 176.617207 -291.038879) (xy 176.587183 -290.994842) (xy 176.564057 -290.946821)
			(xy 176.548347 -290.895891) (xy 176.540404 -290.843187) (xy 159.11576 -290.843187) (xy 159.11576 -291.693325)
			(xy 172.440336 -291.693325) (xy 172.440336 -291.640027) (xy 172.448279 -291.587323) (xy 172.463989 -291.536393)
			(xy 172.487115 -291.488372) (xy 172.517139 -291.444335) (xy 172.553391 -291.405264) (xy 172.595062 -291.372033)
			(xy 172.64122 -291.345384) (xy 172.690834 -291.325912) (xy 172.742796 -291.314052) (xy 172.795946 -291.310069)
			(xy 172.849096 -291.314052) (xy 172.901058 -291.325912) (xy 172.950672 -291.345384) (xy 172.99683 -291.372033)
			(xy 173.038501 -291.405264) (xy 173.074753 -291.444335) (xy 173.104777 -291.488372) (xy 173.127903 -291.536393)
			(xy 173.143613 -291.587323) (xy 173.151556 -291.640027) (xy 173.152054 -291.666676) (xy 173.151556 -291.693325)
			(xy 187.527936 -291.693325) (xy 187.527936 -291.640027) (xy 187.535879 -291.587323) (xy 187.551589 -291.536393)
			(xy 187.574715 -291.488372) (xy 187.604739 -291.444335) (xy 187.640991 -291.405264) (xy 187.682662 -291.372033)
			(xy 187.72882 -291.345384) (xy 187.778434 -291.325912) (xy 187.830396 -291.314052) (xy 187.883546 -291.310069)
			(xy 187.936696 -291.314052) (xy 187.988658 -291.325912) (xy 188.038272 -291.345384) (xy 188.08443 -291.372033)
			(xy 188.126101 -291.405264) (xy 188.162353 -291.444335) (xy 188.192377 -291.488372) (xy 188.215503 -291.536393)
			(xy 188.231213 -291.587323) (xy 188.239156 -291.640027) (xy 188.239654 -291.666676) (xy 188.239156 -291.693325)
			(xy 202.615536 -291.693325) (xy 202.615536 -291.640027) (xy 202.623479 -291.587323) (xy 202.639189 -291.536393)
			(xy 202.662315 -291.488372) (xy 202.692339 -291.444335) (xy 202.728591 -291.405264) (xy 202.770262 -291.372033)
			(xy 202.81642 -291.345384) (xy 202.866034 -291.325912) (xy 202.917996 -291.314052) (xy 202.971146 -291.310069)
			(xy 203.024296 -291.314052) (xy 203.076258 -291.325912) (xy 203.125872 -291.345384) (xy 203.17203 -291.372033)
			(xy 203.213701 -291.405264) (xy 203.249953 -291.444335) (xy 203.279977 -291.488372) (xy 203.303103 -291.536393)
			(xy 203.318813 -291.587323) (xy 203.326756 -291.640027) (xy 203.327254 -291.666676) (xy 203.326756 -291.693325)
			(xy 203.318813 -291.746029) (xy 203.303103 -291.796959) (xy 203.279977 -291.84498) (xy 203.249953 -291.889017)
			(xy 203.213701 -291.928088) (xy 203.17203 -291.961319) (xy 203.125872 -291.987968) (xy 203.076258 -292.00744)
			(xy 203.024296 -292.0193) (xy 202.971146 -292.023284) (xy 202.917996 -292.0193) (xy 202.866034 -292.00744)
			(xy 202.81642 -291.987968) (xy 202.770262 -291.961319) (xy 202.728591 -291.928088) (xy 202.692339 -291.889017)
			(xy 202.662315 -291.84498) (xy 202.639189 -291.796959) (xy 202.623479 -291.746029) (xy 202.615536 -291.693325)
			(xy 188.239156 -291.693325) (xy 188.231213 -291.746029) (xy 188.215503 -291.796959) (xy 188.192377 -291.84498)
			(xy 188.162353 -291.889017) (xy 188.126101 -291.928088) (xy 188.08443 -291.961319) (xy 188.038272 -291.987968)
			(xy 187.988658 -292.00744) (xy 187.936696 -292.0193) (xy 187.883546 -292.023284) (xy 187.830396 -292.0193)
			(xy 187.778434 -292.00744) (xy 187.72882 -291.987968) (xy 187.682662 -291.961319) (xy 187.640991 -291.928088)
			(xy 187.604739 -291.889017) (xy 187.574715 -291.84498) (xy 187.551589 -291.796959) (xy 187.535879 -291.746029)
			(xy 187.527936 -291.693325) (xy 173.151556 -291.693325) (xy 173.143613 -291.746029) (xy 173.127903 -291.796959)
			(xy 173.104777 -291.84498) (xy 173.074753 -291.889017) (xy 173.038501 -291.928088) (xy 172.99683 -291.961319)
			(xy 172.950672 -291.987968) (xy 172.901058 -292.00744) (xy 172.849096 -292.0193) (xy 172.795946 -292.023284)
			(xy 172.742796 -292.0193) (xy 172.690834 -292.00744) (xy 172.64122 -291.987968) (xy 172.595062 -291.961319)
			(xy 172.553391 -291.928088) (xy 172.517139 -291.889017) (xy 172.487115 -291.84498) (xy 172.463989 -291.796959)
			(xy 172.448279 -291.746029) (xy 172.440336 -291.693325) (xy 159.11576 -291.693325) (xy 159.11576 -292.543209)
			(xy 176.540404 -292.543209) (xy 176.540404 -292.489911) (xy 176.548347 -292.437207) (xy 176.564057 -292.386277)
			(xy 176.587183 -292.338256) (xy 176.617207 -292.294219) (xy 176.653459 -292.255148) (xy 176.69513 -292.221917)
			(xy 176.741288 -292.195268) (xy 176.790902 -292.175796) (xy 176.842864 -292.163936) (xy 176.896014 -292.159953)
			(xy 176.949164 -292.163936) (xy 177.001126 -292.175796) (xy 177.05074 -292.195268) (xy 177.096898 -292.221917)
			(xy 177.138569 -292.255148) (xy 177.174821 -292.294219) (xy 177.204845 -292.338256) (xy 177.227971 -292.386277)
			(xy 177.243681 -292.437207) (xy 177.251624 -292.489911) (xy 177.252122 -292.51656) (xy 177.251624 -292.543209)
			(xy 191.628004 -292.543209) (xy 191.628004 -292.489911) (xy 191.635947 -292.437207) (xy 191.651657 -292.386277)
			(xy 191.674783 -292.338256) (xy 191.704807 -292.294219) (xy 191.741059 -292.255148) (xy 191.78273 -292.221917)
			(xy 191.828888 -292.195268) (xy 191.878502 -292.175796) (xy 191.930464 -292.163936) (xy 191.983614 -292.159953)
			(xy 192.036764 -292.163936) (xy 192.088726 -292.175796) (xy 192.13834 -292.195268) (xy 192.184498 -292.221917)
			(xy 192.226169 -292.255148) (xy 192.262421 -292.294219) (xy 192.292445 -292.338256) (xy 192.315571 -292.386277)
			(xy 192.331281 -292.437207) (xy 192.339224 -292.489911) (xy 192.339722 -292.51656) (xy 192.339224 -292.543209)
			(xy 206.715604 -292.543209) (xy 206.715604 -292.489911) (xy 206.723547 -292.437207) (xy 206.739257 -292.386277)
			(xy 206.762383 -292.338256) (xy 206.792407 -292.294219) (xy 206.828659 -292.255148) (xy 206.87033 -292.221917)
			(xy 206.916488 -292.195268) (xy 206.966102 -292.175796) (xy 207.018064 -292.163936) (xy 207.071214 -292.159953)
			(xy 207.124364 -292.163936) (xy 207.176326 -292.175796) (xy 207.22594 -292.195268) (xy 207.272098 -292.221917)
			(xy 207.313769 -292.255148) (xy 207.350021 -292.294219) (xy 207.380045 -292.338256) (xy 207.403171 -292.386277)
			(xy 207.418881 -292.437207) (xy 207.426824 -292.489911) (xy 207.427322 -292.51656) (xy 207.426824 -292.543209)
			(xy 207.418881 -292.595913) (xy 207.403171 -292.646843) (xy 207.380045 -292.694864) (xy 207.350021 -292.738901)
			(xy 207.313769 -292.777972) (xy 207.272098 -292.811203) (xy 207.22594 -292.837852) (xy 207.176326 -292.857324)
			(xy 207.124364 -292.869184) (xy 207.071214 -292.873168) (xy 207.018064 -292.869184) (xy 206.966102 -292.857324)
			(xy 206.916488 -292.837852) (xy 206.87033 -292.811203) (xy 206.828659 -292.777972) (xy 206.792407 -292.738901)
			(xy 206.762383 -292.694864) (xy 206.739257 -292.646843) (xy 206.723547 -292.595913) (xy 206.715604 -292.543209)
			(xy 192.339224 -292.543209) (xy 192.331281 -292.595913) (xy 192.315571 -292.646843) (xy 192.292445 -292.694864)
			(xy 192.262421 -292.738901) (xy 192.226169 -292.777972) (xy 192.184498 -292.811203) (xy 192.13834 -292.837852)
			(xy 192.088726 -292.857324) (xy 192.036764 -292.869184) (xy 191.983614 -292.873168) (xy 191.930464 -292.869184)
			(xy 191.878502 -292.857324) (xy 191.828888 -292.837852) (xy 191.78273 -292.811203) (xy 191.741059 -292.777972)
			(xy 191.704807 -292.738901) (xy 191.674783 -292.694864) (xy 191.651657 -292.646843) (xy 191.635947 -292.595913)
			(xy 191.628004 -292.543209) (xy 177.251624 -292.543209) (xy 177.243681 -292.595913) (xy 177.227971 -292.646843)
			(xy 177.204845 -292.694864) (xy 177.174821 -292.738901) (xy 177.138569 -292.777972) (xy 177.096898 -292.811203)
			(xy 177.05074 -292.837852) (xy 177.001126 -292.857324) (xy 176.949164 -292.869184) (xy 176.896014 -292.873168)
			(xy 176.842864 -292.869184) (xy 176.790902 -292.857324) (xy 176.741288 -292.837852) (xy 176.69513 -292.811203)
			(xy 176.653459 -292.777972) (xy 176.617207 -292.738901) (xy 176.587183 -292.694864) (xy 176.564057 -292.646843)
			(xy 176.548347 -292.595913) (xy 176.540404 -292.543209) (xy 159.11576 -292.543209) (xy 159.11576 -293.393347)
			(xy 172.440336 -293.393347) (xy 172.440336 -293.340049) (xy 172.448279 -293.287345) (xy 172.463989 -293.236415)
			(xy 172.487115 -293.188394) (xy 172.517139 -293.144357) (xy 172.553391 -293.105286) (xy 172.595062 -293.072055)
			(xy 172.64122 -293.045406) (xy 172.690834 -293.025934) (xy 172.742796 -293.014074) (xy 172.795946 -293.010091)
			(xy 172.849096 -293.014074) (xy 172.901058 -293.025934) (xy 172.950672 -293.045406) (xy 172.99683 -293.072055)
			(xy 173.038501 -293.105286) (xy 173.074753 -293.144357) (xy 173.104777 -293.188394) (xy 173.127903 -293.236415)
			(xy 173.143613 -293.287345) (xy 173.151556 -293.340049) (xy 173.152054 -293.366698) (xy 173.151556 -293.393347)
			(xy 176.540404 -293.393347) (xy 176.540404 -293.340049) (xy 176.548347 -293.287345) (xy 176.564057 -293.236415)
			(xy 176.587183 -293.188394) (xy 176.617207 -293.144357) (xy 176.653459 -293.105286) (xy 176.69513 -293.072055)
			(xy 176.741288 -293.045406) (xy 176.790902 -293.025934) (xy 176.842864 -293.014074) (xy 176.896014 -293.010091)
			(xy 176.949164 -293.014074) (xy 177.001126 -293.025934) (xy 177.05074 -293.045406) (xy 177.096898 -293.072055)
			(xy 177.138569 -293.105286) (xy 177.174821 -293.144357) (xy 177.204845 -293.188394) (xy 177.227971 -293.236415)
			(xy 177.243681 -293.287345) (xy 177.251624 -293.340049) (xy 177.252122 -293.366698) (xy 177.251624 -293.393347)
			(xy 187.527936 -293.393347) (xy 187.527936 -293.340049) (xy 187.535879 -293.287345) (xy 187.551589 -293.236415)
			(xy 187.574715 -293.188394) (xy 187.604739 -293.144357) (xy 187.640991 -293.105286) (xy 187.682662 -293.072055)
			(xy 187.72882 -293.045406) (xy 187.778434 -293.025934) (xy 187.830396 -293.014074) (xy 187.883546 -293.010091)
			(xy 187.936696 -293.014074) (xy 187.988658 -293.025934) (xy 188.038272 -293.045406) (xy 188.08443 -293.072055)
			(xy 188.126101 -293.105286) (xy 188.162353 -293.144357) (xy 188.192377 -293.188394) (xy 188.215503 -293.236415)
			(xy 188.231213 -293.287345) (xy 188.239156 -293.340049) (xy 188.239654 -293.366698) (xy 188.239156 -293.393347)
			(xy 191.628004 -293.393347) (xy 191.628004 -293.340049) (xy 191.635947 -293.287345) (xy 191.651657 -293.236415)
			(xy 191.674783 -293.188394) (xy 191.704807 -293.144357) (xy 191.741059 -293.105286) (xy 191.78273 -293.072055)
			(xy 191.828888 -293.045406) (xy 191.878502 -293.025934) (xy 191.930464 -293.014074) (xy 191.983614 -293.010091)
			(xy 192.036764 -293.014074) (xy 192.088726 -293.025934) (xy 192.13834 -293.045406) (xy 192.184498 -293.072055)
			(xy 192.226169 -293.105286) (xy 192.262421 -293.144357) (xy 192.292445 -293.188394) (xy 192.315571 -293.236415)
			(xy 192.331281 -293.287345) (xy 192.339224 -293.340049) (xy 192.339722 -293.366698) (xy 192.339224 -293.393347)
			(xy 202.615536 -293.393347) (xy 202.615536 -293.340049) (xy 202.623479 -293.287345) (xy 202.639189 -293.236415)
			(xy 202.662315 -293.188394) (xy 202.692339 -293.144357) (xy 202.728591 -293.105286) (xy 202.770262 -293.072055)
			(xy 202.81642 -293.045406) (xy 202.866034 -293.025934) (xy 202.917996 -293.014074) (xy 202.971146 -293.010091)
			(xy 203.024296 -293.014074) (xy 203.076258 -293.025934) (xy 203.125872 -293.045406) (xy 203.17203 -293.072055)
			(xy 203.213701 -293.105286) (xy 203.249953 -293.144357) (xy 203.279977 -293.188394) (xy 203.303103 -293.236415)
			(xy 203.318813 -293.287345) (xy 203.326756 -293.340049) (xy 203.327254 -293.366698) (xy 203.326756 -293.393347)
			(xy 206.715604 -293.393347) (xy 206.715604 -293.340049) (xy 206.723547 -293.287345) (xy 206.739257 -293.236415)
			(xy 206.762383 -293.188394) (xy 206.792407 -293.144357) (xy 206.828659 -293.105286) (xy 206.87033 -293.072055)
			(xy 206.916488 -293.045406) (xy 206.966102 -293.025934) (xy 207.018064 -293.014074) (xy 207.071214 -293.010091)
			(xy 207.124364 -293.014074) (xy 207.176326 -293.025934) (xy 207.22594 -293.045406) (xy 207.272098 -293.072055)
			(xy 207.313769 -293.105286) (xy 207.350021 -293.144357) (xy 207.380045 -293.188394) (xy 207.403171 -293.236415)
			(xy 207.418881 -293.287345) (xy 207.426824 -293.340049) (xy 207.427322 -293.366698) (xy 207.426824 -293.393347)
			(xy 207.418881 -293.446051) (xy 207.403171 -293.496981) (xy 207.380045 -293.545002) (xy 207.350021 -293.589039)
			(xy 207.313769 -293.62811) (xy 207.272098 -293.661341) (xy 207.22594 -293.68799) (xy 207.176326 -293.707462)
			(xy 207.124364 -293.719322) (xy 207.071214 -293.723306) (xy 207.018064 -293.719322) (xy 206.966102 -293.707462)
			(xy 206.916488 -293.68799) (xy 206.87033 -293.661341) (xy 206.828659 -293.62811) (xy 206.792407 -293.589039)
			(xy 206.762383 -293.545002) (xy 206.739257 -293.496981) (xy 206.723547 -293.446051) (xy 206.715604 -293.393347)
			(xy 203.326756 -293.393347) (xy 203.318813 -293.446051) (xy 203.303103 -293.496981) (xy 203.279977 -293.545002)
			(xy 203.249953 -293.589039) (xy 203.213701 -293.62811) (xy 203.17203 -293.661341) (xy 203.125872 -293.68799)
			(xy 203.076258 -293.707462) (xy 203.024296 -293.719322) (xy 202.971146 -293.723306) (xy 202.917996 -293.719322)
			(xy 202.866034 -293.707462) (xy 202.81642 -293.68799) (xy 202.770262 -293.661341) (xy 202.728591 -293.62811)
			(xy 202.692339 -293.589039) (xy 202.662315 -293.545002) (xy 202.639189 -293.496981) (xy 202.623479 -293.446051)
			(xy 202.615536 -293.393347) (xy 192.339224 -293.393347) (xy 192.331281 -293.446051) (xy 192.315571 -293.496981)
			(xy 192.292445 -293.545002) (xy 192.262421 -293.589039) (xy 192.226169 -293.62811) (xy 192.184498 -293.661341)
			(xy 192.13834 -293.68799) (xy 192.088726 -293.707462) (xy 192.036764 -293.719322) (xy 191.983614 -293.723306)
			(xy 191.930464 -293.719322) (xy 191.878502 -293.707462) (xy 191.828888 -293.68799) (xy 191.78273 -293.661341)
			(xy 191.741059 -293.62811) (xy 191.704807 -293.589039) (xy 191.674783 -293.545002) (xy 191.651657 -293.496981)
			(xy 191.635947 -293.446051) (xy 191.628004 -293.393347) (xy 188.239156 -293.393347) (xy 188.231213 -293.446051)
			(xy 188.215503 -293.496981) (xy 188.192377 -293.545002) (xy 188.162353 -293.589039) (xy 188.126101 -293.62811)
			(xy 188.08443 -293.661341) (xy 188.038272 -293.68799) (xy 187.988658 -293.707462) (xy 187.936696 -293.719322)
			(xy 187.883546 -293.723306) (xy 187.830396 -293.719322) (xy 187.778434 -293.707462) (xy 187.72882 -293.68799)
			(xy 187.682662 -293.661341) (xy 187.640991 -293.62811) (xy 187.604739 -293.589039) (xy 187.574715 -293.545002)
			(xy 187.551589 -293.496981) (xy 187.535879 -293.446051) (xy 187.527936 -293.393347) (xy 177.251624 -293.393347)
			(xy 177.243681 -293.446051) (xy 177.227971 -293.496981) (xy 177.204845 -293.545002) (xy 177.174821 -293.589039)
			(xy 177.138569 -293.62811) (xy 177.096898 -293.661341) (xy 177.05074 -293.68799) (xy 177.001126 -293.707462)
			(xy 176.949164 -293.719322) (xy 176.896014 -293.723306) (xy 176.842864 -293.719322) (xy 176.790902 -293.707462)
			(xy 176.741288 -293.68799) (xy 176.69513 -293.661341) (xy 176.653459 -293.62811) (xy 176.617207 -293.589039)
			(xy 176.587183 -293.545002) (xy 176.564057 -293.496981) (xy 176.548347 -293.446051) (xy 176.540404 -293.393347)
			(xy 173.151556 -293.393347) (xy 173.143613 -293.446051) (xy 173.127903 -293.496981) (xy 173.104777 -293.545002)
			(xy 173.074753 -293.589039) (xy 173.038501 -293.62811) (xy 172.99683 -293.661341) (xy 172.950672 -293.68799)
			(xy 172.901058 -293.707462) (xy 172.849096 -293.719322) (xy 172.795946 -293.723306) (xy 172.742796 -293.719322)
			(xy 172.690834 -293.707462) (xy 172.64122 -293.68799) (xy 172.595062 -293.661341) (xy 172.553391 -293.62811)
			(xy 172.517139 -293.589039) (xy 172.487115 -293.545002) (xy 172.463989 -293.496981) (xy 172.448279 -293.446051)
			(xy 172.440336 -293.393347) (xy 159.11576 -293.393347) (xy 159.11576 -294.243231) (xy 172.440336 -294.243231)
			(xy 172.440336 -294.189933) (xy 172.448279 -294.137229) (xy 172.463989 -294.086299) (xy 172.487115 -294.038278)
			(xy 172.517139 -293.994241) (xy 172.553391 -293.95517) (xy 172.595062 -293.921939) (xy 172.64122 -293.89529)
			(xy 172.690834 -293.875818) (xy 172.742796 -293.863958) (xy 172.795946 -293.859975) (xy 172.849096 -293.863958)
			(xy 172.901058 -293.875818) (xy 172.950672 -293.89529) (xy 172.99683 -293.921939) (xy 173.038501 -293.95517)
			(xy 173.074753 -293.994241) (xy 173.104777 -294.038278) (xy 173.127903 -294.086299) (xy 173.143613 -294.137229)
			(xy 173.151556 -294.189933) (xy 173.152054 -294.216582) (xy 173.151556 -294.243231) (xy 187.527936 -294.243231)
			(xy 187.527936 -294.189933) (xy 187.535879 -294.137229) (xy 187.551589 -294.086299) (xy 187.574715 -294.038278)
			(xy 187.604739 -293.994241) (xy 187.640991 -293.95517) (xy 187.682662 -293.921939) (xy 187.72882 -293.89529)
			(xy 187.778434 -293.875818) (xy 187.830396 -293.863958) (xy 187.883546 -293.859975) (xy 187.936696 -293.863958)
			(xy 187.988658 -293.875818) (xy 188.038272 -293.89529) (xy 188.08443 -293.921939) (xy 188.126101 -293.95517)
			(xy 188.162353 -293.994241) (xy 188.192377 -294.038278) (xy 188.215503 -294.086299) (xy 188.231213 -294.137229)
			(xy 188.239156 -294.189933) (xy 188.239654 -294.216582) (xy 188.239156 -294.243231) (xy 202.615536 -294.243231)
			(xy 202.615536 -294.189933) (xy 202.623479 -294.137229) (xy 202.639189 -294.086299) (xy 202.662315 -294.038278)
			(xy 202.692339 -293.994241) (xy 202.728591 -293.95517) (xy 202.770262 -293.921939) (xy 202.81642 -293.89529)
			(xy 202.866034 -293.875818) (xy 202.917996 -293.863958) (xy 202.971146 -293.859975) (xy 203.024296 -293.863958)
			(xy 203.076258 -293.875818) (xy 203.125872 -293.89529) (xy 203.17203 -293.921939) (xy 203.213701 -293.95517)
			(xy 203.249953 -293.994241) (xy 203.279977 -294.038278) (xy 203.303103 -294.086299) (xy 203.318813 -294.137229)
			(xy 203.326756 -294.189933) (xy 203.327254 -294.216582) (xy 203.326756 -294.243231) (xy 203.318813 -294.295935)
			(xy 203.303103 -294.346865) (xy 203.279977 -294.394886) (xy 203.249953 -294.438923) (xy 203.213701 -294.477994)
			(xy 203.17203 -294.511225) (xy 203.125872 -294.537874) (xy 203.076258 -294.557346) (xy 203.024296 -294.569206)
			(xy 202.971146 -294.57319) (xy 202.917996 -294.569206) (xy 202.866034 -294.557346) (xy 202.81642 -294.537874)
			(xy 202.770262 -294.511225) (xy 202.728591 -294.477994) (xy 202.692339 -294.438923) (xy 202.662315 -294.394886)
			(xy 202.639189 -294.346865) (xy 202.623479 -294.295935) (xy 202.615536 -294.243231) (xy 188.239156 -294.243231)
			(xy 188.231213 -294.295935) (xy 188.215503 -294.346865) (xy 188.192377 -294.394886) (xy 188.162353 -294.438923)
			(xy 188.126101 -294.477994) (xy 188.08443 -294.511225) (xy 188.038272 -294.537874) (xy 187.988658 -294.557346)
			(xy 187.936696 -294.569206) (xy 187.883546 -294.57319) (xy 187.830396 -294.569206) (xy 187.778434 -294.557346)
			(xy 187.72882 -294.537874) (xy 187.682662 -294.511225) (xy 187.640991 -294.477994) (xy 187.604739 -294.438923)
			(xy 187.574715 -294.394886) (xy 187.551589 -294.346865) (xy 187.535879 -294.295935) (xy 187.527936 -294.243231)
			(xy 173.151556 -294.243231) (xy 173.143613 -294.295935) (xy 173.127903 -294.346865) (xy 173.104777 -294.394886)
			(xy 173.074753 -294.438923) (xy 173.038501 -294.477994) (xy 172.99683 -294.511225) (xy 172.950672 -294.537874)
			(xy 172.901058 -294.557346) (xy 172.849096 -294.569206) (xy 172.795946 -294.57319) (xy 172.742796 -294.569206)
			(xy 172.690834 -294.557346) (xy 172.64122 -294.537874) (xy 172.595062 -294.511225) (xy 172.553391 -294.477994)
			(xy 172.517139 -294.438923) (xy 172.487115 -294.394886) (xy 172.463989 -294.346865) (xy 172.448279 -294.295935)
			(xy 172.440336 -294.243231) (xy 159.11576 -294.243231) (xy 159.11576 -295.093369) (xy 176.540404 -295.093369)
			(xy 176.540404 -295.040071) (xy 176.548347 -294.987367) (xy 176.564057 -294.936437) (xy 176.587183 -294.888416)
			(xy 176.617207 -294.844379) (xy 176.653459 -294.805308) (xy 176.69513 -294.772077) (xy 176.741288 -294.745428)
			(xy 176.790902 -294.725956) (xy 176.842864 -294.714096) (xy 176.896014 -294.710113) (xy 176.949164 -294.714096)
			(xy 177.001126 -294.725956) (xy 177.05074 -294.745428) (xy 177.096898 -294.772077) (xy 177.138569 -294.805308)
			(xy 177.174821 -294.844379) (xy 177.204845 -294.888416) (xy 177.227971 -294.936437) (xy 177.243681 -294.987367)
			(xy 177.251624 -295.040071) (xy 177.252122 -295.06672) (xy 177.251624 -295.093369) (xy 191.628004 -295.093369)
			(xy 191.628004 -295.040071) (xy 191.635947 -294.987367) (xy 191.651657 -294.936437) (xy 191.674783 -294.888416)
			(xy 191.704807 -294.844379) (xy 191.741059 -294.805308) (xy 191.78273 -294.772077) (xy 191.828888 -294.745428)
			(xy 191.878502 -294.725956) (xy 191.930464 -294.714096) (xy 191.983614 -294.710113) (xy 192.036764 -294.714096)
			(xy 192.088726 -294.725956) (xy 192.13834 -294.745428) (xy 192.184498 -294.772077) (xy 192.226169 -294.805308)
			(xy 192.262421 -294.844379) (xy 192.292445 -294.888416) (xy 192.315571 -294.936437) (xy 192.331281 -294.987367)
			(xy 192.339224 -295.040071) (xy 192.339722 -295.06672) (xy 192.339224 -295.093369) (xy 206.715604 -295.093369)
			(xy 206.715604 -295.040071) (xy 206.723547 -294.987367) (xy 206.739257 -294.936437) (xy 206.762383 -294.888416)
			(xy 206.792407 -294.844379) (xy 206.828659 -294.805308) (xy 206.87033 -294.772077) (xy 206.916488 -294.745428)
			(xy 206.966102 -294.725956) (xy 207.018064 -294.714096) (xy 207.071214 -294.710113) (xy 207.124364 -294.714096)
			(xy 207.176326 -294.725956) (xy 207.22594 -294.745428) (xy 207.272098 -294.772077) (xy 207.313769 -294.805308)
			(xy 207.350021 -294.844379) (xy 207.380045 -294.888416) (xy 207.403171 -294.936437) (xy 207.418881 -294.987367)
			(xy 207.426824 -295.040071) (xy 207.427322 -295.06672) (xy 207.426824 -295.093369) (xy 207.418881 -295.146073)
			(xy 207.403171 -295.197003) (xy 207.380045 -295.245024) (xy 207.350021 -295.289061) (xy 207.313769 -295.328132)
			(xy 207.272098 -295.361363) (xy 207.22594 -295.388012) (xy 207.176326 -295.407484) (xy 207.124364 -295.419344)
			(xy 207.071214 -295.423328) (xy 207.018064 -295.419344) (xy 206.966102 -295.407484) (xy 206.916488 -295.388012)
			(xy 206.87033 -295.361363) (xy 206.828659 -295.328132) (xy 206.792407 -295.289061) (xy 206.762383 -295.245024)
			(xy 206.739257 -295.197003) (xy 206.723547 -295.146073) (xy 206.715604 -295.093369) (xy 192.339224 -295.093369)
			(xy 192.331281 -295.146073) (xy 192.315571 -295.197003) (xy 192.292445 -295.245024) (xy 192.262421 -295.289061)
			(xy 192.226169 -295.328132) (xy 192.184498 -295.361363) (xy 192.13834 -295.388012) (xy 192.088726 -295.407484)
			(xy 192.036764 -295.419344) (xy 191.983614 -295.423328) (xy 191.930464 -295.419344) (xy 191.878502 -295.407484)
			(xy 191.828888 -295.388012) (xy 191.78273 -295.361363) (xy 191.741059 -295.328132) (xy 191.704807 -295.289061)
			(xy 191.674783 -295.245024) (xy 191.651657 -295.197003) (xy 191.635947 -295.146073) (xy 191.628004 -295.093369)
			(xy 177.251624 -295.093369) (xy 177.243681 -295.146073) (xy 177.227971 -295.197003) (xy 177.204845 -295.245024)
			(xy 177.174821 -295.289061) (xy 177.138569 -295.328132) (xy 177.096898 -295.361363) (xy 177.05074 -295.388012)
			(xy 177.001126 -295.407484) (xy 176.949164 -295.419344) (xy 176.896014 -295.423328) (xy 176.842864 -295.419344)
			(xy 176.790902 -295.407484) (xy 176.741288 -295.388012) (xy 176.69513 -295.361363) (xy 176.653459 -295.328132)
			(xy 176.617207 -295.289061) (xy 176.587183 -295.245024) (xy 176.564057 -295.197003) (xy 176.548347 -295.146073)
			(xy 176.540404 -295.093369) (xy 159.11576 -295.093369) (xy 159.11576 -295.943253) (xy 172.440336 -295.943253)
			(xy 172.440336 -295.889955) (xy 172.448279 -295.837251) (xy 172.463989 -295.786321) (xy 172.487115 -295.7383)
			(xy 172.517139 -295.694263) (xy 172.553391 -295.655192) (xy 172.595062 -295.621961) (xy 172.64122 -295.595312)
			(xy 172.690834 -295.57584) (xy 172.742796 -295.56398) (xy 172.795946 -295.559997) (xy 172.849096 -295.56398)
			(xy 172.901058 -295.57584) (xy 172.950672 -295.595312) (xy 172.99683 -295.621961) (xy 173.038501 -295.655192)
			(xy 173.074753 -295.694263) (xy 173.104777 -295.7383) (xy 173.127903 -295.786321) (xy 173.143613 -295.837251)
			(xy 173.151556 -295.889955) (xy 173.152054 -295.916604) (xy 173.151556 -295.943253) (xy 187.527936 -295.943253)
			(xy 187.527936 -295.889955) (xy 187.535879 -295.837251) (xy 187.551589 -295.786321) (xy 187.574715 -295.7383)
			(xy 187.604739 -295.694263) (xy 187.640991 -295.655192) (xy 187.682662 -295.621961) (xy 187.72882 -295.595312)
			(xy 187.778434 -295.57584) (xy 187.830396 -295.56398) (xy 187.883546 -295.559997) (xy 187.936696 -295.56398)
			(xy 187.988658 -295.57584) (xy 188.038272 -295.595312) (xy 188.08443 -295.621961) (xy 188.126101 -295.655192)
			(xy 188.162353 -295.694263) (xy 188.192377 -295.7383) (xy 188.215503 -295.786321) (xy 188.231213 -295.837251)
			(xy 188.239156 -295.889955) (xy 188.239654 -295.916604) (xy 188.239156 -295.943253) (xy 202.615536 -295.943253)
			(xy 202.615536 -295.889955) (xy 202.623479 -295.837251) (xy 202.639189 -295.786321) (xy 202.662315 -295.7383)
			(xy 202.692339 -295.694263) (xy 202.728591 -295.655192) (xy 202.770262 -295.621961) (xy 202.81642 -295.595312)
			(xy 202.866034 -295.57584) (xy 202.917996 -295.56398) (xy 202.971146 -295.559997) (xy 203.024296 -295.56398)
			(xy 203.076258 -295.57584) (xy 203.125872 -295.595312) (xy 203.17203 -295.621961) (xy 203.213701 -295.655192)
			(xy 203.249953 -295.694263) (xy 203.279977 -295.7383) (xy 203.303103 -295.786321) (xy 203.318813 -295.837251)
			(xy 203.326756 -295.889955) (xy 203.327254 -295.916604) (xy 203.326756 -295.943253) (xy 203.318813 -295.995957)
			(xy 203.303103 -296.046887) (xy 203.279977 -296.094908) (xy 203.249953 -296.138945) (xy 203.213701 -296.178016)
			(xy 203.17203 -296.211247) (xy 203.125872 -296.237896) (xy 203.076258 -296.257368) (xy 203.024296 -296.269228)
			(xy 202.971146 -296.273212) (xy 202.917996 -296.269228) (xy 202.866034 -296.257368) (xy 202.81642 -296.237896)
			(xy 202.770262 -296.211247) (xy 202.728591 -296.178016) (xy 202.692339 -296.138945) (xy 202.662315 -296.094908)
			(xy 202.639189 -296.046887) (xy 202.623479 -295.995957) (xy 202.615536 -295.943253) (xy 188.239156 -295.943253)
			(xy 188.231213 -295.995957) (xy 188.215503 -296.046887) (xy 188.192377 -296.094908) (xy 188.162353 -296.138945)
			(xy 188.126101 -296.178016) (xy 188.08443 -296.211247) (xy 188.038272 -296.237896) (xy 187.988658 -296.257368)
			(xy 187.936696 -296.269228) (xy 187.883546 -296.273212) (xy 187.830396 -296.269228) (xy 187.778434 -296.257368)
			(xy 187.72882 -296.237896) (xy 187.682662 -296.211247) (xy 187.640991 -296.178016) (xy 187.604739 -296.138945)
			(xy 187.574715 -296.094908) (xy 187.551589 -296.046887) (xy 187.535879 -295.995957) (xy 187.527936 -295.943253)
			(xy 173.151556 -295.943253) (xy 173.143613 -295.995957) (xy 173.127903 -296.046887) (xy 173.104777 -296.094908)
			(xy 173.074753 -296.138945) (xy 173.038501 -296.178016) (xy 172.99683 -296.211247) (xy 172.950672 -296.237896)
			(xy 172.901058 -296.257368) (xy 172.849096 -296.269228) (xy 172.795946 -296.273212) (xy 172.742796 -296.269228)
			(xy 172.690834 -296.257368) (xy 172.64122 -296.237896) (xy 172.595062 -296.211247) (xy 172.553391 -296.178016)
			(xy 172.517139 -296.138945) (xy 172.487115 -296.094908) (xy 172.463989 -296.046887) (xy 172.448279 -295.995957)
			(xy 172.440336 -295.943253) (xy 159.11576 -295.943253) (xy 159.11576 -296.793391) (xy 176.540404 -296.793391)
			(xy 176.540404 -296.740093) (xy 176.548347 -296.687389) (xy 176.564057 -296.636459) (xy 176.587183 -296.588438)
			(xy 176.617207 -296.544401) (xy 176.653459 -296.50533) (xy 176.69513 -296.472099) (xy 176.741288 -296.44545)
			(xy 176.790902 -296.425978) (xy 176.842864 -296.414118) (xy 176.896014 -296.410135) (xy 176.949164 -296.414118)
			(xy 177.001126 -296.425978) (xy 177.05074 -296.44545) (xy 177.096898 -296.472099) (xy 177.138569 -296.50533)
			(xy 177.174821 -296.544401) (xy 177.204845 -296.588438) (xy 177.227971 -296.636459) (xy 177.243681 -296.687389)
			(xy 177.251624 -296.740093) (xy 177.252122 -296.766742) (xy 177.251624 -296.793391) (xy 191.628004 -296.793391)
			(xy 191.628004 -296.740093) (xy 191.635947 -296.687389) (xy 191.651657 -296.636459) (xy 191.674783 -296.588438)
			(xy 191.704807 -296.544401) (xy 191.741059 -296.50533) (xy 191.78273 -296.472099) (xy 191.828888 -296.44545)
			(xy 191.878502 -296.425978) (xy 191.930464 -296.414118) (xy 191.983614 -296.410135) (xy 192.036764 -296.414118)
			(xy 192.088726 -296.425978) (xy 192.13834 -296.44545) (xy 192.184498 -296.472099) (xy 192.226169 -296.50533)
			(xy 192.262421 -296.544401) (xy 192.292445 -296.588438) (xy 192.315571 -296.636459) (xy 192.331281 -296.687389)
			(xy 192.339224 -296.740093) (xy 192.339722 -296.766742) (xy 192.339224 -296.793391) (xy 206.715604 -296.793391)
			(xy 206.715604 -296.740093) (xy 206.723547 -296.687389) (xy 206.739257 -296.636459) (xy 206.762383 -296.588438)
			(xy 206.792407 -296.544401) (xy 206.828659 -296.50533) (xy 206.87033 -296.472099) (xy 206.916488 -296.44545)
			(xy 206.966102 -296.425978) (xy 207.018064 -296.414118) (xy 207.071214 -296.410135) (xy 207.124364 -296.414118)
			(xy 207.176326 -296.425978) (xy 207.22594 -296.44545) (xy 207.272098 -296.472099) (xy 207.313769 -296.50533)
			(xy 207.350021 -296.544401) (xy 207.380045 -296.588438) (xy 207.403171 -296.636459) (xy 207.418881 -296.687389)
			(xy 207.426824 -296.740093) (xy 207.427322 -296.766742) (xy 207.426824 -296.793391) (xy 207.418881 -296.846095)
			(xy 207.403171 -296.897025) (xy 207.380045 -296.945046) (xy 207.350021 -296.989083) (xy 207.313769 -297.028154)
			(xy 207.272098 -297.061385) (xy 207.22594 -297.088034) (xy 207.176326 -297.107506) (xy 207.124364 -297.119366)
			(xy 207.071214 -297.12335) (xy 207.018064 -297.119366) (xy 206.966102 -297.107506) (xy 206.916488 -297.088034)
			(xy 206.87033 -297.061385) (xy 206.828659 -297.028154) (xy 206.792407 -296.989083) (xy 206.762383 -296.945046)
			(xy 206.739257 -296.897025) (xy 206.723547 -296.846095) (xy 206.715604 -296.793391) (xy 192.339224 -296.793391)
			(xy 192.331281 -296.846095) (xy 192.315571 -296.897025) (xy 192.292445 -296.945046) (xy 192.262421 -296.989083)
			(xy 192.226169 -297.028154) (xy 192.184498 -297.061385) (xy 192.13834 -297.088034) (xy 192.088726 -297.107506)
			(xy 192.036764 -297.119366) (xy 191.983614 -297.12335) (xy 191.930464 -297.119366) (xy 191.878502 -297.107506)
			(xy 191.828888 -297.088034) (xy 191.78273 -297.061385) (xy 191.741059 -297.028154) (xy 191.704807 -296.989083)
			(xy 191.674783 -296.945046) (xy 191.651657 -296.897025) (xy 191.635947 -296.846095) (xy 191.628004 -296.793391)
			(xy 177.251624 -296.793391) (xy 177.243681 -296.846095) (xy 177.227971 -296.897025) (xy 177.204845 -296.945046)
			(xy 177.174821 -296.989083) (xy 177.138569 -297.028154) (xy 177.096898 -297.061385) (xy 177.05074 -297.088034)
			(xy 177.001126 -297.107506) (xy 176.949164 -297.119366) (xy 176.896014 -297.12335) (xy 176.842864 -297.119366)
			(xy 176.790902 -297.107506) (xy 176.741288 -297.088034) (xy 176.69513 -297.061385) (xy 176.653459 -297.028154)
			(xy 176.617207 -296.989083) (xy 176.587183 -296.945046) (xy 176.564057 -296.897025) (xy 176.548347 -296.846095)
			(xy 176.540404 -296.793391) (xy 159.11576 -296.793391) (xy 159.11576 -297.643275) (xy 172.440336 -297.643275)
			(xy 172.440336 -297.589977) (xy 172.448279 -297.537273) (xy 172.463989 -297.486343) (xy 172.487115 -297.438322)
			(xy 172.517139 -297.394285) (xy 172.553391 -297.355214) (xy 172.595062 -297.321983) (xy 172.64122 -297.295334)
			(xy 172.690834 -297.275862) (xy 172.742796 -297.264002) (xy 172.795946 -297.260019) (xy 172.849096 -297.264002)
			(xy 172.901058 -297.275862) (xy 172.950672 -297.295334) (xy 172.99683 -297.321983) (xy 173.038501 -297.355214)
			(xy 173.074753 -297.394285) (xy 173.104777 -297.438322) (xy 173.127903 -297.486343) (xy 173.143613 -297.537273)
			(xy 173.151556 -297.589977) (xy 173.152054 -297.616626) (xy 173.151556 -297.643275) (xy 187.527936 -297.643275)
			(xy 187.527936 -297.589977) (xy 187.535879 -297.537273) (xy 187.551589 -297.486343) (xy 187.574715 -297.438322)
			(xy 187.604739 -297.394285) (xy 187.640991 -297.355214) (xy 187.682662 -297.321983) (xy 187.72882 -297.295334)
			(xy 187.778434 -297.275862) (xy 187.830396 -297.264002) (xy 187.883546 -297.260019) (xy 187.936696 -297.264002)
			(xy 187.988658 -297.275862) (xy 188.038272 -297.295334) (xy 188.08443 -297.321983) (xy 188.126101 -297.355214)
			(xy 188.162353 -297.394285) (xy 188.192377 -297.438322) (xy 188.215503 -297.486343) (xy 188.231213 -297.537273)
			(xy 188.239156 -297.589977) (xy 188.239654 -297.616626) (xy 188.239156 -297.643275) (xy 202.615536 -297.643275)
			(xy 202.615536 -297.589977) (xy 202.623479 -297.537273) (xy 202.639189 -297.486343) (xy 202.662315 -297.438322)
			(xy 202.692339 -297.394285) (xy 202.728591 -297.355214) (xy 202.770262 -297.321983) (xy 202.81642 -297.295334)
			(xy 202.866034 -297.275862) (xy 202.917996 -297.264002) (xy 202.971146 -297.260019) (xy 203.024296 -297.264002)
			(xy 203.076258 -297.275862) (xy 203.125872 -297.295334) (xy 203.17203 -297.321983) (xy 203.213701 -297.355214)
			(xy 203.249953 -297.394285) (xy 203.279977 -297.438322) (xy 203.303103 -297.486343) (xy 203.318813 -297.537273)
			(xy 203.326756 -297.589977) (xy 203.327254 -297.616626) (xy 203.326756 -297.643275) (xy 203.318813 -297.695979)
			(xy 203.303103 -297.746909) (xy 203.279977 -297.79493) (xy 203.249953 -297.838967) (xy 203.213701 -297.878038)
			(xy 203.17203 -297.911269) (xy 203.125872 -297.937918) (xy 203.076258 -297.95739) (xy 203.024296 -297.96925)
			(xy 202.971146 -297.973234) (xy 202.917996 -297.96925) (xy 202.866034 -297.95739) (xy 202.81642 -297.937918)
			(xy 202.770262 -297.911269) (xy 202.728591 -297.878038) (xy 202.692339 -297.838967) (xy 202.662315 -297.79493)
			(xy 202.639189 -297.746909) (xy 202.623479 -297.695979) (xy 202.615536 -297.643275) (xy 188.239156 -297.643275)
			(xy 188.231213 -297.695979) (xy 188.215503 -297.746909) (xy 188.192377 -297.79493) (xy 188.162353 -297.838967)
			(xy 188.126101 -297.878038) (xy 188.08443 -297.911269) (xy 188.038272 -297.937918) (xy 187.988658 -297.95739)
			(xy 187.936696 -297.96925) (xy 187.883546 -297.973234) (xy 187.830396 -297.96925) (xy 187.778434 -297.95739)
			(xy 187.72882 -297.937918) (xy 187.682662 -297.911269) (xy 187.640991 -297.878038) (xy 187.604739 -297.838967)
			(xy 187.574715 -297.79493) (xy 187.551589 -297.746909) (xy 187.535879 -297.695979) (xy 187.527936 -297.643275)
			(xy 173.151556 -297.643275) (xy 173.143613 -297.695979) (xy 173.127903 -297.746909) (xy 173.104777 -297.79493)
			(xy 173.074753 -297.838967) (xy 173.038501 -297.878038) (xy 172.99683 -297.911269) (xy 172.950672 -297.937918)
			(xy 172.901058 -297.95739) (xy 172.849096 -297.96925) (xy 172.795946 -297.973234) (xy 172.742796 -297.96925)
			(xy 172.690834 -297.95739) (xy 172.64122 -297.937918) (xy 172.595062 -297.911269) (xy 172.553391 -297.878038)
			(xy 172.517139 -297.838967) (xy 172.487115 -297.79493) (xy 172.463989 -297.746909) (xy 172.448279 -297.695979)
			(xy 172.440336 -297.643275) (xy 159.11576 -297.643275) (xy 159.11576 -298.493413) (xy 161.427404 -298.493413)
			(xy 161.427404 -298.440115) (xy 161.435347 -298.387411) (xy 161.451057 -298.336481) (xy 161.474183 -298.28846)
			(xy 161.504207 -298.244423) (xy 161.540459 -298.205352) (xy 161.58213 -298.172121) (xy 161.628288 -298.145472)
			(xy 161.677902 -298.126) (xy 161.729864 -298.11414) (xy 161.783014 -298.110157) (xy 161.836164 -298.11414)
			(xy 161.888126 -298.126) (xy 161.93774 -298.145472) (xy 161.983898 -298.172121) (xy 162.025569 -298.205352)
			(xy 162.061821 -298.244423) (xy 162.091845 -298.28846) (xy 162.114971 -298.336481) (xy 162.130681 -298.387411)
			(xy 162.138624 -298.440115) (xy 162.139122 -298.466764) (xy 162.138624 -298.493413) (xy 176.540404 -298.493413)
			(xy 176.540404 -298.440115) (xy 176.548347 -298.387411) (xy 176.564057 -298.336481) (xy 176.587183 -298.28846)
			(xy 176.617207 -298.244423) (xy 176.653459 -298.205352) (xy 176.69513 -298.172121) (xy 176.741288 -298.145472)
			(xy 176.790902 -298.126) (xy 176.842864 -298.11414) (xy 176.896014 -298.110157) (xy 176.949164 -298.11414)
			(xy 177.001126 -298.126) (xy 177.05074 -298.145472) (xy 177.096898 -298.172121) (xy 177.138569 -298.205352)
			(xy 177.174821 -298.244423) (xy 177.204845 -298.28846) (xy 177.227971 -298.336481) (xy 177.243681 -298.387411)
			(xy 177.251624 -298.440115) (xy 177.252122 -298.466764) (xy 177.251624 -298.493413) (xy 191.628004 -298.493413)
			(xy 191.628004 -298.440115) (xy 191.635947 -298.387411) (xy 191.651657 -298.336481) (xy 191.674783 -298.28846)
			(xy 191.704807 -298.244423) (xy 191.741059 -298.205352) (xy 191.78273 -298.172121) (xy 191.828888 -298.145472)
			(xy 191.878502 -298.126) (xy 191.930464 -298.11414) (xy 191.983614 -298.110157) (xy 192.036764 -298.11414)
			(xy 192.088726 -298.126) (xy 192.13834 -298.145472) (xy 192.184498 -298.172121) (xy 192.226169 -298.205352)
			(xy 192.262421 -298.244423) (xy 192.292445 -298.28846) (xy 192.315571 -298.336481) (xy 192.331281 -298.387411)
			(xy 192.339224 -298.440115) (xy 192.339722 -298.466764) (xy 192.339224 -298.493413) (xy 206.715604 -298.493413)
			(xy 206.715604 -298.440115) (xy 206.723547 -298.387411) (xy 206.739257 -298.336481) (xy 206.762383 -298.28846)
			(xy 206.792407 -298.244423) (xy 206.828659 -298.205352) (xy 206.87033 -298.172121) (xy 206.916488 -298.145472)
			(xy 206.966102 -298.126) (xy 207.018064 -298.11414) (xy 207.071214 -298.110157) (xy 207.124364 -298.11414)
			(xy 207.176326 -298.126) (xy 207.22594 -298.145472) (xy 207.272098 -298.172121) (xy 207.313769 -298.205352)
			(xy 207.350021 -298.244423) (xy 207.380045 -298.28846) (xy 207.403171 -298.336481) (xy 207.418881 -298.387411)
			(xy 207.426824 -298.440115) (xy 207.427322 -298.466764) (xy 207.426824 -298.493413) (xy 207.418881 -298.546117)
			(xy 207.403171 -298.597047) (xy 207.380045 -298.645068) (xy 207.350021 -298.689105) (xy 207.313769 -298.728176)
			(xy 207.272098 -298.761407) (xy 207.22594 -298.788056) (xy 207.176326 -298.807528) (xy 207.124364 -298.819388)
			(xy 207.071214 -298.823372) (xy 207.018064 -298.819388) (xy 206.966102 -298.807528) (xy 206.916488 -298.788056)
			(xy 206.87033 -298.761407) (xy 206.828659 -298.728176) (xy 206.792407 -298.689105) (xy 206.762383 -298.645068)
			(xy 206.739257 -298.597047) (xy 206.723547 -298.546117) (xy 206.715604 -298.493413) (xy 192.339224 -298.493413)
			(xy 192.331281 -298.546117) (xy 192.315571 -298.597047) (xy 192.292445 -298.645068) (xy 192.262421 -298.689105)
			(xy 192.226169 -298.728176) (xy 192.184498 -298.761407) (xy 192.13834 -298.788056) (xy 192.088726 -298.807528)
			(xy 192.036764 -298.819388) (xy 191.983614 -298.823372) (xy 191.930464 -298.819388) (xy 191.878502 -298.807528)
			(xy 191.828888 -298.788056) (xy 191.78273 -298.761407) (xy 191.741059 -298.728176) (xy 191.704807 -298.689105)
			(xy 191.674783 -298.645068) (xy 191.651657 -298.597047) (xy 191.635947 -298.546117) (xy 191.628004 -298.493413)
			(xy 177.251624 -298.493413) (xy 177.243681 -298.546117) (xy 177.227971 -298.597047) (xy 177.204845 -298.645068)
			(xy 177.174821 -298.689105) (xy 177.138569 -298.728176) (xy 177.096898 -298.761407) (xy 177.05074 -298.788056)
			(xy 177.001126 -298.807528) (xy 176.949164 -298.819388) (xy 176.896014 -298.823372) (xy 176.842864 -298.819388)
			(xy 176.790902 -298.807528) (xy 176.741288 -298.788056) (xy 176.69513 -298.761407) (xy 176.653459 -298.728176)
			(xy 176.617207 -298.689105) (xy 176.587183 -298.645068) (xy 176.564057 -298.597047) (xy 176.548347 -298.546117)
			(xy 176.540404 -298.493413) (xy 162.138624 -298.493413) (xy 162.130681 -298.546117) (xy 162.114971 -298.597047)
			(xy 162.091845 -298.645068) (xy 162.061821 -298.689105) (xy 162.025569 -298.728176) (xy 161.983898 -298.761407)
			(xy 161.93774 -298.788056) (xy 161.888126 -298.807528) (xy 161.836164 -298.819388) (xy 161.783014 -298.823372)
			(xy 161.729864 -298.819388) (xy 161.677902 -298.807528) (xy 161.628288 -298.788056) (xy 161.58213 -298.761407)
			(xy 161.540459 -298.728176) (xy 161.504207 -298.689105) (xy 161.474183 -298.645068) (xy 161.451057 -298.597047)
			(xy 161.435347 -298.546117) (xy 161.427404 -298.493413) (xy 159.11576 -298.493413) (xy 159.11576 -299.343297)
			(xy 172.440336 -299.343297) (xy 172.440336 -299.289999) (xy 172.448279 -299.237295) (xy 172.463989 -299.186365)
			(xy 172.487115 -299.138344) (xy 172.517139 -299.094307) (xy 172.553391 -299.055236) (xy 172.595062 -299.022005)
			(xy 172.64122 -298.995356) (xy 172.690834 -298.975884) (xy 172.742796 -298.964024) (xy 172.795946 -298.960041)
			(xy 172.849096 -298.964024) (xy 172.901058 -298.975884) (xy 172.950672 -298.995356) (xy 172.99683 -299.022005)
			(xy 173.038501 -299.055236) (xy 173.074753 -299.094307) (xy 173.104777 -299.138344) (xy 173.127903 -299.186365)
			(xy 173.143613 -299.237295) (xy 173.151556 -299.289999) (xy 173.152054 -299.316648) (xy 173.151556 -299.343297)
			(xy 187.527936 -299.343297) (xy 187.527936 -299.289999) (xy 187.535879 -299.237295) (xy 187.551589 -299.186365)
			(xy 187.574715 -299.138344) (xy 187.604739 -299.094307) (xy 187.640991 -299.055236) (xy 187.682662 -299.022005)
			(xy 187.72882 -298.995356) (xy 187.778434 -298.975884) (xy 187.830396 -298.964024) (xy 187.883546 -298.960041)
			(xy 187.936696 -298.964024) (xy 187.988658 -298.975884) (xy 188.038272 -298.995356) (xy 188.08443 -299.022005)
			(xy 188.126101 -299.055236) (xy 188.162353 -299.094307) (xy 188.192377 -299.138344) (xy 188.215503 -299.186365)
			(xy 188.231213 -299.237295) (xy 188.239156 -299.289999) (xy 188.239654 -299.316648) (xy 188.239156 -299.343297)
			(xy 202.615536 -299.343297) (xy 202.615536 -299.289999) (xy 202.623479 -299.237295) (xy 202.639189 -299.186365)
			(xy 202.662315 -299.138344) (xy 202.692339 -299.094307) (xy 202.728591 -299.055236) (xy 202.770262 -299.022005)
			(xy 202.81642 -298.995356) (xy 202.866034 -298.975884) (xy 202.917996 -298.964024) (xy 202.971146 -298.960041)
			(xy 203.024296 -298.964024) (xy 203.076258 -298.975884) (xy 203.125872 -298.995356) (xy 203.17203 -299.022005)
			(xy 203.213701 -299.055236) (xy 203.249953 -299.094307) (xy 203.279977 -299.138344) (xy 203.303103 -299.186365)
			(xy 203.318813 -299.237295) (xy 203.326756 -299.289999) (xy 203.327254 -299.316648) (xy 203.326756 -299.343297)
			(xy 203.318813 -299.396001) (xy 203.303103 -299.446931) (xy 203.279977 -299.494952) (xy 203.249953 -299.538989)
			(xy 203.213701 -299.57806) (xy 203.17203 -299.611291) (xy 203.125872 -299.63794) (xy 203.076258 -299.657412)
			(xy 203.024296 -299.669272) (xy 202.971146 -299.673256) (xy 202.917996 -299.669272) (xy 202.866034 -299.657412)
			(xy 202.81642 -299.63794) (xy 202.770262 -299.611291) (xy 202.728591 -299.57806) (xy 202.692339 -299.538989)
			(xy 202.662315 -299.494952) (xy 202.639189 -299.446931) (xy 202.623479 -299.396001) (xy 202.615536 -299.343297)
			(xy 188.239156 -299.343297) (xy 188.231213 -299.396001) (xy 188.215503 -299.446931) (xy 188.192377 -299.494952)
			(xy 188.162353 -299.538989) (xy 188.126101 -299.57806) (xy 188.08443 -299.611291) (xy 188.038272 -299.63794)
			(xy 187.988658 -299.657412) (xy 187.936696 -299.669272) (xy 187.883546 -299.673256) (xy 187.830396 -299.669272)
			(xy 187.778434 -299.657412) (xy 187.72882 -299.63794) (xy 187.682662 -299.611291) (xy 187.640991 -299.57806)
			(xy 187.604739 -299.538989) (xy 187.574715 -299.494952) (xy 187.551589 -299.446931) (xy 187.535879 -299.396001)
			(xy 187.527936 -299.343297) (xy 173.151556 -299.343297) (xy 173.143613 -299.396001) (xy 173.127903 -299.446931)
			(xy 173.104777 -299.494952) (xy 173.074753 -299.538989) (xy 173.038501 -299.57806) (xy 172.99683 -299.611291)
			(xy 172.950672 -299.63794) (xy 172.901058 -299.657412) (xy 172.849096 -299.669272) (xy 172.795946 -299.673256)
			(xy 172.742796 -299.669272) (xy 172.690834 -299.657412) (xy 172.64122 -299.63794) (xy 172.595062 -299.611291)
			(xy 172.553391 -299.57806) (xy 172.517139 -299.538989) (xy 172.487115 -299.494952) (xy 172.463989 -299.446931)
			(xy 172.448279 -299.396001) (xy 172.440336 -299.343297) (xy 159.11576 -299.343297) (xy 159.11576 -300.193435)
			(xy 161.427404 -300.193435) (xy 161.427404 -300.140137) (xy 161.435347 -300.087433) (xy 161.451057 -300.036503)
			(xy 161.474183 -299.988482) (xy 161.504207 -299.944445) (xy 161.540459 -299.905374) (xy 161.58213 -299.872143)
			(xy 161.628288 -299.845494) (xy 161.677902 -299.826022) (xy 161.729864 -299.814162) (xy 161.783014 -299.810179)
			(xy 161.836164 -299.814162) (xy 161.888126 -299.826022) (xy 161.93774 -299.845494) (xy 161.983898 -299.872143)
			(xy 162.025569 -299.905374) (xy 162.061821 -299.944445) (xy 162.091845 -299.988482) (xy 162.114971 -300.036503)
			(xy 162.130681 -300.087433) (xy 162.138624 -300.140137) (xy 162.139122 -300.166786) (xy 162.138629 -300.193181)
			(xy 176.540404 -300.193181) (xy 176.540404 -300.139883) (xy 176.548347 -300.087179) (xy 176.564057 -300.036249)
			(xy 176.587183 -299.988228) (xy 176.617207 -299.944191) (xy 176.653459 -299.90512) (xy 176.69513 -299.871889)
			(xy 176.741288 -299.84524) (xy 176.790902 -299.825768) (xy 176.842864 -299.813908) (xy 176.896014 -299.809925)
			(xy 176.949164 -299.813908) (xy 177.001126 -299.825768) (xy 177.05074 -299.84524) (xy 177.096898 -299.871889)
			(xy 177.138569 -299.90512) (xy 177.174821 -299.944191) (xy 177.204845 -299.988228) (xy 177.227971 -300.036249)
			(xy 177.243681 -300.087179) (xy 177.251624 -300.139883) (xy 177.252122 -300.166532) (xy 177.251624 -300.193181)
			(xy 177.251586 -300.193435) (xy 191.586094 -300.193435) (xy 191.586094 -300.140137) (xy 191.594037 -300.087433)
			(xy 191.609747 -300.036503) (xy 191.632873 -299.988482) (xy 191.662897 -299.944445) (xy 191.699149 -299.905374)
			(xy 191.74082 -299.872143) (xy 191.786978 -299.845494) (xy 191.836592 -299.826022) (xy 191.888554 -299.814162)
			(xy 191.941704 -299.810179) (xy 191.994854 -299.814162) (xy 192.046816 -299.826022) (xy 192.09643 -299.845494)
			(xy 192.142588 -299.872143) (xy 192.184259 -299.905374) (xy 192.220511 -299.944445) (xy 192.250535 -299.988482)
			(xy 192.273661 -300.036503) (xy 192.289371 -300.087433) (xy 192.297314 -300.140137) (xy 192.297812 -300.166786)
			(xy 192.297319 -300.193181) (xy 206.715604 -300.193181) (xy 206.715604 -300.139883) (xy 206.723547 -300.087179)
			(xy 206.739257 -300.036249) (xy 206.762383 -299.988228) (xy 206.792407 -299.944191) (xy 206.828659 -299.90512)
			(xy 206.87033 -299.871889) (xy 206.916488 -299.84524) (xy 206.966102 -299.825768) (xy 207.018064 -299.813908)
			(xy 207.071214 -299.809925) (xy 207.124364 -299.813908) (xy 207.176326 -299.825768) (xy 207.22594 -299.84524)
			(xy 207.272098 -299.871889) (xy 207.313769 -299.90512) (xy 207.350021 -299.944191) (xy 207.380045 -299.988228)
			(xy 207.403171 -300.036249) (xy 207.418881 -300.087179) (xy 207.426824 -300.139883) (xy 207.427322 -300.166532)
			(xy 207.426824 -300.193181) (xy 207.418881 -300.245885) (xy 207.403171 -300.296815) (xy 207.380045 -300.344836)
			(xy 207.350021 -300.388873) (xy 207.313769 -300.427944) (xy 207.272098 -300.461175) (xy 207.22594 -300.487824)
			(xy 207.176326 -300.507296) (xy 207.124364 -300.519156) (xy 207.071214 -300.52314) (xy 207.018064 -300.519156)
			(xy 206.966102 -300.507296) (xy 206.916488 -300.487824) (xy 206.87033 -300.461175) (xy 206.828659 -300.427944)
			(xy 206.792407 -300.388873) (xy 206.762383 -300.344836) (xy 206.739257 -300.296815) (xy 206.723547 -300.245885)
			(xy 206.715604 -300.193181) (xy 192.297319 -300.193181) (xy 192.297314 -300.193435) (xy 192.289371 -300.246139)
			(xy 192.273661 -300.297069) (xy 192.250535 -300.34509) (xy 192.220511 -300.389127) (xy 192.184259 -300.428198)
			(xy 192.142588 -300.461429) (xy 192.09643 -300.488078) (xy 192.046816 -300.50755) (xy 191.994854 -300.51941)
			(xy 191.941704 -300.523394) (xy 191.888554 -300.51941) (xy 191.836592 -300.50755) (xy 191.786978 -300.488078)
			(xy 191.74082 -300.461429) (xy 191.699149 -300.428198) (xy 191.662897 -300.389127) (xy 191.632873 -300.34509)
			(xy 191.609747 -300.297069) (xy 191.594037 -300.246139) (xy 191.586094 -300.193435) (xy 177.251586 -300.193435)
			(xy 177.243681 -300.245885) (xy 177.227971 -300.296815) (xy 177.204845 -300.344836) (xy 177.174821 -300.388873)
			(xy 177.138569 -300.427944) (xy 177.096898 -300.461175) (xy 177.05074 -300.487824) (xy 177.001126 -300.507296)
			(xy 176.949164 -300.519156) (xy 176.896014 -300.52314) (xy 176.842864 -300.519156) (xy 176.790902 -300.507296)
			(xy 176.741288 -300.487824) (xy 176.69513 -300.461175) (xy 176.653459 -300.427944) (xy 176.617207 -300.388873)
			(xy 176.587183 -300.344836) (xy 176.564057 -300.296815) (xy 176.548347 -300.245885) (xy 176.540404 -300.193181)
			(xy 162.138629 -300.193181) (xy 162.138624 -300.193435) (xy 162.130681 -300.246139) (xy 162.114971 -300.297069)
			(xy 162.091845 -300.34509) (xy 162.061821 -300.389127) (xy 162.025569 -300.428198) (xy 161.983898 -300.461429)
			(xy 161.93774 -300.488078) (xy 161.888126 -300.50755) (xy 161.836164 -300.51941) (xy 161.783014 -300.523394)
			(xy 161.729864 -300.51941) (xy 161.677902 -300.50755) (xy 161.628288 -300.488078) (xy 161.58213 -300.461429)
			(xy 161.540459 -300.428198) (xy 161.504207 -300.389127) (xy 161.474183 -300.34509) (xy 161.451057 -300.297069)
			(xy 161.435347 -300.246139) (xy 161.427404 -300.193435) (xy 159.11576 -300.193435) (xy 159.11576 -301.043319)
			(xy 172.440336 -301.043319) (xy 172.440336 -300.990021) (xy 172.448279 -300.937317) (xy 172.463989 -300.886387)
			(xy 172.487115 -300.838366) (xy 172.517139 -300.794329) (xy 172.553391 -300.755258) (xy 172.595062 -300.722027)
			(xy 172.64122 -300.695378) (xy 172.690834 -300.675906) (xy 172.742796 -300.664046) (xy 172.795946 -300.660063)
			(xy 172.849096 -300.664046) (xy 172.901058 -300.675906) (xy 172.950672 -300.695378) (xy 172.99683 -300.722027)
			(xy 173.038501 -300.755258) (xy 173.074753 -300.794329) (xy 173.104777 -300.838366) (xy 173.127903 -300.886387)
			(xy 173.143613 -300.937317) (xy 173.151556 -300.990021) (xy 173.152054 -301.01667) (xy 173.151556 -301.043319)
			(xy 187.527936 -301.043319) (xy 187.527936 -300.990021) (xy 187.535879 -300.937317) (xy 187.551589 -300.886387)
			(xy 187.574715 -300.838366) (xy 187.604739 -300.794329) (xy 187.640991 -300.755258) (xy 187.682662 -300.722027)
			(xy 187.72882 -300.695378) (xy 187.778434 -300.675906) (xy 187.830396 -300.664046) (xy 187.883546 -300.660063)
			(xy 187.936696 -300.664046) (xy 187.988658 -300.675906) (xy 188.038272 -300.695378) (xy 188.08443 -300.722027)
			(xy 188.126101 -300.755258) (xy 188.162353 -300.794329) (xy 188.192377 -300.838366) (xy 188.215503 -300.886387)
			(xy 188.231213 -300.937317) (xy 188.239156 -300.990021) (xy 188.239654 -301.01667) (xy 188.239156 -301.043319)
			(xy 202.615536 -301.043319) (xy 202.615536 -300.990021) (xy 202.623479 -300.937317) (xy 202.639189 -300.886387)
			(xy 202.662315 -300.838366) (xy 202.692339 -300.794329) (xy 202.728591 -300.755258) (xy 202.770262 -300.722027)
			(xy 202.81642 -300.695378) (xy 202.866034 -300.675906) (xy 202.917996 -300.664046) (xy 202.971146 -300.660063)
			(xy 203.024296 -300.664046) (xy 203.076258 -300.675906) (xy 203.125872 -300.695378) (xy 203.17203 -300.722027)
			(xy 203.213701 -300.755258) (xy 203.249953 -300.794329) (xy 203.279977 -300.838366) (xy 203.303103 -300.886387)
			(xy 203.318813 -300.937317) (xy 203.326756 -300.990021) (xy 203.327254 -301.01667) (xy 203.326756 -301.043319)
			(xy 203.318813 -301.096023) (xy 203.303103 -301.146953) (xy 203.279977 -301.194974) (xy 203.249953 -301.239011)
			(xy 203.213701 -301.278082) (xy 203.17203 -301.311313) (xy 203.125872 -301.337962) (xy 203.076258 -301.357434)
			(xy 203.024296 -301.369294) (xy 202.971146 -301.373278) (xy 202.917996 -301.369294) (xy 202.866034 -301.357434)
			(xy 202.81642 -301.337962) (xy 202.770262 -301.311313) (xy 202.728591 -301.278082) (xy 202.692339 -301.239011)
			(xy 202.662315 -301.194974) (xy 202.639189 -301.146953) (xy 202.623479 -301.096023) (xy 202.615536 -301.043319)
			(xy 188.239156 -301.043319) (xy 188.231213 -301.096023) (xy 188.215503 -301.146953) (xy 188.192377 -301.194974)
			(xy 188.162353 -301.239011) (xy 188.126101 -301.278082) (xy 188.08443 -301.311313) (xy 188.038272 -301.337962)
			(xy 187.988658 -301.357434) (xy 187.936696 -301.369294) (xy 187.883546 -301.373278) (xy 187.830396 -301.369294)
			(xy 187.778434 -301.357434) (xy 187.72882 -301.337962) (xy 187.682662 -301.311313) (xy 187.640991 -301.278082)
			(xy 187.604739 -301.239011) (xy 187.574715 -301.194974) (xy 187.551589 -301.146953) (xy 187.535879 -301.096023)
			(xy 187.527936 -301.043319) (xy 173.151556 -301.043319) (xy 173.143613 -301.096023) (xy 173.127903 -301.146953)
			(xy 173.104777 -301.194974) (xy 173.074753 -301.239011) (xy 173.038501 -301.278082) (xy 172.99683 -301.311313)
			(xy 172.950672 -301.337962) (xy 172.901058 -301.357434) (xy 172.849096 -301.369294) (xy 172.795946 -301.373278)
			(xy 172.742796 -301.369294) (xy 172.690834 -301.357434) (xy 172.64122 -301.337962) (xy 172.595062 -301.311313)
			(xy 172.553391 -301.278082) (xy 172.517139 -301.239011) (xy 172.487115 -301.194974) (xy 172.463989 -301.146953)
			(xy 172.448279 -301.096023) (xy 172.440336 -301.043319) (xy 159.11576 -301.043319) (xy 159.11576 -301.893203)
			(xy 161.427404 -301.893203) (xy 161.427404 -301.839905) (xy 161.435347 -301.787201) (xy 161.451057 -301.736271)
			(xy 161.474183 -301.68825) (xy 161.504207 -301.644213) (xy 161.540459 -301.605142) (xy 161.58213 -301.571911)
			(xy 161.628288 -301.545262) (xy 161.677902 -301.52579) (xy 161.729864 -301.51393) (xy 161.783014 -301.509947)
			(xy 161.836164 -301.51393) (xy 161.888126 -301.52579) (xy 161.93774 -301.545262) (xy 161.983898 -301.571911)
			(xy 162.025569 -301.605142) (xy 162.061821 -301.644213) (xy 162.091845 -301.68825) (xy 162.114971 -301.736271)
			(xy 162.130681 -301.787201) (xy 162.138624 -301.839905) (xy 162.139122 -301.866554) (xy 162.138624 -301.893203)
			(xy 176.540404 -301.893203) (xy 176.540404 -301.839905) (xy 176.548347 -301.787201) (xy 176.564057 -301.736271)
			(xy 176.587183 -301.68825) (xy 176.617207 -301.644213) (xy 176.653459 -301.605142) (xy 176.69513 -301.571911)
			(xy 176.741288 -301.545262) (xy 176.790902 -301.52579) (xy 176.842864 -301.51393) (xy 176.896014 -301.509947)
			(xy 176.949164 -301.51393) (xy 177.001126 -301.52579) (xy 177.05074 -301.545262) (xy 177.096898 -301.571911)
			(xy 177.138569 -301.605142) (xy 177.174821 -301.644213) (xy 177.204845 -301.68825) (xy 177.227971 -301.736271)
			(xy 177.243681 -301.787201) (xy 177.251624 -301.839905) (xy 177.252122 -301.866554) (xy 177.251624 -301.893203)
			(xy 177.251586 -301.893457) (xy 191.586094 -301.893457) (xy 191.586094 -301.840159) (xy 191.594037 -301.787455)
			(xy 191.609747 -301.736525) (xy 191.632873 -301.688504) (xy 191.662897 -301.644467) (xy 191.699149 -301.605396)
			(xy 191.74082 -301.572165) (xy 191.786978 -301.545516) (xy 191.836592 -301.526044) (xy 191.888554 -301.514184)
			(xy 191.941704 -301.510201) (xy 191.994854 -301.514184) (xy 192.046816 -301.526044) (xy 192.09643 -301.545516)
			(xy 192.142588 -301.572165) (xy 192.184259 -301.605396) (xy 192.220511 -301.644467) (xy 192.250535 -301.688504)
			(xy 192.273661 -301.736525) (xy 192.289371 -301.787455) (xy 192.297314 -301.840159) (xy 192.297812 -301.866808)
			(xy 192.297319 -301.893203) (xy 206.715604 -301.893203) (xy 206.715604 -301.839905) (xy 206.723547 -301.787201)
			(xy 206.739257 -301.736271) (xy 206.762383 -301.68825) (xy 206.792407 -301.644213) (xy 206.828659 -301.605142)
			(xy 206.87033 -301.571911) (xy 206.916488 -301.545262) (xy 206.966102 -301.52579) (xy 207.018064 -301.51393)
			(xy 207.071214 -301.509947) (xy 207.124364 -301.51393) (xy 207.176326 -301.52579) (xy 207.22594 -301.545262)
			(xy 207.272098 -301.571911) (xy 207.313769 -301.605142) (xy 207.350021 -301.644213) (xy 207.380045 -301.68825)
			(xy 207.403171 -301.736271) (xy 207.418881 -301.787201) (xy 207.426824 -301.839905) (xy 207.427322 -301.866554)
			(xy 207.426824 -301.893203) (xy 207.418881 -301.945907) (xy 207.403171 -301.996837) (xy 207.380045 -302.044858)
			(xy 207.350021 -302.088895) (xy 207.313769 -302.127966) (xy 207.272098 -302.161197) (xy 207.22594 -302.187846)
			(xy 207.176326 -302.207318) (xy 207.124364 -302.219178) (xy 207.071214 -302.223162) (xy 207.018064 -302.219178)
			(xy 206.966102 -302.207318) (xy 206.916488 -302.187846) (xy 206.87033 -302.161197) (xy 206.828659 -302.127966)
			(xy 206.792407 -302.088895) (xy 206.762383 -302.044858) (xy 206.739257 -301.996837) (xy 206.723547 -301.945907)
			(xy 206.715604 -301.893203) (xy 192.297319 -301.893203) (xy 192.297314 -301.893457) (xy 192.289371 -301.946161)
			(xy 192.273661 -301.997091) (xy 192.250535 -302.045112) (xy 192.220511 -302.089149) (xy 192.184259 -302.12822)
			(xy 192.142588 -302.161451) (xy 192.09643 -302.1881) (xy 192.046816 -302.207572) (xy 191.994854 -302.219432)
			(xy 191.941704 -302.223416) (xy 191.888554 -302.219432) (xy 191.836592 -302.207572) (xy 191.786978 -302.1881)
			(xy 191.74082 -302.161451) (xy 191.699149 -302.12822) (xy 191.662897 -302.089149) (xy 191.632873 -302.045112)
			(xy 191.609747 -301.997091) (xy 191.594037 -301.946161) (xy 191.586094 -301.893457) (xy 177.251586 -301.893457)
			(xy 177.243681 -301.945907) (xy 177.227971 -301.996837) (xy 177.204845 -302.044858) (xy 177.174821 -302.088895)
			(xy 177.138569 -302.127966) (xy 177.096898 -302.161197) (xy 177.05074 -302.187846) (xy 177.001126 -302.207318)
			(xy 176.949164 -302.219178) (xy 176.896014 -302.223162) (xy 176.842864 -302.219178) (xy 176.790902 -302.207318)
			(xy 176.741288 -302.187846) (xy 176.69513 -302.161197) (xy 176.653459 -302.127966) (xy 176.617207 -302.088895)
			(xy 176.587183 -302.044858) (xy 176.564057 -301.996837) (xy 176.548347 -301.945907) (xy 176.540404 -301.893203)
			(xy 162.138624 -301.893203) (xy 162.130681 -301.945907) (xy 162.114971 -301.996837) (xy 162.091845 -302.044858)
			(xy 162.061821 -302.088895) (xy 162.025569 -302.127966) (xy 161.983898 -302.161197) (xy 161.93774 -302.187846)
			(xy 161.888126 -302.207318) (xy 161.836164 -302.219178) (xy 161.783014 -302.223162) (xy 161.729864 -302.219178)
			(xy 161.677902 -302.207318) (xy 161.628288 -302.187846) (xy 161.58213 -302.161197) (xy 161.540459 -302.127966)
			(xy 161.504207 -302.088895) (xy 161.474183 -302.044858) (xy 161.451057 -301.996837) (xy 161.435347 -301.945907)
			(xy 161.427404 -301.893203) (xy 159.11576 -301.893203) (xy 159.11576 -302.743341) (xy 161.427404 -302.743341)
			(xy 161.427404 -302.690043) (xy 161.435347 -302.637339) (xy 161.451057 -302.586409) (xy 161.474183 -302.538388)
			(xy 161.504207 -302.494351) (xy 161.540459 -302.45528) (xy 161.58213 -302.422049) (xy 161.628288 -302.3954)
			(xy 161.677902 -302.375928) (xy 161.729864 -302.364068) (xy 161.783014 -302.360085) (xy 161.836164 -302.364068)
			(xy 161.888126 -302.375928) (xy 161.93774 -302.3954) (xy 161.983898 -302.422049) (xy 162.025569 -302.45528)
			(xy 162.061821 -302.494351) (xy 162.091845 -302.538388) (xy 162.114971 -302.586409) (xy 162.130681 -302.637339)
			(xy 162.138624 -302.690043) (xy 162.139122 -302.716692) (xy 162.138624 -302.743341) (xy 172.440336 -302.743341)
			(xy 172.440336 -302.690043) (xy 172.448279 -302.637339) (xy 172.463989 -302.586409) (xy 172.487115 -302.538388)
			(xy 172.517139 -302.494351) (xy 172.553391 -302.45528) (xy 172.595062 -302.422049) (xy 172.64122 -302.3954)
			(xy 172.690834 -302.375928) (xy 172.742796 -302.364068) (xy 172.795946 -302.360085) (xy 172.849096 -302.364068)
			(xy 172.901058 -302.375928) (xy 172.950672 -302.3954) (xy 172.99683 -302.422049) (xy 173.038501 -302.45528)
			(xy 173.074753 -302.494351) (xy 173.104777 -302.538388) (xy 173.127903 -302.586409) (xy 173.143613 -302.637339)
			(xy 173.151556 -302.690043) (xy 173.152054 -302.716692) (xy 173.151556 -302.743341) (xy 176.540404 -302.743341)
			(xy 176.540404 -302.690043) (xy 176.548347 -302.637339) (xy 176.564057 -302.586409) (xy 176.587183 -302.538388)
			(xy 176.617207 -302.494351) (xy 176.653459 -302.45528) (xy 176.69513 -302.422049) (xy 176.741288 -302.3954)
			(xy 176.790902 -302.375928) (xy 176.842864 -302.364068) (xy 176.896014 -302.360085) (xy 176.949164 -302.364068)
			(xy 177.001126 -302.375928) (xy 177.05074 -302.3954) (xy 177.096898 -302.422049) (xy 177.138569 -302.45528)
			(xy 177.174821 -302.494351) (xy 177.204845 -302.538388) (xy 177.227971 -302.586409) (xy 177.243681 -302.637339)
			(xy 177.251624 -302.690043) (xy 177.252122 -302.716692) (xy 177.251624 -302.743341) (xy 187.527936 -302.743341)
			(xy 187.527936 -302.690043) (xy 187.535879 -302.637339) (xy 187.551589 -302.586409) (xy 187.574715 -302.538388)
			(xy 187.604739 -302.494351) (xy 187.640991 -302.45528) (xy 187.682662 -302.422049) (xy 187.72882 -302.3954)
			(xy 187.778434 -302.375928) (xy 187.830396 -302.364068) (xy 187.883546 -302.360085) (xy 187.936696 -302.364068)
			(xy 187.988658 -302.375928) (xy 188.038272 -302.3954) (xy 188.08443 -302.422049) (xy 188.126101 -302.45528)
			(xy 188.162353 -302.494351) (xy 188.192377 -302.538388) (xy 188.215503 -302.586409) (xy 188.231213 -302.637339)
			(xy 188.239156 -302.690043) (xy 188.239654 -302.716692) (xy 188.239156 -302.743341) (xy 191.628004 -302.743341)
			(xy 191.628004 -302.690043) (xy 191.635947 -302.637339) (xy 191.651657 -302.586409) (xy 191.674783 -302.538388)
			(xy 191.704807 -302.494351) (xy 191.741059 -302.45528) (xy 191.78273 -302.422049) (xy 191.828888 -302.3954)
			(xy 191.878502 -302.375928) (xy 191.930464 -302.364068) (xy 191.983614 -302.360085) (xy 192.036764 -302.364068)
			(xy 192.088726 -302.375928) (xy 192.13834 -302.3954) (xy 192.184498 -302.422049) (xy 192.226169 -302.45528)
			(xy 192.262421 -302.494351) (xy 192.292445 -302.538388) (xy 192.315571 -302.586409) (xy 192.331281 -302.637339)
			(xy 192.339224 -302.690043) (xy 192.339722 -302.716692) (xy 192.339224 -302.743341) (xy 202.615536 -302.743341)
			(xy 202.615536 -302.690043) (xy 202.623479 -302.637339) (xy 202.639189 -302.586409) (xy 202.662315 -302.538388)
			(xy 202.692339 -302.494351) (xy 202.728591 -302.45528) (xy 202.770262 -302.422049) (xy 202.81642 -302.3954)
			(xy 202.866034 -302.375928) (xy 202.917996 -302.364068) (xy 202.971146 -302.360085) (xy 203.024296 -302.364068)
			(xy 203.076258 -302.375928) (xy 203.125872 -302.3954) (xy 203.17203 -302.422049) (xy 203.213701 -302.45528)
			(xy 203.249953 -302.494351) (xy 203.279977 -302.538388) (xy 203.303103 -302.586409) (xy 203.318813 -302.637339)
			(xy 203.326756 -302.690043) (xy 203.327254 -302.716692) (xy 203.326756 -302.743341) (xy 206.715604 -302.743341)
			(xy 206.715604 -302.690043) (xy 206.723547 -302.637339) (xy 206.739257 -302.586409) (xy 206.762383 -302.538388)
			(xy 206.792407 -302.494351) (xy 206.828659 -302.45528) (xy 206.87033 -302.422049) (xy 206.916488 -302.3954)
			(xy 206.966102 -302.375928) (xy 207.018064 -302.364068) (xy 207.071214 -302.360085) (xy 207.124364 -302.364068)
			(xy 207.176326 -302.375928) (xy 207.22594 -302.3954) (xy 207.272098 -302.422049) (xy 207.313769 -302.45528)
			(xy 207.350021 -302.494351) (xy 207.380045 -302.538388) (xy 207.403171 -302.586409) (xy 207.418881 -302.637339)
			(xy 207.426824 -302.690043) (xy 207.427322 -302.716692) (xy 207.426824 -302.743341) (xy 207.418881 -302.796045)
			(xy 207.403171 -302.846975) (xy 207.380045 -302.894996) (xy 207.350021 -302.939033) (xy 207.313769 -302.978104)
			(xy 207.272098 -303.011335) (xy 207.22594 -303.037984) (xy 207.176326 -303.057456) (xy 207.124364 -303.069316)
			(xy 207.071214 -303.0733) (xy 207.018064 -303.069316) (xy 206.966102 -303.057456) (xy 206.916488 -303.037984)
			(xy 206.87033 -303.011335) (xy 206.828659 -302.978104) (xy 206.792407 -302.939033) (xy 206.762383 -302.894996)
			(xy 206.739257 -302.846975) (xy 206.723547 -302.796045) (xy 206.715604 -302.743341) (xy 203.326756 -302.743341)
			(xy 203.318813 -302.796045) (xy 203.303103 -302.846975) (xy 203.279977 -302.894996) (xy 203.249953 -302.939033)
			(xy 203.213701 -302.978104) (xy 203.17203 -303.011335) (xy 203.125872 -303.037984) (xy 203.076258 -303.057456)
			(xy 203.024296 -303.069316) (xy 202.971146 -303.0733) (xy 202.917996 -303.069316) (xy 202.866034 -303.057456)
			(xy 202.81642 -303.037984) (xy 202.770262 -303.011335) (xy 202.728591 -302.978104) (xy 202.692339 -302.939033)
			(xy 202.662315 -302.894996) (xy 202.639189 -302.846975) (xy 202.623479 -302.796045) (xy 202.615536 -302.743341)
			(xy 192.339224 -302.743341) (xy 192.331281 -302.796045) (xy 192.315571 -302.846975) (xy 192.292445 -302.894996)
			(xy 192.262421 -302.939033) (xy 192.226169 -302.978104) (xy 192.184498 -303.011335) (xy 192.13834 -303.037984)
			(xy 192.088726 -303.057456) (xy 192.036764 -303.069316) (xy 191.983614 -303.0733) (xy 191.930464 -303.069316)
			(xy 191.878502 -303.057456) (xy 191.828888 -303.037984) (xy 191.78273 -303.011335) (xy 191.741059 -302.978104)
			(xy 191.704807 -302.939033) (xy 191.674783 -302.894996) (xy 191.651657 -302.846975) (xy 191.635947 -302.796045)
			(xy 191.628004 -302.743341) (xy 188.239156 -302.743341) (xy 188.231213 -302.796045) (xy 188.215503 -302.846975)
			(xy 188.192377 -302.894996) (xy 188.162353 -302.939033) (xy 188.126101 -302.978104) (xy 188.08443 -303.011335)
			(xy 188.038272 -303.037984) (xy 187.988658 -303.057456) (xy 187.936696 -303.069316) (xy 187.883546 -303.0733)
			(xy 187.830396 -303.069316) (xy 187.778434 -303.057456) (xy 187.72882 -303.037984) (xy 187.682662 -303.011335)
			(xy 187.640991 -302.978104) (xy 187.604739 -302.939033) (xy 187.574715 -302.894996) (xy 187.551589 -302.846975)
			(xy 187.535879 -302.796045) (xy 187.527936 -302.743341) (xy 177.251624 -302.743341) (xy 177.243681 -302.796045)
			(xy 177.227971 -302.846975) (xy 177.204845 -302.894996) (xy 177.174821 -302.939033) (xy 177.138569 -302.978104)
			(xy 177.096898 -303.011335) (xy 177.05074 -303.037984) (xy 177.001126 -303.057456) (xy 176.949164 -303.069316)
			(xy 176.896014 -303.0733) (xy 176.842864 -303.069316) (xy 176.790902 -303.057456) (xy 176.741288 -303.037984)
			(xy 176.69513 -303.011335) (xy 176.653459 -302.978104) (xy 176.617207 -302.939033) (xy 176.587183 -302.894996)
			(xy 176.564057 -302.846975) (xy 176.548347 -302.796045) (xy 176.540404 -302.743341) (xy 173.151556 -302.743341)
			(xy 173.143613 -302.796045) (xy 173.127903 -302.846975) (xy 173.104777 -302.894996) (xy 173.074753 -302.939033)
			(xy 173.038501 -302.978104) (xy 172.99683 -303.011335) (xy 172.950672 -303.037984) (xy 172.901058 -303.057456)
			(xy 172.849096 -303.069316) (xy 172.795946 -303.0733) (xy 172.742796 -303.069316) (xy 172.690834 -303.057456)
			(xy 172.64122 -303.037984) (xy 172.595062 -303.011335) (xy 172.553391 -302.978104) (xy 172.517139 -302.939033)
			(xy 172.487115 -302.894996) (xy 172.463989 -302.846975) (xy 172.448279 -302.796045) (xy 172.440336 -302.743341)
			(xy 162.138624 -302.743341) (xy 162.130681 -302.796045) (xy 162.114971 -302.846975) (xy 162.091845 -302.894996)
			(xy 162.061821 -302.939033) (xy 162.025569 -302.978104) (xy 161.983898 -303.011335) (xy 161.93774 -303.037984)
			(xy 161.888126 -303.057456) (xy 161.836164 -303.069316) (xy 161.783014 -303.0733) (xy 161.729864 -303.069316)
			(xy 161.677902 -303.057456) (xy 161.628288 -303.037984) (xy 161.58213 -303.011335) (xy 161.540459 -302.978104)
			(xy 161.504207 -302.939033) (xy 161.474183 -302.894996) (xy 161.451057 -302.846975) (xy 161.435347 -302.796045)
			(xy 161.427404 -302.743341) (xy 159.11576 -302.743341) (xy 159.11576 -303.593225) (xy 172.440336 -303.593225)
			(xy 172.440336 -303.539927) (xy 172.448279 -303.487223) (xy 172.463989 -303.436293) (xy 172.487115 -303.388272)
			(xy 172.517139 -303.344235) (xy 172.553391 -303.305164) (xy 172.595062 -303.271933) (xy 172.64122 -303.245284)
			(xy 172.690834 -303.225812) (xy 172.742796 -303.213952) (xy 172.795946 -303.209969) (xy 172.849096 -303.213952)
			(xy 172.901058 -303.225812) (xy 172.950672 -303.245284) (xy 172.99683 -303.271933) (xy 173.038501 -303.305164)
			(xy 173.074753 -303.344235) (xy 173.104777 -303.388272) (xy 173.127903 -303.436293) (xy 173.143613 -303.487223)
			(xy 173.151556 -303.539927) (xy 173.152054 -303.566576) (xy 173.151556 -303.593225) (xy 187.527936 -303.593225)
			(xy 187.527936 -303.539927) (xy 187.535879 -303.487223) (xy 187.551589 -303.436293) (xy 187.574715 -303.388272)
			(xy 187.604739 -303.344235) (xy 187.640991 -303.305164) (xy 187.682662 -303.271933) (xy 187.72882 -303.245284)
			(xy 187.778434 -303.225812) (xy 187.830396 -303.213952) (xy 187.883546 -303.209969) (xy 187.936696 -303.213952)
			(xy 187.988658 -303.225812) (xy 188.038272 -303.245284) (xy 188.08443 -303.271933) (xy 188.126101 -303.305164)
			(xy 188.162353 -303.344235) (xy 188.192377 -303.388272) (xy 188.215503 -303.436293) (xy 188.231213 -303.487223)
			(xy 188.239156 -303.539927) (xy 188.239654 -303.566576) (xy 188.239156 -303.593225) (xy 202.615536 -303.593225)
			(xy 202.615536 -303.539927) (xy 202.623479 -303.487223) (xy 202.639189 -303.436293) (xy 202.662315 -303.388272)
			(xy 202.692339 -303.344235) (xy 202.728591 -303.305164) (xy 202.770262 -303.271933) (xy 202.81642 -303.245284)
			(xy 202.866034 -303.225812) (xy 202.917996 -303.213952) (xy 202.971146 -303.209969) (xy 203.024296 -303.213952)
			(xy 203.076258 -303.225812) (xy 203.125872 -303.245284) (xy 203.17203 -303.271933) (xy 203.213701 -303.305164)
			(xy 203.249953 -303.344235) (xy 203.279977 -303.388272) (xy 203.303103 -303.436293) (xy 203.318813 -303.487223)
			(xy 203.326756 -303.539927) (xy 203.327254 -303.566576) (xy 203.326756 -303.593225) (xy 203.318813 -303.645929)
			(xy 203.303103 -303.696859) (xy 203.279977 -303.74488) (xy 203.249953 -303.788917) (xy 203.213701 -303.827988)
			(xy 203.17203 -303.861219) (xy 203.125872 -303.887868) (xy 203.076258 -303.90734) (xy 203.024296 -303.9192)
			(xy 202.971146 -303.923184) (xy 202.917996 -303.9192) (xy 202.866034 -303.90734) (xy 202.81642 -303.887868)
			(xy 202.770262 -303.861219) (xy 202.728591 -303.827988) (xy 202.692339 -303.788917) (xy 202.662315 -303.74488)
			(xy 202.639189 -303.696859) (xy 202.623479 -303.645929) (xy 202.615536 -303.593225) (xy 188.239156 -303.593225)
			(xy 188.231213 -303.645929) (xy 188.215503 -303.696859) (xy 188.192377 -303.74488) (xy 188.162353 -303.788917)
			(xy 188.126101 -303.827988) (xy 188.08443 -303.861219) (xy 188.038272 -303.887868) (xy 187.988658 -303.90734)
			(xy 187.936696 -303.9192) (xy 187.883546 -303.923184) (xy 187.830396 -303.9192) (xy 187.778434 -303.90734)
			(xy 187.72882 -303.887868) (xy 187.682662 -303.861219) (xy 187.640991 -303.827988) (xy 187.604739 -303.788917)
			(xy 187.574715 -303.74488) (xy 187.551589 -303.696859) (xy 187.535879 -303.645929) (xy 187.527936 -303.593225)
			(xy 173.151556 -303.593225) (xy 173.143613 -303.645929) (xy 173.127903 -303.696859) (xy 173.104777 -303.74488)
			(xy 173.074753 -303.788917) (xy 173.038501 -303.827988) (xy 172.99683 -303.861219) (xy 172.950672 -303.887868)
			(xy 172.901058 -303.90734) (xy 172.849096 -303.9192) (xy 172.795946 -303.923184) (xy 172.742796 -303.9192)
			(xy 172.690834 -303.90734) (xy 172.64122 -303.887868) (xy 172.595062 -303.861219) (xy 172.553391 -303.827988)
			(xy 172.517139 -303.788917) (xy 172.487115 -303.74488) (xy 172.463989 -303.696859) (xy 172.448279 -303.645929)
			(xy 172.440336 -303.593225) (xy 159.11576 -303.593225) (xy 159.11576 -304.443363) (xy 161.427404 -304.443363)
			(xy 161.427404 -304.390065) (xy 161.435347 -304.337361) (xy 161.451057 -304.286431) (xy 161.474183 -304.23841)
			(xy 161.504207 -304.194373) (xy 161.540459 -304.155302) (xy 161.58213 -304.122071) (xy 161.628288 -304.095422)
			(xy 161.677902 -304.07595) (xy 161.729864 -304.06409) (xy 161.783014 -304.060107) (xy 161.836164 -304.06409)
			(xy 161.888126 -304.07595) (xy 161.93774 -304.095422) (xy 161.983898 -304.122071) (xy 162.025569 -304.155302)
			(xy 162.061821 -304.194373) (xy 162.091845 -304.23841) (xy 162.114971 -304.286431) (xy 162.130681 -304.337361)
			(xy 162.138624 -304.390065) (xy 162.139122 -304.416714) (xy 162.138624 -304.443363) (xy 176.540404 -304.443363)
			(xy 176.540404 -304.390065) (xy 176.548347 -304.337361) (xy 176.564057 -304.286431) (xy 176.587183 -304.23841)
			(xy 176.617207 -304.194373) (xy 176.653459 -304.155302) (xy 176.69513 -304.122071) (xy 176.741288 -304.095422)
			(xy 176.790902 -304.07595) (xy 176.842864 -304.06409) (xy 176.896014 -304.060107) (xy 176.949164 -304.06409)
			(xy 177.001126 -304.07595) (xy 177.05074 -304.095422) (xy 177.096898 -304.122071) (xy 177.138569 -304.155302)
			(xy 177.174821 -304.194373) (xy 177.204845 -304.23841) (xy 177.227971 -304.286431) (xy 177.243681 -304.337361)
			(xy 177.251624 -304.390065) (xy 177.252122 -304.416714) (xy 177.251624 -304.443363) (xy 191.628004 -304.443363)
			(xy 191.628004 -304.390065) (xy 191.635947 -304.337361) (xy 191.651657 -304.286431) (xy 191.674783 -304.23841)
			(xy 191.704807 -304.194373) (xy 191.741059 -304.155302) (xy 191.78273 -304.122071) (xy 191.828888 -304.095422)
			(xy 191.878502 -304.07595) (xy 191.930464 -304.06409) (xy 191.983614 -304.060107) (xy 192.036764 -304.06409)
			(xy 192.088726 -304.07595) (xy 192.13834 -304.095422) (xy 192.184498 -304.122071) (xy 192.226169 -304.155302)
			(xy 192.262421 -304.194373) (xy 192.292445 -304.23841) (xy 192.315571 -304.286431) (xy 192.331281 -304.337361)
			(xy 192.339224 -304.390065) (xy 192.339722 -304.416714) (xy 192.339224 -304.443363) (xy 206.715604 -304.443363)
			(xy 206.715604 -304.390065) (xy 206.723547 -304.337361) (xy 206.739257 -304.286431) (xy 206.762383 -304.23841)
			(xy 206.792407 -304.194373) (xy 206.828659 -304.155302) (xy 206.87033 -304.122071) (xy 206.916488 -304.095422)
			(xy 206.966102 -304.07595) (xy 207.018064 -304.06409) (xy 207.071214 -304.060107) (xy 207.124364 -304.06409)
			(xy 207.176326 -304.07595) (xy 207.22594 -304.095422) (xy 207.272098 -304.122071) (xy 207.313769 -304.155302)
			(xy 207.350021 -304.194373) (xy 207.380045 -304.23841) (xy 207.403171 -304.286431) (xy 207.418881 -304.337361)
			(xy 207.426824 -304.390065) (xy 207.427322 -304.416714) (xy 207.426824 -304.443363) (xy 207.418881 -304.496067)
			(xy 207.403171 -304.546997) (xy 207.380045 -304.595018) (xy 207.350021 -304.639055) (xy 207.313769 -304.678126)
			(xy 207.272098 -304.711357) (xy 207.22594 -304.738006) (xy 207.176326 -304.757478) (xy 207.124364 -304.769338)
			(xy 207.071214 -304.773322) (xy 207.018064 -304.769338) (xy 206.966102 -304.757478) (xy 206.916488 -304.738006)
			(xy 206.87033 -304.711357) (xy 206.828659 -304.678126) (xy 206.792407 -304.639055) (xy 206.762383 -304.595018)
			(xy 206.739257 -304.546997) (xy 206.723547 -304.496067) (xy 206.715604 -304.443363) (xy 192.339224 -304.443363)
			(xy 192.331281 -304.496067) (xy 192.315571 -304.546997) (xy 192.292445 -304.595018) (xy 192.262421 -304.639055)
			(xy 192.226169 -304.678126) (xy 192.184498 -304.711357) (xy 192.13834 -304.738006) (xy 192.088726 -304.757478)
			(xy 192.036764 -304.769338) (xy 191.983614 -304.773322) (xy 191.930464 -304.769338) (xy 191.878502 -304.757478)
			(xy 191.828888 -304.738006) (xy 191.78273 -304.711357) (xy 191.741059 -304.678126) (xy 191.704807 -304.639055)
			(xy 191.674783 -304.595018) (xy 191.651657 -304.546997) (xy 191.635947 -304.496067) (xy 191.628004 -304.443363)
			(xy 177.251624 -304.443363) (xy 177.243681 -304.496067) (xy 177.227971 -304.546997) (xy 177.204845 -304.595018)
			(xy 177.174821 -304.639055) (xy 177.138569 -304.678126) (xy 177.096898 -304.711357) (xy 177.05074 -304.738006)
			(xy 177.001126 -304.757478) (xy 176.949164 -304.769338) (xy 176.896014 -304.773322) (xy 176.842864 -304.769338)
			(xy 176.790902 -304.757478) (xy 176.741288 -304.738006) (xy 176.69513 -304.711357) (xy 176.653459 -304.678126)
			(xy 176.617207 -304.639055) (xy 176.587183 -304.595018) (xy 176.564057 -304.546997) (xy 176.548347 -304.496067)
			(xy 176.540404 -304.443363) (xy 162.138624 -304.443363) (xy 162.130681 -304.496067) (xy 162.114971 -304.546997)
			(xy 162.091845 -304.595018) (xy 162.061821 -304.639055) (xy 162.025569 -304.678126) (xy 161.983898 -304.711357)
			(xy 161.93774 -304.738006) (xy 161.888126 -304.757478) (xy 161.836164 -304.769338) (xy 161.783014 -304.773322)
			(xy 161.729864 -304.769338) (xy 161.677902 -304.757478) (xy 161.628288 -304.738006) (xy 161.58213 -304.711357)
			(xy 161.540459 -304.678126) (xy 161.504207 -304.639055) (xy 161.474183 -304.595018) (xy 161.451057 -304.546997)
			(xy 161.435347 -304.496067) (xy 161.427404 -304.443363) (xy 159.11576 -304.443363) (xy 159.11576 -305.293247)
			(xy 172.440336 -305.293247) (xy 172.440336 -305.239949) (xy 172.448279 -305.187245) (xy 172.463989 -305.136315)
			(xy 172.487115 -305.088294) (xy 172.517139 -305.044257) (xy 172.553391 -305.005186) (xy 172.595062 -304.971955)
			(xy 172.64122 -304.945306) (xy 172.690834 -304.925834) (xy 172.742796 -304.913974) (xy 172.795946 -304.909991)
			(xy 172.849096 -304.913974) (xy 172.901058 -304.925834) (xy 172.950672 -304.945306) (xy 172.99683 -304.971955)
			(xy 173.038501 -305.005186) (xy 173.074753 -305.044257) (xy 173.104777 -305.088294) (xy 173.127903 -305.136315)
			(xy 173.143613 -305.187245) (xy 173.151556 -305.239949) (xy 173.152054 -305.266598) (xy 173.151556 -305.293247)
			(xy 187.527936 -305.293247) (xy 187.527936 -305.239949) (xy 187.535879 -305.187245) (xy 187.551589 -305.136315)
			(xy 187.574715 -305.088294) (xy 187.604739 -305.044257) (xy 187.640991 -305.005186) (xy 187.682662 -304.971955)
			(xy 187.72882 -304.945306) (xy 187.778434 -304.925834) (xy 187.830396 -304.913974) (xy 187.883546 -304.909991)
			(xy 187.936696 -304.913974) (xy 187.988658 -304.925834) (xy 188.038272 -304.945306) (xy 188.08443 -304.971955)
			(xy 188.126101 -305.005186) (xy 188.162353 -305.044257) (xy 188.192377 -305.088294) (xy 188.215503 -305.136315)
			(xy 188.231213 -305.187245) (xy 188.239156 -305.239949) (xy 188.239654 -305.266598) (xy 188.239156 -305.293247)
			(xy 202.615536 -305.293247) (xy 202.615536 -305.239949) (xy 202.623479 -305.187245) (xy 202.639189 -305.136315)
			(xy 202.662315 -305.088294) (xy 202.692339 -305.044257) (xy 202.728591 -305.005186) (xy 202.770262 -304.971955)
			(xy 202.81642 -304.945306) (xy 202.866034 -304.925834) (xy 202.917996 -304.913974) (xy 202.971146 -304.909991)
			(xy 203.024296 -304.913974) (xy 203.076258 -304.925834) (xy 203.125872 -304.945306) (xy 203.17203 -304.971955)
			(xy 203.213701 -305.005186) (xy 203.249953 -305.044257) (xy 203.279977 -305.088294) (xy 203.303103 -305.136315)
			(xy 203.318813 -305.187245) (xy 203.326756 -305.239949) (xy 203.327254 -305.266598) (xy 203.326756 -305.293247)
			(xy 203.318813 -305.345951) (xy 203.303103 -305.396881) (xy 203.279977 -305.444902) (xy 203.249953 -305.488939)
			(xy 203.213701 -305.52801) (xy 203.17203 -305.561241) (xy 203.125872 -305.58789) (xy 203.076258 -305.607362)
			(xy 203.024296 -305.619222) (xy 202.971146 -305.623206) (xy 202.917996 -305.619222) (xy 202.866034 -305.607362)
			(xy 202.81642 -305.58789) (xy 202.770262 -305.561241) (xy 202.728591 -305.52801) (xy 202.692339 -305.488939)
			(xy 202.662315 -305.444902) (xy 202.639189 -305.396881) (xy 202.623479 -305.345951) (xy 202.615536 -305.293247)
			(xy 188.239156 -305.293247) (xy 188.231213 -305.345951) (xy 188.215503 -305.396881) (xy 188.192377 -305.444902)
			(xy 188.162353 -305.488939) (xy 188.126101 -305.52801) (xy 188.08443 -305.561241) (xy 188.038272 -305.58789)
			(xy 187.988658 -305.607362) (xy 187.936696 -305.619222) (xy 187.883546 -305.623206) (xy 187.830396 -305.619222)
			(xy 187.778434 -305.607362) (xy 187.72882 -305.58789) (xy 187.682662 -305.561241) (xy 187.640991 -305.52801)
			(xy 187.604739 -305.488939) (xy 187.574715 -305.444902) (xy 187.551589 -305.396881) (xy 187.535879 -305.345951)
			(xy 187.527936 -305.293247) (xy 173.151556 -305.293247) (xy 173.143613 -305.345951) (xy 173.127903 -305.396881)
			(xy 173.104777 -305.444902) (xy 173.074753 -305.488939) (xy 173.038501 -305.52801) (xy 172.99683 -305.561241)
			(xy 172.950672 -305.58789) (xy 172.901058 -305.607362) (xy 172.849096 -305.619222) (xy 172.795946 -305.623206)
			(xy 172.742796 -305.619222) (xy 172.690834 -305.607362) (xy 172.64122 -305.58789) (xy 172.595062 -305.561241)
			(xy 172.553391 -305.52801) (xy 172.517139 -305.488939) (xy 172.487115 -305.444902) (xy 172.463989 -305.396881)
			(xy 172.448279 -305.345951) (xy 172.440336 -305.293247) (xy 159.11576 -305.293247) (xy 159.11576 -306.143385)
			(xy 161.427404 -306.143385) (xy 161.427404 -306.090087) (xy 161.435347 -306.037383) (xy 161.451057 -305.986453)
			(xy 161.474183 -305.938432) (xy 161.504207 -305.894395) (xy 161.540459 -305.855324) (xy 161.58213 -305.822093)
			(xy 161.628288 -305.795444) (xy 161.677902 -305.775972) (xy 161.729864 -305.764112) (xy 161.783014 -305.760129)
			(xy 161.836164 -305.764112) (xy 161.888126 -305.775972) (xy 161.93774 -305.795444) (xy 161.983898 -305.822093)
			(xy 162.025569 -305.855324) (xy 162.061821 -305.894395) (xy 162.091845 -305.938432) (xy 162.114971 -305.986453)
			(xy 162.130681 -306.037383) (xy 162.138624 -306.090087) (xy 162.139122 -306.116736) (xy 162.138624 -306.143385)
			(xy 176.540404 -306.143385) (xy 176.540404 -306.090087) (xy 176.548347 -306.037383) (xy 176.564057 -305.986453)
			(xy 176.587183 -305.938432) (xy 176.617207 -305.894395) (xy 176.653459 -305.855324) (xy 176.69513 -305.822093)
			(xy 176.741288 -305.795444) (xy 176.790902 -305.775972) (xy 176.842864 -305.764112) (xy 176.896014 -305.760129)
			(xy 176.949164 -305.764112) (xy 177.001126 -305.775972) (xy 177.05074 -305.795444) (xy 177.096898 -305.822093)
			(xy 177.138569 -305.855324) (xy 177.174821 -305.894395) (xy 177.204845 -305.938432) (xy 177.227971 -305.986453)
			(xy 177.243681 -306.037383) (xy 177.251624 -306.090087) (xy 177.252122 -306.116736) (xy 177.251624 -306.143385)
			(xy 191.628004 -306.143385) (xy 191.628004 -306.090087) (xy 191.635947 -306.037383) (xy 191.651657 -305.986453)
			(xy 191.674783 -305.938432) (xy 191.704807 -305.894395) (xy 191.741059 -305.855324) (xy 191.78273 -305.822093)
			(xy 191.828888 -305.795444) (xy 191.878502 -305.775972) (xy 191.930464 -305.764112) (xy 191.983614 -305.760129)
			(xy 192.036764 -305.764112) (xy 192.088726 -305.775972) (xy 192.13834 -305.795444) (xy 192.184498 -305.822093)
			(xy 192.226169 -305.855324) (xy 192.262421 -305.894395) (xy 192.292445 -305.938432) (xy 192.315571 -305.986453)
			(xy 192.331281 -306.037383) (xy 192.339224 -306.090087) (xy 192.339722 -306.116736) (xy 192.339224 -306.143385)
			(xy 206.715604 -306.143385) (xy 206.715604 -306.090087) (xy 206.723547 -306.037383) (xy 206.739257 -305.986453)
			(xy 206.762383 -305.938432) (xy 206.792407 -305.894395) (xy 206.828659 -305.855324) (xy 206.87033 -305.822093)
			(xy 206.916488 -305.795444) (xy 206.966102 -305.775972) (xy 207.018064 -305.764112) (xy 207.071214 -305.760129)
			(xy 207.124364 -305.764112) (xy 207.176326 -305.775972) (xy 207.22594 -305.795444) (xy 207.272098 -305.822093)
			(xy 207.313769 -305.855324) (xy 207.350021 -305.894395) (xy 207.380045 -305.938432) (xy 207.403171 -305.986453)
			(xy 207.418881 -306.037383) (xy 207.426824 -306.090087) (xy 207.427322 -306.116736) (xy 207.426824 -306.143385)
			(xy 207.418881 -306.196089) (xy 207.403171 -306.247019) (xy 207.380045 -306.29504) (xy 207.350021 -306.339077)
			(xy 207.313769 -306.378148) (xy 207.272098 -306.411379) (xy 207.22594 -306.438028) (xy 207.176326 -306.4575)
			(xy 207.124364 -306.46936) (xy 207.071214 -306.473344) (xy 207.018064 -306.46936) (xy 206.966102 -306.4575)
			(xy 206.916488 -306.438028) (xy 206.87033 -306.411379) (xy 206.828659 -306.378148) (xy 206.792407 -306.339077)
			(xy 206.762383 -306.29504) (xy 206.739257 -306.247019) (xy 206.723547 -306.196089) (xy 206.715604 -306.143385)
			(xy 192.339224 -306.143385) (xy 192.331281 -306.196089) (xy 192.315571 -306.247019) (xy 192.292445 -306.29504)
			(xy 192.262421 -306.339077) (xy 192.226169 -306.378148) (xy 192.184498 -306.411379) (xy 192.13834 -306.438028)
			(xy 192.088726 -306.4575) (xy 192.036764 -306.46936) (xy 191.983614 -306.473344) (xy 191.930464 -306.46936)
			(xy 191.878502 -306.4575) (xy 191.828888 -306.438028) (xy 191.78273 -306.411379) (xy 191.741059 -306.378148)
			(xy 191.704807 -306.339077) (xy 191.674783 -306.29504) (xy 191.651657 -306.247019) (xy 191.635947 -306.196089)
			(xy 191.628004 -306.143385) (xy 177.251624 -306.143385) (xy 177.243681 -306.196089) (xy 177.227971 -306.247019)
			(xy 177.204845 -306.29504) (xy 177.174821 -306.339077) (xy 177.138569 -306.378148) (xy 177.096898 -306.411379)
			(xy 177.05074 -306.438028) (xy 177.001126 -306.4575) (xy 176.949164 -306.46936) (xy 176.896014 -306.473344)
			(xy 176.842864 -306.46936) (xy 176.790902 -306.4575) (xy 176.741288 -306.438028) (xy 176.69513 -306.411379)
			(xy 176.653459 -306.378148) (xy 176.617207 -306.339077) (xy 176.587183 -306.29504) (xy 176.564057 -306.247019)
			(xy 176.548347 -306.196089) (xy 176.540404 -306.143385) (xy 162.138624 -306.143385) (xy 162.130681 -306.196089)
			(xy 162.114971 -306.247019) (xy 162.091845 -306.29504) (xy 162.061821 -306.339077) (xy 162.025569 -306.378148)
			(xy 161.983898 -306.411379) (xy 161.93774 -306.438028) (xy 161.888126 -306.4575) (xy 161.836164 -306.46936)
			(xy 161.783014 -306.473344) (xy 161.729864 -306.46936) (xy 161.677902 -306.4575) (xy 161.628288 -306.438028)
			(xy 161.58213 -306.411379) (xy 161.540459 -306.378148) (xy 161.504207 -306.339077) (xy 161.474183 -306.29504)
			(xy 161.451057 -306.247019) (xy 161.435347 -306.196089) (xy 161.427404 -306.143385) (xy 159.11576 -306.143385)
			(xy 159.11576 -306.993269) (xy 172.440336 -306.993269) (xy 172.440336 -306.939971) (xy 172.448279 -306.887267)
			(xy 172.463989 -306.836337) (xy 172.487115 -306.788316) (xy 172.517139 -306.744279) (xy 172.553391 -306.705208)
			(xy 172.595062 -306.671977) (xy 172.64122 -306.645328) (xy 172.690834 -306.625856) (xy 172.742796 -306.613996)
			(xy 172.795946 -306.610013) (xy 172.849096 -306.613996) (xy 172.901058 -306.625856) (xy 172.950672 -306.645328)
			(xy 172.99683 -306.671977) (xy 173.038501 -306.705208) (xy 173.074753 -306.744279) (xy 173.104777 -306.788316)
			(xy 173.127903 -306.836337) (xy 173.143613 -306.887267) (xy 173.151556 -306.939971) (xy 173.152054 -306.96662)
			(xy 173.151556 -306.993269) (xy 187.527936 -306.993269) (xy 187.527936 -306.939971) (xy 187.535879 -306.887267)
			(xy 187.551589 -306.836337) (xy 187.574715 -306.788316) (xy 187.604739 -306.744279) (xy 187.640991 -306.705208)
			(xy 187.682662 -306.671977) (xy 187.72882 -306.645328) (xy 187.778434 -306.625856) (xy 187.830396 -306.613996)
			(xy 187.883546 -306.610013) (xy 187.936696 -306.613996) (xy 187.988658 -306.625856) (xy 188.038272 -306.645328)
			(xy 188.08443 -306.671977) (xy 188.126101 -306.705208) (xy 188.162353 -306.744279) (xy 188.192377 -306.788316)
			(xy 188.215503 -306.836337) (xy 188.231213 -306.887267) (xy 188.239156 -306.939971) (xy 188.239654 -306.96662)
			(xy 188.239156 -306.993269) (xy 202.615536 -306.993269) (xy 202.615536 -306.939971) (xy 202.623479 -306.887267)
			(xy 202.639189 -306.836337) (xy 202.662315 -306.788316) (xy 202.692339 -306.744279) (xy 202.728591 -306.705208)
			(xy 202.770262 -306.671977) (xy 202.81642 -306.645328) (xy 202.866034 -306.625856) (xy 202.917996 -306.613996)
			(xy 202.971146 -306.610013) (xy 203.024296 -306.613996) (xy 203.076258 -306.625856) (xy 203.125872 -306.645328)
			(xy 203.17203 -306.671977) (xy 203.213701 -306.705208) (xy 203.249953 -306.744279) (xy 203.279977 -306.788316)
			(xy 203.303103 -306.836337) (xy 203.318813 -306.887267) (xy 203.326756 -306.939971) (xy 203.327254 -306.96662)
			(xy 203.326756 -306.993269) (xy 203.318813 -307.045973) (xy 203.303103 -307.096903) (xy 203.279977 -307.144924)
			(xy 203.249953 -307.188961) (xy 203.213701 -307.228032) (xy 203.17203 -307.261263) (xy 203.125872 -307.287912)
			(xy 203.076258 -307.307384) (xy 203.024296 -307.319244) (xy 202.971146 -307.323228) (xy 202.917996 -307.319244)
			(xy 202.866034 -307.307384) (xy 202.81642 -307.287912) (xy 202.770262 -307.261263) (xy 202.728591 -307.228032)
			(xy 202.692339 -307.188961) (xy 202.662315 -307.144924) (xy 202.639189 -307.096903) (xy 202.623479 -307.045973)
			(xy 202.615536 -306.993269) (xy 188.239156 -306.993269) (xy 188.231213 -307.045973) (xy 188.215503 -307.096903)
			(xy 188.192377 -307.144924) (xy 188.162353 -307.188961) (xy 188.126101 -307.228032) (xy 188.08443 -307.261263)
			(xy 188.038272 -307.287912) (xy 187.988658 -307.307384) (xy 187.936696 -307.319244) (xy 187.883546 -307.323228)
			(xy 187.830396 -307.319244) (xy 187.778434 -307.307384) (xy 187.72882 -307.287912) (xy 187.682662 -307.261263)
			(xy 187.640991 -307.228032) (xy 187.604739 -307.188961) (xy 187.574715 -307.144924) (xy 187.551589 -307.096903)
			(xy 187.535879 -307.045973) (xy 187.527936 -306.993269) (xy 173.151556 -306.993269) (xy 173.143613 -307.045973)
			(xy 173.127903 -307.096903) (xy 173.104777 -307.144924) (xy 173.074753 -307.188961) (xy 173.038501 -307.228032)
			(xy 172.99683 -307.261263) (xy 172.950672 -307.287912) (xy 172.901058 -307.307384) (xy 172.849096 -307.319244)
			(xy 172.795946 -307.323228) (xy 172.742796 -307.319244) (xy 172.690834 -307.307384) (xy 172.64122 -307.287912)
			(xy 172.595062 -307.261263) (xy 172.553391 -307.228032) (xy 172.517139 -307.188961) (xy 172.487115 -307.144924)
			(xy 172.463989 -307.096903) (xy 172.448279 -307.045973) (xy 172.440336 -306.993269) (xy 159.11576 -306.993269)
			(xy 159.11576 -307.843407) (xy 176.540404 -307.843407) (xy 176.540404 -307.790109) (xy 176.548347 -307.737405)
			(xy 176.564057 -307.686475) (xy 176.587183 -307.638454) (xy 176.617207 -307.594417) (xy 176.653459 -307.555346)
			(xy 176.69513 -307.522115) (xy 176.741288 -307.495466) (xy 176.790902 -307.475994) (xy 176.842864 -307.464134)
			(xy 176.896014 -307.460151) (xy 176.949164 -307.464134) (xy 177.001126 -307.475994) (xy 177.05074 -307.495466)
			(xy 177.096898 -307.522115) (xy 177.138569 -307.555346) (xy 177.174821 -307.594417) (xy 177.204845 -307.638454)
			(xy 177.227971 -307.686475) (xy 177.243681 -307.737405) (xy 177.251624 -307.790109) (xy 177.252122 -307.816758)
			(xy 177.251624 -307.843407) (xy 191.628004 -307.843407) (xy 191.628004 -307.790109) (xy 191.635947 -307.737405)
			(xy 191.651657 -307.686475) (xy 191.674783 -307.638454) (xy 191.704807 -307.594417) (xy 191.741059 -307.555346)
			(xy 191.78273 -307.522115) (xy 191.828888 -307.495466) (xy 191.878502 -307.475994) (xy 191.930464 -307.464134)
			(xy 191.983614 -307.460151) (xy 192.036764 -307.464134) (xy 192.088726 -307.475994) (xy 192.13834 -307.495466)
			(xy 192.184498 -307.522115) (xy 192.226169 -307.555346) (xy 192.262421 -307.594417) (xy 192.292445 -307.638454)
			(xy 192.315571 -307.686475) (xy 192.331281 -307.737405) (xy 192.339224 -307.790109) (xy 192.339722 -307.816758)
			(xy 192.339224 -307.843407) (xy 206.715604 -307.843407) (xy 206.715604 -307.790109) (xy 206.723547 -307.737405)
			(xy 206.739257 -307.686475) (xy 206.762383 -307.638454) (xy 206.792407 -307.594417) (xy 206.828659 -307.555346)
			(xy 206.87033 -307.522115) (xy 206.916488 -307.495466) (xy 206.966102 -307.475994) (xy 207.018064 -307.464134)
			(xy 207.071214 -307.460151) (xy 207.124364 -307.464134) (xy 207.176326 -307.475994) (xy 207.22594 -307.495466)
			(xy 207.272098 -307.522115) (xy 207.313769 -307.555346) (xy 207.350021 -307.594417) (xy 207.380045 -307.638454)
			(xy 207.403171 -307.686475) (xy 207.418881 -307.737405) (xy 207.426824 -307.790109) (xy 207.427322 -307.816758)
			(xy 207.426824 -307.843407) (xy 207.418881 -307.896111) (xy 207.403171 -307.947041) (xy 207.380045 -307.995062)
			(xy 207.350021 -308.039099) (xy 207.313769 -308.07817) (xy 207.272098 -308.111401) (xy 207.22594 -308.13805)
			(xy 207.176326 -308.157522) (xy 207.124364 -308.169382) (xy 207.071214 -308.173366) (xy 207.018064 -308.169382)
			(xy 206.966102 -308.157522) (xy 206.916488 -308.13805) (xy 206.87033 -308.111401) (xy 206.828659 -308.07817)
			(xy 206.792407 -308.039099) (xy 206.762383 -307.995062) (xy 206.739257 -307.947041) (xy 206.723547 -307.896111)
			(xy 206.715604 -307.843407) (xy 192.339224 -307.843407) (xy 192.331281 -307.896111) (xy 192.315571 -307.947041)
			(xy 192.292445 -307.995062) (xy 192.262421 -308.039099) (xy 192.226169 -308.07817) (xy 192.184498 -308.111401)
			(xy 192.13834 -308.13805) (xy 192.088726 -308.157522) (xy 192.036764 -308.169382) (xy 191.983614 -308.173366)
			(xy 191.930464 -308.169382) (xy 191.878502 -308.157522) (xy 191.828888 -308.13805) (xy 191.78273 -308.111401)
			(xy 191.741059 -308.07817) (xy 191.704807 -308.039099) (xy 191.674783 -307.995062) (xy 191.651657 -307.947041)
			(xy 191.635947 -307.896111) (xy 191.628004 -307.843407) (xy 177.251624 -307.843407) (xy 177.243681 -307.896111)
			(xy 177.227971 -307.947041) (xy 177.204845 -307.995062) (xy 177.174821 -308.039099) (xy 177.138569 -308.07817)
			(xy 177.096898 -308.111401) (xy 177.05074 -308.13805) (xy 177.001126 -308.157522) (xy 176.949164 -308.169382)
			(xy 176.896014 -308.173366) (xy 176.842864 -308.169382) (xy 176.790902 -308.157522) (xy 176.741288 -308.13805)
			(xy 176.69513 -308.111401) (xy 176.653459 -308.07817) (xy 176.617207 -308.039099) (xy 176.587183 -307.995062)
			(xy 176.564057 -307.947041) (xy 176.548347 -307.896111) (xy 176.540404 -307.843407) (xy 159.11576 -307.843407)
			(xy 159.11576 -308.693291) (xy 172.440336 -308.693291) (xy 172.440336 -308.639993) (xy 172.448279 -308.587289)
			(xy 172.463989 -308.536359) (xy 172.487115 -308.488338) (xy 172.517139 -308.444301) (xy 172.553391 -308.40523)
			(xy 172.595062 -308.371999) (xy 172.64122 -308.34535) (xy 172.690834 -308.325878) (xy 172.742796 -308.314018)
			(xy 172.795946 -308.310035) (xy 172.849096 -308.314018) (xy 172.901058 -308.325878) (xy 172.950672 -308.34535)
			(xy 172.99683 -308.371999) (xy 173.038501 -308.40523) (xy 173.074753 -308.444301) (xy 173.104777 -308.488338)
			(xy 173.127903 -308.536359) (xy 173.143613 -308.587289) (xy 173.151556 -308.639993) (xy 173.152054 -308.666642)
			(xy 173.151556 -308.693291) (xy 187.527936 -308.693291) (xy 187.527936 -308.639993) (xy 187.535879 -308.587289)
			(xy 187.551589 -308.536359) (xy 187.574715 -308.488338) (xy 187.604739 -308.444301) (xy 187.640991 -308.40523)
			(xy 187.682662 -308.371999) (xy 187.72882 -308.34535) (xy 187.778434 -308.325878) (xy 187.830396 -308.314018)
			(xy 187.883546 -308.310035) (xy 187.936696 -308.314018) (xy 187.988658 -308.325878) (xy 188.038272 -308.34535)
			(xy 188.08443 -308.371999) (xy 188.126101 -308.40523) (xy 188.162353 -308.444301) (xy 188.192377 -308.488338)
			(xy 188.215503 -308.536359) (xy 188.231213 -308.587289) (xy 188.239156 -308.639993) (xy 188.239654 -308.666642)
			(xy 188.239156 -308.693291) (xy 202.615536 -308.693291) (xy 202.615536 -308.639993) (xy 202.623479 -308.587289)
			(xy 202.639189 -308.536359) (xy 202.662315 -308.488338) (xy 202.692339 -308.444301) (xy 202.728591 -308.40523)
			(xy 202.770262 -308.371999) (xy 202.81642 -308.34535) (xy 202.866034 -308.325878) (xy 202.917996 -308.314018)
			(xy 202.971146 -308.310035) (xy 203.024296 -308.314018) (xy 203.076258 -308.325878) (xy 203.125872 -308.34535)
			(xy 203.17203 -308.371999) (xy 203.213701 -308.40523) (xy 203.249953 -308.444301) (xy 203.279977 -308.488338)
			(xy 203.303103 -308.536359) (xy 203.318813 -308.587289) (xy 203.326756 -308.639993) (xy 203.327254 -308.666642)
			(xy 203.326756 -308.693291) (xy 203.318813 -308.745995) (xy 203.303103 -308.796925) (xy 203.279977 -308.844946)
			(xy 203.249953 -308.888983) (xy 203.213701 -308.928054) (xy 203.17203 -308.961285) (xy 203.125872 -308.987934)
			(xy 203.076258 -309.007406) (xy 203.024296 -309.019266) (xy 202.971146 -309.02325) (xy 202.917996 -309.019266)
			(xy 202.866034 -309.007406) (xy 202.81642 -308.987934) (xy 202.770262 -308.961285) (xy 202.728591 -308.928054)
			(xy 202.692339 -308.888983) (xy 202.662315 -308.844946) (xy 202.639189 -308.796925) (xy 202.623479 -308.745995)
			(xy 202.615536 -308.693291) (xy 188.239156 -308.693291) (xy 188.231213 -308.745995) (xy 188.215503 -308.796925)
			(xy 188.192377 -308.844946) (xy 188.162353 -308.888983) (xy 188.126101 -308.928054) (xy 188.08443 -308.961285)
			(xy 188.038272 -308.987934) (xy 187.988658 -309.007406) (xy 187.936696 -309.019266) (xy 187.883546 -309.02325)
			(xy 187.830396 -309.019266) (xy 187.778434 -309.007406) (xy 187.72882 -308.987934) (xy 187.682662 -308.961285)
			(xy 187.640991 -308.928054) (xy 187.604739 -308.888983) (xy 187.574715 -308.844946) (xy 187.551589 -308.796925)
			(xy 187.535879 -308.745995) (xy 187.527936 -308.693291) (xy 173.151556 -308.693291) (xy 173.143613 -308.745995)
			(xy 173.127903 -308.796925) (xy 173.104777 -308.844946) (xy 173.074753 -308.888983) (xy 173.038501 -308.928054)
			(xy 172.99683 -308.961285) (xy 172.950672 -308.987934) (xy 172.901058 -309.007406) (xy 172.849096 -309.019266)
			(xy 172.795946 -309.02325) (xy 172.742796 -309.019266) (xy 172.690834 -309.007406) (xy 172.64122 -308.987934)
			(xy 172.595062 -308.961285) (xy 172.553391 -308.928054) (xy 172.517139 -308.888983) (xy 172.487115 -308.844946)
			(xy 172.463989 -308.796925) (xy 172.448279 -308.745995) (xy 172.440336 -308.693291) (xy 159.11576 -308.693291)
			(xy 159.11576 -309.543175) (xy 176.540404 -309.543175) (xy 176.540404 -309.489877) (xy 176.548347 -309.437173)
			(xy 176.564057 -309.386243) (xy 176.587183 -309.338222) (xy 176.617207 -309.294185) (xy 176.653459 -309.255114)
			(xy 176.69513 -309.221883) (xy 176.741288 -309.195234) (xy 176.790902 -309.175762) (xy 176.842864 -309.163902)
			(xy 176.896014 -309.159919) (xy 176.949164 -309.163902) (xy 177.001126 -309.175762) (xy 177.05074 -309.195234)
			(xy 177.096898 -309.221883) (xy 177.138569 -309.255114) (xy 177.174821 -309.294185) (xy 177.204845 -309.338222)
			(xy 177.227971 -309.386243) (xy 177.243681 -309.437173) (xy 177.251624 -309.489877) (xy 177.252122 -309.516526)
			(xy 177.251624 -309.543175) (xy 191.628004 -309.543175) (xy 191.628004 -309.489877) (xy 191.635947 -309.437173)
			(xy 191.651657 -309.386243) (xy 191.674783 -309.338222) (xy 191.704807 -309.294185) (xy 191.741059 -309.255114)
			(xy 191.78273 -309.221883) (xy 191.828888 -309.195234) (xy 191.878502 -309.175762) (xy 191.930464 -309.163902)
			(xy 191.983614 -309.159919) (xy 192.036764 -309.163902) (xy 192.088726 -309.175762) (xy 192.13834 -309.195234)
			(xy 192.184498 -309.221883) (xy 192.226169 -309.255114) (xy 192.262421 -309.294185) (xy 192.292445 -309.338222)
			(xy 192.315571 -309.386243) (xy 192.331281 -309.437173) (xy 192.339224 -309.489877) (xy 192.339722 -309.516526)
			(xy 192.339224 -309.543175) (xy 192.339186 -309.543429) (xy 206.715604 -309.543429) (xy 206.715604 -309.490131)
			(xy 206.723547 -309.437427) (xy 206.739257 -309.386497) (xy 206.762383 -309.338476) (xy 206.792407 -309.294439)
			(xy 206.828659 -309.255368) (xy 206.87033 -309.222137) (xy 206.916488 -309.195488) (xy 206.966102 -309.176016)
			(xy 207.018064 -309.164156) (xy 207.071214 -309.160173) (xy 207.124364 -309.164156) (xy 207.176326 -309.176016)
			(xy 207.22594 -309.195488) (xy 207.272098 -309.222137) (xy 207.313769 -309.255368) (xy 207.350021 -309.294439)
			(xy 207.380045 -309.338476) (xy 207.403171 -309.386497) (xy 207.418881 -309.437427) (xy 207.426824 -309.490131)
			(xy 207.427322 -309.51678) (xy 207.426824 -309.543429) (xy 207.418881 -309.596133) (xy 207.403171 -309.647063)
			(xy 207.380045 -309.695084) (xy 207.350021 -309.739121) (xy 207.313769 -309.778192) (xy 207.272098 -309.811423)
			(xy 207.22594 -309.838072) (xy 207.176326 -309.857544) (xy 207.124364 -309.869404) (xy 207.071214 -309.873388)
			(xy 207.018064 -309.869404) (xy 206.966102 -309.857544) (xy 206.916488 -309.838072) (xy 206.87033 -309.811423)
			(xy 206.828659 -309.778192) (xy 206.792407 -309.739121) (xy 206.762383 -309.695084) (xy 206.739257 -309.647063)
			(xy 206.723547 -309.596133) (xy 206.715604 -309.543429) (xy 192.339186 -309.543429) (xy 192.331281 -309.595879)
			(xy 192.315571 -309.646809) (xy 192.292445 -309.69483) (xy 192.262421 -309.738867) (xy 192.226169 -309.777938)
			(xy 192.184498 -309.811169) (xy 192.13834 -309.837818) (xy 192.088726 -309.85729) (xy 192.036764 -309.86915)
			(xy 191.983614 -309.873134) (xy 191.930464 -309.86915) (xy 191.878502 -309.85729) (xy 191.828888 -309.837818)
			(xy 191.78273 -309.811169) (xy 191.741059 -309.777938) (xy 191.704807 -309.738867) (xy 191.674783 -309.69483)
			(xy 191.651657 -309.646809) (xy 191.635947 -309.595879) (xy 191.628004 -309.543175) (xy 177.251624 -309.543175)
			(xy 177.243681 -309.595879) (xy 177.227971 -309.646809) (xy 177.204845 -309.69483) (xy 177.174821 -309.738867)
			(xy 177.138569 -309.777938) (xy 177.096898 -309.811169) (xy 177.05074 -309.837818) (xy 177.001126 -309.85729)
			(xy 176.949164 -309.86915) (xy 176.896014 -309.873134) (xy 176.842864 -309.86915) (xy 176.790902 -309.85729)
			(xy 176.741288 -309.837818) (xy 176.69513 -309.811169) (xy 176.653459 -309.777938) (xy 176.617207 -309.738867)
			(xy 176.587183 -309.69483) (xy 176.564057 -309.646809) (xy 176.548347 -309.595879) (xy 176.540404 -309.543175)
			(xy 159.11576 -309.543175) (xy 159.11576 -310.393313) (xy 172.440336 -310.393313) (xy 172.440336 -310.340015)
			(xy 172.448279 -310.287311) (xy 172.463989 -310.236381) (xy 172.487115 -310.18836) (xy 172.517139 -310.144323)
			(xy 172.553391 -310.105252) (xy 172.595062 -310.072021) (xy 172.64122 -310.045372) (xy 172.690834 -310.0259)
			(xy 172.742796 -310.01404) (xy 172.795946 -310.010057) (xy 172.849096 -310.01404) (xy 172.901058 -310.0259)
			(xy 172.950672 -310.045372) (xy 172.99683 -310.072021) (xy 173.038501 -310.105252) (xy 173.074753 -310.144323)
			(xy 173.104777 -310.18836) (xy 173.127903 -310.236381) (xy 173.143613 -310.287311) (xy 173.151556 -310.340015)
			(xy 173.152054 -310.366664) (xy 173.151556 -310.393313) (xy 187.527936 -310.393313) (xy 187.527936 -310.340015)
			(xy 187.535879 -310.287311) (xy 187.551589 -310.236381) (xy 187.574715 -310.18836) (xy 187.604739 -310.144323)
			(xy 187.640991 -310.105252) (xy 187.682662 -310.072021) (xy 187.72882 -310.045372) (xy 187.778434 -310.0259)
			(xy 187.830396 -310.01404) (xy 187.883546 -310.010057) (xy 187.936696 -310.01404) (xy 187.988658 -310.0259)
			(xy 188.038272 -310.045372) (xy 188.08443 -310.072021) (xy 188.126101 -310.105252) (xy 188.162353 -310.144323)
			(xy 188.192377 -310.18836) (xy 188.215503 -310.236381) (xy 188.231213 -310.287311) (xy 188.239156 -310.340015)
			(xy 188.239654 -310.366664) (xy 188.239156 -310.393313) (xy 202.615536 -310.393313) (xy 202.615536 -310.340015)
			(xy 202.623479 -310.287311) (xy 202.639189 -310.236381) (xy 202.662315 -310.18836) (xy 202.692339 -310.144323)
			(xy 202.728591 -310.105252) (xy 202.770262 -310.072021) (xy 202.81642 -310.045372) (xy 202.866034 -310.0259)
			(xy 202.917996 -310.01404) (xy 202.971146 -310.010057) (xy 203.024296 -310.01404) (xy 203.076258 -310.0259)
			(xy 203.125872 -310.045372) (xy 203.17203 -310.072021) (xy 203.213701 -310.105252) (xy 203.249953 -310.144323)
			(xy 203.279977 -310.18836) (xy 203.303103 -310.236381) (xy 203.318813 -310.287311) (xy 203.326756 -310.340015)
			(xy 203.327254 -310.366664) (xy 203.326756 -310.393313) (xy 203.318813 -310.446017) (xy 203.303103 -310.496947)
			(xy 203.279977 -310.544968) (xy 203.249953 -310.589005) (xy 203.213701 -310.628076) (xy 203.17203 -310.661307)
			(xy 203.125872 -310.687956) (xy 203.076258 -310.707428) (xy 203.024296 -310.719288) (xy 202.971146 -310.723272)
			(xy 202.917996 -310.719288) (xy 202.866034 -310.707428) (xy 202.81642 -310.687956) (xy 202.770262 -310.661307)
			(xy 202.728591 -310.628076) (xy 202.692339 -310.589005) (xy 202.662315 -310.544968) (xy 202.639189 -310.496947)
			(xy 202.623479 -310.446017) (xy 202.615536 -310.393313) (xy 188.239156 -310.393313) (xy 188.231213 -310.446017)
			(xy 188.215503 -310.496947) (xy 188.192377 -310.544968) (xy 188.162353 -310.589005) (xy 188.126101 -310.628076)
			(xy 188.08443 -310.661307) (xy 188.038272 -310.687956) (xy 187.988658 -310.707428) (xy 187.936696 -310.719288)
			(xy 187.883546 -310.723272) (xy 187.830396 -310.719288) (xy 187.778434 -310.707428) (xy 187.72882 -310.687956)
			(xy 187.682662 -310.661307) (xy 187.640991 -310.628076) (xy 187.604739 -310.589005) (xy 187.574715 -310.544968)
			(xy 187.551589 -310.496947) (xy 187.535879 -310.446017) (xy 187.527936 -310.393313) (xy 173.151556 -310.393313)
			(xy 173.143613 -310.446017) (xy 173.127903 -310.496947) (xy 173.104777 -310.544968) (xy 173.074753 -310.589005)
			(xy 173.038501 -310.628076) (xy 172.99683 -310.661307) (xy 172.950672 -310.687956) (xy 172.901058 -310.707428)
			(xy 172.849096 -310.719288) (xy 172.795946 -310.723272) (xy 172.742796 -310.719288) (xy 172.690834 -310.707428)
			(xy 172.64122 -310.687956) (xy 172.595062 -310.661307) (xy 172.553391 -310.628076) (xy 172.517139 -310.589005)
			(xy 172.487115 -310.544968) (xy 172.463989 -310.496947) (xy 172.448279 -310.446017) (xy 172.440336 -310.393313)
			(xy 159.11576 -310.393313) (xy 159.11576 -311.243197) (xy 176.540404 -311.243197) (xy 176.540404 -311.189899)
			(xy 176.548347 -311.137195) (xy 176.564057 -311.086265) (xy 176.587183 -311.038244) (xy 176.617207 -310.994207)
			(xy 176.653459 -310.955136) (xy 176.69513 -310.921905) (xy 176.741288 -310.895256) (xy 176.790902 -310.875784)
			(xy 176.842864 -310.863924) (xy 176.896014 -310.859941) (xy 176.949164 -310.863924) (xy 177.001126 -310.875784)
			(xy 177.05074 -310.895256) (xy 177.096898 -310.921905) (xy 177.138569 -310.955136) (xy 177.174821 -310.994207)
			(xy 177.204845 -311.038244) (xy 177.227971 -311.086265) (xy 177.243681 -311.137195) (xy 177.251624 -311.189899)
			(xy 177.252122 -311.216548) (xy 177.251624 -311.243197) (xy 191.628004 -311.243197) (xy 191.628004 -311.189899)
			(xy 191.635947 -311.137195) (xy 191.651657 -311.086265) (xy 191.674783 -311.038244) (xy 191.704807 -310.994207)
			(xy 191.741059 -310.955136) (xy 191.78273 -310.921905) (xy 191.828888 -310.895256) (xy 191.878502 -310.875784)
			(xy 191.930464 -310.863924) (xy 191.983614 -310.859941) (xy 192.036764 -310.863924) (xy 192.088726 -310.875784)
			(xy 192.13834 -310.895256) (xy 192.184498 -310.921905) (xy 192.226169 -310.955136) (xy 192.262421 -310.994207)
			(xy 192.292445 -311.038244) (xy 192.315571 -311.086265) (xy 192.331281 -311.137195) (xy 192.339224 -311.189899)
			(xy 192.339722 -311.216548) (xy 192.339224 -311.243197) (xy 192.339186 -311.243451) (xy 206.715604 -311.243451)
			(xy 206.715604 -311.190153) (xy 206.723547 -311.137449) (xy 206.739257 -311.086519) (xy 206.762383 -311.038498)
			(xy 206.792407 -310.994461) (xy 206.828659 -310.95539) (xy 206.87033 -310.922159) (xy 206.916488 -310.89551)
			(xy 206.966102 -310.876038) (xy 207.018064 -310.864178) (xy 207.071214 -310.860195) (xy 207.124364 -310.864178)
			(xy 207.176326 -310.876038) (xy 207.22594 -310.89551) (xy 207.272098 -310.922159) (xy 207.313769 -310.95539)
			(xy 207.350021 -310.994461) (xy 207.380045 -311.038498) (xy 207.403171 -311.086519) (xy 207.418881 -311.137449)
			(xy 207.426824 -311.190153) (xy 207.427322 -311.216802) (xy 207.426824 -311.243451) (xy 207.418881 -311.296155)
			(xy 207.403171 -311.347085) (xy 207.380045 -311.395106) (xy 207.350021 -311.439143) (xy 207.313769 -311.478214)
			(xy 207.272098 -311.511445) (xy 207.22594 -311.538094) (xy 207.176326 -311.557566) (xy 207.124364 -311.569426)
			(xy 207.071214 -311.57341) (xy 207.018064 -311.569426) (xy 206.966102 -311.557566) (xy 206.916488 -311.538094)
			(xy 206.87033 -311.511445) (xy 206.828659 -311.478214) (xy 206.792407 -311.439143) (xy 206.762383 -311.395106)
			(xy 206.739257 -311.347085) (xy 206.723547 -311.296155) (xy 206.715604 -311.243451) (xy 192.339186 -311.243451)
			(xy 192.331281 -311.295901) (xy 192.315571 -311.346831) (xy 192.292445 -311.394852) (xy 192.262421 -311.438889)
			(xy 192.226169 -311.47796) (xy 192.184498 -311.511191) (xy 192.13834 -311.53784) (xy 192.088726 -311.557312)
			(xy 192.036764 -311.569172) (xy 191.983614 -311.573156) (xy 191.930464 -311.569172) (xy 191.878502 -311.557312)
			(xy 191.828888 -311.53784) (xy 191.78273 -311.511191) (xy 191.741059 -311.47796) (xy 191.704807 -311.438889)
			(xy 191.674783 -311.394852) (xy 191.651657 -311.346831) (xy 191.635947 -311.295901) (xy 191.628004 -311.243197)
			(xy 177.251624 -311.243197) (xy 177.243681 -311.295901) (xy 177.227971 -311.346831) (xy 177.204845 -311.394852)
			(xy 177.174821 -311.438889) (xy 177.138569 -311.47796) (xy 177.096898 -311.511191) (xy 177.05074 -311.53784)
			(xy 177.001126 -311.557312) (xy 176.949164 -311.569172) (xy 176.896014 -311.573156) (xy 176.842864 -311.569172)
			(xy 176.790902 -311.557312) (xy 176.741288 -311.53784) (xy 176.69513 -311.511191) (xy 176.653459 -311.47796)
			(xy 176.617207 -311.438889) (xy 176.587183 -311.394852) (xy 176.564057 -311.346831) (xy 176.548347 -311.295901)
			(xy 176.540404 -311.243197) (xy 159.11576 -311.243197) (xy 159.11576 -312.093335) (xy 172.440336 -312.093335)
			(xy 172.440336 -312.040037) (xy 172.448279 -311.987333) (xy 172.463989 -311.936403) (xy 172.487115 -311.888382)
			(xy 172.517139 -311.844345) (xy 172.553391 -311.805274) (xy 172.595062 -311.772043) (xy 172.64122 -311.745394)
			(xy 172.690834 -311.725922) (xy 172.742796 -311.714062) (xy 172.795946 -311.710079) (xy 172.849096 -311.714062)
			(xy 172.901058 -311.725922) (xy 172.950672 -311.745394) (xy 172.99683 -311.772043) (xy 173.038501 -311.805274)
			(xy 173.074753 -311.844345) (xy 173.104777 -311.888382) (xy 173.127903 -311.936403) (xy 173.143613 -311.987333)
			(xy 173.151556 -312.040037) (xy 173.152054 -312.066686) (xy 173.151556 -312.093335) (xy 176.540404 -312.093335)
			(xy 176.540404 -312.040037) (xy 176.548347 -311.987333) (xy 176.564057 -311.936403) (xy 176.587183 -311.888382)
			(xy 176.617207 -311.844345) (xy 176.653459 -311.805274) (xy 176.69513 -311.772043) (xy 176.741288 -311.745394)
			(xy 176.790902 -311.725922) (xy 176.842864 -311.714062) (xy 176.896014 -311.710079) (xy 176.949164 -311.714062)
			(xy 177.001126 -311.725922) (xy 177.05074 -311.745394) (xy 177.096898 -311.772043) (xy 177.138569 -311.805274)
			(xy 177.174821 -311.844345) (xy 177.204845 -311.888382) (xy 177.227971 -311.936403) (xy 177.243681 -311.987333)
			(xy 177.251624 -312.040037) (xy 177.252122 -312.066686) (xy 177.251624 -312.093335) (xy 187.527936 -312.093335)
			(xy 187.527936 -312.040037) (xy 187.535879 -311.987333) (xy 187.551589 -311.936403) (xy 187.574715 -311.888382)
			(xy 187.604739 -311.844345) (xy 187.640991 -311.805274) (xy 187.682662 -311.772043) (xy 187.72882 -311.745394)
			(xy 187.778434 -311.725922) (xy 187.830396 -311.714062) (xy 187.883546 -311.710079) (xy 187.936696 -311.714062)
			(xy 187.988658 -311.725922) (xy 188.038272 -311.745394) (xy 188.08443 -311.772043) (xy 188.126101 -311.805274)
			(xy 188.162353 -311.844345) (xy 188.192377 -311.888382) (xy 188.215503 -311.936403) (xy 188.231213 -311.987333)
			(xy 188.239156 -312.040037) (xy 188.239654 -312.066686) (xy 188.239156 -312.093335) (xy 191.628004 -312.093335)
			(xy 191.628004 -312.040037) (xy 191.635947 -311.987333) (xy 191.651657 -311.936403) (xy 191.674783 -311.888382)
			(xy 191.704807 -311.844345) (xy 191.741059 -311.805274) (xy 191.78273 -311.772043) (xy 191.828888 -311.745394)
			(xy 191.878502 -311.725922) (xy 191.930464 -311.714062) (xy 191.983614 -311.710079) (xy 192.036764 -311.714062)
			(xy 192.088726 -311.725922) (xy 192.13834 -311.745394) (xy 192.184498 -311.772043) (xy 192.226169 -311.805274)
			(xy 192.262421 -311.844345) (xy 192.292445 -311.888382) (xy 192.315571 -311.936403) (xy 192.331281 -311.987333)
			(xy 192.339224 -312.040037) (xy 192.339722 -312.066686) (xy 192.339224 -312.093335) (xy 202.615536 -312.093335)
			(xy 202.615536 -312.040037) (xy 202.623479 -311.987333) (xy 202.639189 -311.936403) (xy 202.662315 -311.888382)
			(xy 202.692339 -311.844345) (xy 202.728591 -311.805274) (xy 202.770262 -311.772043) (xy 202.81642 -311.745394)
			(xy 202.866034 -311.725922) (xy 202.917996 -311.714062) (xy 202.971146 -311.710079) (xy 203.024296 -311.714062)
			(xy 203.076258 -311.725922) (xy 203.125872 -311.745394) (xy 203.17203 -311.772043) (xy 203.213701 -311.805274)
			(xy 203.249953 -311.844345) (xy 203.279977 -311.888382) (xy 203.303103 -311.936403) (xy 203.318813 -311.987333)
			(xy 203.326756 -312.040037) (xy 203.327254 -312.066686) (xy 203.326756 -312.093335) (xy 206.715604 -312.093335)
			(xy 206.715604 -312.040037) (xy 206.723547 -311.987333) (xy 206.739257 -311.936403) (xy 206.762383 -311.888382)
			(xy 206.792407 -311.844345) (xy 206.828659 -311.805274) (xy 206.87033 -311.772043) (xy 206.916488 -311.745394)
			(xy 206.966102 -311.725922) (xy 207.018064 -311.714062) (xy 207.071214 -311.710079) (xy 207.124364 -311.714062)
			(xy 207.176326 -311.725922) (xy 207.22594 -311.745394) (xy 207.272098 -311.772043) (xy 207.313769 -311.805274)
			(xy 207.350021 -311.844345) (xy 207.380045 -311.888382) (xy 207.403171 -311.936403) (xy 207.418881 -311.987333)
			(xy 207.426824 -312.040037) (xy 207.427322 -312.066686) (xy 207.426824 -312.093335) (xy 207.418881 -312.146039)
			(xy 207.403171 -312.196969) (xy 207.380045 -312.24499) (xy 207.350021 -312.289027) (xy 207.313769 -312.328098)
			(xy 207.272098 -312.361329) (xy 207.22594 -312.387978) (xy 207.176326 -312.40745) (xy 207.124364 -312.41931)
			(xy 207.071214 -312.423294) (xy 207.018064 -312.41931) (xy 206.966102 -312.40745) (xy 206.916488 -312.387978)
			(xy 206.87033 -312.361329) (xy 206.828659 -312.328098) (xy 206.792407 -312.289027) (xy 206.762383 -312.24499)
			(xy 206.739257 -312.196969) (xy 206.723547 -312.146039) (xy 206.715604 -312.093335) (xy 203.326756 -312.093335)
			(xy 203.318813 -312.146039) (xy 203.303103 -312.196969) (xy 203.279977 -312.24499) (xy 203.249953 -312.289027)
			(xy 203.213701 -312.328098) (xy 203.17203 -312.361329) (xy 203.125872 -312.387978) (xy 203.076258 -312.40745)
			(xy 203.024296 -312.41931) (xy 202.971146 -312.423294) (xy 202.917996 -312.41931) (xy 202.866034 -312.40745)
			(xy 202.81642 -312.387978) (xy 202.770262 -312.361329) (xy 202.728591 -312.328098) (xy 202.692339 -312.289027)
			(xy 202.662315 -312.24499) (xy 202.639189 -312.196969) (xy 202.623479 -312.146039) (xy 202.615536 -312.093335)
			(xy 192.339224 -312.093335) (xy 192.331281 -312.146039) (xy 192.315571 -312.196969) (xy 192.292445 -312.24499)
			(xy 192.262421 -312.289027) (xy 192.226169 -312.328098) (xy 192.184498 -312.361329) (xy 192.13834 -312.387978)
			(xy 192.088726 -312.40745) (xy 192.036764 -312.41931) (xy 191.983614 -312.423294) (xy 191.930464 -312.41931)
			(xy 191.878502 -312.40745) (xy 191.828888 -312.387978) (xy 191.78273 -312.361329) (xy 191.741059 -312.328098)
			(xy 191.704807 -312.289027) (xy 191.674783 -312.24499) (xy 191.651657 -312.196969) (xy 191.635947 -312.146039)
			(xy 191.628004 -312.093335) (xy 188.239156 -312.093335) (xy 188.231213 -312.146039) (xy 188.215503 -312.196969)
			(xy 188.192377 -312.24499) (xy 188.162353 -312.289027) (xy 188.126101 -312.328098) (xy 188.08443 -312.361329)
			(xy 188.038272 -312.387978) (xy 187.988658 -312.40745) (xy 187.936696 -312.41931) (xy 187.883546 -312.423294)
			(xy 187.830396 -312.41931) (xy 187.778434 -312.40745) (xy 187.72882 -312.387978) (xy 187.682662 -312.361329)
			(xy 187.640991 -312.328098) (xy 187.604739 -312.289027) (xy 187.574715 -312.24499) (xy 187.551589 -312.196969)
			(xy 187.535879 -312.146039) (xy 187.527936 -312.093335) (xy 177.251624 -312.093335) (xy 177.243681 -312.146039)
			(xy 177.227971 -312.196969) (xy 177.204845 -312.24499) (xy 177.174821 -312.289027) (xy 177.138569 -312.328098)
			(xy 177.096898 -312.361329) (xy 177.05074 -312.387978) (xy 177.001126 -312.40745) (xy 176.949164 -312.41931)
			(xy 176.896014 -312.423294) (xy 176.842864 -312.41931) (xy 176.790902 -312.40745) (xy 176.741288 -312.387978)
			(xy 176.69513 -312.361329) (xy 176.653459 -312.328098) (xy 176.617207 -312.289027) (xy 176.587183 -312.24499)
			(xy 176.564057 -312.196969) (xy 176.548347 -312.146039) (xy 176.540404 -312.093335) (xy 173.151556 -312.093335)
			(xy 173.143613 -312.146039) (xy 173.127903 -312.196969) (xy 173.104777 -312.24499) (xy 173.074753 -312.289027)
			(xy 173.038501 -312.328098) (xy 172.99683 -312.361329) (xy 172.950672 -312.387978) (xy 172.901058 -312.40745)
			(xy 172.849096 -312.41931) (xy 172.795946 -312.423294) (xy 172.742796 -312.41931) (xy 172.690834 -312.40745)
			(xy 172.64122 -312.387978) (xy 172.595062 -312.361329) (xy 172.553391 -312.328098) (xy 172.517139 -312.289027)
			(xy 172.487115 -312.24499) (xy 172.463989 -312.196969) (xy 172.448279 -312.146039) (xy 172.440336 -312.093335)
			(xy 159.11576 -312.093335) (xy 159.11576 -312.943219) (xy 172.440336 -312.943219) (xy 172.440336 -312.889921)
			(xy 172.448279 -312.837217) (xy 172.463989 -312.786287) (xy 172.487115 -312.738266) (xy 172.517139 -312.694229)
			(xy 172.553391 -312.655158) (xy 172.595062 -312.621927) (xy 172.64122 -312.595278) (xy 172.690834 -312.575806)
			(xy 172.742796 -312.563946) (xy 172.795946 -312.559963) (xy 172.849096 -312.563946) (xy 172.901058 -312.575806)
			(xy 172.950672 -312.595278) (xy 172.99683 -312.621927) (xy 173.038501 -312.655158) (xy 173.074753 -312.694229)
			(xy 173.104777 -312.738266) (xy 173.127903 -312.786287) (xy 173.143613 -312.837217) (xy 173.151556 -312.889921)
			(xy 173.152054 -312.91657) (xy 173.151556 -312.943219) (xy 187.527936 -312.943219) (xy 187.527936 -312.889921)
			(xy 187.535879 -312.837217) (xy 187.551589 -312.786287) (xy 187.574715 -312.738266) (xy 187.604739 -312.694229)
			(xy 187.640991 -312.655158) (xy 187.682662 -312.621927) (xy 187.72882 -312.595278) (xy 187.778434 -312.575806)
			(xy 187.830396 -312.563946) (xy 187.883546 -312.559963) (xy 187.936696 -312.563946) (xy 187.988658 -312.575806)
			(xy 188.038272 -312.595278) (xy 188.08443 -312.621927) (xy 188.126101 -312.655158) (xy 188.162353 -312.694229)
			(xy 188.192377 -312.738266) (xy 188.215503 -312.786287) (xy 188.231213 -312.837217) (xy 188.239156 -312.889921)
			(xy 188.239654 -312.91657) (xy 188.239156 -312.943219) (xy 202.615536 -312.943219) (xy 202.615536 -312.889921)
			(xy 202.623479 -312.837217) (xy 202.639189 -312.786287) (xy 202.662315 -312.738266) (xy 202.692339 -312.694229)
			(xy 202.728591 -312.655158) (xy 202.770262 -312.621927) (xy 202.81642 -312.595278) (xy 202.866034 -312.575806)
			(xy 202.917996 -312.563946) (xy 202.971146 -312.559963) (xy 203.024296 -312.563946) (xy 203.076258 -312.575806)
			(xy 203.125872 -312.595278) (xy 203.17203 -312.621927) (xy 203.213701 -312.655158) (xy 203.249953 -312.694229)
			(xy 203.279977 -312.738266) (xy 203.303103 -312.786287) (xy 203.318813 -312.837217) (xy 203.326756 -312.889921)
			(xy 203.327254 -312.91657) (xy 203.326756 -312.943219) (xy 203.318813 -312.995923) (xy 203.305918 -313.037728)
			(xy 212.475062 -313.037728) (xy 212.479133 -312.982106) (xy 212.491259 -312.927669) (xy 212.511182 -312.875578)
			(xy 212.538478 -312.826943) (xy 212.572564 -312.7828) (xy 212.612713 -312.744091) (xy 212.658071 -312.71164)
			(xy 212.707671 -312.686139) (xy 212.760455 -312.668132) (xy 212.815298 -312.658002) (xy 212.871032 -312.655965)
			(xy 212.926469 -312.662065) (xy 212.980426 -312.676171) (xy 213.031755 -312.697983) (xy 213.079361 -312.727037)
			(xy 213.122229 -312.762712) (xy 213.159446 -312.804249) (xy 213.190219 -312.850762) (xy 213.213891 -312.901259)
			(xy 213.229959 -312.954666) (xy 213.238079 -313.009842) (xy 213.238588 -313.037728) (xy 213.238079 -313.065614)
			(xy 213.229959 -313.12079) (xy 213.213891 -313.174197) (xy 213.190219 -313.224694) (xy 213.159446 -313.271207)
			(xy 213.122229 -313.312744) (xy 213.079361 -313.348419) (xy 213.031755 -313.377473) (xy 212.980426 -313.399285)
			(xy 212.926469 -313.413391) (xy 212.871032 -313.419491) (xy 212.815298 -313.417454) (xy 212.760455 -313.407324)
			(xy 212.707671 -313.389317) (xy 212.658071 -313.363816) (xy 212.612713 -313.331365) (xy 212.572564 -313.292656)
			(xy 212.538478 -313.248513) (xy 212.511182 -313.199878) (xy 212.491259 -313.147787) (xy 212.479133 -313.09335)
			(xy 212.475062 -313.037728) (xy 203.305918 -313.037728) (xy 203.303103 -313.046853) (xy 203.279977 -313.094874)
			(xy 203.249953 -313.138911) (xy 203.213701 -313.177982) (xy 203.17203 -313.211213) (xy 203.125872 -313.237862)
			(xy 203.076258 -313.257334) (xy 203.024296 -313.269194) (xy 202.971146 -313.273178) (xy 202.917996 -313.269194)
			(xy 202.866034 -313.257334) (xy 202.81642 -313.237862) (xy 202.770262 -313.211213) (xy 202.728591 -313.177982)
			(xy 202.692339 -313.138911) (xy 202.662315 -313.094874) (xy 202.639189 -313.046853) (xy 202.623479 -312.995923)
			(xy 202.615536 -312.943219) (xy 188.239156 -312.943219) (xy 188.231213 -312.995923) (xy 188.215503 -313.046853)
			(xy 188.192377 -313.094874) (xy 188.162353 -313.138911) (xy 188.126101 -313.177982) (xy 188.08443 -313.211213)
			(xy 188.038272 -313.237862) (xy 187.988658 -313.257334) (xy 187.936696 -313.269194) (xy 187.883546 -313.273178)
			(xy 187.830396 -313.269194) (xy 187.778434 -313.257334) (xy 187.72882 -313.237862) (xy 187.682662 -313.211213)
			(xy 187.640991 -313.177982) (xy 187.604739 -313.138911) (xy 187.574715 -313.094874) (xy 187.551589 -313.046853)
			(xy 187.535879 -312.995923) (xy 187.527936 -312.943219) (xy 173.151556 -312.943219) (xy 173.143613 -312.995923)
			(xy 173.127903 -313.046853) (xy 173.104777 -313.094874) (xy 173.074753 -313.138911) (xy 173.038501 -313.177982)
			(xy 172.99683 -313.211213) (xy 172.950672 -313.237862) (xy 172.901058 -313.257334) (xy 172.849096 -313.269194)
			(xy 172.795946 -313.273178) (xy 172.742796 -313.269194) (xy 172.690834 -313.257334) (xy 172.64122 -313.237862)
			(xy 172.595062 -313.211213) (xy 172.553391 -313.177982) (xy 172.517139 -313.138911) (xy 172.487115 -313.094874)
			(xy 172.463989 -313.046853) (xy 172.448279 -312.995923) (xy 172.440336 -312.943219) (xy 159.11576 -312.943219)
			(xy 159.11576 -313.793357) (xy 176.540404 -313.793357) (xy 176.540404 -313.740059) (xy 176.548347 -313.687355)
			(xy 176.564057 -313.636425) (xy 176.587183 -313.588404) (xy 176.617207 -313.544367) (xy 176.653459 -313.505296)
			(xy 176.69513 -313.472065) (xy 176.741288 -313.445416) (xy 176.790902 -313.425944) (xy 176.842864 -313.414084)
			(xy 176.896014 -313.410101) (xy 176.949164 -313.414084) (xy 177.001126 -313.425944) (xy 177.05074 -313.445416)
			(xy 177.096898 -313.472065) (xy 177.138569 -313.505296) (xy 177.174821 -313.544367) (xy 177.204845 -313.588404)
			(xy 177.227971 -313.636425) (xy 177.243681 -313.687355) (xy 177.251624 -313.740059) (xy 177.252122 -313.766708)
			(xy 177.251624 -313.793357) (xy 191.628004 -313.793357) (xy 191.628004 -313.740059) (xy 191.635947 -313.687355)
			(xy 191.651657 -313.636425) (xy 191.674783 -313.588404) (xy 191.704807 -313.544367) (xy 191.741059 -313.505296)
			(xy 191.78273 -313.472065) (xy 191.828888 -313.445416) (xy 191.878502 -313.425944) (xy 191.930464 -313.414084)
			(xy 191.983614 -313.410101) (xy 192.036764 -313.414084) (xy 192.088726 -313.425944) (xy 192.13834 -313.445416)
			(xy 192.184498 -313.472065) (xy 192.226169 -313.505296) (xy 192.262421 -313.544367) (xy 192.292445 -313.588404)
			(xy 192.315571 -313.636425) (xy 192.331281 -313.687355) (xy 192.339224 -313.740059) (xy 192.339722 -313.766708)
			(xy 192.339224 -313.793357) (xy 206.715604 -313.793357) (xy 206.715604 -313.740059) (xy 206.723547 -313.687355)
			(xy 206.739257 -313.636425) (xy 206.762383 -313.588404) (xy 206.792407 -313.544367) (xy 206.828659 -313.505296)
			(xy 206.87033 -313.472065) (xy 206.916488 -313.445416) (xy 206.966102 -313.425944) (xy 207.018064 -313.414084)
			(xy 207.071214 -313.410101) (xy 207.124364 -313.414084) (xy 207.176326 -313.425944) (xy 207.22594 -313.445416)
			(xy 207.272098 -313.472065) (xy 207.313769 -313.505296) (xy 207.350021 -313.544367) (xy 207.380045 -313.588404)
			(xy 207.403171 -313.636425) (xy 207.418881 -313.687355) (xy 207.426824 -313.740059) (xy 207.427322 -313.766708)
			(xy 207.426824 -313.793357) (xy 207.418881 -313.846061) (xy 207.403171 -313.896991) (xy 207.380045 -313.945012)
			(xy 207.350021 -313.989049) (xy 207.313769 -314.02812) (xy 207.272098 -314.061351) (xy 207.22594 -314.088)
			(xy 207.176326 -314.107472) (xy 207.124364 -314.119332) (xy 207.071214 -314.123316) (xy 207.018064 -314.119332)
			(xy 206.966102 -314.107472) (xy 206.916488 -314.088) (xy 206.87033 -314.061351) (xy 206.828659 -314.02812)
			(xy 206.792407 -313.989049) (xy 206.762383 -313.945012) (xy 206.739257 -313.896991) (xy 206.723547 -313.846061)
			(xy 206.715604 -313.793357) (xy 192.339224 -313.793357) (xy 192.331281 -313.846061) (xy 192.315571 -313.896991)
			(xy 192.292445 -313.945012) (xy 192.262421 -313.989049) (xy 192.226169 -314.02812) (xy 192.184498 -314.061351)
			(xy 192.13834 -314.088) (xy 192.088726 -314.107472) (xy 192.036764 -314.119332) (xy 191.983614 -314.123316)
			(xy 191.930464 -314.119332) (xy 191.878502 -314.107472) (xy 191.828888 -314.088) (xy 191.78273 -314.061351)
			(xy 191.741059 -314.02812) (xy 191.704807 -313.989049) (xy 191.674783 -313.945012) (xy 191.651657 -313.896991)
			(xy 191.635947 -313.846061) (xy 191.628004 -313.793357) (xy 177.251624 -313.793357) (xy 177.243681 -313.846061)
			(xy 177.227971 -313.896991) (xy 177.204845 -313.945012) (xy 177.174821 -313.989049) (xy 177.138569 -314.02812)
			(xy 177.096898 -314.061351) (xy 177.05074 -314.088) (xy 177.001126 -314.107472) (xy 176.949164 -314.119332)
			(xy 176.896014 -314.123316) (xy 176.842864 -314.119332) (xy 176.790902 -314.107472) (xy 176.741288 -314.088)
			(xy 176.69513 -314.061351) (xy 176.653459 -314.02812) (xy 176.617207 -313.989049) (xy 176.587183 -313.945012)
			(xy 176.564057 -313.896991) (xy 176.548347 -313.846061) (xy 176.540404 -313.793357) (xy 159.11576 -313.793357)
			(xy 159.11576 -314.643241) (xy 172.440336 -314.643241) (xy 172.440336 -314.589943) (xy 172.448279 -314.537239)
			(xy 172.463989 -314.486309) (xy 172.487115 -314.438288) (xy 172.517139 -314.394251) (xy 172.553391 -314.35518)
			(xy 172.595062 -314.321949) (xy 172.64122 -314.2953) (xy 172.690834 -314.275828) (xy 172.742796 -314.263968)
			(xy 172.795946 -314.259985) (xy 172.849096 -314.263968) (xy 172.901058 -314.275828) (xy 172.950672 -314.2953)
			(xy 172.99683 -314.321949) (xy 173.038501 -314.35518) (xy 173.074753 -314.394251) (xy 173.104777 -314.438288)
			(xy 173.127903 -314.486309) (xy 173.143613 -314.537239) (xy 173.151556 -314.589943) (xy 173.152054 -314.616592)
			(xy 173.151556 -314.643241) (xy 187.527936 -314.643241) (xy 187.527936 -314.589943) (xy 187.535879 -314.537239)
			(xy 187.551589 -314.486309) (xy 187.574715 -314.438288) (xy 187.604739 -314.394251) (xy 187.640991 -314.35518)
			(xy 187.682662 -314.321949) (xy 187.72882 -314.2953) (xy 187.778434 -314.275828) (xy 187.830396 -314.263968)
			(xy 187.883546 -314.259985) (xy 187.936696 -314.263968) (xy 187.988658 -314.275828) (xy 188.038272 -314.2953)
			(xy 188.08443 -314.321949) (xy 188.126101 -314.35518) (xy 188.162353 -314.394251) (xy 188.192377 -314.438288)
			(xy 188.215503 -314.486309) (xy 188.231213 -314.537239) (xy 188.239156 -314.589943) (xy 188.239654 -314.616592)
			(xy 188.239156 -314.643241) (xy 202.615536 -314.643241) (xy 202.615536 -314.589943) (xy 202.623479 -314.537239)
			(xy 202.639189 -314.486309) (xy 202.662315 -314.438288) (xy 202.692339 -314.394251) (xy 202.728591 -314.35518)
			(xy 202.770262 -314.321949) (xy 202.81642 -314.2953) (xy 202.866034 -314.275828) (xy 202.917996 -314.263968)
			(xy 202.971146 -314.259985) (xy 203.024296 -314.263968) (xy 203.076258 -314.275828) (xy 203.125872 -314.2953)
			(xy 203.17203 -314.321949) (xy 203.213701 -314.35518) (xy 203.249953 -314.394251) (xy 203.279977 -314.438288)
			(xy 203.303103 -314.486309) (xy 203.318813 -314.537239) (xy 203.326756 -314.589943) (xy 203.327254 -314.616592)
			(xy 203.326756 -314.643241) (xy 203.318813 -314.695945) (xy 203.303103 -314.746875) (xy 203.279977 -314.794896)
			(xy 203.249953 -314.838933) (xy 203.213701 -314.878004) (xy 203.17203 -314.911235) (xy 203.125872 -314.937884)
			(xy 203.076258 -314.957356) (xy 203.024296 -314.969216) (xy 202.971146 -314.9732) (xy 202.917996 -314.969216)
			(xy 202.866034 -314.957356) (xy 202.81642 -314.937884) (xy 202.770262 -314.911235) (xy 202.728591 -314.878004)
			(xy 202.692339 -314.838933) (xy 202.662315 -314.794896) (xy 202.639189 -314.746875) (xy 202.623479 -314.695945)
			(xy 202.615536 -314.643241) (xy 188.239156 -314.643241) (xy 188.231213 -314.695945) (xy 188.215503 -314.746875)
			(xy 188.192377 -314.794896) (xy 188.162353 -314.838933) (xy 188.126101 -314.878004) (xy 188.08443 -314.911235)
			(xy 188.038272 -314.937884) (xy 187.988658 -314.957356) (xy 187.936696 -314.969216) (xy 187.883546 -314.9732)
			(xy 187.830396 -314.969216) (xy 187.778434 -314.957356) (xy 187.72882 -314.937884) (xy 187.682662 -314.911235)
			(xy 187.640991 -314.878004) (xy 187.604739 -314.838933) (xy 187.574715 -314.794896) (xy 187.551589 -314.746875)
			(xy 187.535879 -314.695945) (xy 187.527936 -314.643241) (xy 173.151556 -314.643241) (xy 173.143613 -314.695945)
			(xy 173.127903 -314.746875) (xy 173.104777 -314.794896) (xy 173.074753 -314.838933) (xy 173.038501 -314.878004)
			(xy 172.99683 -314.911235) (xy 172.950672 -314.937884) (xy 172.901058 -314.957356) (xy 172.849096 -314.969216)
			(xy 172.795946 -314.9732) (xy 172.742796 -314.969216) (xy 172.690834 -314.957356) (xy 172.64122 -314.937884)
			(xy 172.595062 -314.911235) (xy 172.553391 -314.878004) (xy 172.517139 -314.838933) (xy 172.487115 -314.794896)
			(xy 172.463989 -314.746875) (xy 172.448279 -314.695945) (xy 172.440336 -314.643241) (xy 159.11576 -314.643241)
			(xy 159.11576 -315.493379) (xy 176.540404 -315.493379) (xy 176.540404 -315.440081) (xy 176.548347 -315.387377)
			(xy 176.564057 -315.336447) (xy 176.587183 -315.288426) (xy 176.617207 -315.244389) (xy 176.653459 -315.205318)
			(xy 176.69513 -315.172087) (xy 176.741288 -315.145438) (xy 176.790902 -315.125966) (xy 176.842864 -315.114106)
			(xy 176.896014 -315.110123) (xy 176.949164 -315.114106) (xy 177.001126 -315.125966) (xy 177.05074 -315.145438)
			(xy 177.096898 -315.172087) (xy 177.138569 -315.205318) (xy 177.174821 -315.244389) (xy 177.204845 -315.288426)
			(xy 177.227971 -315.336447) (xy 177.243681 -315.387377) (xy 177.251624 -315.440081) (xy 177.252122 -315.46673)
			(xy 177.251624 -315.493379) (xy 191.628004 -315.493379) (xy 191.628004 -315.440081) (xy 191.635947 -315.387377)
			(xy 191.651657 -315.336447) (xy 191.674783 -315.288426) (xy 191.704807 -315.244389) (xy 191.741059 -315.205318)
			(xy 191.78273 -315.172087) (xy 191.828888 -315.145438) (xy 191.878502 -315.125966) (xy 191.930464 -315.114106)
			(xy 191.983614 -315.110123) (xy 192.036764 -315.114106) (xy 192.088726 -315.125966) (xy 192.13834 -315.145438)
			(xy 192.184498 -315.172087) (xy 192.226169 -315.205318) (xy 192.262421 -315.244389) (xy 192.292445 -315.288426)
			(xy 192.315571 -315.336447) (xy 192.331281 -315.387377) (xy 192.339224 -315.440081) (xy 192.339722 -315.46673)
			(xy 192.339224 -315.493379) (xy 206.715604 -315.493379) (xy 206.715604 -315.440081) (xy 206.723547 -315.387377)
			(xy 206.739257 -315.336447) (xy 206.762383 -315.288426) (xy 206.792407 -315.244389) (xy 206.828659 -315.205318)
			(xy 206.87033 -315.172087) (xy 206.916488 -315.145438) (xy 206.966102 -315.125966) (xy 207.018064 -315.114106)
			(xy 207.071214 -315.110123) (xy 207.124364 -315.114106) (xy 207.176326 -315.125966) (xy 207.22594 -315.145438)
			(xy 207.272098 -315.172087) (xy 207.313769 -315.205318) (xy 207.350021 -315.244389) (xy 207.380045 -315.288426)
			(xy 207.403171 -315.336447) (xy 207.418881 -315.387377) (xy 207.426824 -315.440081) (xy 207.427322 -315.46673)
			(xy 207.426824 -315.493379) (xy 207.418881 -315.546083) (xy 207.403171 -315.597013) (xy 207.380045 -315.645034)
			(xy 207.350021 -315.689071) (xy 207.313769 -315.728142) (xy 207.272098 -315.761373) (xy 207.22594 -315.788022)
			(xy 207.176326 -315.807494) (xy 207.124364 -315.819354) (xy 207.071214 -315.823338) (xy 207.018064 -315.819354)
			(xy 206.966102 -315.807494) (xy 206.916488 -315.788022) (xy 206.87033 -315.761373) (xy 206.828659 -315.728142)
			(xy 206.792407 -315.689071) (xy 206.762383 -315.645034) (xy 206.739257 -315.597013) (xy 206.723547 -315.546083)
			(xy 206.715604 -315.493379) (xy 192.339224 -315.493379) (xy 192.331281 -315.546083) (xy 192.315571 -315.597013)
			(xy 192.292445 -315.645034) (xy 192.262421 -315.689071) (xy 192.226169 -315.728142) (xy 192.184498 -315.761373)
			(xy 192.13834 -315.788022) (xy 192.088726 -315.807494) (xy 192.036764 -315.819354) (xy 191.983614 -315.823338)
			(xy 191.930464 -315.819354) (xy 191.878502 -315.807494) (xy 191.828888 -315.788022) (xy 191.78273 -315.761373)
			(xy 191.741059 -315.728142) (xy 191.704807 -315.689071) (xy 191.674783 -315.645034) (xy 191.651657 -315.597013)
			(xy 191.635947 -315.546083) (xy 191.628004 -315.493379) (xy 177.251624 -315.493379) (xy 177.243681 -315.546083)
			(xy 177.227971 -315.597013) (xy 177.204845 -315.645034) (xy 177.174821 -315.689071) (xy 177.138569 -315.728142)
			(xy 177.096898 -315.761373) (xy 177.05074 -315.788022) (xy 177.001126 -315.807494) (xy 176.949164 -315.819354)
			(xy 176.896014 -315.823338) (xy 176.842864 -315.819354) (xy 176.790902 -315.807494) (xy 176.741288 -315.788022)
			(xy 176.69513 -315.761373) (xy 176.653459 -315.728142) (xy 176.617207 -315.689071) (xy 176.587183 -315.645034)
			(xy 176.564057 -315.597013) (xy 176.548347 -315.546083) (xy 176.540404 -315.493379) (xy 159.11576 -315.493379)
			(xy 159.11576 -315.633608) (xy 159.48914 -316.006988) (xy 161.691828 -316.006988)
		)
		(stroke
			(width 0)
			(type solid)
		)
		(fill yes)
		(layer "In15.Cu")
		(net "GND")
	)
	(gr_poly
		(pts
			(xy 264.273538 -316.461648) (xy 264.287673 -316.461195) (xy 264.314864 -316.453457) (xy 264.338889 -316.438558)
			(xy 264.357906 -316.41764) (xy 264.370455 -316.392308) (xy 264.375575 -316.364505) (xy 264.37463 -316.350396)
			(xy 264.373106 -316.316614) (xy 264.373604 -316.289965) (xy 264.381547 -316.237261) (xy 264.397257 -316.186331)
			(xy 264.420383 -316.13831) (xy 264.450407 -316.094273) (xy 264.486659 -316.055202) (xy 264.52833 -316.021971)
			(xy 264.574488 -315.995322) (xy 264.624102 -315.97585) (xy 264.676064 -315.96399) (xy 264.729214 -315.960007)
			(xy 264.782364 -315.96399) (xy 264.834326 -315.97585) (xy 264.88394 -315.995322) (xy 264.930098 -316.021971)
			(xy 264.971769 -316.055202) (xy 265.008021 -316.094273) (xy 265.038045 -316.13831) (xy 265.061171 -316.186331)
			(xy 265.076881 -316.237261) (xy 265.084824 -316.289965) (xy 265.085322 -316.316614) (xy 265.083798 -316.350396)
			(xy 265.08292 -316.364502) (xy 265.088055 -316.392284) (xy 265.100602 -316.417598) (xy 265.119601 -316.438508)
			(xy 265.1436 -316.453416) (xy 265.170764 -316.461183) (xy 265.18489 -316.461648) (xy 276.653752 -316.461648)
			(xy 276.670757 -316.441613) (xy 276.709653 -316.406279) (xy 276.75332 -316.377045) (xy 276.800809 -316.354546)
			(xy 276.851089 -316.339269) (xy 276.903067 -316.331547) (xy 276.955617 -316.331547) (xy 277.007595 -316.339269)
			(xy 277.057875 -316.354546) (xy 277.105364 -316.377045) (xy 277.149031 -316.406279) (xy 277.187927 -316.441613)
			(xy 277.204932 -316.461648) (xy 279.361138 -316.461648) (xy 279.375273 -316.461195) (xy 279.402464 -316.453457)
			(xy 279.426489 -316.438558) (xy 279.445506 -316.41764) (xy 279.458055 -316.392308) (xy 279.463175 -316.364505)
			(xy 279.46223 -316.350396) (xy 279.460706 -316.316614) (xy 279.461204 -316.289965) (xy 279.469147 -316.237261)
			(xy 279.484857 -316.186331) (xy 279.507983 -316.13831) (xy 279.538007 -316.094273) (xy 279.574259 -316.055202)
			(xy 279.61593 -316.021971) (xy 279.662088 -315.995322) (xy 279.711702 -315.97585) (xy 279.763664 -315.96399)
			(xy 279.816814 -315.960007) (xy 279.869964 -315.96399) (xy 279.921926 -315.97585) (xy 279.97154 -315.995322)
			(xy 280.017698 -316.021971) (xy 280.059369 -316.055202) (xy 280.095621 -316.094273) (xy 280.125645 -316.13831)
			(xy 280.148771 -316.186331) (xy 280.164481 -316.237261) (xy 280.172424 -316.289965) (xy 280.172922 -316.316614)
			(xy 280.171398 -316.350396) (xy 280.17052 -316.364502) (xy 280.175655 -316.392284) (xy 280.188202 -316.417598)
			(xy 280.207201 -316.438508) (xy 280.2312 -316.453416) (xy 280.258364 -316.461183) (xy 280.27249 -316.461648)
			(xy 294.448738 -316.461648) (xy 294.462873 -316.461195) (xy 294.490064 -316.453457) (xy 294.514089 -316.438558)
			(xy 294.533106 -316.41764) (xy 294.545655 -316.392308) (xy 294.550775 -316.364505) (xy 294.54983 -316.350396)
			(xy 294.548306 -316.316614) (xy 294.548804 -316.289965) (xy 294.556747 -316.237261) (xy 294.572457 -316.186331)
			(xy 294.595583 -316.13831) (xy 294.625607 -316.094273) (xy 294.661859 -316.055202) (xy 294.70353 -316.021971)
			(xy 294.749688 -315.995322) (xy 294.799302 -315.97585) (xy 294.851264 -315.96399) (xy 294.904414 -315.960007)
			(xy 294.957564 -315.96399) (xy 295.009526 -315.97585) (xy 295.05914 -315.995322) (xy 295.105298 -316.021971)
			(xy 295.146969 -316.055202) (xy 295.183221 -316.094273) (xy 295.213245 -316.13831) (xy 295.236371 -316.186331)
			(xy 295.252081 -316.237261) (xy 295.260024 -316.289965) (xy 295.260522 -316.316614) (xy 295.258998 -316.350396)
			(xy 295.25812 -316.364502) (xy 295.263255 -316.392284) (xy 295.275802 -316.417598) (xy 295.294801 -316.438508)
			(xy 295.3188 -316.453416) (xy 295.345964 -316.461183) (xy 295.36009 -316.461648) (xy 310.646572 -316.461648)
			(xy 310.809894 -316.298072) (xy 310.840732 -316.2679) (xy 310.906828 -316.212439) (xy 310.977505 -316.16295)
			(xy 311.052226 -316.119807) (xy 311.130422 -316.08334) (xy 311.211499 -316.053826) (xy 311.294839 -316.03149)
			(xy 311.379809 -316.016501) (xy 311.465761 -316.008974) (xy 311.508902 -316.008512) (xy 311.682384 -316.008512)
			(xy 313.040014 -314.650882) (xy 313.070831 -314.620735) (xy 313.136881 -314.565321) (xy 313.207509 -314.515873)
			(xy 313.282176 -314.472767) (xy 313.360316 -314.436331) (xy 313.441333 -314.406843) (xy 313.524611 -314.384526)
			(xy 313.609517 -314.369551) (xy 313.695406 -314.362031) (xy 313.738514 -314.361576) (xy 313.88177 -314.361576)
			(xy 313.900101 -314.346934) (xy 313.940113 -314.322437) (xy 313.983192 -314.303857) (xy 314.005722 -314.297314)
			(xy 314.01893 -314.293758) (xy 314.432188 -313.8805) (xy 314.47486 -313.728354) (xy 314.47486 -306.47767)
			(xy 314.474347 -306.463488) (xy 314.46646 -306.436239) (xy 314.451385 -306.412209) (xy 314.430284 -306.393249)
			(xy 314.404784 -306.380821) (xy 314.37685 -306.375882) (xy 314.348634 -306.378814) (xy 314.322312 -306.38939)
			(xy 314.310776 -306.39766) (xy 314.287187 -306.41532) (xy 314.235384 -306.443397) (xy 314.179661 -306.462552)
			(xy 314.121544 -306.47226) (xy 314.092082 -306.472844) (xy 314.065431 -306.472345) (xy 314.012724 -306.464398)
			(xy 313.961791 -306.448685) (xy 313.913768 -306.425556) (xy 313.869728 -306.395529) (xy 313.830656 -306.359273)
			(xy 313.797423 -306.317599) (xy 313.770773 -306.271437) (xy 313.7513 -306.221819) (xy 313.73944 -306.169853)
			(xy 313.735456 -306.1167) (xy 313.73944 -306.063547) (xy 313.7513 -306.011581) (xy 313.770773 -305.961963)
			(xy 313.797423 -305.915801) (xy 313.830656 -305.874127) (xy 313.869728 -305.837871) (xy 313.913768 -305.807844)
			(xy 313.961791 -305.784715) (xy 314.012724 -305.769002) (xy 314.065431 -305.761055) (xy 314.092082 -305.760628)
			(xy 314.121536 -305.761265) (xy 314.179635 -305.771007) (xy 314.235344 -305.790164) (xy 314.287147 -305.818215)
			(xy 314.310776 -305.835812) (xy 314.32226 -305.844165) (xy 314.348589 -305.854772) (xy 314.376821 -305.857719)
			(xy 314.404773 -305.852778) (xy 314.430284 -305.840331) (xy 314.451382 -305.82134) (xy 314.466434 -305.797274)
			(xy 314.474278 -305.769994) (xy 314.47486 -305.755802) (xy 314.47486 -304.777648) (xy 314.474345 -304.763468)
			(xy 314.466454 -304.736225) (xy 314.451378 -304.7122) (xy 314.430279 -304.693245) (xy 314.404782 -304.68082)
			(xy 314.376852 -304.675882) (xy 314.348641 -304.678812) (xy 314.322322 -304.689384) (xy 314.310776 -304.697638)
			(xy 314.287188 -304.715299) (xy 314.235385 -304.743378) (xy 314.179662 -304.762534) (xy 314.121544 -304.772243)
			(xy 314.092082 -304.772822) (xy 314.065433 -304.772323) (xy 314.012729 -304.764377) (xy 313.961799 -304.748665)
			(xy 313.913779 -304.725537) (xy 313.869742 -304.695511) (xy 313.830672 -304.659258) (xy 313.797442 -304.617586)
			(xy 313.770793 -304.571428) (xy 313.751321 -304.521813) (xy 313.739461 -304.46985) (xy 313.735478 -304.4167)
			(xy 313.739461 -304.36355) (xy 313.751321 -304.311587) (xy 313.770793 -304.261972) (xy 313.797442 -304.215814)
			(xy 313.830672 -304.174142) (xy 313.869742 -304.137889) (xy 313.913779 -304.107863) (xy 313.961799 -304.084735)
			(xy 314.012729 -304.069023) (xy 314.065433 -304.061077) (xy 314.092082 -304.060606) (xy 314.121537 -304.061243)
			(xy 314.179636 -304.070985) (xy 314.235345 -304.090141) (xy 314.287149 -304.11819) (xy 314.310776 -304.13579)
			(xy 314.322264 -304.144139) (xy 314.348598 -304.154738) (xy 314.376832 -304.157681) (xy 314.404786 -304.152739)
			(xy 314.4303 -304.140295) (xy 314.451404 -304.12131) (xy 314.466468 -304.09725) (xy 314.474329 -304.069973)
			(xy 314.47486 -304.05578) (xy 314.47486 -303.077626) (xy 314.474354 -303.063438) (xy 314.466476 -303.036175)
			(xy 314.451403 -303.01213) (xy 314.430298 -302.993158) (xy 314.404789 -302.980722) (xy 314.376844 -302.975782)
			(xy 314.348617 -302.978718) (xy 314.322287 -302.989304) (xy 314.310776 -302.997616) (xy 314.287188 -303.015278)
			(xy 314.235385 -303.043358) (xy 314.179662 -303.062516) (xy 314.121544 -303.072225) (xy 314.092082 -303.0728)
			(xy 314.065434 -303.072301) (xy 314.012734 -303.064355) (xy 313.961807 -303.048644) (xy 313.91379 -303.025518)
			(xy 313.869756 -302.995494) (xy 313.830688 -302.959243) (xy 313.79746 -302.917574) (xy 313.770813 -302.871418)
			(xy 313.751342 -302.821806) (xy 313.739483 -302.769847) (xy 313.7355 -302.7167) (xy 313.739483 -302.663553)
			(xy 313.751342 -302.611594) (xy 313.770813 -302.561982) (xy 313.79746 -302.515826) (xy 313.830688 -302.474157)
			(xy 313.869756 -302.437906) (xy 313.91379 -302.407882) (xy 313.961807 -302.384756) (xy 314.012734 -302.369045)
			(xy 314.065434 -302.361099) (xy 314.092082 -302.360584) (xy 314.121537 -302.36122) (xy 314.179636 -302.370962)
			(xy 314.235346 -302.390117) (xy 314.287151 -302.418165) (xy 314.310776 -302.435768) (xy 314.322263 -302.444118)
			(xy 314.348595 -302.45472) (xy 314.376829 -302.457663) (xy 314.404782 -302.452722) (xy 314.430296 -302.440277)
			(xy 314.451398 -302.42129) (xy 314.466459 -302.397228) (xy 314.474315 -302.369951) (xy 314.47486 -302.355758)
			(xy 314.47486 -302.227742) (xy 314.474344 -302.213563) (xy 314.466452 -302.186321) (xy 314.451376 -302.162298)
			(xy 314.430277 -302.143344) (xy 314.404782 -302.13092) (xy 314.376853 -302.125982) (xy 314.348643 -302.128912)
			(xy 314.322324 -302.139482) (xy 314.310776 -302.147732) (xy 314.287188 -302.165394) (xy 314.235385 -302.193473)
			(xy 314.179662 -302.212629) (xy 314.121544 -302.222338) (xy 314.092082 -302.222916) (xy 314.065433 -302.222417)
			(xy 314.012731 -302.214471) (xy 313.961801 -302.198759) (xy 313.913782 -302.175632) (xy 313.869746 -302.145607)
			(xy 313.830677 -302.109354) (xy 313.797447 -302.067683) (xy 313.770798 -302.021525) (xy 313.751327 -301.971911)
			(xy 313.739467 -301.919949) (xy 313.735484 -301.8668) (xy 313.739467 -301.813651) (xy 313.751327 -301.761689)
			(xy 313.770798 -301.712075) (xy 313.797447 -301.665917) (xy 313.830677 -301.624246) (xy 313.869746 -301.587993)
			(xy 313.913782 -301.557968) (xy 313.961801 -301.534841) (xy 314.012731 -301.519129) (xy 314.065433 -301.511183)
			(xy 314.092082 -301.5107) (xy 314.121537 -301.511337) (xy 314.179636 -301.521079) (xy 314.235345 -301.540234)
			(xy 314.287149 -301.568283) (xy 314.310776 -301.585884) (xy 314.322263 -301.594233) (xy 314.348597 -301.604833)
			(xy 314.376831 -301.607776) (xy 314.404785 -301.602834) (xy 314.430299 -301.59039) (xy 314.451402 -301.571405)
			(xy 314.466466 -301.547344) (xy 314.474325 -301.520067) (xy 314.47486 -301.505874) (xy 314.47486 -300.52772)
			(xy 314.474354 -300.513533) (xy 314.466474 -300.486271) (xy 314.451401 -300.462228) (xy 314.430296 -300.443257)
			(xy 314.404789 -300.430822) (xy 314.376844 -300.425882) (xy 314.348619 -300.428818) (xy 314.32229 -300.439403)
			(xy 314.310776 -300.44771) (xy 314.287188 -300.465373) (xy 314.235386 -300.493453) (xy 314.179663 -300.512611)
			(xy 314.121544 -300.522321) (xy 314.092082 -300.522894) (xy 314.065435 -300.522395) (xy 314.012735 -300.51445)
			(xy 313.961809 -300.498739) (xy 313.913793 -300.475613) (xy 313.86976 -300.44559) (xy 313.830693 -300.409339)
			(xy 313.797465 -300.367671) (xy 313.770818 -300.321515) (xy 313.751348 -300.271904) (xy 313.739489 -300.219946)
			(xy 313.735506 -300.1668) (xy 313.739489 -300.113654) (xy 313.751348 -300.061696) (xy 313.770818 -300.012085)
			(xy 313.797465 -299.965929) (xy 313.830693 -299.924261) (xy 313.86976 -299.88801) (xy 313.913793 -299.857987)
			(xy 313.961809 -299.834861) (xy 314.012735 -299.81915) (xy 314.065435 -299.811205) (xy 314.092082 -299.810678)
			(xy 314.121536 -299.811315) (xy 314.179634 -299.821059) (xy 314.235341 -299.840218) (xy 314.287142 -299.868272)
			(xy 314.310776 -299.885862) (xy 314.322262 -299.894213) (xy 314.348595 -299.904815) (xy 314.376828 -299.907759)
			(xy 314.404781 -299.902817) (xy 314.430294 -299.890372) (xy 314.451396 -299.871385) (xy 314.466456 -299.847323)
			(xy 314.474311 -299.820044) (xy 314.47486 -299.805852) (xy 314.47486 -298.827698) (xy 314.474351 -298.813513)
			(xy 314.466468 -298.786257) (xy 314.451394 -298.762219) (xy 314.430291 -298.743254) (xy 314.404787 -298.730822)
			(xy 314.376847 -298.725882) (xy 314.348626 -298.728816) (xy 314.3223 -298.739397) (xy 314.310776 -298.747688)
			(xy 314.287189 -298.765352) (xy 314.235386 -298.793434) (xy 314.179663 -298.812593) (xy 314.121544 -298.822303)
			(xy 314.092082 -298.822872) (xy 314.065436 -298.822373) (xy 314.01274 -298.814428) (xy 313.961817 -298.798718)
			(xy 313.913804 -298.775594) (xy 313.869774 -298.745572) (xy 313.830709 -298.709324) (xy 313.797483 -298.667658)
			(xy 313.770838 -298.621506) (xy 313.751369 -298.571898) (xy 313.739511 -298.519942) (xy 313.735529 -298.4668)
			(xy 313.739511 -298.413658) (xy 313.751369 -298.361702) (xy 313.770838 -298.312094) (xy 313.797483 -298.265942)
			(xy 313.830709 -298.224276) (xy 313.869774 -298.188028) (xy 313.913804 -298.158006) (xy 313.961817 -298.134882)
			(xy 314.01274 -298.119172) (xy 314.065436 -298.111227) (xy 314.092082 -298.110656) (xy 314.121536 -298.111293)
			(xy 314.179635 -298.121036) (xy 314.235342 -298.140194) (xy 314.287144 -298.168247) (xy 314.310776 -298.18584)
			(xy 314.322261 -298.194192) (xy 314.348592 -298.204796) (xy 314.376825 -298.207741) (xy 314.404778 -298.2028)
			(xy 314.43029 -298.190354) (xy 314.45139 -298.171365) (xy 314.466447 -298.147302) (xy 314.474296 -298.120022)
			(xy 314.47486 -298.10583) (xy 314.47486 -269.1638) (xy 314.469272 -269.075662) (xy 314.467971 -269.062012)
			(xy 314.459041 -269.036099) (xy 314.443537 -269.013497) (xy 314.422576 -268.995836) (xy 314.397671 -268.984392)
			(xy 314.370618 -268.979989) (xy 314.343369 -268.982945) (xy 314.31789 -268.993047) (xy 314.306712 -269.000986)
			(xy 314.283379 -269.017894) (xy 314.232397 -269.044742) (xy 314.17776 -269.063038) (xy 314.120892 -269.072305)
			(xy 314.092082 -269.072868) (xy 314.065437 -269.072369) (xy 314.012741 -269.064424) (xy 313.961819 -269.048714)
			(xy 313.913806 -269.02559) (xy 313.869776 -268.995569) (xy 313.830712 -268.959321) (xy 313.797487 -268.917656)
			(xy 313.770842 -268.871504) (xy 313.751373 -268.821897) (xy 313.739515 -268.769942) (xy 313.735533 -268.7168)
			(xy 313.739515 -268.663658) (xy 313.751373 -268.611703) (xy 313.770842 -268.562096) (xy 313.797487 -268.515944)
			(xy 313.830712 -268.474279) (xy 313.869776 -268.438031) (xy 313.913806 -268.40801) (xy 313.961819 -268.384886)
			(xy 314.012741 -268.369176) (xy 314.065437 -268.361231) (xy 314.092082 -268.360652) (xy 314.092336 -268.360652)
			(xy 314.123094 -268.361298) (xy 314.183695 -268.37187) (xy 314.241573 -268.392711) (xy 314.268612 -268.407388)
			(xy 314.280723 -268.413781) (xy 314.307253 -268.420528) (xy 314.334622 -268.419977) (xy 314.360858 -268.412165)
			(xy 314.384073 -268.397658) (xy 314.402592 -268.377499) (xy 314.415083 -268.35314) (xy 314.420646 -268.326336)
			(xy 314.42025 -268.312646) (xy 314.086494 -263.097518) (xy 314.060792 -263.096601) (xy 314.010126 -263.087795)
			(xy 313.961433 -263.07125) (xy 313.915889 -263.047367) (xy 313.874591 -263.01672) (xy 313.838536 -262.98005)
			(xy 313.808593 -262.93824) (xy 313.785484 -262.892298) (xy 313.769766 -262.843332) (xy 313.761818 -262.792523)
			(xy 313.761374 -262.76681) (xy 313.761867 -262.740597) (xy 313.770126 -262.688826) (xy 313.786453 -262.639008)
			(xy 313.81044 -262.592392) (xy 313.841485 -262.550147) (xy 313.878809 -262.513332) (xy 313.921477 -262.482871)
			(xy 313.968418 -262.459527) (xy 314.018456 -262.443886) (xy 314.04433 -262.439658) (xy 313.976258 -261.376414)
			(xy 313.952927 -261.367208) (xy 313.909131 -261.342767) (xy 313.869533 -261.311987) (xy 313.835041 -261.275575)
			(xy 313.80645 -261.234368) (xy 313.784416 -261.189314) (xy 313.769444 -261.141446) (xy 313.76188 -261.091865)
			(xy 313.761374 -261.066788) (xy 313.761865 -261.041153) (xy 313.769794 -260.990499) (xy 313.785445 -260.941675)
			(xy 313.808444 -260.895852) (xy 313.838238 -260.854126) (xy 313.874115 -260.817499) (xy 313.915215 -260.786847)
			(xy 313.93765 -260.774434) (xy 313.803538 -258.677918) (xy 313.790335 -258.653102) (xy 313.771569 -258.600121)
			(xy 313.762022 -258.544731) (xy 313.761374 -258.516628) (xy 313.762113 -258.48504) (xy 313.774142 -258.423018)
			(xy 313.78525 -258.393438) (xy 313.52617 -254.347218) (xy 313.524853 -254.333295) (xy 313.515595 -254.306918)
			(xy 313.499528 -254.28404) (xy 313.477859 -254.266378) (xy 313.452211 -254.255256) (xy 313.424508 -254.251508)
			(xy 313.4106 -254.252984) (xy 313.398158 -254.254651) (xy 313.373115 -254.256429) (xy 313.360562 -254.25654)
			(xy 313.331231 -254.255939) (xy 313.273362 -254.246316) (xy 313.217854 -254.227338) (xy 313.166208 -254.199517)
			(xy 313.119821 -254.163606) (xy 313.09945 -254.142494) (xy 313.089418 -254.132384) (xy 313.065041 -254.117677)
			(xy 313.037551 -254.110272) (xy 313.009085 -254.110746) (xy 312.981856 -254.119061) (xy 312.957982 -254.134571)
			(xy 312.94832 -254.145034) (xy 312.931327 -254.163858) (xy 312.892929 -254.196982) (xy 312.85022 -254.224324)
			(xy 312.804064 -254.245332) (xy 312.755395 -254.259579) (xy 312.705198 -254.266779) (xy 312.679842 -254.267208)
			(xy 312.653189 -254.266738) (xy 312.600477 -254.258799) (xy 312.549538 -254.243091) (xy 312.501508 -254.219966)
			(xy 312.457462 -254.189941) (xy 312.418384 -254.153686) (xy 312.385146 -254.112011) (xy 312.358491 -254.065848)
			(xy 312.339015 -254.016227) (xy 312.327152 -253.964257) (xy 312.323168 -253.9111) (xy 312.327152 -253.857943)
			(xy 312.339015 -253.805973) (xy 312.358491 -253.756352) (xy 312.385146 -253.710189) (xy 312.418384 -253.668514)
			(xy 312.457462 -253.632259) (xy 312.501508 -253.602234) (xy 312.549538 -253.579109) (xy 312.600477 -253.563401)
			(xy 312.653189 -253.555462) (xy 312.679842 -253.554992) (xy 312.709173 -253.555594) (xy 312.76704 -253.565217)
			(xy 312.822547 -253.584198) (xy 312.874191 -253.612021) (xy 312.920575 -253.647934) (xy 312.940954 -253.669038)
			(xy 312.950988 -253.679145) (xy 312.975365 -253.693846) (xy 313.002853 -253.701247) (xy 313.031317 -253.700773)
			(xy 313.058543 -253.69246) (xy 313.082417 -253.676955) (xy 313.092084 -253.666498) (xy 313.109079 -253.647677)
			(xy 313.14748 -253.61456) (xy 313.19019 -253.587223) (xy 313.236345 -253.566221) (xy 313.285012 -253.551977)
			(xy 313.335208 -253.544779) (xy 313.360562 -253.544324) (xy 313.36869 -253.544324) (xy 313.381958 -253.544199)
			(xy 313.407736 -253.53795) (xy 313.431033 -253.525272) (xy 313.450278 -253.50702) (xy 313.464172 -253.484426)
			(xy 313.471777 -253.459016) (xy 313.472576 -253.445772) (xy 313.472576 -253.443994) (xy 313.579256 -249.875294)
			(xy 313.58205 -249.826526) (xy 313.765184 -247.516904) (xy 313.763392 -247.504408) (xy 313.761483 -247.479235)
			(xy 313.761374 -247.466612) (xy 313.761844 -247.440917) (xy 313.76976 -247.390142) (xy 313.777122 -247.36552)
			(xy 313.883548 -246.023384) (xy 313.864811 -246.007581) (xy 313.831755 -245.97139) (xy 313.804398 -245.93072)
			(xy 313.78334 -245.886459) (xy 313.76904 -245.839577) (xy 313.761812 -245.791097) (xy 313.761374 -245.76659)
			(xy 313.761837 -245.741836) (xy 313.769216 -245.692882) (xy 313.783808 -245.645574) (xy 313.805286 -245.600969)
			(xy 313.833172 -245.560062) (xy 313.866843 -245.523768) (xy 313.905546 -245.492897) (xy 313.926728 -245.480078)
			(xy 314.013342 -244.387878) (xy 313.989697 -244.381611) (xy 313.944432 -244.363067) (xy 313.902389 -244.338064)
			(xy 313.864483 -244.307148) (xy 313.831538 -244.27099) (xy 313.804273 -244.230377) (xy 313.783281 -244.186195)
			(xy 313.769018 -244.139405) (xy 313.761796 -244.091026) (xy 313.761374 -244.066568) (xy 313.761829 -244.041939)
			(xy 313.769135 -243.993225) (xy 313.783582 -243.946132) (xy 313.80485 -243.901701) (xy 313.832469 -243.860913)
			(xy 313.865828 -243.82467) (xy 313.904192 -243.793773) (xy 313.946712 -243.768903) (xy 313.992448 -243.750611)
			(xy 314.040391 -243.739301) (xy 314.064904 -243.736876) (xy 314.47486 -238.567976) (xy 314.47486 -231.677718)
			(xy 314.474353 -231.663531) (xy 314.466473 -231.63627) (xy 314.4514 -231.612227) (xy 314.430296 -231.593257)
			(xy 314.404788 -231.580822) (xy 314.376845 -231.575882) (xy 314.34862 -231.578818) (xy 314.322291 -231.589402)
			(xy 314.310776 -231.597708) (xy 314.287188 -231.615371) (xy 314.235386 -231.643451) (xy 314.179663 -231.662609)
			(xy 314.121544 -231.672319) (xy 314.092082 -231.672892) (xy 314.065435 -231.672393) (xy 314.012736 -231.664447)
			(xy 313.96181 -231.648736) (xy 313.913794 -231.625611) (xy 313.869761 -231.595588) (xy 313.830694 -231.559337)
			(xy 313.797467 -231.517669) (xy 313.77082 -231.471514) (xy 313.75135 -231.421904) (xy 313.739492 -231.369945)
			(xy 313.735509 -231.3168) (xy 313.739492 -231.263655) (xy 313.75135 -231.211696) (xy 313.77082 -231.162086)
			(xy 313.797467 -231.115931) (xy 313.830694 -231.074263) (xy 313.869761 -231.038012) (xy 313.913794 -231.007989)
			(xy 313.96181 -230.984864) (xy 314.012736 -230.969153) (xy 314.065435 -230.961207) (xy 314.092082 -230.960676)
			(xy 314.121536 -230.961313) (xy 314.179634 -230.971057) (xy 314.235341 -230.990216) (xy 314.287142 -231.018269)
			(xy 314.310776 -231.03586) (xy 314.322262 -231.044211) (xy 314.348594 -231.054813) (xy 314.376828 -231.057757)
			(xy 314.404781 -231.052816) (xy 314.430294 -231.040371) (xy 314.451396 -231.021383) (xy 314.466455 -230.997321)
			(xy 314.474309 -230.970042) (xy 314.47486 -230.95585) (xy 314.47486 -229.977696) (xy 314.474351 -229.963511)
			(xy 314.466467 -229.936256) (xy 314.451393 -229.912219) (xy 314.430291 -229.893253) (xy 314.404786 -229.880822)
			(xy 314.376847 -229.875882) (xy 314.348626 -229.878816) (xy 314.3223 -229.889396) (xy 314.310776 -229.897686)
			(xy 314.287189 -229.91535) (xy 314.235386 -229.943432) (xy 314.179663 -229.962591) (xy 314.121544 -229.972302)
			(xy 314.092082 -229.97287) (xy 314.065436 -229.972371) (xy 314.012741 -229.964426) (xy 313.961818 -229.948716)
			(xy 313.913805 -229.925592) (xy 313.869775 -229.89557) (xy 313.830711 -229.859322) (xy 313.797485 -229.817657)
			(xy 313.77084 -229.771505) (xy 313.751371 -229.721897) (xy 313.739513 -229.669942) (xy 313.735531 -229.6168)
			(xy 313.739513 -229.563658) (xy 313.751371 -229.511703) (xy 313.77084 -229.462095) (xy 313.797485 -229.415943)
			(xy 313.830711 -229.374278) (xy 313.869775 -229.33803) (xy 313.913805 -229.308008) (xy 313.961818 -229.284884)
			(xy 314.012741 -229.269174) (xy 314.065436 -229.261229) (xy 314.092082 -229.260654) (xy 314.121536 -229.261291)
			(xy 314.179635 -229.271034) (xy 314.235342 -229.290192) (xy 314.287144 -229.318244) (xy 314.310776 -229.335838)
			(xy 314.322261 -229.34419) (xy 314.348592 -229.354795) (xy 314.376825 -229.35774) (xy 314.404778 -229.352799)
			(xy 314.43029 -229.340353) (xy 314.451389 -229.321364) (xy 314.466446 -229.2973) (xy 314.474295 -229.27002)
			(xy 314.47486 -229.255828) (xy 314.47486 -228.277674) (xy 314.474348 -228.263491) (xy 314.466461 -228.236242)
			(xy 314.451386 -228.21221) (xy 314.430285 -228.193249) (xy 314.404784 -228.180821) (xy 314.376849 -228.175882)
			(xy 314.348633 -228.178814) (xy 314.32231 -228.189391) (xy 314.310776 -228.197664) (xy 314.287187 -228.215324)
			(xy 314.235384 -228.243401) (xy 314.179661 -228.262555) (xy 314.121543 -228.272264) (xy 314.092082 -228.272848)
			(xy 314.065431 -228.272349) (xy 314.012723 -228.264402) (xy 313.961789 -228.248689) (xy 313.913766 -228.22556)
			(xy 313.869726 -228.195532) (xy 313.830653 -228.159276) (xy 313.79742 -228.117601) (xy 313.770769 -228.071439)
			(xy 313.751296 -228.02182) (xy 313.739436 -227.969854) (xy 313.735452 -227.9167) (xy 313.739436 -227.863546)
			(xy 313.751296 -227.81158) (xy 313.770769 -227.761961) (xy 313.79742 -227.715799) (xy 313.830653 -227.674124)
			(xy 313.869726 -227.637868) (xy 313.913766 -227.60784) (xy 313.961789 -227.584711) (xy 314.012723 -227.568998)
			(xy 314.065431 -227.561051) (xy 314.092082 -227.560632) (xy 314.121536 -227.561269) (xy 314.179635 -227.571011)
			(xy 314.235343 -227.590169) (xy 314.287146 -227.61822) (xy 314.310776 -227.635816) (xy 314.32226 -227.644169)
			(xy 314.34859 -227.654776) (xy 314.376822 -227.657722) (xy 314.404774 -227.652781) (xy 314.430285 -227.640334)
			(xy 314.451383 -227.621344) (xy 314.466436 -227.597278) (xy 314.47428 -227.569998) (xy 314.47486 -227.555806)
			(xy 314.47486 -227.427536) (xy 314.474343 -227.413357) (xy 314.46645 -227.386117) (xy 314.451374 -227.362096)
			(xy 314.430276 -227.343143) (xy 314.404781 -227.33072) (xy 314.376854 -227.325782) (xy 314.348645 -227.328711)
			(xy 314.322327 -227.339281) (xy 314.310776 -227.347526) (xy 314.287188 -227.365188) (xy 314.235385 -227.393267)
			(xy 314.179662 -227.412424) (xy 314.121544 -227.422133) (xy 314.092082 -227.42271) (xy 314.065433 -227.422211)
			(xy 314.012732 -227.414265) (xy 313.961803 -227.398553) (xy 313.913785 -227.375427) (xy 313.86975 -227.345402)
			(xy 313.830681 -227.30915) (xy 313.797452 -227.26748) (xy 313.770804 -227.221322) (xy 313.751333 -227.171709)
			(xy 313.739473 -227.119748) (xy 313.73549 -227.0666) (xy 313.739473 -227.013452) (xy 313.751333 -226.961491)
			(xy 313.770804 -226.911878) (xy 313.797452 -226.86572) (xy 313.830681 -226.82405) (xy 313.86975 -226.787798)
			(xy 313.913785 -226.757773) (xy 313.961803 -226.734647) (xy 314.012732 -226.718935) (xy 314.065433 -226.710989)
			(xy 314.092082 -226.710494) (xy 314.121537 -226.71113) (xy 314.179636 -226.720872) (xy 314.235346 -226.740027)
			(xy 314.28715 -226.768076) (xy 314.310776 -226.785678) (xy 314.322263 -226.794028) (xy 314.348596 -226.804628)
			(xy 314.37683 -226.807571) (xy 314.404784 -226.80263) (xy 314.430298 -226.790185) (xy 314.451401 -226.771199)
			(xy 314.466463 -226.747138) (xy 314.474321 -226.719861) (xy 314.47486 -226.705668) (xy 314.47486 -225.727514)
			(xy 314.474353 -225.713327) (xy 314.466472 -225.686067) (xy 314.451399 -225.662026) (xy 314.430295 -225.643056)
			(xy 314.404788 -225.630622) (xy 314.376845 -225.625682) (xy 314.348621 -225.628617) (xy 314.322292 -225.639201)
			(xy 314.310776 -225.647504) (xy 314.287188 -225.665167) (xy 314.235386 -225.693248) (xy 314.179663 -225.712406)
			(xy 314.121544 -225.722116) (xy 314.092082 -225.722688) (xy 314.065435 -225.722189) (xy 314.012737 -225.714243)
			(xy 313.961811 -225.698532) (xy 313.913796 -225.675407) (xy 313.869764 -225.645385) (xy 313.830697 -225.609134)
			(xy 313.79747 -225.567467) (xy 313.770824 -225.521313) (xy 313.751354 -225.471703) (xy 313.739496 -225.419745)
			(xy 313.735513 -225.3666) (xy 313.739496 -225.313455) (xy 313.751354 -225.261497) (xy 313.770824 -225.211887)
			(xy 313.79747 -225.165733) (xy 313.830697 -225.124066) (xy 313.869764 -225.087815) (xy 313.913796 -225.057793)
			(xy 313.961811 -225.034668) (xy 314.012737 -225.018957) (xy 314.065435 -225.011011) (xy 314.092082 -225.010472)
			(xy 314.121536 -225.011109) (xy 314.179634 -225.020852) (xy 314.235342 -225.040011) (xy 314.287143 -225.068065)
			(xy 314.310776 -225.085656) (xy 314.322262 -225.094007) (xy 314.348594 -225.10461) (xy 314.376827 -225.107554)
			(xy 314.40478 -225.102613) (xy 314.430293 -225.090167) (xy 314.451394 -225.07118) (xy 314.466453 -225.047117)
			(xy 314.474307 -225.019838) (xy 314.47486 -225.005646) (xy 314.47486 -224.027492) (xy 314.47435 -224.013308)
			(xy 314.466466 -223.986053) (xy 314.451392 -223.962017) (xy 314.43029 -223.943053) (xy 314.404786 -223.930621)
			(xy 314.376847 -223.925682) (xy 314.348628 -223.928616) (xy 314.322302 -223.939195) (xy 314.310776 -223.947482)
			(xy 314.287189 -223.965146) (xy 314.235387 -223.993229) (xy 314.179663 -224.012388) (xy 314.121544 -224.022099)
			(xy 314.092082 -224.022666) (xy 314.065437 -224.022167) (xy 314.012742 -224.014222) (xy 313.961819 -223.998512)
			(xy 313.913807 -223.975388) (xy 313.869777 -223.945367) (xy 313.830714 -223.909119) (xy 313.797488 -223.867455)
			(xy 313.770844 -223.821303) (xy 313.751375 -223.771696) (xy 313.739517 -223.719742) (xy 313.735535 -223.6666)
			(xy 313.739517 -223.613458) (xy 313.751375 -223.561504) (xy 313.770844 -223.511897) (xy 313.797488 -223.465745)
			(xy 313.830714 -223.42408) (xy 313.869777 -223.387833) (xy 313.913807 -223.357812) (xy 313.961819 -223.334688)
			(xy 314.012742 -223.318978) (xy 314.065437 -223.311033) (xy 314.092082 -223.31045) (xy 314.121536 -223.311087)
			(xy 314.179635 -223.32083) (xy 314.235343 -223.339988) (xy 314.287145 -223.36804) (xy 314.310776 -223.385634)
			(xy 314.322261 -223.393986) (xy 314.348591 -223.404591) (xy 314.376824 -223.407537) (xy 314.404777 -223.402595)
			(xy 314.430289 -223.390149) (xy 314.451388 -223.37116) (xy 314.466444 -223.347096) (xy 314.474292 -223.319816)
			(xy 314.47486 -223.305624) (xy 314.47486 -194.645788) (xy 314.01766 -194.188588) (xy 305.2064 -194.188588)
			(xy 301.89678 -190.878968) (xy 258.54406 -190.878968) (xy 254.629687 -194.793341) (xy 256.887716 -194.793341)
			(xy 256.887716 -194.740043) (xy 256.895659 -194.687339) (xy 256.911369 -194.636409) (xy 256.934495 -194.588388)
			(xy 256.964519 -194.544351) (xy 257.000771 -194.50528) (xy 257.042442 -194.472049) (xy 257.0886 -194.4454)
			(xy 257.138214 -194.425928) (xy 257.190176 -194.414068) (xy 257.243326 -194.410085) (xy 257.296476 -194.414068)
			(xy 257.348438 -194.425928) (xy 257.398052 -194.4454) (xy 257.44421 -194.472049) (xy 257.485881 -194.50528)
			(xy 257.522133 -194.544351) (xy 257.552157 -194.588388) (xy 257.575283 -194.636409) (xy 257.590993 -194.687339)
			(xy 257.598936 -194.740043) (xy 257.599434 -194.766692) (xy 257.598936 -194.793341) (xy 262.138404 -194.793341)
			(xy 262.138404 -194.740043) (xy 262.146347 -194.687339) (xy 262.162057 -194.636409) (xy 262.185183 -194.588388)
			(xy 262.215207 -194.544351) (xy 262.251459 -194.50528) (xy 262.29313 -194.472049) (xy 262.339288 -194.4454)
			(xy 262.388902 -194.425928) (xy 262.440864 -194.414068) (xy 262.494014 -194.410085) (xy 262.547164 -194.414068)
			(xy 262.599126 -194.425928) (xy 262.64874 -194.4454) (xy 262.694898 -194.472049) (xy 262.736569 -194.50528)
			(xy 262.772821 -194.544351) (xy 262.802845 -194.588388) (xy 262.825971 -194.636409) (xy 262.841681 -194.687339)
			(xy 262.849624 -194.740043) (xy 262.850122 -194.766692) (xy 262.849624 -194.793341) (xy 269.682204 -194.793341)
			(xy 269.682204 -194.740043) (xy 269.690147 -194.687339) (xy 269.705857 -194.636409) (xy 269.728983 -194.588388)
			(xy 269.759007 -194.544351) (xy 269.795259 -194.50528) (xy 269.83693 -194.472049) (xy 269.883088 -194.4454)
			(xy 269.932702 -194.425928) (xy 269.984664 -194.414068) (xy 270.037814 -194.410085) (xy 270.090964 -194.414068)
			(xy 270.142926 -194.425928) (xy 270.19254 -194.4454) (xy 270.238698 -194.472049) (xy 270.280369 -194.50528)
			(xy 270.316621 -194.544351) (xy 270.346645 -194.588388) (xy 270.369771 -194.636409) (xy 270.385481 -194.687339)
			(xy 270.393424 -194.740043) (xy 270.393922 -194.766692) (xy 270.393533 -194.787499) (xy 277.192476 -194.787499)
			(xy 277.192476 -194.734201) (xy 277.200419 -194.681497) (xy 277.216129 -194.630567) (xy 277.239255 -194.582546)
			(xy 277.269279 -194.538509) (xy 277.305531 -194.499438) (xy 277.347202 -194.466207) (xy 277.39336 -194.439558)
			(xy 277.442974 -194.420086) (xy 277.494936 -194.408226) (xy 277.548086 -194.404243) (xy 277.601236 -194.408226)
			(xy 277.653198 -194.420086) (xy 277.702812 -194.439558) (xy 277.74897 -194.466207) (xy 277.790641 -194.499438)
			(xy 277.826893 -194.538509) (xy 277.856917 -194.582546) (xy 277.880043 -194.630567) (xy 277.895753 -194.681497)
			(xy 277.903696 -194.734201) (xy 277.904194 -194.76085) (xy 277.903696 -194.787499) (xy 277.902816 -194.793341)
			(xy 284.769804 -194.793341) (xy 284.769804 -194.740043) (xy 284.777747 -194.687339) (xy 284.793457 -194.636409)
			(xy 284.816583 -194.588388) (xy 284.846607 -194.544351) (xy 284.882859 -194.50528) (xy 284.92453 -194.472049)
			(xy 284.970688 -194.4454) (xy 285.020302 -194.425928) (xy 285.072264 -194.414068) (xy 285.125414 -194.410085)
			(xy 285.178564 -194.414068) (xy 285.230526 -194.425928) (xy 285.28014 -194.4454) (xy 285.326298 -194.472049)
			(xy 285.367969 -194.50528) (xy 285.404221 -194.544351) (xy 285.434245 -194.588388) (xy 285.457371 -194.636409)
			(xy 285.473081 -194.687339) (xy 285.481024 -194.740043) (xy 285.481522 -194.766692) (xy 285.481024 -194.793341)
			(xy 292.313604 -194.793341) (xy 292.313604 -194.740043) (xy 292.321547 -194.687339) (xy 292.337257 -194.636409)
			(xy 292.360383 -194.588388) (xy 292.390407 -194.544351) (xy 292.426659 -194.50528) (xy 292.46833 -194.472049)
			(xy 292.514488 -194.4454) (xy 292.564102 -194.425928) (xy 292.616064 -194.414068) (xy 292.669214 -194.410085)
			(xy 292.722364 -194.414068) (xy 292.774326 -194.425928) (xy 292.82394 -194.4454) (xy 292.870098 -194.472049)
			(xy 292.911769 -194.50528) (xy 292.948021 -194.544351) (xy 292.978045 -194.588388) (xy 293.001171 -194.636409)
			(xy 293.016881 -194.687339) (xy 293.024824 -194.740043) (xy 293.025322 -194.766692) (xy 293.024824 -194.793341)
			(xy 299.857404 -194.793341) (xy 299.857404 -194.740043) (xy 299.865347 -194.687339) (xy 299.881057 -194.636409)
			(xy 299.904183 -194.588388) (xy 299.934207 -194.544351) (xy 299.970459 -194.50528) (xy 300.01213 -194.472049)
			(xy 300.058288 -194.4454) (xy 300.107902 -194.425928) (xy 300.159864 -194.414068) (xy 300.213014 -194.410085)
			(xy 300.266164 -194.414068) (xy 300.318126 -194.425928) (xy 300.36774 -194.4454) (xy 300.413898 -194.472049)
			(xy 300.455569 -194.50528) (xy 300.491821 -194.544351) (xy 300.521845 -194.588388) (xy 300.544971 -194.636409)
			(xy 300.560681 -194.687339) (xy 300.568624 -194.740043) (xy 300.569122 -194.766692) (xy 300.568624 -194.793341)
			(xy 307.401204 -194.793341) (xy 307.401204 -194.740043) (xy 307.409147 -194.687339) (xy 307.424857 -194.636409)
			(xy 307.447983 -194.588388) (xy 307.478007 -194.544351) (xy 307.514259 -194.50528) (xy 307.55593 -194.472049)
			(xy 307.602088 -194.4454) (xy 307.651702 -194.425928) (xy 307.703664 -194.414068) (xy 307.756814 -194.410085)
			(xy 307.809964 -194.414068) (xy 307.861926 -194.425928) (xy 307.91154 -194.4454) (xy 307.957698 -194.472049)
			(xy 307.999369 -194.50528) (xy 308.035621 -194.544351) (xy 308.065645 -194.588388) (xy 308.088771 -194.636409)
			(xy 308.104481 -194.687339) (xy 308.112424 -194.740043) (xy 308.112922 -194.766692) (xy 308.112424 -194.793341)
			(xy 308.104481 -194.846045) (xy 308.088771 -194.896975) (xy 308.065645 -194.944996) (xy 308.035621 -194.989033)
			(xy 307.999369 -195.028104) (xy 307.957698 -195.061335) (xy 307.91154 -195.087984) (xy 307.861926 -195.107456)
			(xy 307.809964 -195.119316) (xy 307.756814 -195.1233) (xy 307.703664 -195.119316) (xy 307.651702 -195.107456)
			(xy 307.602088 -195.087984) (xy 307.55593 -195.061335) (xy 307.514259 -195.028104) (xy 307.478007 -194.989033)
			(xy 307.447983 -194.944996) (xy 307.424857 -194.896975) (xy 307.409147 -194.846045) (xy 307.401204 -194.793341)
			(xy 300.568624 -194.793341) (xy 300.560681 -194.846045) (xy 300.544971 -194.896975) (xy 300.521845 -194.944996)
			(xy 300.491821 -194.989033) (xy 300.455569 -195.028104) (xy 300.413898 -195.061335) (xy 300.36774 -195.087984)
			(xy 300.318126 -195.107456) (xy 300.266164 -195.119316) (xy 300.213014 -195.1233) (xy 300.159864 -195.119316)
			(xy 300.107902 -195.107456) (xy 300.058288 -195.087984) (xy 300.01213 -195.061335) (xy 299.970459 -195.028104)
			(xy 299.934207 -194.989033) (xy 299.904183 -194.944996) (xy 299.881057 -194.896975) (xy 299.865347 -194.846045)
			(xy 299.857404 -194.793341) (xy 293.024824 -194.793341) (xy 293.016881 -194.846045) (xy 293.001171 -194.896975)
			(xy 292.978045 -194.944996) (xy 292.948021 -194.989033) (xy 292.911769 -195.028104) (xy 292.870098 -195.061335)
			(xy 292.82394 -195.087984) (xy 292.774326 -195.107456) (xy 292.722364 -195.119316) (xy 292.669214 -195.1233)
			(xy 292.616064 -195.119316) (xy 292.564102 -195.107456) (xy 292.514488 -195.087984) (xy 292.46833 -195.061335)
			(xy 292.426659 -195.028104) (xy 292.390407 -194.989033) (xy 292.360383 -194.944996) (xy 292.337257 -194.896975)
			(xy 292.321547 -194.846045) (xy 292.313604 -194.793341) (xy 285.481024 -194.793341) (xy 285.473081 -194.846045)
			(xy 285.457371 -194.896975) (xy 285.434245 -194.944996) (xy 285.404221 -194.989033) (xy 285.367969 -195.028104)
			(xy 285.326298 -195.061335) (xy 285.28014 -195.087984) (xy 285.230526 -195.107456) (xy 285.178564 -195.119316)
			(xy 285.125414 -195.1233) (xy 285.072264 -195.119316) (xy 285.020302 -195.107456) (xy 284.970688 -195.087984)
			(xy 284.92453 -195.061335) (xy 284.882859 -195.028104) (xy 284.846607 -194.989033) (xy 284.816583 -194.944996)
			(xy 284.793457 -194.896975) (xy 284.777747 -194.846045) (xy 284.769804 -194.793341) (xy 277.902816 -194.793341)
			(xy 277.895753 -194.840203) (xy 277.880043 -194.891133) (xy 277.856917 -194.939154) (xy 277.826893 -194.983191)
			(xy 277.790641 -195.022262) (xy 277.74897 -195.055493) (xy 277.702812 -195.082142) (xy 277.653198 -195.101614)
			(xy 277.601236 -195.113474) (xy 277.548086 -195.117458) (xy 277.494936 -195.113474) (xy 277.442974 -195.101614)
			(xy 277.39336 -195.082142) (xy 277.347202 -195.055493) (xy 277.305531 -195.022262) (xy 277.269279 -194.983191)
			(xy 277.239255 -194.939154) (xy 277.216129 -194.891133) (xy 277.200419 -194.840203) (xy 277.192476 -194.787499)
			(xy 270.393533 -194.787499) (xy 270.393424 -194.793341) (xy 270.385481 -194.846045) (xy 270.369771 -194.896975)
			(xy 270.346645 -194.944996) (xy 270.316621 -194.989033) (xy 270.280369 -195.028104) (xy 270.238698 -195.061335)
			(xy 270.19254 -195.087984) (xy 270.142926 -195.107456) (xy 270.090964 -195.119316) (xy 270.037814 -195.1233)
			(xy 269.984664 -195.119316) (xy 269.932702 -195.107456) (xy 269.883088 -195.087984) (xy 269.83693 -195.061335)
			(xy 269.795259 -195.028104) (xy 269.759007 -194.989033) (xy 269.728983 -194.944996) (xy 269.705857 -194.896975)
			(xy 269.690147 -194.846045) (xy 269.682204 -194.793341) (xy 262.849624 -194.793341) (xy 262.841681 -194.846045)
			(xy 262.825971 -194.896975) (xy 262.802845 -194.944996) (xy 262.772821 -194.989033) (xy 262.736569 -195.028104)
			(xy 262.694898 -195.061335) (xy 262.64874 -195.087984) (xy 262.599126 -195.107456) (xy 262.547164 -195.119316)
			(xy 262.494014 -195.1233) (xy 262.440864 -195.119316) (xy 262.388902 -195.107456) (xy 262.339288 -195.087984)
			(xy 262.29313 -195.061335) (xy 262.251459 -195.028104) (xy 262.215207 -194.989033) (xy 262.185183 -194.944996)
			(xy 262.162057 -194.896975) (xy 262.146347 -194.846045) (xy 262.138404 -194.793341) (xy 257.598936 -194.793341)
			(xy 257.590993 -194.846045) (xy 257.575283 -194.896975) (xy 257.552157 -194.944996) (xy 257.522133 -194.989033)
			(xy 257.485881 -195.028104) (xy 257.44421 -195.061335) (xy 257.398052 -195.087984) (xy 257.348438 -195.107456)
			(xy 257.296476 -195.119316) (xy 257.243326 -195.1233) (xy 257.190176 -195.119316) (xy 257.138214 -195.107456)
			(xy 257.0886 -195.087984) (xy 257.042442 -195.061335) (xy 257.000771 -195.028104) (xy 256.964519 -194.989033)
			(xy 256.934495 -194.944996) (xy 256.911369 -194.896975) (xy 256.895659 -194.846045) (xy 256.887716 -194.793341)
			(xy 254.629687 -194.793341) (xy 254.20828 -195.214748) (xy 254.20828 -195.643225) (xy 268.473672 -195.643225)
			(xy 268.473672 -195.589927) (xy 268.481615 -195.537223) (xy 268.497325 -195.486293) (xy 268.520451 -195.438272)
			(xy 268.550475 -195.394235) (xy 268.586727 -195.355164) (xy 268.628398 -195.321933) (xy 268.674556 -195.295284)
			(xy 268.72417 -195.275812) (xy 268.776132 -195.263952) (xy 268.829282 -195.259969) (xy 268.882432 -195.263952)
			(xy 268.934394 -195.275812) (xy 268.984008 -195.295284) (xy 269.030166 -195.321933) (xy 269.071837 -195.355164)
			(xy 269.108089 -195.394235) (xy 269.138113 -195.438272) (xy 269.161239 -195.486293) (xy 269.176949 -195.537223)
			(xy 269.184892 -195.589927) (xy 269.18539 -195.616576) (xy 269.184892 -195.643225) (xy 283.561272 -195.643225)
			(xy 283.561272 -195.589927) (xy 283.569215 -195.537223) (xy 283.584925 -195.486293) (xy 283.608051 -195.438272)
			(xy 283.638075 -195.394235) (xy 283.674327 -195.355164) (xy 283.715998 -195.321933) (xy 283.762156 -195.295284)
			(xy 283.81177 -195.275812) (xy 283.863732 -195.263952) (xy 283.916882 -195.259969) (xy 283.970032 -195.263952)
			(xy 284.021994 -195.275812) (xy 284.071608 -195.295284) (xy 284.117766 -195.321933) (xy 284.159437 -195.355164)
			(xy 284.195689 -195.394235) (xy 284.225713 -195.438272) (xy 284.248839 -195.486293) (xy 284.264549 -195.537223)
			(xy 284.272492 -195.589927) (xy 284.27299 -195.616576) (xy 284.272492 -195.643225) (xy 298.648872 -195.643225)
			(xy 298.648872 -195.589927) (xy 298.656815 -195.537223) (xy 298.672525 -195.486293) (xy 298.695651 -195.438272)
			(xy 298.725675 -195.394235) (xy 298.761927 -195.355164) (xy 298.803598 -195.321933) (xy 298.849756 -195.295284)
			(xy 298.89937 -195.275812) (xy 298.951332 -195.263952) (xy 299.004482 -195.259969) (xy 299.057632 -195.263952)
			(xy 299.109594 -195.275812) (xy 299.159208 -195.295284) (xy 299.205366 -195.321933) (xy 299.247037 -195.355164)
			(xy 299.283289 -195.394235) (xy 299.313313 -195.438272) (xy 299.336439 -195.486293) (xy 299.352149 -195.537223)
			(xy 299.360092 -195.589927) (xy 299.36059 -195.616576) (xy 299.360092 -195.643225) (xy 299.352149 -195.695929)
			(xy 299.336439 -195.746859) (xy 299.313313 -195.79488) (xy 299.283289 -195.838917) (xy 299.247037 -195.877988)
			(xy 299.205366 -195.911219) (xy 299.159208 -195.937868) (xy 299.109594 -195.95734) (xy 299.057632 -195.9692)
			(xy 299.004482 -195.973184) (xy 298.951332 -195.9692) (xy 298.89937 -195.95734) (xy 298.849756 -195.937868)
			(xy 298.803598 -195.911219) (xy 298.761927 -195.877988) (xy 298.725675 -195.838917) (xy 298.695651 -195.79488)
			(xy 298.672525 -195.746859) (xy 298.656815 -195.695929) (xy 298.648872 -195.643225) (xy 284.272492 -195.643225)
			(xy 284.264549 -195.695929) (xy 284.248839 -195.746859) (xy 284.225713 -195.79488) (xy 284.195689 -195.838917)
			(xy 284.159437 -195.877988) (xy 284.117766 -195.911219) (xy 284.071608 -195.937868) (xy 284.021994 -195.95734)
			(xy 283.970032 -195.9692) (xy 283.916882 -195.973184) (xy 283.863732 -195.9692) (xy 283.81177 -195.95734)
			(xy 283.762156 -195.937868) (xy 283.715998 -195.911219) (xy 283.674327 -195.877988) (xy 283.638075 -195.838917)
			(xy 283.608051 -195.79488) (xy 283.584925 -195.746859) (xy 283.569215 -195.695929) (xy 283.561272 -195.643225)
			(xy 269.184892 -195.643225) (xy 269.176949 -195.695929) (xy 269.161239 -195.746859) (xy 269.138113 -195.79488)
			(xy 269.108089 -195.838917) (xy 269.071837 -195.877988) (xy 269.030166 -195.911219) (xy 268.984008 -195.937868)
			(xy 268.934394 -195.95734) (xy 268.882432 -195.9692) (xy 268.829282 -195.973184) (xy 268.776132 -195.9692)
			(xy 268.72417 -195.95734) (xy 268.674556 -195.937868) (xy 268.628398 -195.911219) (xy 268.586727 -195.877988)
			(xy 268.550475 -195.838917) (xy 268.520451 -195.79488) (xy 268.497325 -195.746859) (xy 268.481615 -195.695929)
			(xy 268.473672 -195.643225) (xy 254.20828 -195.643225) (xy 254.20828 -196.493363) (xy 264.373604 -196.493363)
			(xy 264.373604 -196.440065) (xy 264.381547 -196.387361) (xy 264.397257 -196.336431) (xy 264.420383 -196.28841)
			(xy 264.450407 -196.244373) (xy 264.486659 -196.205302) (xy 264.52833 -196.172071) (xy 264.574488 -196.145422)
			(xy 264.624102 -196.12595) (xy 264.676064 -196.11409) (xy 264.729214 -196.110107) (xy 264.782364 -196.11409)
			(xy 264.834326 -196.12595) (xy 264.88394 -196.145422) (xy 264.930098 -196.172071) (xy 264.971769 -196.205302)
			(xy 265.008021 -196.244373) (xy 265.038045 -196.28841) (xy 265.061171 -196.336431) (xy 265.076881 -196.387361)
			(xy 265.084824 -196.440065) (xy 265.085322 -196.466714) (xy 265.084824 -196.493363) (xy 279.461204 -196.493363)
			(xy 279.461204 -196.440065) (xy 279.469147 -196.387361) (xy 279.484857 -196.336431) (xy 279.507983 -196.28841)
			(xy 279.538007 -196.244373) (xy 279.574259 -196.205302) (xy 279.61593 -196.172071) (xy 279.662088 -196.145422)
			(xy 279.711702 -196.12595) (xy 279.763664 -196.11409) (xy 279.816814 -196.110107) (xy 279.869964 -196.11409)
			(xy 279.921926 -196.12595) (xy 279.97154 -196.145422) (xy 280.017698 -196.172071) (xy 280.059369 -196.205302)
			(xy 280.095621 -196.244373) (xy 280.125645 -196.28841) (xy 280.148771 -196.336431) (xy 280.164481 -196.387361)
			(xy 280.172424 -196.440065) (xy 280.172922 -196.466714) (xy 280.172424 -196.493363) (xy 294.548804 -196.493363)
			(xy 294.548804 -196.440065) (xy 294.556747 -196.387361) (xy 294.572457 -196.336431) (xy 294.595583 -196.28841)
			(xy 294.625607 -196.244373) (xy 294.661859 -196.205302) (xy 294.70353 -196.172071) (xy 294.749688 -196.145422)
			(xy 294.799302 -196.12595) (xy 294.851264 -196.11409) (xy 294.904414 -196.110107) (xy 294.957564 -196.11409)
			(xy 295.009526 -196.12595) (xy 295.05914 -196.145422) (xy 295.105298 -196.172071) (xy 295.146969 -196.205302)
			(xy 295.183221 -196.244373) (xy 295.213245 -196.28841) (xy 295.236371 -196.336431) (xy 295.252081 -196.387361)
			(xy 295.260024 -196.440065) (xy 295.260522 -196.466714) (xy 295.260024 -196.493363) (xy 295.252081 -196.546067)
			(xy 295.236371 -196.596997) (xy 295.213245 -196.645018) (xy 295.183221 -196.689055) (xy 295.146969 -196.728126)
			(xy 295.105298 -196.761357) (xy 295.05914 -196.788006) (xy 295.009526 -196.807478) (xy 294.957564 -196.819338)
			(xy 294.904414 -196.823322) (xy 294.851264 -196.819338) (xy 294.799302 -196.807478) (xy 294.749688 -196.788006)
			(xy 294.70353 -196.761357) (xy 294.661859 -196.728126) (xy 294.625607 -196.689055) (xy 294.595583 -196.645018)
			(xy 294.572457 -196.596997) (xy 294.556747 -196.546067) (xy 294.548804 -196.493363) (xy 280.172424 -196.493363)
			(xy 280.164481 -196.546067) (xy 280.148771 -196.596997) (xy 280.125645 -196.645018) (xy 280.095621 -196.689055)
			(xy 280.059369 -196.728126) (xy 280.017698 -196.761357) (xy 279.97154 -196.788006) (xy 279.921926 -196.807478)
			(xy 279.869964 -196.819338) (xy 279.816814 -196.823322) (xy 279.763664 -196.819338) (xy 279.711702 -196.807478)
			(xy 279.662088 -196.788006) (xy 279.61593 -196.761357) (xy 279.574259 -196.728126) (xy 279.538007 -196.689055)
			(xy 279.507983 -196.645018) (xy 279.484857 -196.596997) (xy 279.469147 -196.546067) (xy 279.461204 -196.493363)
			(xy 265.084824 -196.493363) (xy 265.076881 -196.546067) (xy 265.061171 -196.596997) (xy 265.038045 -196.645018)
			(xy 265.008021 -196.689055) (xy 264.971769 -196.728126) (xy 264.930098 -196.761357) (xy 264.88394 -196.788006)
			(xy 264.834326 -196.807478) (xy 264.782364 -196.819338) (xy 264.729214 -196.823322) (xy 264.676064 -196.819338)
			(xy 264.624102 -196.807478) (xy 264.574488 -196.788006) (xy 264.52833 -196.761357) (xy 264.486659 -196.728126)
			(xy 264.450407 -196.689055) (xy 264.420383 -196.645018) (xy 264.397257 -196.596997) (xy 264.381547 -196.546067)
			(xy 264.373604 -196.493363) (xy 254.20828 -196.493363) (xy 254.20828 -197.343247) (xy 268.473672 -197.343247)
			(xy 268.473672 -197.289949) (xy 268.481615 -197.237245) (xy 268.497325 -197.186315) (xy 268.520451 -197.138294)
			(xy 268.550475 -197.094257) (xy 268.586727 -197.055186) (xy 268.628398 -197.021955) (xy 268.674556 -196.995306)
			(xy 268.72417 -196.975834) (xy 268.776132 -196.963974) (xy 268.829282 -196.959991) (xy 268.882432 -196.963974)
			(xy 268.934394 -196.975834) (xy 268.984008 -196.995306) (xy 269.030166 -197.021955) (xy 269.071837 -197.055186)
			(xy 269.108089 -197.094257) (xy 269.138113 -197.138294) (xy 269.161239 -197.186315) (xy 269.176949 -197.237245)
			(xy 269.184892 -197.289949) (xy 269.18539 -197.316598) (xy 269.184892 -197.343247) (xy 283.561272 -197.343247)
			(xy 283.561272 -197.289949) (xy 283.569215 -197.237245) (xy 283.584925 -197.186315) (xy 283.608051 -197.138294)
			(xy 283.638075 -197.094257) (xy 283.674327 -197.055186) (xy 283.715998 -197.021955) (xy 283.762156 -196.995306)
			(xy 283.81177 -196.975834) (xy 283.863732 -196.963974) (xy 283.916882 -196.959991) (xy 283.970032 -196.963974)
			(xy 284.021994 -196.975834) (xy 284.071608 -196.995306) (xy 284.117766 -197.021955) (xy 284.159437 -197.055186)
			(xy 284.195689 -197.094257) (xy 284.225713 -197.138294) (xy 284.248839 -197.186315) (xy 284.264549 -197.237245)
			(xy 284.272492 -197.289949) (xy 284.27299 -197.316598) (xy 284.272492 -197.343247) (xy 298.648872 -197.343247)
			(xy 298.648872 -197.289949) (xy 298.656815 -197.237245) (xy 298.672525 -197.186315) (xy 298.695651 -197.138294)
			(xy 298.725675 -197.094257) (xy 298.761927 -197.055186) (xy 298.803598 -197.021955) (xy 298.849756 -196.995306)
			(xy 298.89937 -196.975834) (xy 298.951332 -196.963974) (xy 299.004482 -196.959991) (xy 299.057632 -196.963974)
			(xy 299.109594 -196.975834) (xy 299.159208 -196.995306) (xy 299.205366 -197.021955) (xy 299.247037 -197.055186)
			(xy 299.283289 -197.094257) (xy 299.313313 -197.138294) (xy 299.336439 -197.186315) (xy 299.352149 -197.237245)
			(xy 299.360092 -197.289949) (xy 299.36059 -197.316598) (xy 299.360092 -197.343247) (xy 299.352149 -197.395951)
			(xy 299.336439 -197.446881) (xy 299.313313 -197.494902) (xy 299.283289 -197.538939) (xy 299.247037 -197.57801)
			(xy 299.205366 -197.611241) (xy 299.159208 -197.63789) (xy 299.109594 -197.657362) (xy 299.057632 -197.669222)
			(xy 299.004482 -197.673206) (xy 298.951332 -197.669222) (xy 298.89937 -197.657362) (xy 298.849756 -197.63789)
			(xy 298.803598 -197.611241) (xy 298.761927 -197.57801) (xy 298.725675 -197.538939) (xy 298.695651 -197.494902)
			(xy 298.672525 -197.446881) (xy 298.656815 -197.395951) (xy 298.648872 -197.343247) (xy 284.272492 -197.343247)
			(xy 284.264549 -197.395951) (xy 284.248839 -197.446881) (xy 284.225713 -197.494902) (xy 284.195689 -197.538939)
			(xy 284.159437 -197.57801) (xy 284.117766 -197.611241) (xy 284.071608 -197.63789) (xy 284.021994 -197.657362)
			(xy 283.970032 -197.669222) (xy 283.916882 -197.673206) (xy 283.863732 -197.669222) (xy 283.81177 -197.657362)
			(xy 283.762156 -197.63789) (xy 283.715998 -197.611241) (xy 283.674327 -197.57801) (xy 283.638075 -197.538939)
			(xy 283.608051 -197.494902) (xy 283.584925 -197.446881) (xy 283.569215 -197.395951) (xy 283.561272 -197.343247)
			(xy 269.184892 -197.343247) (xy 269.176949 -197.395951) (xy 269.161239 -197.446881) (xy 269.138113 -197.494902)
			(xy 269.108089 -197.538939) (xy 269.071837 -197.57801) (xy 269.030166 -197.611241) (xy 268.984008 -197.63789)
			(xy 268.934394 -197.657362) (xy 268.882432 -197.669222) (xy 268.829282 -197.673206) (xy 268.776132 -197.669222)
			(xy 268.72417 -197.657362) (xy 268.674556 -197.63789) (xy 268.628398 -197.611241) (xy 268.586727 -197.57801)
			(xy 268.550475 -197.538939) (xy 268.520451 -197.494902) (xy 268.497325 -197.446881) (xy 268.481615 -197.395951)
			(xy 268.473672 -197.343247) (xy 254.20828 -197.343247) (xy 254.20828 -198.193385) (xy 264.373604 -198.193385)
			(xy 264.373604 -198.140087) (xy 264.381547 -198.087383) (xy 264.397257 -198.036453) (xy 264.420383 -197.988432)
			(xy 264.450407 -197.944395) (xy 264.486659 -197.905324) (xy 264.52833 -197.872093) (xy 264.574488 -197.845444)
			(xy 264.624102 -197.825972) (xy 264.676064 -197.814112) (xy 264.729214 -197.810129) (xy 264.782364 -197.814112)
			(xy 264.834326 -197.825972) (xy 264.88394 -197.845444) (xy 264.930098 -197.872093) (xy 264.971769 -197.905324)
			(xy 265.008021 -197.944395) (xy 265.038045 -197.988432) (xy 265.061171 -198.036453) (xy 265.076881 -198.087383)
			(xy 265.084824 -198.140087) (xy 265.085322 -198.166736) (xy 265.084824 -198.193385) (xy 279.461204 -198.193385)
			(xy 279.461204 -198.140087) (xy 279.469147 -198.087383) (xy 279.484857 -198.036453) (xy 279.507983 -197.988432)
			(xy 279.538007 -197.944395) (xy 279.574259 -197.905324) (xy 279.61593 -197.872093) (xy 279.662088 -197.845444)
			(xy 279.711702 -197.825972) (xy 279.763664 -197.814112) (xy 279.816814 -197.810129) (xy 279.869964 -197.814112)
			(xy 279.921926 -197.825972) (xy 279.97154 -197.845444) (xy 280.017698 -197.872093) (xy 280.059369 -197.905324)
			(xy 280.095621 -197.944395) (xy 280.125645 -197.988432) (xy 280.148771 -198.036453) (xy 280.164481 -198.087383)
			(xy 280.172424 -198.140087) (xy 280.172922 -198.166736) (xy 280.172424 -198.193385) (xy 294.548804 -198.193385)
			(xy 294.548804 -198.140087) (xy 294.556747 -198.087383) (xy 294.572457 -198.036453) (xy 294.595583 -197.988432)
			(xy 294.625607 -197.944395) (xy 294.661859 -197.905324) (xy 294.70353 -197.872093) (xy 294.749688 -197.845444)
			(xy 294.799302 -197.825972) (xy 294.851264 -197.814112) (xy 294.904414 -197.810129) (xy 294.957564 -197.814112)
			(xy 295.009526 -197.825972) (xy 295.05914 -197.845444) (xy 295.105298 -197.872093) (xy 295.146969 -197.905324)
			(xy 295.183221 -197.944395) (xy 295.213245 -197.988432) (xy 295.236371 -198.036453) (xy 295.252081 -198.087383)
			(xy 295.260024 -198.140087) (xy 295.260522 -198.166736) (xy 295.260024 -198.193385) (xy 295.252081 -198.246089)
			(xy 295.236371 -198.297019) (xy 295.213245 -198.34504) (xy 295.183221 -198.389077) (xy 295.146969 -198.428148)
			(xy 295.105298 -198.461379) (xy 295.05914 -198.488028) (xy 295.009526 -198.5075) (xy 294.957564 -198.51936)
			(xy 294.904414 -198.523344) (xy 294.851264 -198.51936) (xy 294.799302 -198.5075) (xy 294.749688 -198.488028)
			(xy 294.70353 -198.461379) (xy 294.661859 -198.428148) (xy 294.625607 -198.389077) (xy 294.595583 -198.34504)
			(xy 294.572457 -198.297019) (xy 294.556747 -198.246089) (xy 294.548804 -198.193385) (xy 280.172424 -198.193385)
			(xy 280.164481 -198.246089) (xy 280.148771 -198.297019) (xy 280.125645 -198.34504) (xy 280.095621 -198.389077)
			(xy 280.059369 -198.428148) (xy 280.017698 -198.461379) (xy 279.97154 -198.488028) (xy 279.921926 -198.5075)
			(xy 279.869964 -198.51936) (xy 279.816814 -198.523344) (xy 279.763664 -198.51936) (xy 279.711702 -198.5075)
			(xy 279.662088 -198.488028) (xy 279.61593 -198.461379) (xy 279.574259 -198.428148) (xy 279.538007 -198.389077)
			(xy 279.507983 -198.34504) (xy 279.484857 -198.297019) (xy 279.469147 -198.246089) (xy 279.461204 -198.193385)
			(xy 265.084824 -198.193385) (xy 265.076881 -198.246089) (xy 265.061171 -198.297019) (xy 265.038045 -198.34504)
			(xy 265.008021 -198.389077) (xy 264.971769 -198.428148) (xy 264.930098 -198.461379) (xy 264.88394 -198.488028)
			(xy 264.834326 -198.5075) (xy 264.782364 -198.51936) (xy 264.729214 -198.523344) (xy 264.676064 -198.51936)
			(xy 264.624102 -198.5075) (xy 264.574488 -198.488028) (xy 264.52833 -198.461379) (xy 264.486659 -198.428148)
			(xy 264.450407 -198.389077) (xy 264.420383 -198.34504) (xy 264.397257 -198.297019) (xy 264.381547 -198.246089)
			(xy 264.373604 -198.193385) (xy 254.20828 -198.193385) (xy 254.20828 -199.043269) (xy 268.473672 -199.043269)
			(xy 268.473672 -198.989971) (xy 268.481615 -198.937267) (xy 268.497325 -198.886337) (xy 268.520451 -198.838316)
			(xy 268.550475 -198.794279) (xy 268.586727 -198.755208) (xy 268.628398 -198.721977) (xy 268.674556 -198.695328)
			(xy 268.72417 -198.675856) (xy 268.776132 -198.663996) (xy 268.829282 -198.660013) (xy 268.882432 -198.663996)
			(xy 268.934394 -198.675856) (xy 268.984008 -198.695328) (xy 269.030166 -198.721977) (xy 269.071837 -198.755208)
			(xy 269.108089 -198.794279) (xy 269.138113 -198.838316) (xy 269.161239 -198.886337) (xy 269.176949 -198.937267)
			(xy 269.184892 -198.989971) (xy 269.18539 -199.01662) (xy 269.184892 -199.043269) (xy 283.561272 -199.043269)
			(xy 283.561272 -198.989971) (xy 283.569215 -198.937267) (xy 283.584925 -198.886337) (xy 283.608051 -198.838316)
			(xy 283.638075 -198.794279) (xy 283.674327 -198.755208) (xy 283.715998 -198.721977) (xy 283.762156 -198.695328)
			(xy 283.81177 -198.675856) (xy 283.863732 -198.663996) (xy 283.916882 -198.660013) (xy 283.970032 -198.663996)
			(xy 284.021994 -198.675856) (xy 284.071608 -198.695328) (xy 284.117766 -198.721977) (xy 284.159437 -198.755208)
			(xy 284.195689 -198.794279) (xy 284.225713 -198.838316) (xy 284.248839 -198.886337) (xy 284.264549 -198.937267)
			(xy 284.272492 -198.989971) (xy 284.27299 -199.01662) (xy 284.272492 -199.043269) (xy 298.648872 -199.043269)
			(xy 298.648872 -198.989971) (xy 298.656815 -198.937267) (xy 298.672525 -198.886337) (xy 298.695651 -198.838316)
			(xy 298.725675 -198.794279) (xy 298.761927 -198.755208) (xy 298.803598 -198.721977) (xy 298.849756 -198.695328)
			(xy 298.89937 -198.675856) (xy 298.951332 -198.663996) (xy 299.004482 -198.660013) (xy 299.057632 -198.663996)
			(xy 299.109594 -198.675856) (xy 299.159208 -198.695328) (xy 299.205366 -198.721977) (xy 299.247037 -198.755208)
			(xy 299.283289 -198.794279) (xy 299.313313 -198.838316) (xy 299.336439 -198.886337) (xy 299.352149 -198.937267)
			(xy 299.360092 -198.989971) (xy 299.36059 -199.01662) (xy 299.360092 -199.043269) (xy 299.352149 -199.095973)
			(xy 299.336439 -199.146903) (xy 299.313313 -199.194924) (xy 299.283289 -199.238961) (xy 299.247037 -199.278032)
			(xy 299.205366 -199.311263) (xy 299.159208 -199.337912) (xy 299.109594 -199.357384) (xy 299.057632 -199.369244)
			(xy 299.004482 -199.373228) (xy 298.951332 -199.369244) (xy 298.89937 -199.357384) (xy 298.849756 -199.337912)
			(xy 298.803598 -199.311263) (xy 298.761927 -199.278032) (xy 298.725675 -199.238961) (xy 298.695651 -199.194924)
			(xy 298.672525 -199.146903) (xy 298.656815 -199.095973) (xy 298.648872 -199.043269) (xy 284.272492 -199.043269)
			(xy 284.264549 -199.095973) (xy 284.248839 -199.146903) (xy 284.225713 -199.194924) (xy 284.195689 -199.238961)
			(xy 284.159437 -199.278032) (xy 284.117766 -199.311263) (xy 284.071608 -199.337912) (xy 284.021994 -199.357384)
			(xy 283.970032 -199.369244) (xy 283.916882 -199.373228) (xy 283.863732 -199.369244) (xy 283.81177 -199.357384)
			(xy 283.762156 -199.337912) (xy 283.715998 -199.311263) (xy 283.674327 -199.278032) (xy 283.638075 -199.238961)
			(xy 283.608051 -199.194924) (xy 283.584925 -199.146903) (xy 283.569215 -199.095973) (xy 283.561272 -199.043269)
			(xy 269.184892 -199.043269) (xy 269.176949 -199.095973) (xy 269.161239 -199.146903) (xy 269.138113 -199.194924)
			(xy 269.108089 -199.238961) (xy 269.071837 -199.278032) (xy 269.030166 -199.311263) (xy 268.984008 -199.337912)
			(xy 268.934394 -199.357384) (xy 268.882432 -199.369244) (xy 268.829282 -199.373228) (xy 268.776132 -199.369244)
			(xy 268.72417 -199.357384) (xy 268.674556 -199.337912) (xy 268.628398 -199.311263) (xy 268.586727 -199.278032)
			(xy 268.550475 -199.238961) (xy 268.520451 -199.194924) (xy 268.497325 -199.146903) (xy 268.481615 -199.095973)
			(xy 268.473672 -199.043269) (xy 254.20828 -199.043269) (xy 254.20828 -199.893407) (xy 264.373604 -199.893407)
			(xy 264.373604 -199.840109) (xy 264.381547 -199.787405) (xy 264.397257 -199.736475) (xy 264.420383 -199.688454)
			(xy 264.450407 -199.644417) (xy 264.486659 -199.605346) (xy 264.52833 -199.572115) (xy 264.574488 -199.545466)
			(xy 264.624102 -199.525994) (xy 264.676064 -199.514134) (xy 264.729214 -199.510151) (xy 264.782364 -199.514134)
			(xy 264.834326 -199.525994) (xy 264.88394 -199.545466) (xy 264.930098 -199.572115) (xy 264.971769 -199.605346)
			(xy 265.008021 -199.644417) (xy 265.038045 -199.688454) (xy 265.061171 -199.736475) (xy 265.076881 -199.787405)
			(xy 265.084824 -199.840109) (xy 265.085322 -199.866758) (xy 265.084824 -199.893407) (xy 268.473672 -199.893407)
			(xy 268.473672 -199.840109) (xy 268.481615 -199.787405) (xy 268.497325 -199.736475) (xy 268.520451 -199.688454)
			(xy 268.550475 -199.644417) (xy 268.586727 -199.605346) (xy 268.628398 -199.572115) (xy 268.674556 -199.545466)
			(xy 268.72417 -199.525994) (xy 268.776132 -199.514134) (xy 268.829282 -199.510151) (xy 268.882432 -199.514134)
			(xy 268.934394 -199.525994) (xy 268.984008 -199.545466) (xy 269.030166 -199.572115) (xy 269.071837 -199.605346)
			(xy 269.108089 -199.644417) (xy 269.138113 -199.688454) (xy 269.161239 -199.736475) (xy 269.176949 -199.787405)
			(xy 269.184892 -199.840109) (xy 269.18539 -199.866758) (xy 269.184892 -199.893407) (xy 279.461204 -199.893407)
			(xy 279.461204 -199.840109) (xy 279.469147 -199.787405) (xy 279.484857 -199.736475) (xy 279.507983 -199.688454)
			(xy 279.538007 -199.644417) (xy 279.574259 -199.605346) (xy 279.61593 -199.572115) (xy 279.662088 -199.545466)
			(xy 279.711702 -199.525994) (xy 279.763664 -199.514134) (xy 279.816814 -199.510151) (xy 279.869964 -199.514134)
			(xy 279.921926 -199.525994) (xy 279.97154 -199.545466) (xy 280.017698 -199.572115) (xy 280.059369 -199.605346)
			(xy 280.095621 -199.644417) (xy 280.125645 -199.688454) (xy 280.148771 -199.736475) (xy 280.164481 -199.787405)
			(xy 280.172424 -199.840109) (xy 280.172922 -199.866758) (xy 280.172424 -199.893407) (xy 283.561272 -199.893407)
			(xy 283.561272 -199.840109) (xy 283.569215 -199.787405) (xy 283.584925 -199.736475) (xy 283.608051 -199.688454)
			(xy 283.638075 -199.644417) (xy 283.674327 -199.605346) (xy 283.715998 -199.572115) (xy 283.762156 -199.545466)
			(xy 283.81177 -199.525994) (xy 283.863732 -199.514134) (xy 283.916882 -199.510151) (xy 283.970032 -199.514134)
			(xy 284.021994 -199.525994) (xy 284.071608 -199.545466) (xy 284.117766 -199.572115) (xy 284.159437 -199.605346)
			(xy 284.195689 -199.644417) (xy 284.225713 -199.688454) (xy 284.248839 -199.736475) (xy 284.264549 -199.787405)
			(xy 284.272492 -199.840109) (xy 284.27299 -199.866758) (xy 284.272492 -199.893407) (xy 294.548804 -199.893407)
			(xy 294.548804 -199.840109) (xy 294.556747 -199.787405) (xy 294.572457 -199.736475) (xy 294.595583 -199.688454)
			(xy 294.625607 -199.644417) (xy 294.661859 -199.605346) (xy 294.70353 -199.572115) (xy 294.749688 -199.545466)
			(xy 294.799302 -199.525994) (xy 294.851264 -199.514134) (xy 294.904414 -199.510151) (xy 294.957564 -199.514134)
			(xy 295.009526 -199.525994) (xy 295.05914 -199.545466) (xy 295.105298 -199.572115) (xy 295.146969 -199.605346)
			(xy 295.183221 -199.644417) (xy 295.213245 -199.688454) (xy 295.236371 -199.736475) (xy 295.252081 -199.787405)
			(xy 295.260024 -199.840109) (xy 295.260522 -199.866758) (xy 295.260024 -199.893407) (xy 298.648872 -199.893407)
			(xy 298.648872 -199.840109) (xy 298.656815 -199.787405) (xy 298.672525 -199.736475) (xy 298.695651 -199.688454)
			(xy 298.725675 -199.644417) (xy 298.761927 -199.605346) (xy 298.803598 -199.572115) (xy 298.849756 -199.545466)
			(xy 298.89937 -199.525994) (xy 298.951332 -199.514134) (xy 299.004482 -199.510151) (xy 299.057632 -199.514134)
			(xy 299.109594 -199.525994) (xy 299.159208 -199.545466) (xy 299.205366 -199.572115) (xy 299.247037 -199.605346)
			(xy 299.283289 -199.644417) (xy 299.313313 -199.688454) (xy 299.336439 -199.736475) (xy 299.352149 -199.787405)
			(xy 299.360092 -199.840109) (xy 299.36059 -199.866758) (xy 299.360092 -199.893407) (xy 299.352149 -199.946111)
			(xy 299.336439 -199.997041) (xy 299.313313 -200.045062) (xy 299.283289 -200.089099) (xy 299.247037 -200.12817)
			(xy 299.205366 -200.161401) (xy 299.159208 -200.18805) (xy 299.109594 -200.207522) (xy 299.057632 -200.219382)
			(xy 299.004482 -200.223366) (xy 298.951332 -200.219382) (xy 298.89937 -200.207522) (xy 298.849756 -200.18805)
			(xy 298.803598 -200.161401) (xy 298.761927 -200.12817) (xy 298.725675 -200.089099) (xy 298.695651 -200.045062)
			(xy 298.672525 -199.997041) (xy 298.656815 -199.946111) (xy 298.648872 -199.893407) (xy 295.260024 -199.893407)
			(xy 295.252081 -199.946111) (xy 295.236371 -199.997041) (xy 295.213245 -200.045062) (xy 295.183221 -200.089099)
			(xy 295.146969 -200.12817) (xy 295.105298 -200.161401) (xy 295.05914 -200.18805) (xy 295.009526 -200.207522)
			(xy 294.957564 -200.219382) (xy 294.904414 -200.223366) (xy 294.851264 -200.219382) (xy 294.799302 -200.207522)
			(xy 294.749688 -200.18805) (xy 294.70353 -200.161401) (xy 294.661859 -200.12817) (xy 294.625607 -200.089099)
			(xy 294.595583 -200.045062) (xy 294.572457 -199.997041) (xy 294.556747 -199.946111) (xy 294.548804 -199.893407)
			(xy 284.272492 -199.893407) (xy 284.264549 -199.946111) (xy 284.248839 -199.997041) (xy 284.225713 -200.045062)
			(xy 284.195689 -200.089099) (xy 284.159437 -200.12817) (xy 284.117766 -200.161401) (xy 284.071608 -200.18805)
			(xy 284.021994 -200.207522) (xy 283.970032 -200.219382) (xy 283.916882 -200.223366) (xy 283.863732 -200.219382)
			(xy 283.81177 -200.207522) (xy 283.762156 -200.18805) (xy 283.715998 -200.161401) (xy 283.674327 -200.12817)
			(xy 283.638075 -200.089099) (xy 283.608051 -200.045062) (xy 283.584925 -199.997041) (xy 283.569215 -199.946111)
			(xy 283.561272 -199.893407) (xy 280.172424 -199.893407) (xy 280.164481 -199.946111) (xy 280.148771 -199.997041)
			(xy 280.125645 -200.045062) (xy 280.095621 -200.089099) (xy 280.059369 -200.12817) (xy 280.017698 -200.161401)
			(xy 279.97154 -200.18805) (xy 279.921926 -200.207522) (xy 279.869964 -200.219382) (xy 279.816814 -200.223366)
			(xy 279.763664 -200.219382) (xy 279.711702 -200.207522) (xy 279.662088 -200.18805) (xy 279.61593 -200.161401)
			(xy 279.574259 -200.12817) (xy 279.538007 -200.089099) (xy 279.507983 -200.045062) (xy 279.484857 -199.997041)
			(xy 279.469147 -199.946111) (xy 279.461204 -199.893407) (xy 269.184892 -199.893407) (xy 269.176949 -199.946111)
			(xy 269.161239 -199.997041) (xy 269.138113 -200.045062) (xy 269.108089 -200.089099) (xy 269.071837 -200.12817)
			(xy 269.030166 -200.161401) (xy 268.984008 -200.18805) (xy 268.934394 -200.207522) (xy 268.882432 -200.219382)
			(xy 268.829282 -200.223366) (xy 268.776132 -200.219382) (xy 268.72417 -200.207522) (xy 268.674556 -200.18805)
			(xy 268.628398 -200.161401) (xy 268.586727 -200.12817) (xy 268.550475 -200.089099) (xy 268.520451 -200.045062)
			(xy 268.497325 -199.997041) (xy 268.481615 -199.946111) (xy 268.473672 -199.893407) (xy 265.084824 -199.893407)
			(xy 265.076881 -199.946111) (xy 265.061171 -199.997041) (xy 265.038045 -200.045062) (xy 265.008021 -200.089099)
			(xy 264.971769 -200.12817) (xy 264.930098 -200.161401) (xy 264.88394 -200.18805) (xy 264.834326 -200.207522)
			(xy 264.782364 -200.219382) (xy 264.729214 -200.223366) (xy 264.676064 -200.219382) (xy 264.624102 -200.207522)
			(xy 264.574488 -200.18805) (xy 264.52833 -200.161401) (xy 264.486659 -200.12817) (xy 264.450407 -200.089099)
			(xy 264.420383 -200.045062) (xy 264.397257 -199.997041) (xy 264.381547 -199.946111) (xy 264.373604 -199.893407)
			(xy 254.20828 -199.893407) (xy 254.20828 -200.743291) (xy 264.373604 -200.743291) (xy 264.373604 -200.689993)
			(xy 264.381547 -200.637289) (xy 264.397257 -200.586359) (xy 264.420383 -200.538338) (xy 264.450407 -200.494301)
			(xy 264.486659 -200.45523) (xy 264.52833 -200.421999) (xy 264.574488 -200.39535) (xy 264.624102 -200.375878)
			(xy 264.676064 -200.364018) (xy 264.729214 -200.360035) (xy 264.782364 -200.364018) (xy 264.834326 -200.375878)
			(xy 264.88394 -200.39535) (xy 264.930098 -200.421999) (xy 264.971769 -200.45523) (xy 265.008021 -200.494301)
			(xy 265.038045 -200.538338) (xy 265.061171 -200.586359) (xy 265.076881 -200.637289) (xy 265.084824 -200.689993)
			(xy 265.085322 -200.716642) (xy 265.084824 -200.743291) (xy 279.461204 -200.743291) (xy 279.461204 -200.689993)
			(xy 279.469147 -200.637289) (xy 279.484857 -200.586359) (xy 279.507983 -200.538338) (xy 279.538007 -200.494301)
			(xy 279.574259 -200.45523) (xy 279.61593 -200.421999) (xy 279.662088 -200.39535) (xy 279.711702 -200.375878)
			(xy 279.763664 -200.364018) (xy 279.816814 -200.360035) (xy 279.869964 -200.364018) (xy 279.921926 -200.375878)
			(xy 279.97154 -200.39535) (xy 280.017698 -200.421999) (xy 280.059369 -200.45523) (xy 280.095621 -200.494301)
			(xy 280.125645 -200.538338) (xy 280.148771 -200.586359) (xy 280.164481 -200.637289) (xy 280.172424 -200.689993)
			(xy 280.172922 -200.716642) (xy 280.172424 -200.743291) (xy 294.548804 -200.743291) (xy 294.548804 -200.689993)
			(xy 294.556747 -200.637289) (xy 294.572457 -200.586359) (xy 294.595583 -200.538338) (xy 294.625607 -200.494301)
			(xy 294.661859 -200.45523) (xy 294.70353 -200.421999) (xy 294.749688 -200.39535) (xy 294.799302 -200.375878)
			(xy 294.851264 -200.364018) (xy 294.904414 -200.360035) (xy 294.957564 -200.364018) (xy 295.009526 -200.375878)
			(xy 295.05914 -200.39535) (xy 295.105298 -200.421999) (xy 295.146969 -200.45523) (xy 295.183221 -200.494301)
			(xy 295.213245 -200.538338) (xy 295.236371 -200.586359) (xy 295.252081 -200.637289) (xy 295.260024 -200.689993)
			(xy 295.260522 -200.716642) (xy 295.260024 -200.743291) (xy 295.252081 -200.795995) (xy 295.236371 -200.846925)
			(xy 295.213245 -200.894946) (xy 295.183221 -200.938983) (xy 295.146969 -200.978054) (xy 295.105298 -201.011285)
			(xy 295.05914 -201.037934) (xy 295.009526 -201.057406) (xy 294.957564 -201.069266) (xy 294.904414 -201.07325)
			(xy 294.851264 -201.069266) (xy 294.799302 -201.057406) (xy 294.749688 -201.037934) (xy 294.70353 -201.011285)
			(xy 294.661859 -200.978054) (xy 294.625607 -200.938983) (xy 294.595583 -200.894946) (xy 294.572457 -200.846925)
			(xy 294.556747 -200.795995) (xy 294.548804 -200.743291) (xy 280.172424 -200.743291) (xy 280.164481 -200.795995)
			(xy 280.148771 -200.846925) (xy 280.125645 -200.894946) (xy 280.095621 -200.938983) (xy 280.059369 -200.978054)
			(xy 280.017698 -201.011285) (xy 279.97154 -201.037934) (xy 279.921926 -201.057406) (xy 279.869964 -201.069266)
			(xy 279.816814 -201.07325) (xy 279.763664 -201.069266) (xy 279.711702 -201.057406) (xy 279.662088 -201.037934)
			(xy 279.61593 -201.011285) (xy 279.574259 -200.978054) (xy 279.538007 -200.938983) (xy 279.507983 -200.894946)
			(xy 279.484857 -200.846925) (xy 279.469147 -200.795995) (xy 279.461204 -200.743291) (xy 265.084824 -200.743291)
			(xy 265.076881 -200.795995) (xy 265.061171 -200.846925) (xy 265.038045 -200.894946) (xy 265.008021 -200.938983)
			(xy 264.971769 -200.978054) (xy 264.930098 -201.011285) (xy 264.88394 -201.037934) (xy 264.834326 -201.057406)
			(xy 264.782364 -201.069266) (xy 264.729214 -201.07325) (xy 264.676064 -201.069266) (xy 264.624102 -201.057406)
			(xy 264.574488 -201.037934) (xy 264.52833 -201.011285) (xy 264.486659 -200.978054) (xy 264.450407 -200.938983)
			(xy 264.420383 -200.894946) (xy 264.397257 -200.846925) (xy 264.381547 -200.795995) (xy 264.373604 -200.743291)
			(xy 254.20828 -200.743291) (xy 254.20828 -201.593429) (xy 268.473672 -201.593429) (xy 268.473672 -201.540131)
			(xy 268.481615 -201.487427) (xy 268.497325 -201.436497) (xy 268.520451 -201.388476) (xy 268.550475 -201.344439)
			(xy 268.586727 -201.305368) (xy 268.628398 -201.272137) (xy 268.674556 -201.245488) (xy 268.72417 -201.226016)
			(xy 268.776132 -201.214156) (xy 268.829282 -201.210173) (xy 268.882432 -201.214156) (xy 268.934394 -201.226016)
			(xy 268.984008 -201.245488) (xy 269.030166 -201.272137) (xy 269.071837 -201.305368) (xy 269.108089 -201.344439)
			(xy 269.138113 -201.388476) (xy 269.161239 -201.436497) (xy 269.176949 -201.487427) (xy 269.184892 -201.540131)
			(xy 269.18539 -201.56678) (xy 269.184892 -201.593429) (xy 283.561272 -201.593429) (xy 283.561272 -201.540131)
			(xy 283.569215 -201.487427) (xy 283.584925 -201.436497) (xy 283.608051 -201.388476) (xy 283.638075 -201.344439)
			(xy 283.674327 -201.305368) (xy 283.715998 -201.272137) (xy 283.762156 -201.245488) (xy 283.81177 -201.226016)
			(xy 283.863732 -201.214156) (xy 283.916882 -201.210173) (xy 283.970032 -201.214156) (xy 284.021994 -201.226016)
			(xy 284.071608 -201.245488) (xy 284.117766 -201.272137) (xy 284.159437 -201.305368) (xy 284.195689 -201.344439)
			(xy 284.225713 -201.388476) (xy 284.248839 -201.436497) (xy 284.264549 -201.487427) (xy 284.272492 -201.540131)
			(xy 284.27299 -201.56678) (xy 284.272492 -201.593429) (xy 298.648872 -201.593429) (xy 298.648872 -201.540131)
			(xy 298.656815 -201.487427) (xy 298.672525 -201.436497) (xy 298.695651 -201.388476) (xy 298.725675 -201.344439)
			(xy 298.761927 -201.305368) (xy 298.803598 -201.272137) (xy 298.849756 -201.245488) (xy 298.89937 -201.226016)
			(xy 298.951332 -201.214156) (xy 299.004482 -201.210173) (xy 299.057632 -201.214156) (xy 299.109594 -201.226016)
			(xy 299.159208 -201.245488) (xy 299.205366 -201.272137) (xy 299.247037 -201.305368) (xy 299.283289 -201.344439)
			(xy 299.313313 -201.388476) (xy 299.336439 -201.436497) (xy 299.352149 -201.487427) (xy 299.360092 -201.540131)
			(xy 299.36059 -201.56678) (xy 299.360092 -201.593429) (xy 299.352149 -201.646133) (xy 299.336439 -201.697063)
			(xy 299.313313 -201.745084) (xy 299.283289 -201.789121) (xy 299.247037 -201.828192) (xy 299.205366 -201.861423)
			(xy 299.159208 -201.888072) (xy 299.109594 -201.907544) (xy 299.057632 -201.919404) (xy 299.004482 -201.923388)
			(xy 298.951332 -201.919404) (xy 298.89937 -201.907544) (xy 298.849756 -201.888072) (xy 298.803598 -201.861423)
			(xy 298.761927 -201.828192) (xy 298.725675 -201.789121) (xy 298.695651 -201.745084) (xy 298.672525 -201.697063)
			(xy 298.656815 -201.646133) (xy 298.648872 -201.593429) (xy 284.272492 -201.593429) (xy 284.264549 -201.646133)
			(xy 284.248839 -201.697063) (xy 284.225713 -201.745084) (xy 284.195689 -201.789121) (xy 284.159437 -201.828192)
			(xy 284.117766 -201.861423) (xy 284.071608 -201.888072) (xy 284.021994 -201.907544) (xy 283.970032 -201.919404)
			(xy 283.916882 -201.923388) (xy 283.863732 -201.919404) (xy 283.81177 -201.907544) (xy 283.762156 -201.888072)
			(xy 283.715998 -201.861423) (xy 283.674327 -201.828192) (xy 283.638075 -201.789121) (xy 283.608051 -201.745084)
			(xy 283.584925 -201.697063) (xy 283.569215 -201.646133) (xy 283.561272 -201.593429) (xy 269.184892 -201.593429)
			(xy 269.176949 -201.646133) (xy 269.161239 -201.697063) (xy 269.138113 -201.745084) (xy 269.108089 -201.789121)
			(xy 269.071837 -201.828192) (xy 269.030166 -201.861423) (xy 268.984008 -201.888072) (xy 268.934394 -201.907544)
			(xy 268.882432 -201.919404) (xy 268.829282 -201.923388) (xy 268.776132 -201.919404) (xy 268.72417 -201.907544)
			(xy 268.674556 -201.888072) (xy 268.628398 -201.861423) (xy 268.586727 -201.828192) (xy 268.550475 -201.789121)
			(xy 268.520451 -201.745084) (xy 268.497325 -201.697063) (xy 268.481615 -201.646133) (xy 268.473672 -201.593429)
			(xy 254.20828 -201.593429) (xy 254.20828 -202.443313) (xy 264.373604 -202.443313) (xy 264.373604 -202.390015)
			(xy 264.381547 -202.337311) (xy 264.397257 -202.286381) (xy 264.420383 -202.23836) (xy 264.450407 -202.194323)
			(xy 264.486659 -202.155252) (xy 264.52833 -202.122021) (xy 264.574488 -202.095372) (xy 264.624102 -202.0759)
			(xy 264.676064 -202.06404) (xy 264.729214 -202.060057) (xy 264.782364 -202.06404) (xy 264.834326 -202.0759)
			(xy 264.88394 -202.095372) (xy 264.930098 -202.122021) (xy 264.971769 -202.155252) (xy 265.008021 -202.194323)
			(xy 265.038045 -202.23836) (xy 265.061171 -202.286381) (xy 265.076881 -202.337311) (xy 265.084824 -202.390015)
			(xy 265.085322 -202.416664) (xy 265.084824 -202.443313) (xy 279.461204 -202.443313) (xy 279.461204 -202.390015)
			(xy 279.469147 -202.337311) (xy 279.484857 -202.286381) (xy 279.507983 -202.23836) (xy 279.538007 -202.194323)
			(xy 279.574259 -202.155252) (xy 279.61593 -202.122021) (xy 279.662088 -202.095372) (xy 279.711702 -202.0759)
			(xy 279.763664 -202.06404) (xy 279.816814 -202.060057) (xy 279.869964 -202.06404) (xy 279.921926 -202.0759)
			(xy 279.97154 -202.095372) (xy 280.017698 -202.122021) (xy 280.059369 -202.155252) (xy 280.095621 -202.194323)
			(xy 280.125645 -202.23836) (xy 280.148771 -202.286381) (xy 280.164481 -202.337311) (xy 280.172424 -202.390015)
			(xy 280.172922 -202.416664) (xy 280.172424 -202.443313) (xy 294.548804 -202.443313) (xy 294.548804 -202.390015)
			(xy 294.556747 -202.337311) (xy 294.572457 -202.286381) (xy 294.595583 -202.23836) (xy 294.625607 -202.194323)
			(xy 294.661859 -202.155252) (xy 294.70353 -202.122021) (xy 294.749688 -202.095372) (xy 294.799302 -202.0759)
			(xy 294.851264 -202.06404) (xy 294.904414 -202.060057) (xy 294.957564 -202.06404) (xy 295.009526 -202.0759)
			(xy 295.05914 -202.095372) (xy 295.105298 -202.122021) (xy 295.146969 -202.155252) (xy 295.183221 -202.194323)
			(xy 295.213245 -202.23836) (xy 295.236371 -202.286381) (xy 295.252081 -202.337311) (xy 295.260024 -202.390015)
			(xy 295.260522 -202.416664) (xy 295.260024 -202.443313) (xy 295.252081 -202.496017) (xy 295.236371 -202.546947)
			(xy 295.213245 -202.594968) (xy 295.183221 -202.639005) (xy 295.146969 -202.678076) (xy 295.105298 -202.711307)
			(xy 295.05914 -202.737956) (xy 295.009526 -202.757428) (xy 294.957564 -202.769288) (xy 294.904414 -202.773272)
			(xy 294.851264 -202.769288) (xy 294.799302 -202.757428) (xy 294.749688 -202.737956) (xy 294.70353 -202.711307)
			(xy 294.661859 -202.678076) (xy 294.625607 -202.639005) (xy 294.595583 -202.594968) (xy 294.572457 -202.546947)
			(xy 294.556747 -202.496017) (xy 294.548804 -202.443313) (xy 280.172424 -202.443313) (xy 280.164481 -202.496017)
			(xy 280.148771 -202.546947) (xy 280.125645 -202.594968) (xy 280.095621 -202.639005) (xy 280.059369 -202.678076)
			(xy 280.017698 -202.711307) (xy 279.97154 -202.737956) (xy 279.921926 -202.757428) (xy 279.869964 -202.769288)
			(xy 279.816814 -202.773272) (xy 279.763664 -202.769288) (xy 279.711702 -202.757428) (xy 279.662088 -202.737956)
			(xy 279.61593 -202.711307) (xy 279.574259 -202.678076) (xy 279.538007 -202.639005) (xy 279.507983 -202.594968)
			(xy 279.484857 -202.546947) (xy 279.469147 -202.496017) (xy 279.461204 -202.443313) (xy 265.084824 -202.443313)
			(xy 265.076881 -202.496017) (xy 265.061171 -202.546947) (xy 265.038045 -202.594968) (xy 265.008021 -202.639005)
			(xy 264.971769 -202.678076) (xy 264.930098 -202.711307) (xy 264.88394 -202.737956) (xy 264.834326 -202.757428)
			(xy 264.782364 -202.769288) (xy 264.729214 -202.773272) (xy 264.676064 -202.769288) (xy 264.624102 -202.757428)
			(xy 264.574488 -202.737956) (xy 264.52833 -202.711307) (xy 264.486659 -202.678076) (xy 264.450407 -202.639005)
			(xy 264.420383 -202.594968) (xy 264.397257 -202.546947) (xy 264.381547 -202.496017) (xy 264.373604 -202.443313)
			(xy 254.20828 -202.443313) (xy 254.20828 -203.293451) (xy 268.473672 -203.293451) (xy 268.473672 -203.240153)
			(xy 268.481615 -203.187449) (xy 268.497325 -203.136519) (xy 268.520451 -203.088498) (xy 268.550475 -203.044461)
			(xy 268.586727 -203.00539) (xy 268.628398 -202.972159) (xy 268.674556 -202.94551) (xy 268.72417 -202.926038)
			(xy 268.776132 -202.914178) (xy 268.829282 -202.910195) (xy 268.882432 -202.914178) (xy 268.934394 -202.926038)
			(xy 268.984008 -202.94551) (xy 269.030166 -202.972159) (xy 269.071837 -203.00539) (xy 269.108089 -203.044461)
			(xy 269.138113 -203.088498) (xy 269.161239 -203.136519) (xy 269.176949 -203.187449) (xy 269.184892 -203.240153)
			(xy 269.18539 -203.266802) (xy 269.184892 -203.293451) (xy 283.561272 -203.293451) (xy 283.561272 -203.240153)
			(xy 283.569215 -203.187449) (xy 283.584925 -203.136519) (xy 283.608051 -203.088498) (xy 283.638075 -203.044461)
			(xy 283.674327 -203.00539) (xy 283.715998 -202.972159) (xy 283.762156 -202.94551) (xy 283.81177 -202.926038)
			(xy 283.863732 -202.914178) (xy 283.916882 -202.910195) (xy 283.970032 -202.914178) (xy 284.021994 -202.926038)
			(xy 284.071608 -202.94551) (xy 284.117766 -202.972159) (xy 284.159437 -203.00539) (xy 284.195689 -203.044461)
			(xy 284.225713 -203.088498) (xy 284.248839 -203.136519) (xy 284.264549 -203.187449) (xy 284.272492 -203.240153)
			(xy 284.27299 -203.266802) (xy 284.272492 -203.293451) (xy 298.648872 -203.293451) (xy 298.648872 -203.240153)
			(xy 298.656815 -203.187449) (xy 298.672525 -203.136519) (xy 298.695651 -203.088498) (xy 298.725675 -203.044461)
			(xy 298.761927 -203.00539) (xy 298.803598 -202.972159) (xy 298.849756 -202.94551) (xy 298.89937 -202.926038)
			(xy 298.951332 -202.914178) (xy 299.004482 -202.910195) (xy 299.057632 -202.914178) (xy 299.109594 -202.926038)
			(xy 299.159208 -202.94551) (xy 299.205366 -202.972159) (xy 299.247037 -203.00539) (xy 299.283289 -203.044461)
			(xy 299.313313 -203.088498) (xy 299.336439 -203.136519) (xy 299.352149 -203.187449) (xy 299.360092 -203.240153)
			(xy 299.36059 -203.266802) (xy 299.360092 -203.293451) (xy 299.352149 -203.346155) (xy 299.336439 -203.397085)
			(xy 299.313313 -203.445106) (xy 299.283289 -203.489143) (xy 299.247037 -203.528214) (xy 299.205366 -203.561445)
			(xy 299.159208 -203.588094) (xy 299.109594 -203.607566) (xy 299.057632 -203.619426) (xy 299.004482 -203.62341)
			(xy 298.951332 -203.619426) (xy 298.89937 -203.607566) (xy 298.849756 -203.588094) (xy 298.803598 -203.561445)
			(xy 298.761927 -203.528214) (xy 298.725675 -203.489143) (xy 298.695651 -203.445106) (xy 298.672525 -203.397085)
			(xy 298.656815 -203.346155) (xy 298.648872 -203.293451) (xy 284.272492 -203.293451) (xy 284.264549 -203.346155)
			(xy 284.248839 -203.397085) (xy 284.225713 -203.445106) (xy 284.195689 -203.489143) (xy 284.159437 -203.528214)
			(xy 284.117766 -203.561445) (xy 284.071608 -203.588094) (xy 284.021994 -203.607566) (xy 283.970032 -203.619426)
			(xy 283.916882 -203.62341) (xy 283.863732 -203.619426) (xy 283.81177 -203.607566) (xy 283.762156 -203.588094)
			(xy 283.715998 -203.561445) (xy 283.674327 -203.528214) (xy 283.638075 -203.489143) (xy 283.608051 -203.445106)
			(xy 283.584925 -203.397085) (xy 283.569215 -203.346155) (xy 283.561272 -203.293451) (xy 269.184892 -203.293451)
			(xy 269.176949 -203.346155) (xy 269.161239 -203.397085) (xy 269.138113 -203.445106) (xy 269.108089 -203.489143)
			(xy 269.071837 -203.528214) (xy 269.030166 -203.561445) (xy 268.984008 -203.588094) (xy 268.934394 -203.607566)
			(xy 268.882432 -203.619426) (xy 268.829282 -203.62341) (xy 268.776132 -203.619426) (xy 268.72417 -203.607566)
			(xy 268.674556 -203.588094) (xy 268.628398 -203.561445) (xy 268.586727 -203.528214) (xy 268.550475 -203.489143)
			(xy 268.520451 -203.445106) (xy 268.497325 -203.397085) (xy 268.481615 -203.346155) (xy 268.473672 -203.293451)
			(xy 254.20828 -203.293451) (xy 254.20828 -204.143335) (xy 264.373604 -204.143335) (xy 264.373604 -204.090037)
			(xy 264.381547 -204.037333) (xy 264.397257 -203.986403) (xy 264.420383 -203.938382) (xy 264.450407 -203.894345)
			(xy 264.486659 -203.855274) (xy 264.52833 -203.822043) (xy 264.574488 -203.795394) (xy 264.624102 -203.775922)
			(xy 264.676064 -203.764062) (xy 264.729214 -203.760079) (xy 264.782364 -203.764062) (xy 264.834326 -203.775922)
			(xy 264.88394 -203.795394) (xy 264.930098 -203.822043) (xy 264.971769 -203.855274) (xy 265.008021 -203.894345)
			(xy 265.038045 -203.938382) (xy 265.061171 -203.986403) (xy 265.076881 -204.037333) (xy 265.084824 -204.090037)
			(xy 265.085322 -204.116686) (xy 265.084824 -204.143335) (xy 279.461204 -204.143335) (xy 279.461204 -204.090037)
			(xy 279.469147 -204.037333) (xy 279.484857 -203.986403) (xy 279.507983 -203.938382) (xy 279.538007 -203.894345)
			(xy 279.574259 -203.855274) (xy 279.61593 -203.822043) (xy 279.662088 -203.795394) (xy 279.711702 -203.775922)
			(xy 279.763664 -203.764062) (xy 279.816814 -203.760079) (xy 279.869964 -203.764062) (xy 279.921926 -203.775922)
			(xy 279.97154 -203.795394) (xy 280.017698 -203.822043) (xy 280.059369 -203.855274) (xy 280.095621 -203.894345)
			(xy 280.125645 -203.938382) (xy 280.148771 -203.986403) (xy 280.164481 -204.037333) (xy 280.172424 -204.090037)
			(xy 280.172922 -204.116686) (xy 280.172424 -204.143335) (xy 294.548804 -204.143335) (xy 294.548804 -204.090037)
			(xy 294.556747 -204.037333) (xy 294.572457 -203.986403) (xy 294.595583 -203.938382) (xy 294.625607 -203.894345)
			(xy 294.661859 -203.855274) (xy 294.70353 -203.822043) (xy 294.749688 -203.795394) (xy 294.799302 -203.775922)
			(xy 294.851264 -203.764062) (xy 294.904414 -203.760079) (xy 294.957564 -203.764062) (xy 295.009526 -203.775922)
			(xy 295.05914 -203.795394) (xy 295.105298 -203.822043) (xy 295.146969 -203.855274) (xy 295.183221 -203.894345)
			(xy 295.213245 -203.938382) (xy 295.236371 -203.986403) (xy 295.252081 -204.037333) (xy 295.260024 -204.090037)
			(xy 295.260522 -204.116686) (xy 295.260024 -204.143335) (xy 295.252081 -204.196039) (xy 295.236371 -204.246969)
			(xy 295.213245 -204.29499) (xy 295.183221 -204.339027) (xy 295.146969 -204.378098) (xy 295.105298 -204.411329)
			(xy 295.05914 -204.437978) (xy 295.009526 -204.45745) (xy 294.957564 -204.46931) (xy 294.904414 -204.473294)
			(xy 294.851264 -204.46931) (xy 294.799302 -204.45745) (xy 294.749688 -204.437978) (xy 294.70353 -204.411329)
			(xy 294.661859 -204.378098) (xy 294.625607 -204.339027) (xy 294.595583 -204.29499) (xy 294.572457 -204.246969)
			(xy 294.556747 -204.196039) (xy 294.548804 -204.143335) (xy 280.172424 -204.143335) (xy 280.164481 -204.196039)
			(xy 280.148771 -204.246969) (xy 280.125645 -204.29499) (xy 280.095621 -204.339027) (xy 280.059369 -204.378098)
			(xy 280.017698 -204.411329) (xy 279.97154 -204.437978) (xy 279.921926 -204.45745) (xy 279.869964 -204.46931)
			(xy 279.816814 -204.473294) (xy 279.763664 -204.46931) (xy 279.711702 -204.45745) (xy 279.662088 -204.437978)
			(xy 279.61593 -204.411329) (xy 279.574259 -204.378098) (xy 279.538007 -204.339027) (xy 279.507983 -204.29499)
			(xy 279.484857 -204.246969) (xy 279.469147 -204.196039) (xy 279.461204 -204.143335) (xy 265.084824 -204.143335)
			(xy 265.076881 -204.196039) (xy 265.061171 -204.246969) (xy 265.038045 -204.29499) (xy 265.008021 -204.339027)
			(xy 264.971769 -204.378098) (xy 264.930098 -204.411329) (xy 264.88394 -204.437978) (xy 264.834326 -204.45745)
			(xy 264.782364 -204.46931) (xy 264.729214 -204.473294) (xy 264.676064 -204.46931) (xy 264.624102 -204.45745)
			(xy 264.574488 -204.437978) (xy 264.52833 -204.411329) (xy 264.486659 -204.378098) (xy 264.450407 -204.339027)
			(xy 264.420383 -204.29499) (xy 264.397257 -204.246969) (xy 264.381547 -204.196039) (xy 264.373604 -204.143335)
			(xy 254.20828 -204.143335) (xy 254.20828 -204.993219) (xy 268.473672 -204.993219) (xy 268.473672 -204.939921)
			(xy 268.481615 -204.887217) (xy 268.497325 -204.836287) (xy 268.520451 -204.788266) (xy 268.550475 -204.744229)
			(xy 268.586727 -204.705158) (xy 268.628398 -204.671927) (xy 268.674556 -204.645278) (xy 268.72417 -204.625806)
			(xy 268.776132 -204.613946) (xy 268.829282 -204.609963) (xy 268.882432 -204.613946) (xy 268.934394 -204.625806)
			(xy 268.984008 -204.645278) (xy 269.030166 -204.671927) (xy 269.071837 -204.705158) (xy 269.108089 -204.744229)
			(xy 269.138113 -204.788266) (xy 269.161239 -204.836287) (xy 269.176949 -204.887217) (xy 269.184892 -204.939921)
			(xy 269.18539 -204.96657) (xy 269.184892 -204.993219) (xy 283.561272 -204.993219) (xy 283.561272 -204.939921)
			(xy 283.569215 -204.887217) (xy 283.584925 -204.836287) (xy 283.608051 -204.788266) (xy 283.638075 -204.744229)
			(xy 283.674327 -204.705158) (xy 283.715998 -204.671927) (xy 283.762156 -204.645278) (xy 283.81177 -204.625806)
			(xy 283.863732 -204.613946) (xy 283.916882 -204.609963) (xy 283.970032 -204.613946) (xy 284.021994 -204.625806)
			(xy 284.071608 -204.645278) (xy 284.117766 -204.671927) (xy 284.159437 -204.705158) (xy 284.195689 -204.744229)
			(xy 284.225713 -204.788266) (xy 284.248839 -204.836287) (xy 284.264549 -204.887217) (xy 284.272492 -204.939921)
			(xy 284.27299 -204.96657) (xy 284.272492 -204.993219) (xy 298.648872 -204.993219) (xy 298.648872 -204.939921)
			(xy 298.656815 -204.887217) (xy 298.672525 -204.836287) (xy 298.695651 -204.788266) (xy 298.725675 -204.744229)
			(xy 298.761927 -204.705158) (xy 298.803598 -204.671927) (xy 298.849756 -204.645278) (xy 298.89937 -204.625806)
			(xy 298.951332 -204.613946) (xy 299.004482 -204.609963) (xy 299.057632 -204.613946) (xy 299.109594 -204.625806)
			(xy 299.159208 -204.645278) (xy 299.205366 -204.671927) (xy 299.247037 -204.705158) (xy 299.283289 -204.744229)
			(xy 299.313313 -204.788266) (xy 299.336439 -204.836287) (xy 299.352149 -204.887217) (xy 299.360092 -204.939921)
			(xy 299.36059 -204.96657) (xy 299.360092 -204.993219) (xy 299.352149 -205.045923) (xy 299.336439 -205.096853)
			(xy 299.313313 -205.144874) (xy 299.283289 -205.188911) (xy 299.247037 -205.227982) (xy 299.205366 -205.261213)
			(xy 299.159208 -205.287862) (xy 299.109594 -205.307334) (xy 299.057632 -205.319194) (xy 299.004482 -205.323178)
			(xy 298.951332 -205.319194) (xy 298.89937 -205.307334) (xy 298.849756 -205.287862) (xy 298.803598 -205.261213)
			(xy 298.761927 -205.227982) (xy 298.725675 -205.188911) (xy 298.695651 -205.144874) (xy 298.672525 -205.096853)
			(xy 298.656815 -205.045923) (xy 298.648872 -204.993219) (xy 284.272492 -204.993219) (xy 284.264549 -205.045923)
			(xy 284.248839 -205.096853) (xy 284.225713 -205.144874) (xy 284.195689 -205.188911) (xy 284.159437 -205.227982)
			(xy 284.117766 -205.261213) (xy 284.071608 -205.287862) (xy 284.021994 -205.307334) (xy 283.970032 -205.319194)
			(xy 283.916882 -205.323178) (xy 283.863732 -205.319194) (xy 283.81177 -205.307334) (xy 283.762156 -205.287862)
			(xy 283.715998 -205.261213) (xy 283.674327 -205.227982) (xy 283.638075 -205.188911) (xy 283.608051 -205.144874)
			(xy 283.584925 -205.096853) (xy 283.569215 -205.045923) (xy 283.561272 -204.993219) (xy 269.184892 -204.993219)
			(xy 269.176949 -205.045923) (xy 269.161239 -205.096853) (xy 269.138113 -205.144874) (xy 269.108089 -205.188911)
			(xy 269.071837 -205.227982) (xy 269.030166 -205.261213) (xy 268.984008 -205.287862) (xy 268.934394 -205.307334)
			(xy 268.882432 -205.319194) (xy 268.829282 -205.323178) (xy 268.776132 -205.319194) (xy 268.72417 -205.307334)
			(xy 268.674556 -205.287862) (xy 268.628398 -205.261213) (xy 268.586727 -205.227982) (xy 268.550475 -205.188911)
			(xy 268.520451 -205.144874) (xy 268.497325 -205.096853) (xy 268.481615 -205.045923) (xy 268.473672 -204.993219)
			(xy 254.20828 -204.993219) (xy 254.20828 -205.843357) (xy 264.373604 -205.843357) (xy 264.373604 -205.790059)
			(xy 264.381547 -205.737355) (xy 264.397257 -205.686425) (xy 264.420383 -205.638404) (xy 264.450407 -205.594367)
			(xy 264.486659 -205.555296) (xy 264.52833 -205.522065) (xy 264.574488 -205.495416) (xy 264.624102 -205.475944)
			(xy 264.676064 -205.464084) (xy 264.729214 -205.460101) (xy 264.782364 -205.464084) (xy 264.834326 -205.475944)
			(xy 264.88394 -205.495416) (xy 264.930098 -205.522065) (xy 264.971769 -205.555296) (xy 265.008021 -205.594367)
			(xy 265.038045 -205.638404) (xy 265.061171 -205.686425) (xy 265.076881 -205.737355) (xy 265.084824 -205.790059)
			(xy 265.085322 -205.816708) (xy 265.084824 -205.843357) (xy 279.461204 -205.843357) (xy 279.461204 -205.790059)
			(xy 279.469147 -205.737355) (xy 279.484857 -205.686425) (xy 279.507983 -205.638404) (xy 279.538007 -205.594367)
			(xy 279.574259 -205.555296) (xy 279.61593 -205.522065) (xy 279.662088 -205.495416) (xy 279.711702 -205.475944)
			(xy 279.763664 -205.464084) (xy 279.816814 -205.460101) (xy 279.869964 -205.464084) (xy 279.921926 -205.475944)
			(xy 279.97154 -205.495416) (xy 280.017698 -205.522065) (xy 280.059369 -205.555296) (xy 280.095621 -205.594367)
			(xy 280.125645 -205.638404) (xy 280.148771 -205.686425) (xy 280.164481 -205.737355) (xy 280.172424 -205.790059)
			(xy 280.172922 -205.816708) (xy 280.172424 -205.843357) (xy 294.548804 -205.843357) (xy 294.548804 -205.790059)
			(xy 294.556747 -205.737355) (xy 294.572457 -205.686425) (xy 294.595583 -205.638404) (xy 294.625607 -205.594367)
			(xy 294.661859 -205.555296) (xy 294.70353 -205.522065) (xy 294.749688 -205.495416) (xy 294.799302 -205.475944)
			(xy 294.851264 -205.464084) (xy 294.904414 -205.460101) (xy 294.957564 -205.464084) (xy 295.009526 -205.475944)
			(xy 295.05914 -205.495416) (xy 295.105298 -205.522065) (xy 295.146969 -205.555296) (xy 295.183221 -205.594367)
			(xy 295.213245 -205.638404) (xy 295.236371 -205.686425) (xy 295.252081 -205.737355) (xy 295.260024 -205.790059)
			(xy 295.260522 -205.816708) (xy 295.260024 -205.843357) (xy 295.252081 -205.896061) (xy 295.236371 -205.946991)
			(xy 295.213245 -205.995012) (xy 295.183221 -206.039049) (xy 295.146969 -206.07812) (xy 295.105298 -206.111351)
			(xy 295.05914 -206.138) (xy 295.009526 -206.157472) (xy 294.957564 -206.169332) (xy 294.904414 -206.173316)
			(xy 294.851264 -206.169332) (xy 294.799302 -206.157472) (xy 294.749688 -206.138) (xy 294.70353 -206.111351)
			(xy 294.661859 -206.07812) (xy 294.625607 -206.039049) (xy 294.595583 -205.995012) (xy 294.572457 -205.946991)
			(xy 294.556747 -205.896061) (xy 294.548804 -205.843357) (xy 280.172424 -205.843357) (xy 280.164481 -205.896061)
			(xy 280.148771 -205.946991) (xy 280.125645 -205.995012) (xy 280.095621 -206.039049) (xy 280.059369 -206.07812)
			(xy 280.017698 -206.111351) (xy 279.97154 -206.138) (xy 279.921926 -206.157472) (xy 279.869964 -206.169332)
			(xy 279.816814 -206.173316) (xy 279.763664 -206.169332) (xy 279.711702 -206.157472) (xy 279.662088 -206.138)
			(xy 279.61593 -206.111351) (xy 279.574259 -206.07812) (xy 279.538007 -206.039049) (xy 279.507983 -205.995012)
			(xy 279.484857 -205.946991) (xy 279.469147 -205.896061) (xy 279.461204 -205.843357) (xy 265.084824 -205.843357)
			(xy 265.076881 -205.896061) (xy 265.061171 -205.946991) (xy 265.038045 -205.995012) (xy 265.008021 -206.039049)
			(xy 264.971769 -206.07812) (xy 264.930098 -206.111351) (xy 264.88394 -206.138) (xy 264.834326 -206.157472)
			(xy 264.782364 -206.169332) (xy 264.729214 -206.173316) (xy 264.676064 -206.169332) (xy 264.624102 -206.157472)
			(xy 264.574488 -206.138) (xy 264.52833 -206.111351) (xy 264.486659 -206.07812) (xy 264.450407 -206.039049)
			(xy 264.420383 -205.995012) (xy 264.397257 -205.946991) (xy 264.381547 -205.896061) (xy 264.373604 -205.843357)
			(xy 254.20828 -205.843357) (xy 254.20828 -206.693241) (xy 268.473672 -206.693241) (xy 268.473672 -206.639943)
			(xy 268.481615 -206.587239) (xy 268.497325 -206.536309) (xy 268.520451 -206.488288) (xy 268.550475 -206.444251)
			(xy 268.586727 -206.40518) (xy 268.628398 -206.371949) (xy 268.674556 -206.3453) (xy 268.72417 -206.325828)
			(xy 268.776132 -206.313968) (xy 268.829282 -206.309985) (xy 268.882432 -206.313968) (xy 268.934394 -206.325828)
			(xy 268.984008 -206.3453) (xy 269.030166 -206.371949) (xy 269.071837 -206.40518) (xy 269.108089 -206.444251)
			(xy 269.138113 -206.488288) (xy 269.161239 -206.536309) (xy 269.176949 -206.587239) (xy 269.184892 -206.639943)
			(xy 269.18539 -206.666592) (xy 269.184892 -206.693241) (xy 283.561272 -206.693241) (xy 283.561272 -206.639943)
			(xy 283.569215 -206.587239) (xy 283.584925 -206.536309) (xy 283.608051 -206.488288) (xy 283.638075 -206.444251)
			(xy 283.674327 -206.40518) (xy 283.715998 -206.371949) (xy 283.762156 -206.3453) (xy 283.81177 -206.325828)
			(xy 283.863732 -206.313968) (xy 283.916882 -206.309985) (xy 283.970032 -206.313968) (xy 284.021994 -206.325828)
			(xy 284.071608 -206.3453) (xy 284.117766 -206.371949) (xy 284.159437 -206.40518) (xy 284.195689 -206.444251)
			(xy 284.225713 -206.488288) (xy 284.248839 -206.536309) (xy 284.264549 -206.587239) (xy 284.272492 -206.639943)
			(xy 284.27299 -206.666592) (xy 284.272492 -206.693241) (xy 298.648872 -206.693241) (xy 298.648872 -206.639943)
			(xy 298.656815 -206.587239) (xy 298.672525 -206.536309) (xy 298.695651 -206.488288) (xy 298.725675 -206.444251)
			(xy 298.761927 -206.40518) (xy 298.803598 -206.371949) (xy 298.849756 -206.3453) (xy 298.89937 -206.325828)
			(xy 298.951332 -206.313968) (xy 299.004482 -206.309985) (xy 299.057632 -206.313968) (xy 299.109594 -206.325828)
			(xy 299.159208 -206.3453) (xy 299.205366 -206.371949) (xy 299.247037 -206.40518) (xy 299.283289 -206.444251)
			(xy 299.313313 -206.488288) (xy 299.336439 -206.536309) (xy 299.352149 -206.587239) (xy 299.360092 -206.639943)
			(xy 299.36059 -206.666592) (xy 299.360092 -206.693241) (xy 299.352149 -206.745945) (xy 299.336439 -206.796875)
			(xy 299.313313 -206.844896) (xy 299.283289 -206.888933) (xy 299.247037 -206.928004) (xy 299.205366 -206.961235)
			(xy 299.159208 -206.987884) (xy 299.109594 -207.007356) (xy 299.057632 -207.019216) (xy 299.004482 -207.0232)
			(xy 298.951332 -207.019216) (xy 298.89937 -207.007356) (xy 298.849756 -206.987884) (xy 298.803598 -206.961235)
			(xy 298.761927 -206.928004) (xy 298.725675 -206.888933) (xy 298.695651 -206.844896) (xy 298.672525 -206.796875)
			(xy 298.656815 -206.745945) (xy 298.648872 -206.693241) (xy 284.272492 -206.693241) (xy 284.264549 -206.745945)
			(xy 284.248839 -206.796875) (xy 284.225713 -206.844896) (xy 284.195689 -206.888933) (xy 284.159437 -206.928004)
			(xy 284.117766 -206.961235) (xy 284.071608 -206.987884) (xy 284.021994 -207.007356) (xy 283.970032 -207.019216)
			(xy 283.916882 -207.0232) (xy 283.863732 -207.019216) (xy 283.81177 -207.007356) (xy 283.762156 -206.987884)
			(xy 283.715998 -206.961235) (xy 283.674327 -206.928004) (xy 283.638075 -206.888933) (xy 283.608051 -206.844896)
			(xy 283.584925 -206.796875) (xy 283.569215 -206.745945) (xy 283.561272 -206.693241) (xy 269.184892 -206.693241)
			(xy 269.176949 -206.745945) (xy 269.161239 -206.796875) (xy 269.138113 -206.844896) (xy 269.108089 -206.888933)
			(xy 269.071837 -206.928004) (xy 269.030166 -206.961235) (xy 268.984008 -206.987884) (xy 268.934394 -207.007356)
			(xy 268.882432 -207.019216) (xy 268.829282 -207.0232) (xy 268.776132 -207.019216) (xy 268.72417 -207.007356)
			(xy 268.674556 -206.987884) (xy 268.628398 -206.961235) (xy 268.586727 -206.928004) (xy 268.550475 -206.888933)
			(xy 268.520451 -206.844896) (xy 268.497325 -206.796875) (xy 268.481615 -206.745945) (xy 268.473672 -206.693241)
			(xy 254.20828 -206.693241) (xy 254.20828 -207.543379) (xy 264.373604 -207.543379) (xy 264.373604 -207.490081)
			(xy 264.381547 -207.437377) (xy 264.397257 -207.386447) (xy 264.420383 -207.338426) (xy 264.450407 -207.294389)
			(xy 264.486659 -207.255318) (xy 264.52833 -207.222087) (xy 264.574488 -207.195438) (xy 264.624102 -207.175966)
			(xy 264.676064 -207.164106) (xy 264.729214 -207.160123) (xy 264.782364 -207.164106) (xy 264.834326 -207.175966)
			(xy 264.88394 -207.195438) (xy 264.930098 -207.222087) (xy 264.971769 -207.255318) (xy 265.008021 -207.294389)
			(xy 265.038045 -207.338426) (xy 265.061171 -207.386447) (xy 265.076881 -207.437377) (xy 265.084824 -207.490081)
			(xy 265.085322 -207.51673) (xy 265.084824 -207.543379) (xy 279.461204 -207.543379) (xy 279.461204 -207.490081)
			(xy 279.469147 -207.437377) (xy 279.484857 -207.386447) (xy 279.507983 -207.338426) (xy 279.538007 -207.294389)
			(xy 279.574259 -207.255318) (xy 279.61593 -207.222087) (xy 279.662088 -207.195438) (xy 279.711702 -207.175966)
			(xy 279.763664 -207.164106) (xy 279.816814 -207.160123) (xy 279.869964 -207.164106) (xy 279.921926 -207.175966)
			(xy 279.97154 -207.195438) (xy 280.017698 -207.222087) (xy 280.059369 -207.255318) (xy 280.095621 -207.294389)
			(xy 280.125645 -207.338426) (xy 280.148771 -207.386447) (xy 280.164481 -207.437377) (xy 280.172424 -207.490081)
			(xy 280.172922 -207.51673) (xy 280.172424 -207.543379) (xy 294.548804 -207.543379) (xy 294.548804 -207.490081)
			(xy 294.556747 -207.437377) (xy 294.572457 -207.386447) (xy 294.595583 -207.338426) (xy 294.625607 -207.294389)
			(xy 294.661859 -207.255318) (xy 294.70353 -207.222087) (xy 294.749688 -207.195438) (xy 294.799302 -207.175966)
			(xy 294.851264 -207.164106) (xy 294.904414 -207.160123) (xy 294.957564 -207.164106) (xy 295.009526 -207.175966)
			(xy 295.05914 -207.195438) (xy 295.105298 -207.222087) (xy 295.146969 -207.255318) (xy 295.183221 -207.294389)
			(xy 295.213245 -207.338426) (xy 295.236371 -207.386447) (xy 295.252081 -207.437377) (xy 295.260024 -207.490081)
			(xy 295.260522 -207.51673) (xy 295.260024 -207.543379) (xy 295.252081 -207.596083) (xy 295.236371 -207.647013)
			(xy 295.213245 -207.695034) (xy 295.183221 -207.739071) (xy 295.146969 -207.778142) (xy 295.105298 -207.811373)
			(xy 295.05914 -207.838022) (xy 295.009526 -207.857494) (xy 294.957564 -207.869354) (xy 294.904414 -207.873338)
			(xy 294.851264 -207.869354) (xy 294.799302 -207.857494) (xy 294.749688 -207.838022) (xy 294.70353 -207.811373)
			(xy 294.661859 -207.778142) (xy 294.625607 -207.739071) (xy 294.595583 -207.695034) (xy 294.572457 -207.647013)
			(xy 294.556747 -207.596083) (xy 294.548804 -207.543379) (xy 280.172424 -207.543379) (xy 280.164481 -207.596083)
			(xy 280.148771 -207.647013) (xy 280.125645 -207.695034) (xy 280.095621 -207.739071) (xy 280.059369 -207.778142)
			(xy 280.017698 -207.811373) (xy 279.97154 -207.838022) (xy 279.921926 -207.857494) (xy 279.869964 -207.869354)
			(xy 279.816814 -207.873338) (xy 279.763664 -207.869354) (xy 279.711702 -207.857494) (xy 279.662088 -207.838022)
			(xy 279.61593 -207.811373) (xy 279.574259 -207.778142) (xy 279.538007 -207.739071) (xy 279.507983 -207.695034)
			(xy 279.484857 -207.647013) (xy 279.469147 -207.596083) (xy 279.461204 -207.543379) (xy 265.084824 -207.543379)
			(xy 265.076881 -207.596083) (xy 265.061171 -207.647013) (xy 265.038045 -207.695034) (xy 265.008021 -207.739071)
			(xy 264.971769 -207.778142) (xy 264.930098 -207.811373) (xy 264.88394 -207.838022) (xy 264.834326 -207.857494)
			(xy 264.782364 -207.869354) (xy 264.729214 -207.873338) (xy 264.676064 -207.869354) (xy 264.624102 -207.857494)
			(xy 264.574488 -207.838022) (xy 264.52833 -207.811373) (xy 264.486659 -207.778142) (xy 264.450407 -207.739071)
			(xy 264.420383 -207.695034) (xy 264.397257 -207.647013) (xy 264.381547 -207.596083) (xy 264.373604 -207.543379)
			(xy 254.20828 -207.543379) (xy 254.20828 -208.393263) (xy 268.473672 -208.393263) (xy 268.473672 -208.339965)
			(xy 268.481615 -208.287261) (xy 268.497325 -208.236331) (xy 268.520451 -208.18831) (xy 268.550475 -208.144273)
			(xy 268.586727 -208.105202) (xy 268.628398 -208.071971) (xy 268.674556 -208.045322) (xy 268.72417 -208.02585)
			(xy 268.776132 -208.01399) (xy 268.829282 -208.010007) (xy 268.882432 -208.01399) (xy 268.934394 -208.02585)
			(xy 268.984008 -208.045322) (xy 269.030166 -208.071971) (xy 269.071837 -208.105202) (xy 269.108089 -208.144273)
			(xy 269.138113 -208.18831) (xy 269.161239 -208.236331) (xy 269.176949 -208.287261) (xy 269.184892 -208.339965)
			(xy 269.18539 -208.366614) (xy 269.184892 -208.393263) (xy 283.561272 -208.393263) (xy 283.561272 -208.339965)
			(xy 283.569215 -208.287261) (xy 283.584925 -208.236331) (xy 283.608051 -208.18831) (xy 283.638075 -208.144273)
			(xy 283.674327 -208.105202) (xy 283.715998 -208.071971) (xy 283.762156 -208.045322) (xy 283.81177 -208.02585)
			(xy 283.863732 -208.01399) (xy 283.916882 -208.010007) (xy 283.970032 -208.01399) (xy 284.021994 -208.02585)
			(xy 284.071608 -208.045322) (xy 284.117766 -208.071971) (xy 284.159437 -208.105202) (xy 284.195689 -208.144273)
			(xy 284.225713 -208.18831) (xy 284.248839 -208.236331) (xy 284.264549 -208.287261) (xy 284.272492 -208.339965)
			(xy 284.27299 -208.366614) (xy 284.272492 -208.393263) (xy 298.648872 -208.393263) (xy 298.648872 -208.339965)
			(xy 298.656815 -208.287261) (xy 298.672525 -208.236331) (xy 298.695651 -208.18831) (xy 298.725675 -208.144273)
			(xy 298.761927 -208.105202) (xy 298.803598 -208.071971) (xy 298.849756 -208.045322) (xy 298.89937 -208.02585)
			(xy 298.951332 -208.01399) (xy 299.004482 -208.010007) (xy 299.057632 -208.01399) (xy 299.109594 -208.02585)
			(xy 299.159208 -208.045322) (xy 299.205366 -208.071971) (xy 299.247037 -208.105202) (xy 299.283289 -208.144273)
			(xy 299.313313 -208.18831) (xy 299.336439 -208.236331) (xy 299.352149 -208.287261) (xy 299.360092 -208.339965)
			(xy 299.36059 -208.366614) (xy 299.360092 -208.393263) (xy 299.352149 -208.445967) (xy 299.336439 -208.496897)
			(xy 299.313313 -208.544918) (xy 299.283289 -208.588955) (xy 299.247037 -208.628026) (xy 299.205366 -208.661257)
			(xy 299.159208 -208.687906) (xy 299.109594 -208.707378) (xy 299.057632 -208.719238) (xy 299.004482 -208.723222)
			(xy 298.951332 -208.719238) (xy 298.89937 -208.707378) (xy 298.849756 -208.687906) (xy 298.803598 -208.661257)
			(xy 298.761927 -208.628026) (xy 298.725675 -208.588955) (xy 298.695651 -208.544918) (xy 298.672525 -208.496897)
			(xy 298.656815 -208.445967) (xy 298.648872 -208.393263) (xy 284.272492 -208.393263) (xy 284.264549 -208.445967)
			(xy 284.248839 -208.496897) (xy 284.225713 -208.544918) (xy 284.195689 -208.588955) (xy 284.159437 -208.628026)
			(xy 284.117766 -208.661257) (xy 284.071608 -208.687906) (xy 284.021994 -208.707378) (xy 283.970032 -208.719238)
			(xy 283.916882 -208.723222) (xy 283.863732 -208.719238) (xy 283.81177 -208.707378) (xy 283.762156 -208.687906)
			(xy 283.715998 -208.661257) (xy 283.674327 -208.628026) (xy 283.638075 -208.588955) (xy 283.608051 -208.544918)
			(xy 283.584925 -208.496897) (xy 283.569215 -208.445967) (xy 283.561272 -208.393263) (xy 269.184892 -208.393263)
			(xy 269.176949 -208.445967) (xy 269.161239 -208.496897) (xy 269.138113 -208.544918) (xy 269.108089 -208.588955)
			(xy 269.071837 -208.628026) (xy 269.030166 -208.661257) (xy 268.984008 -208.687906) (xy 268.934394 -208.707378)
			(xy 268.882432 -208.719238) (xy 268.829282 -208.723222) (xy 268.776132 -208.719238) (xy 268.72417 -208.707378)
			(xy 268.674556 -208.687906) (xy 268.628398 -208.661257) (xy 268.586727 -208.628026) (xy 268.550475 -208.588955)
			(xy 268.520451 -208.544918) (xy 268.497325 -208.496897) (xy 268.481615 -208.445967) (xy 268.473672 -208.393263)
			(xy 254.20828 -208.393263) (xy 254.20828 -209.243401) (xy 264.373604 -209.243401) (xy 264.373604 -209.190103)
			(xy 264.381547 -209.137399) (xy 264.397257 -209.086469) (xy 264.420383 -209.038448) (xy 264.450407 -208.994411)
			(xy 264.486659 -208.95534) (xy 264.52833 -208.922109) (xy 264.574488 -208.89546) (xy 264.624102 -208.875988)
			(xy 264.676064 -208.864128) (xy 264.729214 -208.860145) (xy 264.782364 -208.864128) (xy 264.834326 -208.875988)
			(xy 264.88394 -208.89546) (xy 264.930098 -208.922109) (xy 264.971769 -208.95534) (xy 265.008021 -208.994411)
			(xy 265.038045 -209.038448) (xy 265.061171 -209.086469) (xy 265.076881 -209.137399) (xy 265.084824 -209.190103)
			(xy 265.085322 -209.216752) (xy 265.084824 -209.243401) (xy 268.473672 -209.243401) (xy 268.473672 -209.190103)
			(xy 268.481615 -209.137399) (xy 268.497325 -209.086469) (xy 268.520451 -209.038448) (xy 268.550475 -208.994411)
			(xy 268.586727 -208.95534) (xy 268.628398 -208.922109) (xy 268.674556 -208.89546) (xy 268.72417 -208.875988)
			(xy 268.776132 -208.864128) (xy 268.829282 -208.860145) (xy 268.882432 -208.864128) (xy 268.934394 -208.875988)
			(xy 268.984008 -208.89546) (xy 269.030166 -208.922109) (xy 269.071837 -208.95534) (xy 269.108089 -208.994411)
			(xy 269.138113 -209.038448) (xy 269.161239 -209.086469) (xy 269.176949 -209.137399) (xy 269.184892 -209.190103)
			(xy 269.18539 -209.216752) (xy 269.184892 -209.243401) (xy 279.461204 -209.243401) (xy 279.461204 -209.190103)
			(xy 279.469147 -209.137399) (xy 279.484857 -209.086469) (xy 279.507983 -209.038448) (xy 279.538007 -208.994411)
			(xy 279.574259 -208.95534) (xy 279.61593 -208.922109) (xy 279.662088 -208.89546) (xy 279.711702 -208.875988)
			(xy 279.763664 -208.864128) (xy 279.816814 -208.860145) (xy 279.869964 -208.864128) (xy 279.921926 -208.875988)
			(xy 279.97154 -208.89546) (xy 280.017698 -208.922109) (xy 280.059369 -208.95534) (xy 280.095621 -208.994411)
			(xy 280.125645 -209.038448) (xy 280.148771 -209.086469) (xy 280.164481 -209.137399) (xy 280.172424 -209.190103)
			(xy 280.172922 -209.216752) (xy 280.172424 -209.243401) (xy 283.561272 -209.243401) (xy 283.561272 -209.190103)
			(xy 283.569215 -209.137399) (xy 283.584925 -209.086469) (xy 283.608051 -209.038448) (xy 283.638075 -208.994411)
			(xy 283.674327 -208.95534) (xy 283.715998 -208.922109) (xy 283.762156 -208.89546) (xy 283.81177 -208.875988)
			(xy 283.863732 -208.864128) (xy 283.916882 -208.860145) (xy 283.970032 -208.864128) (xy 284.021994 -208.875988)
			(xy 284.071608 -208.89546) (xy 284.117766 -208.922109) (xy 284.159437 -208.95534) (xy 284.195689 -208.994411)
			(xy 284.225713 -209.038448) (xy 284.248839 -209.086469) (xy 284.264549 -209.137399) (xy 284.272492 -209.190103)
			(xy 284.27299 -209.216752) (xy 284.272492 -209.243401) (xy 294.548804 -209.243401) (xy 294.548804 -209.190103)
			(xy 294.556747 -209.137399) (xy 294.572457 -209.086469) (xy 294.595583 -209.038448) (xy 294.625607 -208.994411)
			(xy 294.661859 -208.95534) (xy 294.70353 -208.922109) (xy 294.749688 -208.89546) (xy 294.799302 -208.875988)
			(xy 294.851264 -208.864128) (xy 294.904414 -208.860145) (xy 294.957564 -208.864128) (xy 295.009526 -208.875988)
			(xy 295.05914 -208.89546) (xy 295.105298 -208.922109) (xy 295.146969 -208.95534) (xy 295.183221 -208.994411)
			(xy 295.213245 -209.038448) (xy 295.236371 -209.086469) (xy 295.252081 -209.137399) (xy 295.260024 -209.190103)
			(xy 295.260522 -209.216752) (xy 295.260024 -209.243401) (xy 298.648872 -209.243401) (xy 298.648872 -209.190103)
			(xy 298.656815 -209.137399) (xy 298.672525 -209.086469) (xy 298.695651 -209.038448) (xy 298.725675 -208.994411)
			(xy 298.761927 -208.95534) (xy 298.803598 -208.922109) (xy 298.849756 -208.89546) (xy 298.89937 -208.875988)
			(xy 298.951332 -208.864128) (xy 299.004482 -208.860145) (xy 299.057632 -208.864128) (xy 299.109594 -208.875988)
			(xy 299.159208 -208.89546) (xy 299.205366 -208.922109) (xy 299.247037 -208.95534) (xy 299.283289 -208.994411)
			(xy 299.313313 -209.038448) (xy 299.336439 -209.086469) (xy 299.352149 -209.137399) (xy 299.360092 -209.190103)
			(xy 299.36059 -209.216752) (xy 299.360092 -209.243401) (xy 299.352149 -209.296105) (xy 299.336439 -209.347035)
			(xy 299.313313 -209.395056) (xy 299.283289 -209.439093) (xy 299.247037 -209.478164) (xy 299.205366 -209.511395)
			(xy 299.159208 -209.538044) (xy 299.109594 -209.557516) (xy 299.057632 -209.569376) (xy 299.004482 -209.57336)
			(xy 298.951332 -209.569376) (xy 298.89937 -209.557516) (xy 298.849756 -209.538044) (xy 298.803598 -209.511395)
			(xy 298.761927 -209.478164) (xy 298.725675 -209.439093) (xy 298.695651 -209.395056) (xy 298.672525 -209.347035)
			(xy 298.656815 -209.296105) (xy 298.648872 -209.243401) (xy 295.260024 -209.243401) (xy 295.252081 -209.296105)
			(xy 295.236371 -209.347035) (xy 295.213245 -209.395056) (xy 295.183221 -209.439093) (xy 295.146969 -209.478164)
			(xy 295.105298 -209.511395) (xy 295.05914 -209.538044) (xy 295.009526 -209.557516) (xy 294.957564 -209.569376)
			(xy 294.904414 -209.57336) (xy 294.851264 -209.569376) (xy 294.799302 -209.557516) (xy 294.749688 -209.538044)
			(xy 294.70353 -209.511395) (xy 294.661859 -209.478164) (xy 294.625607 -209.439093) (xy 294.595583 -209.395056)
			(xy 294.572457 -209.347035) (xy 294.556747 -209.296105) (xy 294.548804 -209.243401) (xy 284.272492 -209.243401)
			(xy 284.264549 -209.296105) (xy 284.248839 -209.347035) (xy 284.225713 -209.395056) (xy 284.195689 -209.439093)
			(xy 284.159437 -209.478164) (xy 284.117766 -209.511395) (xy 284.071608 -209.538044) (xy 284.021994 -209.557516)
			(xy 283.970032 -209.569376) (xy 283.916882 -209.57336) (xy 283.863732 -209.569376) (xy 283.81177 -209.557516)
			(xy 283.762156 -209.538044) (xy 283.715998 -209.511395) (xy 283.674327 -209.478164) (xy 283.638075 -209.439093)
			(xy 283.608051 -209.395056) (xy 283.584925 -209.347035) (xy 283.569215 -209.296105) (xy 283.561272 -209.243401)
			(xy 280.172424 -209.243401) (xy 280.164481 -209.296105) (xy 280.148771 -209.347035) (xy 280.125645 -209.395056)
			(xy 280.095621 -209.439093) (xy 280.059369 -209.478164) (xy 280.017698 -209.511395) (xy 279.97154 -209.538044)
			(xy 279.921926 -209.557516) (xy 279.869964 -209.569376) (xy 279.816814 -209.57336) (xy 279.763664 -209.569376)
			(xy 279.711702 -209.557516) (xy 279.662088 -209.538044) (xy 279.61593 -209.511395) (xy 279.574259 -209.478164)
			(xy 279.538007 -209.439093) (xy 279.507983 -209.395056) (xy 279.484857 -209.347035) (xy 279.469147 -209.296105)
			(xy 279.461204 -209.243401) (xy 269.184892 -209.243401) (xy 269.176949 -209.296105) (xy 269.161239 -209.347035)
			(xy 269.138113 -209.395056) (xy 269.108089 -209.439093) (xy 269.071837 -209.478164) (xy 269.030166 -209.511395)
			(xy 268.984008 -209.538044) (xy 268.934394 -209.557516) (xy 268.882432 -209.569376) (xy 268.829282 -209.57336)
			(xy 268.776132 -209.569376) (xy 268.72417 -209.557516) (xy 268.674556 -209.538044) (xy 268.628398 -209.511395)
			(xy 268.586727 -209.478164) (xy 268.550475 -209.439093) (xy 268.520451 -209.395056) (xy 268.497325 -209.347035)
			(xy 268.481615 -209.296105) (xy 268.473672 -209.243401) (xy 265.084824 -209.243401) (xy 265.076881 -209.296105)
			(xy 265.061171 -209.347035) (xy 265.038045 -209.395056) (xy 265.008021 -209.439093) (xy 264.971769 -209.478164)
			(xy 264.930098 -209.511395) (xy 264.88394 -209.538044) (xy 264.834326 -209.557516) (xy 264.782364 -209.569376)
			(xy 264.729214 -209.57336) (xy 264.676064 -209.569376) (xy 264.624102 -209.557516) (xy 264.574488 -209.538044)
			(xy 264.52833 -209.511395) (xy 264.486659 -209.478164) (xy 264.450407 -209.439093) (xy 264.420383 -209.395056)
			(xy 264.397257 -209.347035) (xy 264.381547 -209.296105) (xy 264.373604 -209.243401) (xy 254.20828 -209.243401)
			(xy 254.20828 -210.093285) (xy 264.373604 -210.093285) (xy 264.373604 -210.039987) (xy 264.381547 -209.987283)
			(xy 264.397257 -209.936353) (xy 264.420383 -209.888332) (xy 264.450407 -209.844295) (xy 264.486659 -209.805224)
			(xy 264.52833 -209.771993) (xy 264.574488 -209.745344) (xy 264.624102 -209.725872) (xy 264.676064 -209.714012)
			(xy 264.729214 -209.710029) (xy 264.782364 -209.714012) (xy 264.834326 -209.725872) (xy 264.88394 -209.745344)
			(xy 264.930098 -209.771993) (xy 264.971769 -209.805224) (xy 265.008021 -209.844295) (xy 265.038045 -209.888332)
			(xy 265.061171 -209.936353) (xy 265.076881 -209.987283) (xy 265.084824 -210.039987) (xy 265.085322 -210.066636)
			(xy 265.084824 -210.093285) (xy 279.461204 -210.093285) (xy 279.461204 -210.039987) (xy 279.469147 -209.987283)
			(xy 279.484857 -209.936353) (xy 279.507983 -209.888332) (xy 279.538007 -209.844295) (xy 279.574259 -209.805224)
			(xy 279.61593 -209.771993) (xy 279.662088 -209.745344) (xy 279.711702 -209.725872) (xy 279.763664 -209.714012)
			(xy 279.816814 -209.710029) (xy 279.869964 -209.714012) (xy 279.921926 -209.725872) (xy 279.97154 -209.745344)
			(xy 280.017698 -209.771993) (xy 280.059369 -209.805224) (xy 280.095621 -209.844295) (xy 280.125645 -209.888332)
			(xy 280.148771 -209.936353) (xy 280.164481 -209.987283) (xy 280.172424 -210.039987) (xy 280.172922 -210.066636)
			(xy 280.172424 -210.093285) (xy 294.548804 -210.093285) (xy 294.548804 -210.039987) (xy 294.556747 -209.987283)
			(xy 294.572457 -209.936353) (xy 294.595583 -209.888332) (xy 294.625607 -209.844295) (xy 294.661859 -209.805224)
			(xy 294.70353 -209.771993) (xy 294.749688 -209.745344) (xy 294.799302 -209.725872) (xy 294.851264 -209.714012)
			(xy 294.904414 -209.710029) (xy 294.957564 -209.714012) (xy 295.009526 -209.725872) (xy 295.05914 -209.745344)
			(xy 295.105298 -209.771993) (xy 295.146969 -209.805224) (xy 295.183221 -209.844295) (xy 295.213245 -209.888332)
			(xy 295.236371 -209.936353) (xy 295.252081 -209.987283) (xy 295.260024 -210.039987) (xy 295.260522 -210.066636)
			(xy 295.260024 -210.093285) (xy 295.252081 -210.145989) (xy 295.236371 -210.196919) (xy 295.213245 -210.24494)
			(xy 295.183221 -210.288977) (xy 295.146969 -210.328048) (xy 295.105298 -210.361279) (xy 295.05914 -210.387928)
			(xy 295.009526 -210.4074) (xy 294.957564 -210.41926) (xy 294.904414 -210.423244) (xy 294.851264 -210.41926)
			(xy 294.799302 -210.4074) (xy 294.749688 -210.387928) (xy 294.70353 -210.361279) (xy 294.661859 -210.328048)
			(xy 294.625607 -210.288977) (xy 294.595583 -210.24494) (xy 294.572457 -210.196919) (xy 294.556747 -210.145989)
			(xy 294.548804 -210.093285) (xy 280.172424 -210.093285) (xy 280.164481 -210.145989) (xy 280.148771 -210.196919)
			(xy 280.125645 -210.24494) (xy 280.095621 -210.288977) (xy 280.059369 -210.328048) (xy 280.017698 -210.361279)
			(xy 279.97154 -210.387928) (xy 279.921926 -210.4074) (xy 279.869964 -210.41926) (xy 279.816814 -210.423244)
			(xy 279.763664 -210.41926) (xy 279.711702 -210.4074) (xy 279.662088 -210.387928) (xy 279.61593 -210.361279)
			(xy 279.574259 -210.328048) (xy 279.538007 -210.288977) (xy 279.507983 -210.24494) (xy 279.484857 -210.196919)
			(xy 279.469147 -210.145989) (xy 279.461204 -210.093285) (xy 265.084824 -210.093285) (xy 265.076881 -210.145989)
			(xy 265.061171 -210.196919) (xy 265.038045 -210.24494) (xy 265.008021 -210.288977) (xy 264.971769 -210.328048)
			(xy 264.930098 -210.361279) (xy 264.88394 -210.387928) (xy 264.834326 -210.4074) (xy 264.782364 -210.41926)
			(xy 264.729214 -210.423244) (xy 264.676064 -210.41926) (xy 264.624102 -210.4074) (xy 264.574488 -210.387928)
			(xy 264.52833 -210.361279) (xy 264.486659 -210.328048) (xy 264.450407 -210.288977) (xy 264.420383 -210.24494)
			(xy 264.397257 -210.196919) (xy 264.381547 -210.145989) (xy 264.373604 -210.093285) (xy 254.20828 -210.093285)
			(xy 254.20828 -210.943423) (xy 268.473672 -210.943423) (xy 268.473672 -210.890125) (xy 268.481615 -210.837421)
			(xy 268.497325 -210.786491) (xy 268.520451 -210.73847) (xy 268.550475 -210.694433) (xy 268.586727 -210.655362)
			(xy 268.628398 -210.622131) (xy 268.674556 -210.595482) (xy 268.72417 -210.57601) (xy 268.776132 -210.56415)
			(xy 268.829282 -210.560167) (xy 268.882432 -210.56415) (xy 268.934394 -210.57601) (xy 268.984008 -210.595482)
			(xy 269.030166 -210.622131) (xy 269.071837 -210.655362) (xy 269.108089 -210.694433) (xy 269.138113 -210.73847)
			(xy 269.161239 -210.786491) (xy 269.176949 -210.837421) (xy 269.184892 -210.890125) (xy 269.18539 -210.916774)
			(xy 269.184892 -210.943423) (xy 283.561272 -210.943423) (xy 283.561272 -210.890125) (xy 283.569215 -210.837421)
			(xy 283.584925 -210.786491) (xy 283.608051 -210.73847) (xy 283.638075 -210.694433) (xy 283.674327 -210.655362)
			(xy 283.715998 -210.622131) (xy 283.762156 -210.595482) (xy 283.81177 -210.57601) (xy 283.863732 -210.56415)
			(xy 283.916882 -210.560167) (xy 283.970032 -210.56415) (xy 284.021994 -210.57601) (xy 284.071608 -210.595482)
			(xy 284.117766 -210.622131) (xy 284.159437 -210.655362) (xy 284.195689 -210.694433) (xy 284.225713 -210.73847)
			(xy 284.248839 -210.786491) (xy 284.264549 -210.837421) (xy 284.272492 -210.890125) (xy 284.27299 -210.916774)
			(xy 284.272492 -210.943423) (xy 298.648872 -210.943423) (xy 298.648872 -210.890125) (xy 298.656815 -210.837421)
			(xy 298.672525 -210.786491) (xy 298.695651 -210.73847) (xy 298.725675 -210.694433) (xy 298.761927 -210.655362)
			(xy 298.803598 -210.622131) (xy 298.849756 -210.595482) (xy 298.89937 -210.57601) (xy 298.951332 -210.56415)
			(xy 299.004482 -210.560167) (xy 299.057632 -210.56415) (xy 299.109594 -210.57601) (xy 299.159208 -210.595482)
			(xy 299.205366 -210.622131) (xy 299.247037 -210.655362) (xy 299.283289 -210.694433) (xy 299.313313 -210.73847)
			(xy 299.336439 -210.786491) (xy 299.352149 -210.837421) (xy 299.360092 -210.890125) (xy 299.36059 -210.916774)
			(xy 299.360092 -210.943423) (xy 299.352149 -210.996127) (xy 299.336439 -211.047057) (xy 299.313313 -211.095078)
			(xy 299.283289 -211.139115) (xy 299.247037 -211.178186) (xy 299.205366 -211.211417) (xy 299.159208 -211.238066)
			(xy 299.109594 -211.257538) (xy 299.057632 -211.269398) (xy 299.004482 -211.273382) (xy 298.951332 -211.269398)
			(xy 298.89937 -211.257538) (xy 298.849756 -211.238066) (xy 298.803598 -211.211417) (xy 298.761927 -211.178186)
			(xy 298.725675 -211.139115) (xy 298.695651 -211.095078) (xy 298.672525 -211.047057) (xy 298.656815 -210.996127)
			(xy 298.648872 -210.943423) (xy 284.272492 -210.943423) (xy 284.264549 -210.996127) (xy 284.248839 -211.047057)
			(xy 284.225713 -211.095078) (xy 284.195689 -211.139115) (xy 284.159437 -211.178186) (xy 284.117766 -211.211417)
			(xy 284.071608 -211.238066) (xy 284.021994 -211.257538) (xy 283.970032 -211.269398) (xy 283.916882 -211.273382)
			(xy 283.863732 -211.269398) (xy 283.81177 -211.257538) (xy 283.762156 -211.238066) (xy 283.715998 -211.211417)
			(xy 283.674327 -211.178186) (xy 283.638075 -211.139115) (xy 283.608051 -211.095078) (xy 283.584925 -211.047057)
			(xy 283.569215 -210.996127) (xy 283.561272 -210.943423) (xy 269.184892 -210.943423) (xy 269.176949 -210.996127)
			(xy 269.161239 -211.047057) (xy 269.138113 -211.095078) (xy 269.108089 -211.139115) (xy 269.071837 -211.178186)
			(xy 269.030166 -211.211417) (xy 268.984008 -211.238066) (xy 268.934394 -211.257538) (xy 268.882432 -211.269398)
			(xy 268.829282 -211.273382) (xy 268.776132 -211.269398) (xy 268.72417 -211.257538) (xy 268.674556 -211.238066)
			(xy 268.628398 -211.211417) (xy 268.586727 -211.178186) (xy 268.550475 -211.139115) (xy 268.520451 -211.095078)
			(xy 268.497325 -211.047057) (xy 268.481615 -210.996127) (xy 268.473672 -210.943423) (xy 254.20828 -210.943423)
			(xy 254.20828 -211.793307) (xy 264.373604 -211.793307) (xy 264.373604 -211.740009) (xy 264.381547 -211.687305)
			(xy 264.397257 -211.636375) (xy 264.420383 -211.588354) (xy 264.450407 -211.544317) (xy 264.486659 -211.505246)
			(xy 264.52833 -211.472015) (xy 264.574488 -211.445366) (xy 264.624102 -211.425894) (xy 264.676064 -211.414034)
			(xy 264.729214 -211.410051) (xy 264.782364 -211.414034) (xy 264.834326 -211.425894) (xy 264.88394 -211.445366)
			(xy 264.930098 -211.472015) (xy 264.971769 -211.505246) (xy 265.008021 -211.544317) (xy 265.038045 -211.588354)
			(xy 265.061171 -211.636375) (xy 265.076881 -211.687305) (xy 265.084824 -211.740009) (xy 265.085322 -211.766658)
			(xy 265.084824 -211.793307) (xy 279.461204 -211.793307) (xy 279.461204 -211.740009) (xy 279.469147 -211.687305)
			(xy 279.484857 -211.636375) (xy 279.507983 -211.588354) (xy 279.538007 -211.544317) (xy 279.574259 -211.505246)
			(xy 279.61593 -211.472015) (xy 279.662088 -211.445366) (xy 279.711702 -211.425894) (xy 279.763664 -211.414034)
			(xy 279.816814 -211.410051) (xy 279.869964 -211.414034) (xy 279.921926 -211.425894) (xy 279.97154 -211.445366)
			(xy 280.017698 -211.472015) (xy 280.059369 -211.505246) (xy 280.095621 -211.544317) (xy 280.125645 -211.588354)
			(xy 280.148771 -211.636375) (xy 280.164481 -211.687305) (xy 280.172424 -211.740009) (xy 280.172922 -211.766658)
			(xy 280.172424 -211.793307) (xy 294.548804 -211.793307) (xy 294.548804 -211.740009) (xy 294.556747 -211.687305)
			(xy 294.572457 -211.636375) (xy 294.595583 -211.588354) (xy 294.625607 -211.544317) (xy 294.661859 -211.505246)
			(xy 294.70353 -211.472015) (xy 294.749688 -211.445366) (xy 294.799302 -211.425894) (xy 294.851264 -211.414034)
			(xy 294.904414 -211.410051) (xy 294.957564 -211.414034) (xy 295.009526 -211.425894) (xy 295.05914 -211.445366)
			(xy 295.105298 -211.472015) (xy 295.146969 -211.505246) (xy 295.183221 -211.544317) (xy 295.213245 -211.588354)
			(xy 295.236371 -211.636375) (xy 295.252081 -211.687305) (xy 295.260024 -211.740009) (xy 295.260522 -211.766658)
			(xy 295.260024 -211.793307) (xy 295.252081 -211.846011) (xy 295.236371 -211.896941) (xy 295.213245 -211.944962)
			(xy 295.183221 -211.988999) (xy 295.146969 -212.02807) (xy 295.105298 -212.061301) (xy 295.05914 -212.08795)
			(xy 295.009526 -212.107422) (xy 294.957564 -212.119282) (xy 294.904414 -212.123266) (xy 294.851264 -212.119282)
			(xy 294.799302 -212.107422) (xy 294.749688 -212.08795) (xy 294.70353 -212.061301) (xy 294.661859 -212.02807)
			(xy 294.625607 -211.988999) (xy 294.595583 -211.944962) (xy 294.572457 -211.896941) (xy 294.556747 -211.846011)
			(xy 294.548804 -211.793307) (xy 280.172424 -211.793307) (xy 280.164481 -211.846011) (xy 280.148771 -211.896941)
			(xy 280.125645 -211.944962) (xy 280.095621 -211.988999) (xy 280.059369 -212.02807) (xy 280.017698 -212.061301)
			(xy 279.97154 -212.08795) (xy 279.921926 -212.107422) (xy 279.869964 -212.119282) (xy 279.816814 -212.123266)
			(xy 279.763664 -212.119282) (xy 279.711702 -212.107422) (xy 279.662088 -212.08795) (xy 279.61593 -212.061301)
			(xy 279.574259 -212.02807) (xy 279.538007 -211.988999) (xy 279.507983 -211.944962) (xy 279.484857 -211.896941)
			(xy 279.469147 -211.846011) (xy 279.461204 -211.793307) (xy 265.084824 -211.793307) (xy 265.076881 -211.846011)
			(xy 265.061171 -211.896941) (xy 265.038045 -211.944962) (xy 265.008021 -211.988999) (xy 264.971769 -212.02807)
			(xy 264.930098 -212.061301) (xy 264.88394 -212.08795) (xy 264.834326 -212.107422) (xy 264.782364 -212.119282)
			(xy 264.729214 -212.123266) (xy 264.676064 -212.119282) (xy 264.624102 -212.107422) (xy 264.574488 -212.08795)
			(xy 264.52833 -212.061301) (xy 264.486659 -212.02807) (xy 264.450407 -211.988999) (xy 264.420383 -211.944962)
			(xy 264.397257 -211.896941) (xy 264.381547 -211.846011) (xy 264.373604 -211.793307) (xy 254.20828 -211.793307)
			(xy 254.20828 -212.643445) (xy 268.473672 -212.643445) (xy 268.473672 -212.590147) (xy 268.481615 -212.537443)
			(xy 268.497325 -212.486513) (xy 268.520451 -212.438492) (xy 268.550475 -212.394455) (xy 268.586727 -212.355384)
			(xy 268.628398 -212.322153) (xy 268.674556 -212.295504) (xy 268.72417 -212.276032) (xy 268.776132 -212.264172)
			(xy 268.829282 -212.260189) (xy 268.882432 -212.264172) (xy 268.934394 -212.276032) (xy 268.984008 -212.295504)
			(xy 269.030166 -212.322153) (xy 269.071837 -212.355384) (xy 269.108089 -212.394455) (xy 269.138113 -212.438492)
			(xy 269.161239 -212.486513) (xy 269.176949 -212.537443) (xy 269.184892 -212.590147) (xy 269.18539 -212.616796)
			(xy 269.184892 -212.643445) (xy 283.561272 -212.643445) (xy 283.561272 -212.590147) (xy 283.569215 -212.537443)
			(xy 283.584925 -212.486513) (xy 283.608051 -212.438492) (xy 283.638075 -212.394455) (xy 283.674327 -212.355384)
			(xy 283.715998 -212.322153) (xy 283.762156 -212.295504) (xy 283.81177 -212.276032) (xy 283.863732 -212.264172)
			(xy 283.916882 -212.260189) (xy 283.970032 -212.264172) (xy 284.021994 -212.276032) (xy 284.071608 -212.295504)
			(xy 284.117766 -212.322153) (xy 284.159437 -212.355384) (xy 284.195689 -212.394455) (xy 284.225713 -212.438492)
			(xy 284.248839 -212.486513) (xy 284.264549 -212.537443) (xy 284.272492 -212.590147) (xy 284.27299 -212.616796)
			(xy 284.272492 -212.643445) (xy 298.648872 -212.643445) (xy 298.648872 -212.590147) (xy 298.656815 -212.537443)
			(xy 298.672525 -212.486513) (xy 298.695651 -212.438492) (xy 298.725675 -212.394455) (xy 298.761927 -212.355384)
			(xy 298.803598 -212.322153) (xy 298.849756 -212.295504) (xy 298.89937 -212.276032) (xy 298.951332 -212.264172)
			(xy 299.004482 -212.260189) (xy 299.057632 -212.264172) (xy 299.109594 -212.276032) (xy 299.159208 -212.295504)
			(xy 299.205366 -212.322153) (xy 299.247037 -212.355384) (xy 299.283289 -212.394455) (xy 299.313313 -212.438492)
			(xy 299.336439 -212.486513) (xy 299.352149 -212.537443) (xy 299.360092 -212.590147) (xy 299.36059 -212.616796)
			(xy 299.360092 -212.643445) (xy 299.352149 -212.696149) (xy 299.336439 -212.747079) (xy 299.313313 -212.7951)
			(xy 299.283289 -212.839137) (xy 299.247037 -212.878208) (xy 299.205366 -212.911439) (xy 299.159208 -212.938088)
			(xy 299.109594 -212.95756) (xy 299.057632 -212.96942) (xy 299.004482 -212.973404) (xy 298.951332 -212.96942)
			(xy 298.89937 -212.95756) (xy 298.849756 -212.938088) (xy 298.803598 -212.911439) (xy 298.761927 -212.878208)
			(xy 298.725675 -212.839137) (xy 298.695651 -212.7951) (xy 298.672525 -212.747079) (xy 298.656815 -212.696149)
			(xy 298.648872 -212.643445) (xy 284.272492 -212.643445) (xy 284.264549 -212.696149) (xy 284.248839 -212.747079)
			(xy 284.225713 -212.7951) (xy 284.195689 -212.839137) (xy 284.159437 -212.878208) (xy 284.117766 -212.911439)
			(xy 284.071608 -212.938088) (xy 284.021994 -212.95756) (xy 283.970032 -212.96942) (xy 283.916882 -212.973404)
			(xy 283.863732 -212.96942) (xy 283.81177 -212.95756) (xy 283.762156 -212.938088) (xy 283.715998 -212.911439)
			(xy 283.674327 -212.878208) (xy 283.638075 -212.839137) (xy 283.608051 -212.7951) (xy 283.584925 -212.747079)
			(xy 283.569215 -212.696149) (xy 283.561272 -212.643445) (xy 269.184892 -212.643445) (xy 269.176949 -212.696149)
			(xy 269.161239 -212.747079) (xy 269.138113 -212.7951) (xy 269.108089 -212.839137) (xy 269.071837 -212.878208)
			(xy 269.030166 -212.911439) (xy 268.984008 -212.938088) (xy 268.934394 -212.95756) (xy 268.882432 -212.96942)
			(xy 268.829282 -212.973404) (xy 268.776132 -212.96942) (xy 268.72417 -212.95756) (xy 268.674556 -212.938088)
			(xy 268.628398 -212.911439) (xy 268.586727 -212.878208) (xy 268.550475 -212.839137) (xy 268.520451 -212.7951)
			(xy 268.497325 -212.747079) (xy 268.481615 -212.696149) (xy 268.473672 -212.643445) (xy 254.20828 -212.643445)
			(xy 254.20828 -213.493329) (xy 264.373604 -213.493329) (xy 264.373604 -213.440031) (xy 264.381547 -213.387327)
			(xy 264.397257 -213.336397) (xy 264.420383 -213.288376) (xy 264.450407 -213.244339) (xy 264.486659 -213.205268)
			(xy 264.52833 -213.172037) (xy 264.574488 -213.145388) (xy 264.624102 -213.125916) (xy 264.676064 -213.114056)
			(xy 264.729214 -213.110073) (xy 264.782364 -213.114056) (xy 264.834326 -213.125916) (xy 264.88394 -213.145388)
			(xy 264.930098 -213.172037) (xy 264.971769 -213.205268) (xy 265.008021 -213.244339) (xy 265.038045 -213.288376)
			(xy 265.061171 -213.336397) (xy 265.076881 -213.387327) (xy 265.084824 -213.440031) (xy 265.085322 -213.46668)
			(xy 265.084824 -213.493329) (xy 279.461204 -213.493329) (xy 279.461204 -213.440031) (xy 279.469147 -213.387327)
			(xy 279.484857 -213.336397) (xy 279.507983 -213.288376) (xy 279.538007 -213.244339) (xy 279.574259 -213.205268)
			(xy 279.61593 -213.172037) (xy 279.662088 -213.145388) (xy 279.711702 -213.125916) (xy 279.763664 -213.114056)
			(xy 279.816814 -213.110073) (xy 279.869964 -213.114056) (xy 279.921926 -213.125916) (xy 279.97154 -213.145388)
			(xy 280.017698 -213.172037) (xy 280.059369 -213.205268) (xy 280.095621 -213.244339) (xy 280.125645 -213.288376)
			(xy 280.148771 -213.336397) (xy 280.164481 -213.387327) (xy 280.172424 -213.440031) (xy 280.172922 -213.46668)
			(xy 280.172424 -213.493329) (xy 294.548804 -213.493329) (xy 294.548804 -213.440031) (xy 294.556747 -213.387327)
			(xy 294.572457 -213.336397) (xy 294.595583 -213.288376) (xy 294.625607 -213.244339) (xy 294.661859 -213.205268)
			(xy 294.70353 -213.172037) (xy 294.749688 -213.145388) (xy 294.799302 -213.125916) (xy 294.851264 -213.114056)
			(xy 294.904414 -213.110073) (xy 294.957564 -213.114056) (xy 295.009526 -213.125916) (xy 295.05914 -213.145388)
			(xy 295.105298 -213.172037) (xy 295.146969 -213.205268) (xy 295.183221 -213.244339) (xy 295.213245 -213.288376)
			(xy 295.236371 -213.336397) (xy 295.252081 -213.387327) (xy 295.260024 -213.440031) (xy 295.260522 -213.46668)
			(xy 295.260024 -213.493329) (xy 295.252081 -213.546033) (xy 295.236371 -213.596963) (xy 295.213245 -213.644984)
			(xy 295.183221 -213.689021) (xy 295.146969 -213.728092) (xy 295.105298 -213.761323) (xy 295.05914 -213.787972)
			(xy 295.009526 -213.807444) (xy 294.957564 -213.819304) (xy 294.904414 -213.823288) (xy 294.851264 -213.819304)
			(xy 294.799302 -213.807444) (xy 294.749688 -213.787972) (xy 294.70353 -213.761323) (xy 294.661859 -213.728092)
			(xy 294.625607 -213.689021) (xy 294.595583 -213.644984) (xy 294.572457 -213.596963) (xy 294.556747 -213.546033)
			(xy 294.548804 -213.493329) (xy 280.172424 -213.493329) (xy 280.164481 -213.546033) (xy 280.148771 -213.596963)
			(xy 280.125645 -213.644984) (xy 280.095621 -213.689021) (xy 280.059369 -213.728092) (xy 280.017698 -213.761323)
			(xy 279.97154 -213.787972) (xy 279.921926 -213.807444) (xy 279.869964 -213.819304) (xy 279.816814 -213.823288)
			(xy 279.763664 -213.819304) (xy 279.711702 -213.807444) (xy 279.662088 -213.787972) (xy 279.61593 -213.761323)
			(xy 279.574259 -213.728092) (xy 279.538007 -213.689021) (xy 279.507983 -213.644984) (xy 279.484857 -213.596963)
			(xy 279.469147 -213.546033) (xy 279.461204 -213.493329) (xy 265.084824 -213.493329) (xy 265.076881 -213.546033)
			(xy 265.061171 -213.596963) (xy 265.038045 -213.644984) (xy 265.008021 -213.689021) (xy 264.971769 -213.728092)
			(xy 264.930098 -213.761323) (xy 264.88394 -213.787972) (xy 264.834326 -213.807444) (xy 264.782364 -213.819304)
			(xy 264.729214 -213.823288) (xy 264.676064 -213.819304) (xy 264.624102 -213.807444) (xy 264.574488 -213.787972)
			(xy 264.52833 -213.761323) (xy 264.486659 -213.728092) (xy 264.450407 -213.689021) (xy 264.420383 -213.644984)
			(xy 264.397257 -213.596963) (xy 264.381547 -213.546033) (xy 264.373604 -213.493329) (xy 254.20828 -213.493329)
			(xy 254.20828 -214.343213) (xy 268.473672 -214.343213) (xy 268.473672 -214.289915) (xy 268.481615 -214.237211)
			(xy 268.497325 -214.186281) (xy 268.520451 -214.13826) (xy 268.550475 -214.094223) (xy 268.586727 -214.055152)
			(xy 268.628398 -214.021921) (xy 268.674556 -213.995272) (xy 268.72417 -213.9758) (xy 268.776132 -213.96394)
			(xy 268.829282 -213.959957) (xy 268.882432 -213.96394) (xy 268.934394 -213.9758) (xy 268.984008 -213.995272)
			(xy 269.030166 -214.021921) (xy 269.071837 -214.055152) (xy 269.108089 -214.094223) (xy 269.138113 -214.13826)
			(xy 269.161239 -214.186281) (xy 269.176949 -214.237211) (xy 269.184892 -214.289915) (xy 269.18539 -214.316564)
			(xy 269.184892 -214.343213) (xy 283.561272 -214.343213) (xy 283.561272 -214.289915) (xy 283.569215 -214.237211)
			(xy 283.584925 -214.186281) (xy 283.608051 -214.13826) (xy 283.638075 -214.094223) (xy 283.674327 -214.055152)
			(xy 283.715998 -214.021921) (xy 283.762156 -213.995272) (xy 283.81177 -213.9758) (xy 283.863732 -213.96394)
			(xy 283.916882 -213.959957) (xy 283.970032 -213.96394) (xy 284.021994 -213.9758) (xy 284.071608 -213.995272)
			(xy 284.117766 -214.021921) (xy 284.159437 -214.055152) (xy 284.195689 -214.094223) (xy 284.225713 -214.13826)
			(xy 284.248839 -214.186281) (xy 284.264549 -214.237211) (xy 284.272492 -214.289915) (xy 284.27299 -214.316564)
			(xy 284.272492 -214.343213) (xy 298.648872 -214.343213) (xy 298.648872 -214.289915) (xy 298.656815 -214.237211)
			(xy 298.672525 -214.186281) (xy 298.695651 -214.13826) (xy 298.725675 -214.094223) (xy 298.761927 -214.055152)
			(xy 298.803598 -214.021921) (xy 298.849756 -213.995272) (xy 298.89937 -213.9758) (xy 298.951332 -213.96394)
			(xy 299.004482 -213.959957) (xy 299.057632 -213.96394) (xy 299.109594 -213.9758) (xy 299.159208 -213.995272)
			(xy 299.205366 -214.021921) (xy 299.247037 -214.055152) (xy 299.283289 -214.094223) (xy 299.313313 -214.13826)
			(xy 299.336439 -214.186281) (xy 299.352149 -214.237211) (xy 299.360092 -214.289915) (xy 299.36059 -214.316564)
			(xy 299.360092 -214.343213) (xy 299.352149 -214.395917) (xy 299.336439 -214.446847) (xy 299.313313 -214.494868)
			(xy 299.283289 -214.538905) (xy 299.247037 -214.577976) (xy 299.205366 -214.611207) (xy 299.159208 -214.637856)
			(xy 299.109594 -214.657328) (xy 299.057632 -214.669188) (xy 299.004482 -214.673172) (xy 298.951332 -214.669188)
			(xy 298.89937 -214.657328) (xy 298.849756 -214.637856) (xy 298.803598 -214.611207) (xy 298.761927 -214.577976)
			(xy 298.725675 -214.538905) (xy 298.695651 -214.494868) (xy 298.672525 -214.446847) (xy 298.656815 -214.395917)
			(xy 298.648872 -214.343213) (xy 284.272492 -214.343213) (xy 284.264549 -214.395917) (xy 284.248839 -214.446847)
			(xy 284.225713 -214.494868) (xy 284.195689 -214.538905) (xy 284.159437 -214.577976) (xy 284.117766 -214.611207)
			(xy 284.071608 -214.637856) (xy 284.021994 -214.657328) (xy 283.970032 -214.669188) (xy 283.916882 -214.673172)
			(xy 283.863732 -214.669188) (xy 283.81177 -214.657328) (xy 283.762156 -214.637856) (xy 283.715998 -214.611207)
			(xy 283.674327 -214.577976) (xy 283.638075 -214.538905) (xy 283.608051 -214.494868) (xy 283.584925 -214.446847)
			(xy 283.569215 -214.395917) (xy 283.561272 -214.343213) (xy 269.184892 -214.343213) (xy 269.176949 -214.395917)
			(xy 269.161239 -214.446847) (xy 269.138113 -214.494868) (xy 269.108089 -214.538905) (xy 269.071837 -214.577976)
			(xy 269.030166 -214.611207) (xy 268.984008 -214.637856) (xy 268.934394 -214.657328) (xy 268.882432 -214.669188)
			(xy 268.829282 -214.673172) (xy 268.776132 -214.669188) (xy 268.72417 -214.657328) (xy 268.674556 -214.637856)
			(xy 268.628398 -214.611207) (xy 268.586727 -214.577976) (xy 268.550475 -214.538905) (xy 268.520451 -214.494868)
			(xy 268.497325 -214.446847) (xy 268.481615 -214.395917) (xy 268.473672 -214.343213) (xy 254.20828 -214.343213)
			(xy 254.20828 -215.193351) (xy 264.373604 -215.193351) (xy 264.373604 -215.140053) (xy 264.381547 -215.087349)
			(xy 264.397257 -215.036419) (xy 264.420383 -214.988398) (xy 264.450407 -214.944361) (xy 264.486659 -214.90529)
			(xy 264.52833 -214.872059) (xy 264.574488 -214.84541) (xy 264.624102 -214.825938) (xy 264.676064 -214.814078)
			(xy 264.729214 -214.810095) (xy 264.782364 -214.814078) (xy 264.834326 -214.825938) (xy 264.88394 -214.84541)
			(xy 264.930098 -214.872059) (xy 264.971769 -214.90529) (xy 265.008021 -214.944361) (xy 265.038045 -214.988398)
			(xy 265.061171 -215.036419) (xy 265.076881 -215.087349) (xy 265.084824 -215.140053) (xy 265.085322 -215.166702)
			(xy 265.084824 -215.193351) (xy 279.461204 -215.193351) (xy 279.461204 -215.140053) (xy 279.469147 -215.087349)
			(xy 279.484857 -215.036419) (xy 279.507983 -214.988398) (xy 279.538007 -214.944361) (xy 279.574259 -214.90529)
			(xy 279.61593 -214.872059) (xy 279.662088 -214.84541) (xy 279.711702 -214.825938) (xy 279.763664 -214.814078)
			(xy 279.816814 -214.810095) (xy 279.869964 -214.814078) (xy 279.921926 -214.825938) (xy 279.97154 -214.84541)
			(xy 280.017698 -214.872059) (xy 280.059369 -214.90529) (xy 280.095621 -214.944361) (xy 280.125645 -214.988398)
			(xy 280.148771 -215.036419) (xy 280.164481 -215.087349) (xy 280.172424 -215.140053) (xy 280.172922 -215.166702)
			(xy 280.172424 -215.193351) (xy 294.548804 -215.193351) (xy 294.548804 -215.140053) (xy 294.556747 -215.087349)
			(xy 294.572457 -215.036419) (xy 294.595583 -214.988398) (xy 294.625607 -214.944361) (xy 294.661859 -214.90529)
			(xy 294.70353 -214.872059) (xy 294.749688 -214.84541) (xy 294.799302 -214.825938) (xy 294.851264 -214.814078)
			(xy 294.904414 -214.810095) (xy 294.957564 -214.814078) (xy 295.009526 -214.825938) (xy 295.05914 -214.84541)
			(xy 295.105298 -214.872059) (xy 295.146969 -214.90529) (xy 295.183221 -214.944361) (xy 295.213245 -214.988398)
			(xy 295.236371 -215.036419) (xy 295.252081 -215.087349) (xy 295.260024 -215.140053) (xy 295.260522 -215.166702)
			(xy 295.260024 -215.193351) (xy 295.252081 -215.246055) (xy 295.236371 -215.296985) (xy 295.213245 -215.345006)
			(xy 295.183221 -215.389043) (xy 295.146969 -215.428114) (xy 295.105298 -215.461345) (xy 295.05914 -215.487994)
			(xy 295.009526 -215.507466) (xy 294.957564 -215.519326) (xy 294.904414 -215.52331) (xy 294.851264 -215.519326)
			(xy 294.799302 -215.507466) (xy 294.749688 -215.487994) (xy 294.70353 -215.461345) (xy 294.661859 -215.428114)
			(xy 294.625607 -215.389043) (xy 294.595583 -215.345006) (xy 294.572457 -215.296985) (xy 294.556747 -215.246055)
			(xy 294.548804 -215.193351) (xy 280.172424 -215.193351) (xy 280.164481 -215.246055) (xy 280.148771 -215.296985)
			(xy 280.125645 -215.345006) (xy 280.095621 -215.389043) (xy 280.059369 -215.428114) (xy 280.017698 -215.461345)
			(xy 279.97154 -215.487994) (xy 279.921926 -215.507466) (xy 279.869964 -215.519326) (xy 279.816814 -215.52331)
			(xy 279.763664 -215.519326) (xy 279.711702 -215.507466) (xy 279.662088 -215.487994) (xy 279.61593 -215.461345)
			(xy 279.574259 -215.428114) (xy 279.538007 -215.389043) (xy 279.507983 -215.345006) (xy 279.484857 -215.296985)
			(xy 279.469147 -215.246055) (xy 279.461204 -215.193351) (xy 265.084824 -215.193351) (xy 265.076881 -215.246055)
			(xy 265.061171 -215.296985) (xy 265.038045 -215.345006) (xy 265.008021 -215.389043) (xy 264.971769 -215.428114)
			(xy 264.930098 -215.461345) (xy 264.88394 -215.487994) (xy 264.834326 -215.507466) (xy 264.782364 -215.519326)
			(xy 264.729214 -215.52331) (xy 264.676064 -215.519326) (xy 264.624102 -215.507466) (xy 264.574488 -215.487994)
			(xy 264.52833 -215.461345) (xy 264.486659 -215.428114) (xy 264.450407 -215.389043) (xy 264.420383 -215.345006)
			(xy 264.397257 -215.296985) (xy 264.381547 -215.246055) (xy 264.373604 -215.193351) (xy 254.20828 -215.193351)
			(xy 254.20828 -216.043235) (xy 268.473672 -216.043235) (xy 268.473672 -215.989937) (xy 268.481615 -215.937233)
			(xy 268.497325 -215.886303) (xy 268.520451 -215.838282) (xy 268.550475 -215.794245) (xy 268.586727 -215.755174)
			(xy 268.628398 -215.721943) (xy 268.674556 -215.695294) (xy 268.72417 -215.675822) (xy 268.776132 -215.663962)
			(xy 268.829282 -215.659979) (xy 268.882432 -215.663962) (xy 268.934394 -215.675822) (xy 268.984008 -215.695294)
			(xy 269.030166 -215.721943) (xy 269.071837 -215.755174) (xy 269.108089 -215.794245) (xy 269.138113 -215.838282)
			(xy 269.161239 -215.886303) (xy 269.176949 -215.937233) (xy 269.184892 -215.989937) (xy 269.18539 -216.016586)
			(xy 269.184892 -216.043235) (xy 283.561272 -216.043235) (xy 283.561272 -215.989937) (xy 283.569215 -215.937233)
			(xy 283.584925 -215.886303) (xy 283.608051 -215.838282) (xy 283.638075 -215.794245) (xy 283.674327 -215.755174)
			(xy 283.715998 -215.721943) (xy 283.762156 -215.695294) (xy 283.81177 -215.675822) (xy 283.863732 -215.663962)
			(xy 283.916882 -215.659979) (xy 283.970032 -215.663962) (xy 284.021994 -215.675822) (xy 284.071608 -215.695294)
			(xy 284.117766 -215.721943) (xy 284.159437 -215.755174) (xy 284.195689 -215.794245) (xy 284.225713 -215.838282)
			(xy 284.248839 -215.886303) (xy 284.264549 -215.937233) (xy 284.272492 -215.989937) (xy 284.27299 -216.016586)
			(xy 284.272492 -216.043235) (xy 298.648872 -216.043235) (xy 298.648872 -215.989937) (xy 298.656815 -215.937233)
			(xy 298.672525 -215.886303) (xy 298.695651 -215.838282) (xy 298.725675 -215.794245) (xy 298.761927 -215.755174)
			(xy 298.803598 -215.721943) (xy 298.849756 -215.695294) (xy 298.89937 -215.675822) (xy 298.951332 -215.663962)
			(xy 299.004482 -215.659979) (xy 299.057632 -215.663962) (xy 299.109594 -215.675822) (xy 299.159208 -215.695294)
			(xy 299.205366 -215.721943) (xy 299.247037 -215.755174) (xy 299.283289 -215.794245) (xy 299.313313 -215.838282)
			(xy 299.336439 -215.886303) (xy 299.352149 -215.937233) (xy 299.360092 -215.989937) (xy 299.36059 -216.016586)
			(xy 299.360092 -216.043235) (xy 299.352149 -216.095939) (xy 299.336439 -216.146869) (xy 299.313313 -216.19489)
			(xy 299.283289 -216.238927) (xy 299.247037 -216.277998) (xy 299.205366 -216.311229) (xy 299.159208 -216.337878)
			(xy 299.109594 -216.35735) (xy 299.057632 -216.36921) (xy 299.004482 -216.373194) (xy 298.951332 -216.36921)
			(xy 298.89937 -216.35735) (xy 298.849756 -216.337878) (xy 298.803598 -216.311229) (xy 298.761927 -216.277998)
			(xy 298.725675 -216.238927) (xy 298.695651 -216.19489) (xy 298.672525 -216.146869) (xy 298.656815 -216.095939)
			(xy 298.648872 -216.043235) (xy 284.272492 -216.043235) (xy 284.264549 -216.095939) (xy 284.248839 -216.146869)
			(xy 284.225713 -216.19489) (xy 284.195689 -216.238927) (xy 284.159437 -216.277998) (xy 284.117766 -216.311229)
			(xy 284.071608 -216.337878) (xy 284.021994 -216.35735) (xy 283.970032 -216.36921) (xy 283.916882 -216.373194)
			(xy 283.863732 -216.36921) (xy 283.81177 -216.35735) (xy 283.762156 -216.337878) (xy 283.715998 -216.311229)
			(xy 283.674327 -216.277998) (xy 283.638075 -216.238927) (xy 283.608051 -216.19489) (xy 283.584925 -216.146869)
			(xy 283.569215 -216.095939) (xy 283.561272 -216.043235) (xy 269.184892 -216.043235) (xy 269.176949 -216.095939)
			(xy 269.161239 -216.146869) (xy 269.138113 -216.19489) (xy 269.108089 -216.238927) (xy 269.071837 -216.277998)
			(xy 269.030166 -216.311229) (xy 268.984008 -216.337878) (xy 268.934394 -216.35735) (xy 268.882432 -216.36921)
			(xy 268.829282 -216.373194) (xy 268.776132 -216.36921) (xy 268.72417 -216.35735) (xy 268.674556 -216.337878)
			(xy 268.628398 -216.311229) (xy 268.586727 -216.277998) (xy 268.550475 -216.238927) (xy 268.520451 -216.19489)
			(xy 268.497325 -216.146869) (xy 268.481615 -216.095939) (xy 268.473672 -216.043235) (xy 254.20828 -216.043235)
			(xy 254.20828 -216.893373) (xy 264.373604 -216.893373) (xy 264.373604 -216.840075) (xy 264.381547 -216.787371)
			(xy 264.397257 -216.736441) (xy 264.420383 -216.68842) (xy 264.450407 -216.644383) (xy 264.486659 -216.605312)
			(xy 264.52833 -216.572081) (xy 264.574488 -216.545432) (xy 264.624102 -216.52596) (xy 264.676064 -216.5141)
			(xy 264.729214 -216.510117) (xy 264.782364 -216.5141) (xy 264.834326 -216.52596) (xy 264.88394 -216.545432)
			(xy 264.930098 -216.572081) (xy 264.971769 -216.605312) (xy 265.008021 -216.644383) (xy 265.038045 -216.68842)
			(xy 265.061171 -216.736441) (xy 265.076881 -216.787371) (xy 265.084824 -216.840075) (xy 265.085322 -216.866724)
			(xy 265.084824 -216.893373) (xy 279.461204 -216.893373) (xy 279.461204 -216.840075) (xy 279.469147 -216.787371)
			(xy 279.484857 -216.736441) (xy 279.507983 -216.68842) (xy 279.538007 -216.644383) (xy 279.574259 -216.605312)
			(xy 279.61593 -216.572081) (xy 279.662088 -216.545432) (xy 279.711702 -216.52596) (xy 279.763664 -216.5141)
			(xy 279.816814 -216.510117) (xy 279.869964 -216.5141) (xy 279.921926 -216.52596) (xy 279.97154 -216.545432)
			(xy 280.017698 -216.572081) (xy 280.059369 -216.605312) (xy 280.095621 -216.644383) (xy 280.125645 -216.68842)
			(xy 280.148771 -216.736441) (xy 280.164481 -216.787371) (xy 280.172424 -216.840075) (xy 280.172922 -216.866724)
			(xy 280.172424 -216.893373) (xy 294.548804 -216.893373) (xy 294.548804 -216.840075) (xy 294.556747 -216.787371)
			(xy 294.572457 -216.736441) (xy 294.595583 -216.68842) (xy 294.625607 -216.644383) (xy 294.661859 -216.605312)
			(xy 294.70353 -216.572081) (xy 294.749688 -216.545432) (xy 294.799302 -216.52596) (xy 294.851264 -216.5141)
			(xy 294.904414 -216.510117) (xy 294.957564 -216.5141) (xy 295.009526 -216.52596) (xy 295.05914 -216.545432)
			(xy 295.105298 -216.572081) (xy 295.146969 -216.605312) (xy 295.183221 -216.644383) (xy 295.213245 -216.68842)
			(xy 295.236371 -216.736441) (xy 295.252081 -216.787371) (xy 295.260024 -216.840075) (xy 295.260522 -216.866724)
			(xy 295.260024 -216.893373) (xy 295.252081 -216.946077) (xy 295.236371 -216.997007) (xy 295.213245 -217.045028)
			(xy 295.183221 -217.089065) (xy 295.146969 -217.128136) (xy 295.105298 -217.161367) (xy 295.05914 -217.188016)
			(xy 295.009526 -217.207488) (xy 294.957564 -217.219348) (xy 294.904414 -217.223332) (xy 294.851264 -217.219348)
			(xy 294.799302 -217.207488) (xy 294.749688 -217.188016) (xy 294.70353 -217.161367) (xy 294.661859 -217.128136)
			(xy 294.625607 -217.089065) (xy 294.595583 -217.045028) (xy 294.572457 -216.997007) (xy 294.556747 -216.946077)
			(xy 294.548804 -216.893373) (xy 280.172424 -216.893373) (xy 280.164481 -216.946077) (xy 280.148771 -216.997007)
			(xy 280.125645 -217.045028) (xy 280.095621 -217.089065) (xy 280.059369 -217.128136) (xy 280.017698 -217.161367)
			(xy 279.97154 -217.188016) (xy 279.921926 -217.207488) (xy 279.869964 -217.219348) (xy 279.816814 -217.223332)
			(xy 279.763664 -217.219348) (xy 279.711702 -217.207488) (xy 279.662088 -217.188016) (xy 279.61593 -217.161367)
			(xy 279.574259 -217.128136) (xy 279.538007 -217.089065) (xy 279.507983 -217.045028) (xy 279.484857 -216.997007)
			(xy 279.469147 -216.946077) (xy 279.461204 -216.893373) (xy 265.084824 -216.893373) (xy 265.076881 -216.946077)
			(xy 265.061171 -216.997007) (xy 265.038045 -217.045028) (xy 265.008021 -217.089065) (xy 264.971769 -217.128136)
			(xy 264.930098 -217.161367) (xy 264.88394 -217.188016) (xy 264.834326 -217.207488) (xy 264.782364 -217.219348)
			(xy 264.729214 -217.223332) (xy 264.676064 -217.219348) (xy 264.624102 -217.207488) (xy 264.574488 -217.188016)
			(xy 264.52833 -217.161367) (xy 264.486659 -217.128136) (xy 264.450407 -217.089065) (xy 264.420383 -217.045028)
			(xy 264.397257 -216.997007) (xy 264.381547 -216.946077) (xy 264.373604 -216.893373) (xy 254.20828 -216.893373)
			(xy 254.20828 -217.743257) (xy 268.473672 -217.743257) (xy 268.473672 -217.689959) (xy 268.481615 -217.637255)
			(xy 268.497325 -217.586325) (xy 268.520451 -217.538304) (xy 268.550475 -217.494267) (xy 268.586727 -217.455196)
			(xy 268.628398 -217.421965) (xy 268.674556 -217.395316) (xy 268.72417 -217.375844) (xy 268.776132 -217.363984)
			(xy 268.829282 -217.360001) (xy 268.882432 -217.363984) (xy 268.934394 -217.375844) (xy 268.984008 -217.395316)
			(xy 269.030166 -217.421965) (xy 269.071837 -217.455196) (xy 269.108089 -217.494267) (xy 269.138113 -217.538304)
			(xy 269.161239 -217.586325) (xy 269.176949 -217.637255) (xy 269.184892 -217.689959) (xy 269.18539 -217.716608)
			(xy 269.184892 -217.743257) (xy 283.561272 -217.743257) (xy 283.561272 -217.689959) (xy 283.569215 -217.637255)
			(xy 283.584925 -217.586325) (xy 283.608051 -217.538304) (xy 283.638075 -217.494267) (xy 283.674327 -217.455196)
			(xy 283.715998 -217.421965) (xy 283.762156 -217.395316) (xy 283.81177 -217.375844) (xy 283.863732 -217.363984)
			(xy 283.916882 -217.360001) (xy 283.970032 -217.363984) (xy 284.021994 -217.375844) (xy 284.071608 -217.395316)
			(xy 284.117766 -217.421965) (xy 284.159437 -217.455196) (xy 284.195689 -217.494267) (xy 284.225713 -217.538304)
			(xy 284.248839 -217.586325) (xy 284.264549 -217.637255) (xy 284.272492 -217.689959) (xy 284.27299 -217.716608)
			(xy 284.272492 -217.743257) (xy 298.648872 -217.743257) (xy 298.648872 -217.689959) (xy 298.656815 -217.637255)
			(xy 298.672525 -217.586325) (xy 298.695651 -217.538304) (xy 298.725675 -217.494267) (xy 298.761927 -217.455196)
			(xy 298.803598 -217.421965) (xy 298.849756 -217.395316) (xy 298.89937 -217.375844) (xy 298.951332 -217.363984)
			(xy 299.004482 -217.360001) (xy 299.057632 -217.363984) (xy 299.109594 -217.375844) (xy 299.159208 -217.395316)
			(xy 299.205366 -217.421965) (xy 299.247037 -217.455196) (xy 299.283289 -217.494267) (xy 299.313313 -217.538304)
			(xy 299.336439 -217.586325) (xy 299.352149 -217.637255) (xy 299.360092 -217.689959) (xy 299.36059 -217.716608)
			(xy 299.360092 -217.743257) (xy 299.352149 -217.795961) (xy 299.336439 -217.846891) (xy 299.313313 -217.894912)
			(xy 299.283289 -217.938949) (xy 299.247037 -217.97802) (xy 299.205366 -218.011251) (xy 299.159208 -218.0379)
			(xy 299.109594 -218.057372) (xy 299.057632 -218.069232) (xy 299.004482 -218.073216) (xy 298.951332 -218.069232)
			(xy 298.89937 -218.057372) (xy 298.849756 -218.0379) (xy 298.803598 -218.011251) (xy 298.761927 -217.97802)
			(xy 298.725675 -217.938949) (xy 298.695651 -217.894912) (xy 298.672525 -217.846891) (xy 298.656815 -217.795961)
			(xy 298.648872 -217.743257) (xy 284.272492 -217.743257) (xy 284.264549 -217.795961) (xy 284.248839 -217.846891)
			(xy 284.225713 -217.894912) (xy 284.195689 -217.938949) (xy 284.159437 -217.97802) (xy 284.117766 -218.011251)
			(xy 284.071608 -218.0379) (xy 284.021994 -218.057372) (xy 283.970032 -218.069232) (xy 283.916882 -218.073216)
			(xy 283.863732 -218.069232) (xy 283.81177 -218.057372) (xy 283.762156 -218.0379) (xy 283.715998 -218.011251)
			(xy 283.674327 -217.97802) (xy 283.638075 -217.938949) (xy 283.608051 -217.894912) (xy 283.584925 -217.846891)
			(xy 283.569215 -217.795961) (xy 283.561272 -217.743257) (xy 269.184892 -217.743257) (xy 269.176949 -217.795961)
			(xy 269.161239 -217.846891) (xy 269.138113 -217.894912) (xy 269.108089 -217.938949) (xy 269.071837 -217.97802)
			(xy 269.030166 -218.011251) (xy 268.984008 -218.0379) (xy 268.934394 -218.057372) (xy 268.882432 -218.069232)
			(xy 268.829282 -218.073216) (xy 268.776132 -218.069232) (xy 268.72417 -218.057372) (xy 268.674556 -218.0379)
			(xy 268.628398 -218.011251) (xy 268.586727 -217.97802) (xy 268.550475 -217.938949) (xy 268.520451 -217.894912)
			(xy 268.497325 -217.846891) (xy 268.481615 -217.795961) (xy 268.473672 -217.743257) (xy 254.20828 -217.743257)
			(xy 254.20828 -218.593395) (xy 264.373604 -218.593395) (xy 264.373604 -218.540097) (xy 264.381547 -218.487393)
			(xy 264.397257 -218.436463) (xy 264.420383 -218.388442) (xy 264.450407 -218.344405) (xy 264.486659 -218.305334)
			(xy 264.52833 -218.272103) (xy 264.574488 -218.245454) (xy 264.624102 -218.225982) (xy 264.676064 -218.214122)
			(xy 264.729214 -218.210139) (xy 264.782364 -218.214122) (xy 264.834326 -218.225982) (xy 264.88394 -218.245454)
			(xy 264.930098 -218.272103) (xy 264.971769 -218.305334) (xy 265.008021 -218.344405) (xy 265.038045 -218.388442)
			(xy 265.061171 -218.436463) (xy 265.076881 -218.487393) (xy 265.084824 -218.540097) (xy 265.085322 -218.566746)
			(xy 265.084824 -218.593395) (xy 268.473672 -218.593395) (xy 268.473672 -218.540097) (xy 268.481615 -218.487393)
			(xy 268.497325 -218.436463) (xy 268.520451 -218.388442) (xy 268.550475 -218.344405) (xy 268.586727 -218.305334)
			(xy 268.628398 -218.272103) (xy 268.674556 -218.245454) (xy 268.72417 -218.225982) (xy 268.776132 -218.214122)
			(xy 268.829282 -218.210139) (xy 268.882432 -218.214122) (xy 268.934394 -218.225982) (xy 268.984008 -218.245454)
			(xy 269.030166 -218.272103) (xy 269.071837 -218.305334) (xy 269.108089 -218.344405) (xy 269.138113 -218.388442)
			(xy 269.161239 -218.436463) (xy 269.176949 -218.487393) (xy 269.184892 -218.540097) (xy 269.18539 -218.566746)
			(xy 269.184892 -218.593395) (xy 279.461204 -218.593395) (xy 279.461204 -218.540097) (xy 279.469147 -218.487393)
			(xy 279.484857 -218.436463) (xy 279.507983 -218.388442) (xy 279.538007 -218.344405) (xy 279.574259 -218.305334)
			(xy 279.61593 -218.272103) (xy 279.662088 -218.245454) (xy 279.711702 -218.225982) (xy 279.763664 -218.214122)
			(xy 279.816814 -218.210139) (xy 279.869964 -218.214122) (xy 279.921926 -218.225982) (xy 279.97154 -218.245454)
			(xy 280.017698 -218.272103) (xy 280.059369 -218.305334) (xy 280.095621 -218.344405) (xy 280.125645 -218.388442)
			(xy 280.148771 -218.436463) (xy 280.164481 -218.487393) (xy 280.172424 -218.540097) (xy 280.172922 -218.566746)
			(xy 280.172424 -218.593395) (xy 283.561272 -218.593395) (xy 283.561272 -218.540097) (xy 283.569215 -218.487393)
			(xy 283.584925 -218.436463) (xy 283.608051 -218.388442) (xy 283.638075 -218.344405) (xy 283.674327 -218.305334)
			(xy 283.715998 -218.272103) (xy 283.762156 -218.245454) (xy 283.81177 -218.225982) (xy 283.863732 -218.214122)
			(xy 283.916882 -218.210139) (xy 283.970032 -218.214122) (xy 284.021994 -218.225982) (xy 284.071608 -218.245454)
			(xy 284.117766 -218.272103) (xy 284.159437 -218.305334) (xy 284.195689 -218.344405) (xy 284.225713 -218.388442)
			(xy 284.248839 -218.436463) (xy 284.264549 -218.487393) (xy 284.272492 -218.540097) (xy 284.27299 -218.566746)
			(xy 284.272492 -218.593395) (xy 294.548804 -218.593395) (xy 294.548804 -218.540097) (xy 294.556747 -218.487393)
			(xy 294.572457 -218.436463) (xy 294.595583 -218.388442) (xy 294.625607 -218.344405) (xy 294.661859 -218.305334)
			(xy 294.70353 -218.272103) (xy 294.749688 -218.245454) (xy 294.799302 -218.225982) (xy 294.851264 -218.214122)
			(xy 294.904414 -218.210139) (xy 294.957564 -218.214122) (xy 295.009526 -218.225982) (xy 295.05914 -218.245454)
			(xy 295.105298 -218.272103) (xy 295.146969 -218.305334) (xy 295.183221 -218.344405) (xy 295.213245 -218.388442)
			(xy 295.236371 -218.436463) (xy 295.252081 -218.487393) (xy 295.260024 -218.540097) (xy 295.260522 -218.566746)
			(xy 295.260024 -218.593395) (xy 298.648872 -218.593395) (xy 298.648872 -218.540097) (xy 298.656815 -218.487393)
			(xy 298.672525 -218.436463) (xy 298.695651 -218.388442) (xy 298.725675 -218.344405) (xy 298.761927 -218.305334)
			(xy 298.803598 -218.272103) (xy 298.849756 -218.245454) (xy 298.89937 -218.225982) (xy 298.951332 -218.214122)
			(xy 299.004482 -218.210139) (xy 299.057632 -218.214122) (xy 299.109594 -218.225982) (xy 299.159208 -218.245454)
			(xy 299.205366 -218.272103) (xy 299.247037 -218.305334) (xy 299.283289 -218.344405) (xy 299.313313 -218.388442)
			(xy 299.336439 -218.436463) (xy 299.352149 -218.487393) (xy 299.360092 -218.540097) (xy 299.36059 -218.566746)
			(xy 299.360092 -218.593395) (xy 299.352149 -218.646099) (xy 299.336439 -218.697029) (xy 299.313313 -218.74505)
			(xy 299.283289 -218.789087) (xy 299.247037 -218.828158) (xy 299.205366 -218.861389) (xy 299.159208 -218.888038)
			(xy 299.109594 -218.90751) (xy 299.057632 -218.91937) (xy 299.004482 -218.923354) (xy 298.951332 -218.91937)
			(xy 298.89937 -218.90751) (xy 298.849756 -218.888038) (xy 298.803598 -218.861389) (xy 298.761927 -218.828158)
			(xy 298.725675 -218.789087) (xy 298.695651 -218.74505) (xy 298.672525 -218.697029) (xy 298.656815 -218.646099)
			(xy 298.648872 -218.593395) (xy 295.260024 -218.593395) (xy 295.252081 -218.646099) (xy 295.236371 -218.697029)
			(xy 295.213245 -218.74505) (xy 295.183221 -218.789087) (xy 295.146969 -218.828158) (xy 295.105298 -218.861389)
			(xy 295.05914 -218.888038) (xy 295.009526 -218.90751) (xy 294.957564 -218.91937) (xy 294.904414 -218.923354)
			(xy 294.851264 -218.91937) (xy 294.799302 -218.90751) (xy 294.749688 -218.888038) (xy 294.70353 -218.861389)
			(xy 294.661859 -218.828158) (xy 294.625607 -218.789087) (xy 294.595583 -218.74505) (xy 294.572457 -218.697029)
			(xy 294.556747 -218.646099) (xy 294.548804 -218.593395) (xy 284.272492 -218.593395) (xy 284.264549 -218.646099)
			(xy 284.248839 -218.697029) (xy 284.225713 -218.74505) (xy 284.195689 -218.789087) (xy 284.159437 -218.828158)
			(xy 284.117766 -218.861389) (xy 284.071608 -218.888038) (xy 284.021994 -218.90751) (xy 283.970032 -218.91937)
			(xy 283.916882 -218.923354) (xy 283.863732 -218.91937) (xy 283.81177 -218.90751) (xy 283.762156 -218.888038)
			(xy 283.715998 -218.861389) (xy 283.674327 -218.828158) (xy 283.638075 -218.789087) (xy 283.608051 -218.74505)
			(xy 283.584925 -218.697029) (xy 283.569215 -218.646099) (xy 283.561272 -218.593395) (xy 280.172424 -218.593395)
			(xy 280.164481 -218.646099) (xy 280.148771 -218.697029) (xy 280.125645 -218.74505) (xy 280.095621 -218.789087)
			(xy 280.059369 -218.828158) (xy 280.017698 -218.861389) (xy 279.97154 -218.888038) (xy 279.921926 -218.90751)
			(xy 279.869964 -218.91937) (xy 279.816814 -218.923354) (xy 279.763664 -218.91937) (xy 279.711702 -218.90751)
			(xy 279.662088 -218.888038) (xy 279.61593 -218.861389) (xy 279.574259 -218.828158) (xy 279.538007 -218.789087)
			(xy 279.507983 -218.74505) (xy 279.484857 -218.697029) (xy 279.469147 -218.646099) (xy 279.461204 -218.593395)
			(xy 269.184892 -218.593395) (xy 269.176949 -218.646099) (xy 269.161239 -218.697029) (xy 269.138113 -218.74505)
			(xy 269.108089 -218.789087) (xy 269.071837 -218.828158) (xy 269.030166 -218.861389) (xy 268.984008 -218.888038)
			(xy 268.934394 -218.90751) (xy 268.882432 -218.91937) (xy 268.829282 -218.923354) (xy 268.776132 -218.91937)
			(xy 268.72417 -218.90751) (xy 268.674556 -218.888038) (xy 268.628398 -218.861389) (xy 268.586727 -218.828158)
			(xy 268.550475 -218.789087) (xy 268.520451 -218.74505) (xy 268.497325 -218.697029) (xy 268.481615 -218.646099)
			(xy 268.473672 -218.593395) (xy 265.084824 -218.593395) (xy 265.076881 -218.646099) (xy 265.061171 -218.697029)
			(xy 265.038045 -218.74505) (xy 265.008021 -218.789087) (xy 264.971769 -218.828158) (xy 264.930098 -218.861389)
			(xy 264.88394 -218.888038) (xy 264.834326 -218.90751) (xy 264.782364 -218.91937) (xy 264.729214 -218.923354)
			(xy 264.676064 -218.91937) (xy 264.624102 -218.90751) (xy 264.574488 -218.888038) (xy 264.52833 -218.861389)
			(xy 264.486659 -218.828158) (xy 264.450407 -218.789087) (xy 264.420383 -218.74505) (xy 264.397257 -218.697029)
			(xy 264.381547 -218.646099) (xy 264.373604 -218.593395) (xy 254.20828 -218.593395) (xy 254.20828 -219.443279)
			(xy 264.373604 -219.443279) (xy 264.373604 -219.389981) (xy 264.381547 -219.337277) (xy 264.397257 -219.286347)
			(xy 264.420383 -219.238326) (xy 264.450407 -219.194289) (xy 264.486659 -219.155218) (xy 264.52833 -219.121987)
			(xy 264.574488 -219.095338) (xy 264.624102 -219.075866) (xy 264.676064 -219.064006) (xy 264.729214 -219.060023)
			(xy 264.782364 -219.064006) (xy 264.834326 -219.075866) (xy 264.88394 -219.095338) (xy 264.930098 -219.121987)
			(xy 264.971769 -219.155218) (xy 265.008021 -219.194289) (xy 265.038045 -219.238326) (xy 265.061171 -219.286347)
			(xy 265.076881 -219.337277) (xy 265.084824 -219.389981) (xy 265.085322 -219.41663) (xy 265.084824 -219.443279)
			(xy 279.461204 -219.443279) (xy 279.461204 -219.389981) (xy 279.469147 -219.337277) (xy 279.484857 -219.286347)
			(xy 279.507983 -219.238326) (xy 279.538007 -219.194289) (xy 279.574259 -219.155218) (xy 279.61593 -219.121987)
			(xy 279.662088 -219.095338) (xy 279.711702 -219.075866) (xy 279.763664 -219.064006) (xy 279.816814 -219.060023)
			(xy 279.869964 -219.064006) (xy 279.921926 -219.075866) (xy 279.97154 -219.095338) (xy 280.017698 -219.121987)
			(xy 280.059369 -219.155218) (xy 280.095621 -219.194289) (xy 280.125645 -219.238326) (xy 280.148771 -219.286347)
			(xy 280.164481 -219.337277) (xy 280.172424 -219.389981) (xy 280.172922 -219.41663) (xy 280.172424 -219.443279)
			(xy 294.548804 -219.443279) (xy 294.548804 -219.389981) (xy 294.556747 -219.337277) (xy 294.572457 -219.286347)
			(xy 294.595583 -219.238326) (xy 294.625607 -219.194289) (xy 294.661859 -219.155218) (xy 294.70353 -219.121987)
			(xy 294.749688 -219.095338) (xy 294.799302 -219.075866) (xy 294.851264 -219.064006) (xy 294.904414 -219.060023)
			(xy 294.957564 -219.064006) (xy 295.009526 -219.075866) (xy 295.05914 -219.095338) (xy 295.105298 -219.121987)
			(xy 295.146969 -219.155218) (xy 295.183221 -219.194289) (xy 295.213245 -219.238326) (xy 295.236371 -219.286347)
			(xy 295.252081 -219.337277) (xy 295.260024 -219.389981) (xy 295.260522 -219.41663) (xy 295.260024 -219.443279)
			(xy 295.252081 -219.495983) (xy 295.236371 -219.546913) (xy 295.213245 -219.594934) (xy 295.183221 -219.638971)
			(xy 295.146969 -219.678042) (xy 295.105298 -219.711273) (xy 295.05914 -219.737922) (xy 295.009526 -219.757394)
			(xy 294.957564 -219.769254) (xy 294.904414 -219.773238) (xy 294.851264 -219.769254) (xy 294.799302 -219.757394)
			(xy 294.749688 -219.737922) (xy 294.70353 -219.711273) (xy 294.661859 -219.678042) (xy 294.625607 -219.638971)
			(xy 294.595583 -219.594934) (xy 294.572457 -219.546913) (xy 294.556747 -219.495983) (xy 294.548804 -219.443279)
			(xy 280.172424 -219.443279) (xy 280.164481 -219.495983) (xy 280.148771 -219.546913) (xy 280.125645 -219.594934)
			(xy 280.095621 -219.638971) (xy 280.059369 -219.678042) (xy 280.017698 -219.711273) (xy 279.97154 -219.737922)
			(xy 279.921926 -219.757394) (xy 279.869964 -219.769254) (xy 279.816814 -219.773238) (xy 279.763664 -219.769254)
			(xy 279.711702 -219.757394) (xy 279.662088 -219.737922) (xy 279.61593 -219.711273) (xy 279.574259 -219.678042)
			(xy 279.538007 -219.638971) (xy 279.507983 -219.594934) (xy 279.484857 -219.546913) (xy 279.469147 -219.495983)
			(xy 279.461204 -219.443279) (xy 265.084824 -219.443279) (xy 265.076881 -219.495983) (xy 265.061171 -219.546913)
			(xy 265.038045 -219.594934) (xy 265.008021 -219.638971) (xy 264.971769 -219.678042) (xy 264.930098 -219.711273)
			(xy 264.88394 -219.737922) (xy 264.834326 -219.757394) (xy 264.782364 -219.769254) (xy 264.729214 -219.773238)
			(xy 264.676064 -219.769254) (xy 264.624102 -219.757394) (xy 264.574488 -219.737922) (xy 264.52833 -219.711273)
			(xy 264.486659 -219.678042) (xy 264.450407 -219.638971) (xy 264.420383 -219.594934) (xy 264.397257 -219.546913)
			(xy 264.381547 -219.495983) (xy 264.373604 -219.443279) (xy 254.20828 -219.443279) (xy 254.20828 -220.293417)
			(xy 268.473672 -220.293417) (xy 268.473672 -220.240119) (xy 268.481615 -220.187415) (xy 268.497325 -220.136485)
			(xy 268.520451 -220.088464) (xy 268.550475 -220.044427) (xy 268.586727 -220.005356) (xy 268.628398 -219.972125)
			(xy 268.674556 -219.945476) (xy 268.72417 -219.926004) (xy 268.776132 -219.914144) (xy 268.829282 -219.910161)
			(xy 268.882432 -219.914144) (xy 268.934394 -219.926004) (xy 268.984008 -219.945476) (xy 269.030166 -219.972125)
			(xy 269.071837 -220.005356) (xy 269.108089 -220.044427) (xy 269.138113 -220.088464) (xy 269.161239 -220.136485)
			(xy 269.176949 -220.187415) (xy 269.184892 -220.240119) (xy 269.18539 -220.266768) (xy 269.184892 -220.293417)
			(xy 283.561272 -220.293417) (xy 283.561272 -220.240119) (xy 283.569215 -220.187415) (xy 283.584925 -220.136485)
			(xy 283.608051 -220.088464) (xy 283.638075 -220.044427) (xy 283.674327 -220.005356) (xy 283.715998 -219.972125)
			(xy 283.762156 -219.945476) (xy 283.81177 -219.926004) (xy 283.863732 -219.914144) (xy 283.916882 -219.910161)
			(xy 283.970032 -219.914144) (xy 284.021994 -219.926004) (xy 284.071608 -219.945476) (xy 284.117766 -219.972125)
			(xy 284.159437 -220.005356) (xy 284.195689 -220.044427) (xy 284.225713 -220.088464) (xy 284.248839 -220.136485)
			(xy 284.264549 -220.187415) (xy 284.272492 -220.240119) (xy 284.27299 -220.266768) (xy 284.272492 -220.293417)
			(xy 298.648872 -220.293417) (xy 298.648872 -220.240119) (xy 298.656815 -220.187415) (xy 298.672525 -220.136485)
			(xy 298.695651 -220.088464) (xy 298.725675 -220.044427) (xy 298.761927 -220.005356) (xy 298.803598 -219.972125)
			(xy 298.849756 -219.945476) (xy 298.89937 -219.926004) (xy 298.951332 -219.914144) (xy 299.004482 -219.910161)
			(xy 299.057632 -219.914144) (xy 299.109594 -219.926004) (xy 299.159208 -219.945476) (xy 299.205366 -219.972125)
			(xy 299.247037 -220.005356) (xy 299.283289 -220.044427) (xy 299.313313 -220.088464) (xy 299.336439 -220.136485)
			(xy 299.352149 -220.187415) (xy 299.360092 -220.240119) (xy 299.36059 -220.266768) (xy 299.360092 -220.293417)
			(xy 299.352149 -220.346121) (xy 299.336439 -220.397051) (xy 299.313313 -220.445072) (xy 299.283289 -220.489109)
			(xy 299.247037 -220.52818) (xy 299.205366 -220.561411) (xy 299.159208 -220.58806) (xy 299.109594 -220.607532)
			(xy 299.057632 -220.619392) (xy 299.004482 -220.623376) (xy 298.951332 -220.619392) (xy 298.89937 -220.607532)
			(xy 298.849756 -220.58806) (xy 298.803598 -220.561411) (xy 298.761927 -220.52818) (xy 298.725675 -220.489109)
			(xy 298.695651 -220.445072) (xy 298.672525 -220.397051) (xy 298.656815 -220.346121) (xy 298.648872 -220.293417)
			(xy 284.272492 -220.293417) (xy 284.264549 -220.346121) (xy 284.248839 -220.397051) (xy 284.225713 -220.445072)
			(xy 284.195689 -220.489109) (xy 284.159437 -220.52818) (xy 284.117766 -220.561411) (xy 284.071608 -220.58806)
			(xy 284.021994 -220.607532) (xy 283.970032 -220.619392) (xy 283.916882 -220.623376) (xy 283.863732 -220.619392)
			(xy 283.81177 -220.607532) (xy 283.762156 -220.58806) (xy 283.715998 -220.561411) (xy 283.674327 -220.52818)
			(xy 283.638075 -220.489109) (xy 283.608051 -220.445072) (xy 283.584925 -220.397051) (xy 283.569215 -220.346121)
			(xy 283.561272 -220.293417) (xy 269.184892 -220.293417) (xy 269.176949 -220.346121) (xy 269.161239 -220.397051)
			(xy 269.138113 -220.445072) (xy 269.108089 -220.489109) (xy 269.071837 -220.52818) (xy 269.030166 -220.561411)
			(xy 268.984008 -220.58806) (xy 268.934394 -220.607532) (xy 268.882432 -220.619392) (xy 268.829282 -220.623376)
			(xy 268.776132 -220.619392) (xy 268.72417 -220.607532) (xy 268.674556 -220.58806) (xy 268.628398 -220.561411)
			(xy 268.586727 -220.52818) (xy 268.550475 -220.489109) (xy 268.520451 -220.445072) (xy 268.497325 -220.397051)
			(xy 268.481615 -220.346121) (xy 268.473672 -220.293417) (xy 254.20828 -220.293417) (xy 254.20828 -221.143301)
			(xy 264.373604 -221.143301) (xy 264.373604 -221.090003) (xy 264.381547 -221.037299) (xy 264.397257 -220.986369)
			(xy 264.420383 -220.938348) (xy 264.450407 -220.894311) (xy 264.486659 -220.85524) (xy 264.52833 -220.822009)
			(xy 264.574488 -220.79536) (xy 264.624102 -220.775888) (xy 264.676064 -220.764028) (xy 264.729214 -220.760045)
			(xy 264.782364 -220.764028) (xy 264.834326 -220.775888) (xy 264.88394 -220.79536) (xy 264.930098 -220.822009)
			(xy 264.971769 -220.85524) (xy 265.008021 -220.894311) (xy 265.038045 -220.938348) (xy 265.061171 -220.986369)
			(xy 265.076881 -221.037299) (xy 265.084824 -221.090003) (xy 265.085322 -221.116652) (xy 265.084824 -221.143301)
			(xy 279.461204 -221.143301) (xy 279.461204 -221.090003) (xy 279.469147 -221.037299) (xy 279.484857 -220.986369)
			(xy 279.507983 -220.938348) (xy 279.538007 -220.894311) (xy 279.574259 -220.85524) (xy 279.61593 -220.822009)
			(xy 279.662088 -220.79536) (xy 279.711702 -220.775888) (xy 279.763664 -220.764028) (xy 279.816814 -220.760045)
			(xy 279.869964 -220.764028) (xy 279.921926 -220.775888) (xy 279.97154 -220.79536) (xy 280.017698 -220.822009)
			(xy 280.059369 -220.85524) (xy 280.095621 -220.894311) (xy 280.125645 -220.938348) (xy 280.148771 -220.986369)
			(xy 280.164481 -221.037299) (xy 280.172424 -221.090003) (xy 280.172922 -221.116652) (xy 280.172424 -221.143301)
			(xy 294.548804 -221.143301) (xy 294.548804 -221.090003) (xy 294.556747 -221.037299) (xy 294.572457 -220.986369)
			(xy 294.595583 -220.938348) (xy 294.625607 -220.894311) (xy 294.661859 -220.85524) (xy 294.70353 -220.822009)
			(xy 294.749688 -220.79536) (xy 294.799302 -220.775888) (xy 294.851264 -220.764028) (xy 294.904414 -220.760045)
			(xy 294.957564 -220.764028) (xy 295.009526 -220.775888) (xy 295.05914 -220.79536) (xy 295.105298 -220.822009)
			(xy 295.146969 -220.85524) (xy 295.183221 -220.894311) (xy 295.213245 -220.938348) (xy 295.236371 -220.986369)
			(xy 295.252081 -221.037299) (xy 295.260024 -221.090003) (xy 295.260522 -221.116652) (xy 295.260024 -221.143301)
			(xy 295.252081 -221.196005) (xy 295.236371 -221.246935) (xy 295.213245 -221.294956) (xy 295.183221 -221.338993)
			(xy 295.146969 -221.378064) (xy 295.105298 -221.411295) (xy 295.05914 -221.437944) (xy 295.009526 -221.457416)
			(xy 294.957564 -221.469276) (xy 294.904414 -221.47326) (xy 294.851264 -221.469276) (xy 294.799302 -221.457416)
			(xy 294.749688 -221.437944) (xy 294.70353 -221.411295) (xy 294.661859 -221.378064) (xy 294.625607 -221.338993)
			(xy 294.595583 -221.294956) (xy 294.572457 -221.246935) (xy 294.556747 -221.196005) (xy 294.548804 -221.143301)
			(xy 280.172424 -221.143301) (xy 280.164481 -221.196005) (xy 280.148771 -221.246935) (xy 280.125645 -221.294956)
			(xy 280.095621 -221.338993) (xy 280.059369 -221.378064) (xy 280.017698 -221.411295) (xy 279.97154 -221.437944)
			(xy 279.921926 -221.457416) (xy 279.869964 -221.469276) (xy 279.816814 -221.47326) (xy 279.763664 -221.469276)
			(xy 279.711702 -221.457416) (xy 279.662088 -221.437944) (xy 279.61593 -221.411295) (xy 279.574259 -221.378064)
			(xy 279.538007 -221.338993) (xy 279.507983 -221.294956) (xy 279.484857 -221.246935) (xy 279.469147 -221.196005)
			(xy 279.461204 -221.143301) (xy 265.084824 -221.143301) (xy 265.076881 -221.196005) (xy 265.061171 -221.246935)
			(xy 265.038045 -221.294956) (xy 265.008021 -221.338993) (xy 264.971769 -221.378064) (xy 264.930098 -221.411295)
			(xy 264.88394 -221.437944) (xy 264.834326 -221.457416) (xy 264.782364 -221.469276) (xy 264.729214 -221.47326)
			(xy 264.676064 -221.469276) (xy 264.624102 -221.457416) (xy 264.574488 -221.437944) (xy 264.52833 -221.411295)
			(xy 264.486659 -221.378064) (xy 264.450407 -221.338993) (xy 264.420383 -221.294956) (xy 264.397257 -221.246935)
			(xy 264.381547 -221.196005) (xy 264.373604 -221.143301) (xy 254.20828 -221.143301) (xy 254.20828 -221.993439)
			(xy 268.473672 -221.993439) (xy 268.473672 -221.940141) (xy 268.481615 -221.887437) (xy 268.497325 -221.836507)
			(xy 268.520451 -221.788486) (xy 268.550475 -221.744449) (xy 268.586727 -221.705378) (xy 268.628398 -221.672147)
			(xy 268.674556 -221.645498) (xy 268.72417 -221.626026) (xy 268.776132 -221.614166) (xy 268.829282 -221.610183)
			(xy 268.882432 -221.614166) (xy 268.934394 -221.626026) (xy 268.984008 -221.645498) (xy 269.030166 -221.672147)
			(xy 269.071837 -221.705378) (xy 269.108089 -221.744449) (xy 269.138113 -221.788486) (xy 269.161239 -221.836507)
			(xy 269.176949 -221.887437) (xy 269.184892 -221.940141) (xy 269.18539 -221.96679) (xy 269.184892 -221.993439)
			(xy 283.561272 -221.993439) (xy 283.561272 -221.940141) (xy 283.569215 -221.887437) (xy 283.584925 -221.836507)
			(xy 283.608051 -221.788486) (xy 283.638075 -221.744449) (xy 283.674327 -221.705378) (xy 283.715998 -221.672147)
			(xy 283.762156 -221.645498) (xy 283.81177 -221.626026) (xy 283.863732 -221.614166) (xy 283.916882 -221.610183)
			(xy 283.970032 -221.614166) (xy 284.021994 -221.626026) (xy 284.071608 -221.645498) (xy 284.117766 -221.672147)
			(xy 284.159437 -221.705378) (xy 284.195689 -221.744449) (xy 284.225713 -221.788486) (xy 284.248839 -221.836507)
			(xy 284.264549 -221.887437) (xy 284.272492 -221.940141) (xy 284.27299 -221.96679) (xy 284.272492 -221.993439)
			(xy 298.648872 -221.993439) (xy 298.648872 -221.940141) (xy 298.656815 -221.887437) (xy 298.672525 -221.836507)
			(xy 298.695651 -221.788486) (xy 298.725675 -221.744449) (xy 298.761927 -221.705378) (xy 298.803598 -221.672147)
			(xy 298.849756 -221.645498) (xy 298.89937 -221.626026) (xy 298.951332 -221.614166) (xy 299.004482 -221.610183)
			(xy 299.057632 -221.614166) (xy 299.109594 -221.626026) (xy 299.159208 -221.645498) (xy 299.205366 -221.672147)
			(xy 299.247037 -221.705378) (xy 299.283289 -221.744449) (xy 299.313313 -221.788486) (xy 299.336439 -221.836507)
			(xy 299.352149 -221.887437) (xy 299.360092 -221.940141) (xy 299.36059 -221.96679) (xy 299.360092 -221.993439)
			(xy 299.352149 -222.046143) (xy 299.336439 -222.097073) (xy 299.313313 -222.145094) (xy 299.283289 -222.189131)
			(xy 299.247037 -222.228202) (xy 299.205366 -222.261433) (xy 299.159208 -222.288082) (xy 299.109594 -222.307554)
			(xy 299.057632 -222.319414) (xy 299.004482 -222.323398) (xy 298.951332 -222.319414) (xy 298.89937 -222.307554)
			(xy 298.849756 -222.288082) (xy 298.803598 -222.261433) (xy 298.761927 -222.228202) (xy 298.725675 -222.189131)
			(xy 298.695651 -222.145094) (xy 298.672525 -222.097073) (xy 298.656815 -222.046143) (xy 298.648872 -221.993439)
			(xy 284.272492 -221.993439) (xy 284.264549 -222.046143) (xy 284.248839 -222.097073) (xy 284.225713 -222.145094)
			(xy 284.195689 -222.189131) (xy 284.159437 -222.228202) (xy 284.117766 -222.261433) (xy 284.071608 -222.288082)
			(xy 284.021994 -222.307554) (xy 283.970032 -222.319414) (xy 283.916882 -222.323398) (xy 283.863732 -222.319414)
			(xy 283.81177 -222.307554) (xy 283.762156 -222.288082) (xy 283.715998 -222.261433) (xy 283.674327 -222.228202)
			(xy 283.638075 -222.189131) (xy 283.608051 -222.145094) (xy 283.584925 -222.097073) (xy 283.569215 -222.046143)
			(xy 283.561272 -221.993439) (xy 269.184892 -221.993439) (xy 269.176949 -222.046143) (xy 269.161239 -222.097073)
			(xy 269.138113 -222.145094) (xy 269.108089 -222.189131) (xy 269.071837 -222.228202) (xy 269.030166 -222.261433)
			(xy 268.984008 -222.288082) (xy 268.934394 -222.307554) (xy 268.882432 -222.319414) (xy 268.829282 -222.323398)
			(xy 268.776132 -222.319414) (xy 268.72417 -222.307554) (xy 268.674556 -222.288082) (xy 268.628398 -222.261433)
			(xy 268.586727 -222.228202) (xy 268.550475 -222.189131) (xy 268.520451 -222.145094) (xy 268.497325 -222.097073)
			(xy 268.481615 -222.046143) (xy 268.473672 -221.993439) (xy 254.20828 -221.993439) (xy 254.20828 -222.843323)
			(xy 264.373604 -222.843323) (xy 264.373604 -222.790025) (xy 264.381547 -222.737321) (xy 264.397257 -222.686391)
			(xy 264.420383 -222.63837) (xy 264.450407 -222.594333) (xy 264.486659 -222.555262) (xy 264.52833 -222.522031)
			(xy 264.574488 -222.495382) (xy 264.624102 -222.47591) (xy 264.676064 -222.46405) (xy 264.729214 -222.460067)
			(xy 264.782364 -222.46405) (xy 264.834326 -222.47591) (xy 264.88394 -222.495382) (xy 264.930098 -222.522031)
			(xy 264.971769 -222.555262) (xy 265.008021 -222.594333) (xy 265.038045 -222.63837) (xy 265.061171 -222.686391)
			(xy 265.076881 -222.737321) (xy 265.084824 -222.790025) (xy 265.085322 -222.816674) (xy 265.084824 -222.843323)
			(xy 279.461204 -222.843323) (xy 279.461204 -222.790025) (xy 279.469147 -222.737321) (xy 279.484857 -222.686391)
			(xy 279.507983 -222.63837) (xy 279.538007 -222.594333) (xy 279.574259 -222.555262) (xy 279.61593 -222.522031)
			(xy 279.662088 -222.495382) (xy 279.711702 -222.47591) (xy 279.763664 -222.46405) (xy 279.816814 -222.460067)
			(xy 279.869964 -222.46405) (xy 279.921926 -222.47591) (xy 279.97154 -222.495382) (xy 280.017698 -222.522031)
			(xy 280.059369 -222.555262) (xy 280.095621 -222.594333) (xy 280.125645 -222.63837) (xy 280.148771 -222.686391)
			(xy 280.164481 -222.737321) (xy 280.172424 -222.790025) (xy 280.172922 -222.816674) (xy 280.172424 -222.843323)
			(xy 294.548804 -222.843323) (xy 294.548804 -222.790025) (xy 294.556747 -222.737321) (xy 294.572457 -222.686391)
			(xy 294.595583 -222.63837) (xy 294.625607 -222.594333) (xy 294.661859 -222.555262) (xy 294.70353 -222.522031)
			(xy 294.749688 -222.495382) (xy 294.799302 -222.47591) (xy 294.851264 -222.46405) (xy 294.904414 -222.460067)
			(xy 294.957564 -222.46405) (xy 295.009526 -222.47591) (xy 295.05914 -222.495382) (xy 295.105298 -222.522031)
			(xy 295.146969 -222.555262) (xy 295.183221 -222.594333) (xy 295.213245 -222.63837) (xy 295.236371 -222.686391)
			(xy 295.252081 -222.737321) (xy 295.260024 -222.790025) (xy 295.260522 -222.816674) (xy 295.260024 -222.843323)
			(xy 295.252081 -222.896027) (xy 295.236371 -222.946957) (xy 295.213245 -222.994978) (xy 295.183221 -223.039015)
			(xy 295.146969 -223.078086) (xy 295.105298 -223.111317) (xy 295.05914 -223.137966) (xy 295.009526 -223.157438)
			(xy 294.957564 -223.169298) (xy 294.904414 -223.173282) (xy 294.851264 -223.169298) (xy 294.799302 -223.157438)
			(xy 294.749688 -223.137966) (xy 294.70353 -223.111317) (xy 294.661859 -223.078086) (xy 294.625607 -223.039015)
			(xy 294.595583 -222.994978) (xy 294.572457 -222.946957) (xy 294.556747 -222.896027) (xy 294.548804 -222.843323)
			(xy 280.172424 -222.843323) (xy 280.164481 -222.896027) (xy 280.148771 -222.946957) (xy 280.125645 -222.994978)
			(xy 280.095621 -223.039015) (xy 280.059369 -223.078086) (xy 280.017698 -223.111317) (xy 279.97154 -223.137966)
			(xy 279.921926 -223.157438) (xy 279.869964 -223.169298) (xy 279.816814 -223.173282) (xy 279.763664 -223.169298)
			(xy 279.711702 -223.157438) (xy 279.662088 -223.137966) (xy 279.61593 -223.111317) (xy 279.574259 -223.078086)
			(xy 279.538007 -223.039015) (xy 279.507983 -222.994978) (xy 279.484857 -222.946957) (xy 279.469147 -222.896027)
			(xy 279.461204 -222.843323) (xy 265.084824 -222.843323) (xy 265.076881 -222.896027) (xy 265.061171 -222.946957)
			(xy 265.038045 -222.994978) (xy 265.008021 -223.039015) (xy 264.971769 -223.078086) (xy 264.930098 -223.111317)
			(xy 264.88394 -223.137966) (xy 264.834326 -223.157438) (xy 264.782364 -223.169298) (xy 264.729214 -223.173282)
			(xy 264.676064 -223.169298) (xy 264.624102 -223.157438) (xy 264.574488 -223.137966) (xy 264.52833 -223.111317)
			(xy 264.486659 -223.078086) (xy 264.450407 -223.039015) (xy 264.420383 -222.994978) (xy 264.397257 -222.946957)
			(xy 264.381547 -222.896027) (xy 264.373604 -222.843323) (xy 254.20828 -222.843323) (xy 254.20828 -223.693207)
			(xy 268.473672 -223.693207) (xy 268.473672 -223.639909) (xy 268.481615 -223.587205) (xy 268.497325 -223.536275)
			(xy 268.520451 -223.488254) (xy 268.550475 -223.444217) (xy 268.586727 -223.405146) (xy 268.628398 -223.371915)
			(xy 268.674556 -223.345266) (xy 268.72417 -223.325794) (xy 268.776132 -223.313934) (xy 268.829282 -223.309951)
			(xy 268.882432 -223.313934) (xy 268.934394 -223.325794) (xy 268.984008 -223.345266) (xy 269.030166 -223.371915)
			(xy 269.071837 -223.405146) (xy 269.108089 -223.444217) (xy 269.138113 -223.488254) (xy 269.161239 -223.536275)
			(xy 269.176949 -223.587205) (xy 269.184892 -223.639909) (xy 269.18539 -223.666558) (xy 269.184892 -223.693207)
			(xy 283.561272 -223.693207) (xy 283.561272 -223.639909) (xy 283.569215 -223.587205) (xy 283.584925 -223.536275)
			(xy 283.608051 -223.488254) (xy 283.638075 -223.444217) (xy 283.674327 -223.405146) (xy 283.715998 -223.371915)
			(xy 283.762156 -223.345266) (xy 283.81177 -223.325794) (xy 283.863732 -223.313934) (xy 283.916882 -223.309951)
			(xy 283.970032 -223.313934) (xy 284.021994 -223.325794) (xy 284.071608 -223.345266) (xy 284.117766 -223.371915)
			(xy 284.159437 -223.405146) (xy 284.195689 -223.444217) (xy 284.225713 -223.488254) (xy 284.248839 -223.536275)
			(xy 284.264549 -223.587205) (xy 284.272492 -223.639909) (xy 284.27299 -223.666558) (xy 284.272492 -223.693207)
			(xy 298.648872 -223.693207) (xy 298.648872 -223.639909) (xy 298.656815 -223.587205) (xy 298.672525 -223.536275)
			(xy 298.695651 -223.488254) (xy 298.725675 -223.444217) (xy 298.761927 -223.405146) (xy 298.803598 -223.371915)
			(xy 298.849756 -223.345266) (xy 298.89937 -223.325794) (xy 298.951332 -223.313934) (xy 299.004482 -223.309951)
			(xy 299.057632 -223.313934) (xy 299.109594 -223.325794) (xy 299.159208 -223.345266) (xy 299.205366 -223.371915)
			(xy 299.247037 -223.405146) (xy 299.283289 -223.444217) (xy 299.313313 -223.488254) (xy 299.336439 -223.536275)
			(xy 299.352149 -223.587205) (xy 299.360092 -223.639909) (xy 299.36059 -223.666558) (xy 299.360092 -223.693207)
			(xy 299.352149 -223.745911) (xy 299.336439 -223.796841) (xy 299.313313 -223.844862) (xy 299.283289 -223.888899)
			(xy 299.247037 -223.92797) (xy 299.205366 -223.961201) (xy 299.159208 -223.98785) (xy 299.109594 -224.007322)
			(xy 299.057632 -224.019182) (xy 299.004482 -224.023166) (xy 298.951332 -224.019182) (xy 298.89937 -224.007322)
			(xy 298.849756 -223.98785) (xy 298.803598 -223.961201) (xy 298.761927 -223.92797) (xy 298.725675 -223.888899)
			(xy 298.695651 -223.844862) (xy 298.672525 -223.796841) (xy 298.656815 -223.745911) (xy 298.648872 -223.693207)
			(xy 284.272492 -223.693207) (xy 284.264549 -223.745911) (xy 284.248839 -223.796841) (xy 284.225713 -223.844862)
			(xy 284.195689 -223.888899) (xy 284.159437 -223.92797) (xy 284.117766 -223.961201) (xy 284.071608 -223.98785)
			(xy 284.021994 -224.007322) (xy 283.970032 -224.019182) (xy 283.916882 -224.023166) (xy 283.863732 -224.019182)
			(xy 283.81177 -224.007322) (xy 283.762156 -223.98785) (xy 283.715998 -223.961201) (xy 283.674327 -223.92797)
			(xy 283.638075 -223.888899) (xy 283.608051 -223.844862) (xy 283.584925 -223.796841) (xy 283.569215 -223.745911)
			(xy 283.561272 -223.693207) (xy 269.184892 -223.693207) (xy 269.176949 -223.745911) (xy 269.161239 -223.796841)
			(xy 269.138113 -223.844862) (xy 269.108089 -223.888899) (xy 269.071837 -223.92797) (xy 269.030166 -223.961201)
			(xy 268.984008 -223.98785) (xy 268.934394 -224.007322) (xy 268.882432 -224.019182) (xy 268.829282 -224.023166)
			(xy 268.776132 -224.019182) (xy 268.72417 -224.007322) (xy 268.674556 -223.98785) (xy 268.628398 -223.961201)
			(xy 268.586727 -223.92797) (xy 268.550475 -223.888899) (xy 268.520451 -223.844862) (xy 268.497325 -223.796841)
			(xy 268.481615 -223.745911) (xy 268.473672 -223.693207) (xy 254.20828 -223.693207) (xy 254.20828 -224.543345)
			(xy 264.373604 -224.543345) (xy 264.373604 -224.490047) (xy 264.381547 -224.437343) (xy 264.397257 -224.386413)
			(xy 264.420383 -224.338392) (xy 264.450407 -224.294355) (xy 264.486659 -224.255284) (xy 264.52833 -224.222053)
			(xy 264.574488 -224.195404) (xy 264.624102 -224.175932) (xy 264.676064 -224.164072) (xy 264.729214 -224.160089)
			(xy 264.782364 -224.164072) (xy 264.834326 -224.175932) (xy 264.88394 -224.195404) (xy 264.930098 -224.222053)
			(xy 264.971769 -224.255284) (xy 265.008021 -224.294355) (xy 265.038045 -224.338392) (xy 265.061171 -224.386413)
			(xy 265.076881 -224.437343) (xy 265.084824 -224.490047) (xy 265.085322 -224.516696) (xy 265.084824 -224.543345)
			(xy 279.461204 -224.543345) (xy 279.461204 -224.490047) (xy 279.469147 -224.437343) (xy 279.484857 -224.386413)
			(xy 279.507983 -224.338392) (xy 279.538007 -224.294355) (xy 279.574259 -224.255284) (xy 279.61593 -224.222053)
			(xy 279.662088 -224.195404) (xy 279.711702 -224.175932) (xy 279.763664 -224.164072) (xy 279.816814 -224.160089)
			(xy 279.869964 -224.164072) (xy 279.921926 -224.175932) (xy 279.97154 -224.195404) (xy 280.017698 -224.222053)
			(xy 280.059369 -224.255284) (xy 280.095621 -224.294355) (xy 280.125645 -224.338392) (xy 280.148771 -224.386413)
			(xy 280.164481 -224.437343) (xy 280.172424 -224.490047) (xy 280.172922 -224.516696) (xy 280.172424 -224.543345)
			(xy 294.548804 -224.543345) (xy 294.548804 -224.490047) (xy 294.556747 -224.437343) (xy 294.572457 -224.386413)
			(xy 294.595583 -224.338392) (xy 294.625607 -224.294355) (xy 294.661859 -224.255284) (xy 294.70353 -224.222053)
			(xy 294.749688 -224.195404) (xy 294.799302 -224.175932) (xy 294.851264 -224.164072) (xy 294.904414 -224.160089)
			(xy 294.957564 -224.164072) (xy 295.009526 -224.175932) (xy 295.05914 -224.195404) (xy 295.105298 -224.222053)
			(xy 295.146969 -224.255284) (xy 295.183221 -224.294355) (xy 295.213245 -224.338392) (xy 295.236371 -224.386413)
			(xy 295.252081 -224.437343) (xy 295.260024 -224.490047) (xy 295.260522 -224.516696) (xy 295.260024 -224.543345)
			(xy 309.636404 -224.543345) (xy 309.636404 -224.490047) (xy 309.644347 -224.437343) (xy 309.660057 -224.386413)
			(xy 309.683183 -224.338392) (xy 309.713207 -224.294355) (xy 309.749459 -224.255284) (xy 309.79113 -224.222053)
			(xy 309.837288 -224.195404) (xy 309.886902 -224.175932) (xy 309.938864 -224.164072) (xy 309.992014 -224.160089)
			(xy 310.045164 -224.164072) (xy 310.097126 -224.175932) (xy 310.14674 -224.195404) (xy 310.192898 -224.222053)
			(xy 310.234569 -224.255284) (xy 310.270821 -224.294355) (xy 310.300845 -224.338392) (xy 310.323971 -224.386413)
			(xy 310.339681 -224.437343) (xy 310.347624 -224.490047) (xy 310.348122 -224.516696) (xy 310.347624 -224.543345)
			(xy 310.339681 -224.596049) (xy 310.323971 -224.646979) (xy 310.300845 -224.695) (xy 310.270821 -224.739037)
			(xy 310.234569 -224.778108) (xy 310.192898 -224.811339) (xy 310.14674 -224.837988) (xy 310.097126 -224.85746)
			(xy 310.045164 -224.86932) (xy 309.992014 -224.873304) (xy 309.938864 -224.86932) (xy 309.886902 -224.85746)
			(xy 309.837288 -224.837988) (xy 309.79113 -224.811339) (xy 309.749459 -224.778108) (xy 309.713207 -224.739037)
			(xy 309.683183 -224.695) (xy 309.660057 -224.646979) (xy 309.644347 -224.596049) (xy 309.636404 -224.543345)
			(xy 295.260024 -224.543345) (xy 295.252081 -224.596049) (xy 295.236371 -224.646979) (xy 295.213245 -224.695)
			(xy 295.183221 -224.739037) (xy 295.146969 -224.778108) (xy 295.105298 -224.811339) (xy 295.05914 -224.837988)
			(xy 295.009526 -224.85746) (xy 294.957564 -224.86932) (xy 294.904414 -224.873304) (xy 294.851264 -224.86932)
			(xy 294.799302 -224.85746) (xy 294.749688 -224.837988) (xy 294.70353 -224.811339) (xy 294.661859 -224.778108)
			(xy 294.625607 -224.739037) (xy 294.595583 -224.695) (xy 294.572457 -224.646979) (xy 294.556747 -224.596049)
			(xy 294.548804 -224.543345) (xy 280.172424 -224.543345) (xy 280.164481 -224.596049) (xy 280.148771 -224.646979)
			(xy 280.125645 -224.695) (xy 280.095621 -224.739037) (xy 280.059369 -224.778108) (xy 280.017698 -224.811339)
			(xy 279.97154 -224.837988) (xy 279.921926 -224.85746) (xy 279.869964 -224.86932) (xy 279.816814 -224.873304)
			(xy 279.763664 -224.86932) (xy 279.711702 -224.85746) (xy 279.662088 -224.837988) (xy 279.61593 -224.811339)
			(xy 279.574259 -224.778108) (xy 279.538007 -224.739037) (xy 279.507983 -224.695) (xy 279.484857 -224.646979)
			(xy 279.469147 -224.596049) (xy 279.461204 -224.543345) (xy 265.084824 -224.543345) (xy 265.076881 -224.596049)
			(xy 265.061171 -224.646979) (xy 265.038045 -224.695) (xy 265.008021 -224.739037) (xy 264.971769 -224.778108)
			(xy 264.930098 -224.811339) (xy 264.88394 -224.837988) (xy 264.834326 -224.85746) (xy 264.782364 -224.86932)
			(xy 264.729214 -224.873304) (xy 264.676064 -224.86932) (xy 264.624102 -224.85746) (xy 264.574488 -224.837988)
			(xy 264.52833 -224.811339) (xy 264.486659 -224.778108) (xy 264.450407 -224.739037) (xy 264.420383 -224.695)
			(xy 264.397257 -224.646979) (xy 264.381547 -224.596049) (xy 264.373604 -224.543345) (xy 254.20828 -224.543345)
			(xy 254.20828 -225.393229) (xy 268.473672 -225.393229) (xy 268.473672 -225.339931) (xy 268.481615 -225.287227)
			(xy 268.497325 -225.236297) (xy 268.520451 -225.188276) (xy 268.550475 -225.144239) (xy 268.586727 -225.105168)
			(xy 268.628398 -225.071937) (xy 268.674556 -225.045288) (xy 268.72417 -225.025816) (xy 268.776132 -225.013956)
			(xy 268.829282 -225.009973) (xy 268.882432 -225.013956) (xy 268.934394 -225.025816) (xy 268.984008 -225.045288)
			(xy 269.030166 -225.071937) (xy 269.071837 -225.105168) (xy 269.108089 -225.144239) (xy 269.138113 -225.188276)
			(xy 269.161239 -225.236297) (xy 269.176949 -225.287227) (xy 269.184892 -225.339931) (xy 269.18539 -225.36658)
			(xy 269.184892 -225.393229) (xy 283.561272 -225.393229) (xy 283.561272 -225.339931) (xy 283.569215 -225.287227)
			(xy 283.584925 -225.236297) (xy 283.608051 -225.188276) (xy 283.638075 -225.144239) (xy 283.674327 -225.105168)
			(xy 283.715998 -225.071937) (xy 283.762156 -225.045288) (xy 283.81177 -225.025816) (xy 283.863732 -225.013956)
			(xy 283.916882 -225.009973) (xy 283.970032 -225.013956) (xy 284.021994 -225.025816) (xy 284.071608 -225.045288)
			(xy 284.117766 -225.071937) (xy 284.159437 -225.105168) (xy 284.195689 -225.144239) (xy 284.225713 -225.188276)
			(xy 284.248839 -225.236297) (xy 284.264549 -225.287227) (xy 284.272492 -225.339931) (xy 284.27299 -225.36658)
			(xy 284.272492 -225.393229) (xy 298.648872 -225.393229) (xy 298.648872 -225.339931) (xy 298.656815 -225.287227)
			(xy 298.672525 -225.236297) (xy 298.695651 -225.188276) (xy 298.725675 -225.144239) (xy 298.761927 -225.105168)
			(xy 298.803598 -225.071937) (xy 298.849756 -225.045288) (xy 298.89937 -225.025816) (xy 298.951332 -225.013956)
			(xy 299.004482 -225.009973) (xy 299.057632 -225.013956) (xy 299.109594 -225.025816) (xy 299.159208 -225.045288)
			(xy 299.205366 -225.071937) (xy 299.247037 -225.105168) (xy 299.283289 -225.144239) (xy 299.313313 -225.188276)
			(xy 299.336439 -225.236297) (xy 299.352149 -225.287227) (xy 299.360092 -225.339931) (xy 299.36059 -225.36658)
			(xy 299.360092 -225.393229) (xy 299.352149 -225.445933) (xy 299.336439 -225.496863) (xy 299.313313 -225.544884)
			(xy 299.283289 -225.588921) (xy 299.247037 -225.627992) (xy 299.205366 -225.661223) (xy 299.159208 -225.687872)
			(xy 299.109594 -225.707344) (xy 299.057632 -225.719204) (xy 299.004482 -225.723188) (xy 298.951332 -225.719204)
			(xy 298.89937 -225.707344) (xy 298.849756 -225.687872) (xy 298.803598 -225.661223) (xy 298.761927 -225.627992)
			(xy 298.725675 -225.588921) (xy 298.695651 -225.544884) (xy 298.672525 -225.496863) (xy 298.656815 -225.445933)
			(xy 298.648872 -225.393229) (xy 284.272492 -225.393229) (xy 284.264549 -225.445933) (xy 284.248839 -225.496863)
			(xy 284.225713 -225.544884) (xy 284.195689 -225.588921) (xy 284.159437 -225.627992) (xy 284.117766 -225.661223)
			(xy 284.071608 -225.687872) (xy 284.021994 -225.707344) (xy 283.970032 -225.719204) (xy 283.916882 -225.723188)
			(xy 283.863732 -225.719204) (xy 283.81177 -225.707344) (xy 283.762156 -225.687872) (xy 283.715998 -225.661223)
			(xy 283.674327 -225.627992) (xy 283.638075 -225.588921) (xy 283.608051 -225.544884) (xy 283.584925 -225.496863)
			(xy 283.569215 -225.445933) (xy 283.561272 -225.393229) (xy 269.184892 -225.393229) (xy 269.176949 -225.445933)
			(xy 269.161239 -225.496863) (xy 269.138113 -225.544884) (xy 269.108089 -225.588921) (xy 269.071837 -225.627992)
			(xy 269.030166 -225.661223) (xy 268.984008 -225.687872) (xy 268.934394 -225.707344) (xy 268.882432 -225.719204)
			(xy 268.829282 -225.723188) (xy 268.776132 -225.719204) (xy 268.72417 -225.707344) (xy 268.674556 -225.687872)
			(xy 268.628398 -225.661223) (xy 268.586727 -225.627992) (xy 268.550475 -225.588921) (xy 268.520451 -225.544884)
			(xy 268.497325 -225.496863) (xy 268.481615 -225.445933) (xy 268.473672 -225.393229) (xy 254.20828 -225.393229)
			(xy 254.20828 -226.243367) (xy 264.373604 -226.243367) (xy 264.373604 -226.190069) (xy 264.381547 -226.137365)
			(xy 264.397257 -226.086435) (xy 264.420383 -226.038414) (xy 264.450407 -225.994377) (xy 264.486659 -225.955306)
			(xy 264.52833 -225.922075) (xy 264.574488 -225.895426) (xy 264.624102 -225.875954) (xy 264.676064 -225.864094)
			(xy 264.729214 -225.860111) (xy 264.782364 -225.864094) (xy 264.834326 -225.875954) (xy 264.88394 -225.895426)
			(xy 264.930098 -225.922075) (xy 264.971769 -225.955306) (xy 265.008021 -225.994377) (xy 265.038045 -226.038414)
			(xy 265.061171 -226.086435) (xy 265.076881 -226.137365) (xy 265.084824 -226.190069) (xy 265.085322 -226.216718)
			(xy 265.084824 -226.243367) (xy 279.461204 -226.243367) (xy 279.461204 -226.190069) (xy 279.469147 -226.137365)
			(xy 279.484857 -226.086435) (xy 279.507983 -226.038414) (xy 279.538007 -225.994377) (xy 279.574259 -225.955306)
			(xy 279.61593 -225.922075) (xy 279.662088 -225.895426) (xy 279.711702 -225.875954) (xy 279.763664 -225.864094)
			(xy 279.816814 -225.860111) (xy 279.869964 -225.864094) (xy 279.921926 -225.875954) (xy 279.97154 -225.895426)
			(xy 280.017698 -225.922075) (xy 280.059369 -225.955306) (xy 280.095621 -225.994377) (xy 280.125645 -226.038414)
			(xy 280.148771 -226.086435) (xy 280.164481 -226.137365) (xy 280.172424 -226.190069) (xy 280.172922 -226.216718)
			(xy 280.172424 -226.243367) (xy 294.548804 -226.243367) (xy 294.548804 -226.190069) (xy 294.556747 -226.137365)
			(xy 294.572457 -226.086435) (xy 294.595583 -226.038414) (xy 294.625607 -225.994377) (xy 294.661859 -225.955306)
			(xy 294.70353 -225.922075) (xy 294.749688 -225.895426) (xy 294.799302 -225.875954) (xy 294.851264 -225.864094)
			(xy 294.904414 -225.860111) (xy 294.957564 -225.864094) (xy 295.009526 -225.875954) (xy 295.05914 -225.895426)
			(xy 295.105298 -225.922075) (xy 295.146969 -225.955306) (xy 295.183221 -225.994377) (xy 295.213245 -226.038414)
			(xy 295.236371 -226.086435) (xy 295.252081 -226.137365) (xy 295.260024 -226.190069) (xy 295.260522 -226.216718)
			(xy 295.260024 -226.243367) (xy 309.636404 -226.243367) (xy 309.636404 -226.190069) (xy 309.644347 -226.137365)
			(xy 309.660057 -226.086435) (xy 309.683183 -226.038414) (xy 309.713207 -225.994377) (xy 309.749459 -225.955306)
			(xy 309.79113 -225.922075) (xy 309.837288 -225.895426) (xy 309.886902 -225.875954) (xy 309.938864 -225.864094)
			(xy 309.992014 -225.860111) (xy 310.045164 -225.864094) (xy 310.097126 -225.875954) (xy 310.14674 -225.895426)
			(xy 310.192898 -225.922075) (xy 310.234569 -225.955306) (xy 310.270821 -225.994377) (xy 310.300845 -226.038414)
			(xy 310.323971 -226.086435) (xy 310.339681 -226.137365) (xy 310.347624 -226.190069) (xy 310.348122 -226.216718)
			(xy 310.347624 -226.243367) (xy 310.339681 -226.296071) (xy 310.323971 -226.347001) (xy 310.300845 -226.395022)
			(xy 310.270821 -226.439059) (xy 310.234569 -226.47813) (xy 310.192898 -226.511361) (xy 310.14674 -226.53801)
			(xy 310.097126 -226.557482) (xy 310.045164 -226.569342) (xy 309.992014 -226.573326) (xy 309.938864 -226.569342)
			(xy 309.886902 -226.557482) (xy 309.837288 -226.53801) (xy 309.79113 -226.511361) (xy 309.749459 -226.47813)
			(xy 309.713207 -226.439059) (xy 309.683183 -226.395022) (xy 309.660057 -226.347001) (xy 309.644347 -226.296071)
			(xy 309.636404 -226.243367) (xy 295.260024 -226.243367) (xy 295.252081 -226.296071) (xy 295.236371 -226.347001)
			(xy 295.213245 -226.395022) (xy 295.183221 -226.439059) (xy 295.146969 -226.47813) (xy 295.105298 -226.511361)
			(xy 295.05914 -226.53801) (xy 295.009526 -226.557482) (xy 294.957564 -226.569342) (xy 294.904414 -226.573326)
			(xy 294.851264 -226.569342) (xy 294.799302 -226.557482) (xy 294.749688 -226.53801) (xy 294.70353 -226.511361)
			(xy 294.661859 -226.47813) (xy 294.625607 -226.439059) (xy 294.595583 -226.395022) (xy 294.572457 -226.347001)
			(xy 294.556747 -226.296071) (xy 294.548804 -226.243367) (xy 280.172424 -226.243367) (xy 280.164481 -226.296071)
			(xy 280.148771 -226.347001) (xy 280.125645 -226.395022) (xy 280.095621 -226.439059) (xy 280.059369 -226.47813)
			(xy 280.017698 -226.511361) (xy 279.97154 -226.53801) (xy 279.921926 -226.557482) (xy 279.869964 -226.569342)
			(xy 279.816814 -226.573326) (xy 279.763664 -226.569342) (xy 279.711702 -226.557482) (xy 279.662088 -226.53801)
			(xy 279.61593 -226.511361) (xy 279.574259 -226.47813) (xy 279.538007 -226.439059) (xy 279.507983 -226.395022)
			(xy 279.484857 -226.347001) (xy 279.469147 -226.296071) (xy 279.461204 -226.243367) (xy 265.084824 -226.243367)
			(xy 265.076881 -226.296071) (xy 265.061171 -226.347001) (xy 265.038045 -226.395022) (xy 265.008021 -226.439059)
			(xy 264.971769 -226.47813) (xy 264.930098 -226.511361) (xy 264.88394 -226.53801) (xy 264.834326 -226.557482)
			(xy 264.782364 -226.569342) (xy 264.729214 -226.573326) (xy 264.676064 -226.569342) (xy 264.624102 -226.557482)
			(xy 264.574488 -226.53801) (xy 264.52833 -226.511361) (xy 264.486659 -226.47813) (xy 264.450407 -226.439059)
			(xy 264.420383 -226.395022) (xy 264.397257 -226.347001) (xy 264.381547 -226.296071) (xy 264.373604 -226.243367)
			(xy 254.20828 -226.243367) (xy 254.20828 -227.093251) (xy 268.473672 -227.093251) (xy 268.473672 -227.039953)
			(xy 268.481615 -226.987249) (xy 268.497325 -226.936319) (xy 268.520451 -226.888298) (xy 268.550475 -226.844261)
			(xy 268.586727 -226.80519) (xy 268.628398 -226.771959) (xy 268.674556 -226.74531) (xy 268.72417 -226.725838)
			(xy 268.776132 -226.713978) (xy 268.829282 -226.709995) (xy 268.882432 -226.713978) (xy 268.934394 -226.725838)
			(xy 268.984008 -226.74531) (xy 269.030166 -226.771959) (xy 269.071837 -226.80519) (xy 269.108089 -226.844261)
			(xy 269.138113 -226.888298) (xy 269.161239 -226.936319) (xy 269.176949 -226.987249) (xy 269.184892 -227.039953)
			(xy 269.18539 -227.066602) (xy 269.184892 -227.093251) (xy 283.561272 -227.093251) (xy 283.561272 -227.039953)
			(xy 283.569215 -226.987249) (xy 283.584925 -226.936319) (xy 283.608051 -226.888298) (xy 283.638075 -226.844261)
			(xy 283.674327 -226.80519) (xy 283.715998 -226.771959) (xy 283.762156 -226.74531) (xy 283.81177 -226.725838)
			(xy 283.863732 -226.713978) (xy 283.916882 -226.709995) (xy 283.970032 -226.713978) (xy 284.021994 -226.725838)
			(xy 284.071608 -226.74531) (xy 284.117766 -226.771959) (xy 284.159437 -226.80519) (xy 284.195689 -226.844261)
			(xy 284.225713 -226.888298) (xy 284.248839 -226.936319) (xy 284.264549 -226.987249) (xy 284.272492 -227.039953)
			(xy 284.27299 -227.066602) (xy 284.272492 -227.093251) (xy 298.648872 -227.093251) (xy 298.648872 -227.039953)
			(xy 298.656815 -226.987249) (xy 298.672525 -226.936319) (xy 298.695651 -226.888298) (xy 298.725675 -226.844261)
			(xy 298.761927 -226.80519) (xy 298.803598 -226.771959) (xy 298.849756 -226.74531) (xy 298.89937 -226.725838)
			(xy 298.951332 -226.713978) (xy 299.004482 -226.709995) (xy 299.057632 -226.713978) (xy 299.109594 -226.725838)
			(xy 299.159208 -226.74531) (xy 299.205366 -226.771959) (xy 299.247037 -226.80519) (xy 299.283289 -226.844261)
			(xy 299.313313 -226.888298) (xy 299.336439 -226.936319) (xy 299.352149 -226.987249) (xy 299.360092 -227.039953)
			(xy 299.36059 -227.066602) (xy 299.360092 -227.093251) (xy 299.352149 -227.145955) (xy 299.336439 -227.196885)
			(xy 299.313313 -227.244906) (xy 299.283289 -227.288943) (xy 299.247037 -227.328014) (xy 299.205366 -227.361245)
			(xy 299.159208 -227.387894) (xy 299.109594 -227.407366) (xy 299.057632 -227.419226) (xy 299.004482 -227.42321)
			(xy 298.951332 -227.419226) (xy 298.89937 -227.407366) (xy 298.849756 -227.387894) (xy 298.803598 -227.361245)
			(xy 298.761927 -227.328014) (xy 298.725675 -227.288943) (xy 298.695651 -227.244906) (xy 298.672525 -227.196885)
			(xy 298.656815 -227.145955) (xy 298.648872 -227.093251) (xy 284.272492 -227.093251) (xy 284.264549 -227.145955)
			(xy 284.248839 -227.196885) (xy 284.225713 -227.244906) (xy 284.195689 -227.288943) (xy 284.159437 -227.328014)
			(xy 284.117766 -227.361245) (xy 284.071608 -227.387894) (xy 284.021994 -227.407366) (xy 283.970032 -227.419226)
			(xy 283.916882 -227.42321) (xy 283.863732 -227.419226) (xy 283.81177 -227.407366) (xy 283.762156 -227.387894)
			(xy 283.715998 -227.361245) (xy 283.674327 -227.328014) (xy 283.638075 -227.288943) (xy 283.608051 -227.244906)
			(xy 283.584925 -227.196885) (xy 283.569215 -227.145955) (xy 283.561272 -227.093251) (xy 269.184892 -227.093251)
			(xy 269.176949 -227.145955) (xy 269.161239 -227.196885) (xy 269.138113 -227.244906) (xy 269.108089 -227.288943)
			(xy 269.071837 -227.328014) (xy 269.030166 -227.361245) (xy 268.984008 -227.387894) (xy 268.934394 -227.407366)
			(xy 268.882432 -227.419226) (xy 268.829282 -227.42321) (xy 268.776132 -227.419226) (xy 268.72417 -227.407366)
			(xy 268.674556 -227.387894) (xy 268.628398 -227.361245) (xy 268.586727 -227.328014) (xy 268.550475 -227.288943)
			(xy 268.520451 -227.244906) (xy 268.497325 -227.196885) (xy 268.481615 -227.145955) (xy 268.473672 -227.093251)
			(xy 254.20828 -227.093251) (xy 254.20828 -227.943389) (xy 264.373604 -227.943389) (xy 264.373604 -227.890091)
			(xy 264.381547 -227.837387) (xy 264.397257 -227.786457) (xy 264.420383 -227.738436) (xy 264.450407 -227.694399)
			(xy 264.486659 -227.655328) (xy 264.52833 -227.622097) (xy 264.574488 -227.595448) (xy 264.624102 -227.575976)
			(xy 264.676064 -227.564116) (xy 264.729214 -227.560133) (xy 264.782364 -227.564116) (xy 264.834326 -227.575976)
			(xy 264.88394 -227.595448) (xy 264.930098 -227.622097) (xy 264.971769 -227.655328) (xy 265.008021 -227.694399)
			(xy 265.038045 -227.738436) (xy 265.061171 -227.786457) (xy 265.076881 -227.837387) (xy 265.084824 -227.890091)
			(xy 265.085322 -227.91674) (xy 265.084824 -227.943389) (xy 268.473672 -227.943389) (xy 268.473672 -227.890091)
			(xy 268.481615 -227.837387) (xy 268.497325 -227.786457) (xy 268.520451 -227.738436) (xy 268.550475 -227.694399)
			(xy 268.586727 -227.655328) (xy 268.628398 -227.622097) (xy 268.674556 -227.595448) (xy 268.72417 -227.575976)
			(xy 268.776132 -227.564116) (xy 268.829282 -227.560133) (xy 268.882432 -227.564116) (xy 268.934394 -227.575976)
			(xy 268.984008 -227.595448) (xy 269.030166 -227.622097) (xy 269.071837 -227.655328) (xy 269.108089 -227.694399)
			(xy 269.138113 -227.738436) (xy 269.161239 -227.786457) (xy 269.176949 -227.837387) (xy 269.184892 -227.890091)
			(xy 269.18539 -227.91674) (xy 269.184892 -227.943389) (xy 279.461204 -227.943389) (xy 279.461204 -227.890091)
			(xy 279.469147 -227.837387) (xy 279.484857 -227.786457) (xy 279.507983 -227.738436) (xy 279.538007 -227.694399)
			(xy 279.574259 -227.655328) (xy 279.61593 -227.622097) (xy 279.662088 -227.595448) (xy 279.711702 -227.575976)
			(xy 279.763664 -227.564116) (xy 279.816814 -227.560133) (xy 279.869964 -227.564116) (xy 279.921926 -227.575976)
			(xy 279.97154 -227.595448) (xy 280.017698 -227.622097) (xy 280.059369 -227.655328) (xy 280.095621 -227.694399)
			(xy 280.125645 -227.738436) (xy 280.148771 -227.786457) (xy 280.164481 -227.837387) (xy 280.172424 -227.890091)
			(xy 280.172922 -227.91674) (xy 280.172424 -227.943389) (xy 283.561272 -227.943389) (xy 283.561272 -227.890091)
			(xy 283.569215 -227.837387) (xy 283.584925 -227.786457) (xy 283.608051 -227.738436) (xy 283.638075 -227.694399)
			(xy 283.674327 -227.655328) (xy 283.715998 -227.622097) (xy 283.762156 -227.595448) (xy 283.81177 -227.575976)
			(xy 283.863732 -227.564116) (xy 283.916882 -227.560133) (xy 283.970032 -227.564116) (xy 284.021994 -227.575976)
			(xy 284.071608 -227.595448) (xy 284.117766 -227.622097) (xy 284.159437 -227.655328) (xy 284.195689 -227.694399)
			(xy 284.225713 -227.738436) (xy 284.248839 -227.786457) (xy 284.264549 -227.837387) (xy 284.272492 -227.890091)
			(xy 284.27299 -227.91674) (xy 284.272492 -227.943389) (xy 294.548804 -227.943389) (xy 294.548804 -227.890091)
			(xy 294.556747 -227.837387) (xy 294.572457 -227.786457) (xy 294.595583 -227.738436) (xy 294.625607 -227.694399)
			(xy 294.661859 -227.655328) (xy 294.70353 -227.622097) (xy 294.749688 -227.595448) (xy 294.799302 -227.575976)
			(xy 294.851264 -227.564116) (xy 294.904414 -227.560133) (xy 294.957564 -227.564116) (xy 295.009526 -227.575976)
			(xy 295.05914 -227.595448) (xy 295.105298 -227.622097) (xy 295.146969 -227.655328) (xy 295.183221 -227.694399)
			(xy 295.213245 -227.738436) (xy 295.236371 -227.786457) (xy 295.252081 -227.837387) (xy 295.260024 -227.890091)
			(xy 295.260522 -227.91674) (xy 295.260024 -227.943389) (xy 298.648872 -227.943389) (xy 298.648872 -227.890091)
			(xy 298.656815 -227.837387) (xy 298.672525 -227.786457) (xy 298.695651 -227.738436) (xy 298.725675 -227.694399)
			(xy 298.761927 -227.655328) (xy 298.803598 -227.622097) (xy 298.849756 -227.595448) (xy 298.89937 -227.575976)
			(xy 298.951332 -227.564116) (xy 299.004482 -227.560133) (xy 299.057632 -227.564116) (xy 299.109594 -227.575976)
			(xy 299.159208 -227.595448) (xy 299.205366 -227.622097) (xy 299.247037 -227.655328) (xy 299.283289 -227.694399)
			(xy 299.313313 -227.738436) (xy 299.336439 -227.786457) (xy 299.352149 -227.837387) (xy 299.360092 -227.890091)
			(xy 299.36059 -227.91674) (xy 299.360092 -227.943389) (xy 309.636404 -227.943389) (xy 309.636404 -227.890091)
			(xy 309.644347 -227.837387) (xy 309.660057 -227.786457) (xy 309.683183 -227.738436) (xy 309.713207 -227.694399)
			(xy 309.749459 -227.655328) (xy 309.79113 -227.622097) (xy 309.837288 -227.595448) (xy 309.886902 -227.575976)
			(xy 309.938864 -227.564116) (xy 309.992014 -227.560133) (xy 310.045164 -227.564116) (xy 310.097126 -227.575976)
			(xy 310.14674 -227.595448) (xy 310.192898 -227.622097) (xy 310.234569 -227.655328) (xy 310.270821 -227.694399)
			(xy 310.300845 -227.738436) (xy 310.323971 -227.786457) (xy 310.339681 -227.837387) (xy 310.347624 -227.890091)
			(xy 310.348122 -227.91674) (xy 310.347624 -227.943389) (xy 310.339681 -227.996093) (xy 310.323971 -228.047023)
			(xy 310.300845 -228.095044) (xy 310.270821 -228.139081) (xy 310.234569 -228.178152) (xy 310.192898 -228.211383)
			(xy 310.14674 -228.238032) (xy 310.097126 -228.257504) (xy 310.045164 -228.269364) (xy 309.992014 -228.273348)
			(xy 309.938864 -228.269364) (xy 309.886902 -228.257504) (xy 309.837288 -228.238032) (xy 309.79113 -228.211383)
			(xy 309.749459 -228.178152) (xy 309.713207 -228.139081) (xy 309.683183 -228.095044) (xy 309.660057 -228.047023)
			(xy 309.644347 -227.996093) (xy 309.636404 -227.943389) (xy 299.360092 -227.943389) (xy 299.352149 -227.996093)
			(xy 299.336439 -228.047023) (xy 299.313313 -228.095044) (xy 299.283289 -228.139081) (xy 299.247037 -228.178152)
			(xy 299.205366 -228.211383) (xy 299.159208 -228.238032) (xy 299.109594 -228.257504) (xy 299.057632 -228.269364)
			(xy 299.004482 -228.273348) (xy 298.951332 -228.269364) (xy 298.89937 -228.257504) (xy 298.849756 -228.238032)
			(xy 298.803598 -228.211383) (xy 298.761927 -228.178152) (xy 298.725675 -228.139081) (xy 298.695651 -228.095044)
			(xy 298.672525 -228.047023) (xy 298.656815 -227.996093) (xy 298.648872 -227.943389) (xy 295.260024 -227.943389)
			(xy 295.252081 -227.996093) (xy 295.236371 -228.047023) (xy 295.213245 -228.095044) (xy 295.183221 -228.139081)
			(xy 295.146969 -228.178152) (xy 295.105298 -228.211383) (xy 295.05914 -228.238032) (xy 295.009526 -228.257504)
			(xy 294.957564 -228.269364) (xy 294.904414 -228.273348) (xy 294.851264 -228.269364) (xy 294.799302 -228.257504)
			(xy 294.749688 -228.238032) (xy 294.70353 -228.211383) (xy 294.661859 -228.178152) (xy 294.625607 -228.139081)
			(xy 294.595583 -228.095044) (xy 294.572457 -228.047023) (xy 294.556747 -227.996093) (xy 294.548804 -227.943389)
			(xy 284.272492 -227.943389) (xy 284.264549 -227.996093) (xy 284.248839 -228.047023) (xy 284.225713 -228.095044)
			(xy 284.195689 -228.139081) (xy 284.159437 -228.178152) (xy 284.117766 -228.211383) (xy 284.071608 -228.238032)
			(xy 284.021994 -228.257504) (xy 283.970032 -228.269364) (xy 283.916882 -228.273348) (xy 283.863732 -228.269364)
			(xy 283.81177 -228.257504) (xy 283.762156 -228.238032) (xy 283.715998 -228.211383) (xy 283.674327 -228.178152)
			(xy 283.638075 -228.139081) (xy 283.608051 -228.095044) (xy 283.584925 -228.047023) (xy 283.569215 -227.996093)
			(xy 283.561272 -227.943389) (xy 280.172424 -227.943389) (xy 280.164481 -227.996093) (xy 280.148771 -228.047023)
			(xy 280.125645 -228.095044) (xy 280.095621 -228.139081) (xy 280.059369 -228.178152) (xy 280.017698 -228.211383)
			(xy 279.97154 -228.238032) (xy 279.921926 -228.257504) (xy 279.869964 -228.269364) (xy 279.816814 -228.273348)
			(xy 279.763664 -228.269364) (xy 279.711702 -228.257504) (xy 279.662088 -228.238032) (xy 279.61593 -228.211383)
			(xy 279.574259 -228.178152) (xy 279.538007 -228.139081) (xy 279.507983 -228.095044) (xy 279.484857 -228.047023)
			(xy 279.469147 -227.996093) (xy 279.461204 -227.943389) (xy 269.184892 -227.943389) (xy 269.176949 -227.996093)
			(xy 269.161239 -228.047023) (xy 269.138113 -228.095044) (xy 269.108089 -228.139081) (xy 269.071837 -228.178152)
			(xy 269.030166 -228.211383) (xy 268.984008 -228.238032) (xy 268.934394 -228.257504) (xy 268.882432 -228.269364)
			(xy 268.829282 -228.273348) (xy 268.776132 -228.269364) (xy 268.72417 -228.257504) (xy 268.674556 -228.238032)
			(xy 268.628398 -228.211383) (xy 268.586727 -228.178152) (xy 268.550475 -228.139081) (xy 268.520451 -228.095044)
			(xy 268.497325 -228.047023) (xy 268.481615 -227.996093) (xy 268.473672 -227.943389) (xy 265.084824 -227.943389)
			(xy 265.076881 -227.996093) (xy 265.061171 -228.047023) (xy 265.038045 -228.095044) (xy 265.008021 -228.139081)
			(xy 264.971769 -228.178152) (xy 264.930098 -228.211383) (xy 264.88394 -228.238032) (xy 264.834326 -228.257504)
			(xy 264.782364 -228.269364) (xy 264.729214 -228.273348) (xy 264.676064 -228.269364) (xy 264.624102 -228.257504)
			(xy 264.574488 -228.238032) (xy 264.52833 -228.211383) (xy 264.486659 -228.178152) (xy 264.450407 -228.139081)
			(xy 264.420383 -228.095044) (xy 264.397257 -228.047023) (xy 264.381547 -227.996093) (xy 264.373604 -227.943389)
			(xy 254.20828 -227.943389) (xy 254.20828 -228.793273) (xy 264.373604 -228.793273) (xy 264.373604 -228.739975)
			(xy 264.381547 -228.687271) (xy 264.397257 -228.636341) (xy 264.420383 -228.58832) (xy 264.450407 -228.544283)
			(xy 264.486659 -228.505212) (xy 264.52833 -228.471981) (xy 264.574488 -228.445332) (xy 264.624102 -228.42586)
			(xy 264.676064 -228.414) (xy 264.729214 -228.410017) (xy 264.782364 -228.414) (xy 264.834326 -228.42586)
			(xy 264.88394 -228.445332) (xy 264.930098 -228.471981) (xy 264.971769 -228.505212) (xy 265.008021 -228.544283)
			(xy 265.038045 -228.58832) (xy 265.061171 -228.636341) (xy 265.076881 -228.687271) (xy 265.084824 -228.739975)
			(xy 265.085322 -228.766624) (xy 265.084824 -228.793273) (xy 279.461204 -228.793273) (xy 279.461204 -228.739975)
			(xy 279.469147 -228.687271) (xy 279.484857 -228.636341) (xy 279.507983 -228.58832) (xy 279.538007 -228.544283)
			(xy 279.574259 -228.505212) (xy 279.61593 -228.471981) (xy 279.662088 -228.445332) (xy 279.711702 -228.42586)
			(xy 279.763664 -228.414) (xy 279.816814 -228.410017) (xy 279.869964 -228.414) (xy 279.921926 -228.42586)
			(xy 279.97154 -228.445332) (xy 280.017698 -228.471981) (xy 280.059369 -228.505212) (xy 280.095621 -228.544283)
			(xy 280.125645 -228.58832) (xy 280.148771 -228.636341) (xy 280.164481 -228.687271) (xy 280.172424 -228.739975)
			(xy 280.172922 -228.766624) (xy 280.172424 -228.793273) (xy 294.548804 -228.793273) (xy 294.548804 -228.739975)
			(xy 294.556747 -228.687271) (xy 294.572457 -228.636341) (xy 294.595583 -228.58832) (xy 294.625607 -228.544283)
			(xy 294.661859 -228.505212) (xy 294.70353 -228.471981) (xy 294.749688 -228.445332) (xy 294.799302 -228.42586)
			(xy 294.851264 -228.414) (xy 294.904414 -228.410017) (xy 294.957564 -228.414) (xy 295.009526 -228.42586)
			(xy 295.05914 -228.445332) (xy 295.105298 -228.471981) (xy 295.146969 -228.505212) (xy 295.183221 -228.544283)
			(xy 295.213245 -228.58832) (xy 295.236371 -228.636341) (xy 295.252081 -228.687271) (xy 295.260024 -228.739975)
			(xy 295.260522 -228.766624) (xy 295.260024 -228.793273) (xy 309.636404 -228.793273) (xy 309.636404 -228.739975)
			(xy 309.644347 -228.687271) (xy 309.660057 -228.636341) (xy 309.683183 -228.58832) (xy 309.713207 -228.544283)
			(xy 309.749459 -228.505212) (xy 309.79113 -228.471981) (xy 309.837288 -228.445332) (xy 309.886902 -228.42586)
			(xy 309.938864 -228.414) (xy 309.992014 -228.410017) (xy 310.045164 -228.414) (xy 310.097126 -228.42586)
			(xy 310.14674 -228.445332) (xy 310.192898 -228.471981) (xy 310.234569 -228.505212) (xy 310.270821 -228.544283)
			(xy 310.300845 -228.58832) (xy 310.323971 -228.636341) (xy 310.339681 -228.687271) (xy 310.347624 -228.739975)
			(xy 310.348122 -228.766624) (xy 310.347624 -228.793273) (xy 310.339681 -228.845977) (xy 310.323971 -228.896907)
			(xy 310.300845 -228.944928) (xy 310.270821 -228.988965) (xy 310.234569 -229.028036) (xy 310.192898 -229.061267)
			(xy 310.14674 -229.087916) (xy 310.097126 -229.107388) (xy 310.045164 -229.119248) (xy 309.992014 -229.123232)
			(xy 309.938864 -229.119248) (xy 309.886902 -229.107388) (xy 309.837288 -229.087916) (xy 309.79113 -229.061267)
			(xy 309.749459 -229.028036) (xy 309.713207 -228.988965) (xy 309.683183 -228.944928) (xy 309.660057 -228.896907)
			(xy 309.644347 -228.845977) (xy 309.636404 -228.793273) (xy 295.260024 -228.793273) (xy 295.252081 -228.845977)
			(xy 295.236371 -228.896907) (xy 295.213245 -228.944928) (xy 295.183221 -228.988965) (xy 295.146969 -229.028036)
			(xy 295.105298 -229.061267) (xy 295.05914 -229.087916) (xy 295.009526 -229.107388) (xy 294.957564 -229.119248)
			(xy 294.904414 -229.123232) (xy 294.851264 -229.119248) (xy 294.799302 -229.107388) (xy 294.749688 -229.087916)
			(xy 294.70353 -229.061267) (xy 294.661859 -229.028036) (xy 294.625607 -228.988965) (xy 294.595583 -228.944928)
			(xy 294.572457 -228.896907) (xy 294.556747 -228.845977) (xy 294.548804 -228.793273) (xy 280.172424 -228.793273)
			(xy 280.164481 -228.845977) (xy 280.148771 -228.896907) (xy 280.125645 -228.944928) (xy 280.095621 -228.988965)
			(xy 280.059369 -229.028036) (xy 280.017698 -229.061267) (xy 279.97154 -229.087916) (xy 279.921926 -229.107388)
			(xy 279.869964 -229.119248) (xy 279.816814 -229.123232) (xy 279.763664 -229.119248) (xy 279.711702 -229.107388)
			(xy 279.662088 -229.087916) (xy 279.61593 -229.061267) (xy 279.574259 -229.028036) (xy 279.538007 -228.988965)
			(xy 279.507983 -228.944928) (xy 279.484857 -228.896907) (xy 279.469147 -228.845977) (xy 279.461204 -228.793273)
			(xy 265.084824 -228.793273) (xy 265.076881 -228.845977) (xy 265.061171 -228.896907) (xy 265.038045 -228.944928)
			(xy 265.008021 -228.988965) (xy 264.971769 -229.028036) (xy 264.930098 -229.061267) (xy 264.88394 -229.087916)
			(xy 264.834326 -229.107388) (xy 264.782364 -229.119248) (xy 264.729214 -229.123232) (xy 264.676064 -229.119248)
			(xy 264.624102 -229.107388) (xy 264.574488 -229.087916) (xy 264.52833 -229.061267) (xy 264.486659 -229.028036)
			(xy 264.450407 -228.988965) (xy 264.420383 -228.944928) (xy 264.397257 -228.896907) (xy 264.381547 -228.845977)
			(xy 264.373604 -228.793273) (xy 254.20828 -228.793273) (xy 254.20828 -229.643411) (xy 268.473672 -229.643411)
			(xy 268.473672 -229.590113) (xy 268.481615 -229.537409) (xy 268.497325 -229.486479) (xy 268.520451 -229.438458)
			(xy 268.550475 -229.394421) (xy 268.586727 -229.35535) (xy 268.628398 -229.322119) (xy 268.674556 -229.29547)
			(xy 268.72417 -229.275998) (xy 268.776132 -229.264138) (xy 268.829282 -229.260155) (xy 268.882432 -229.264138)
			(xy 268.934394 -229.275998) (xy 268.984008 -229.29547) (xy 269.030166 -229.322119) (xy 269.071837 -229.35535)
			(xy 269.108089 -229.394421) (xy 269.138113 -229.438458) (xy 269.161239 -229.486479) (xy 269.176949 -229.537409)
			(xy 269.184892 -229.590113) (xy 269.18539 -229.616762) (xy 269.184892 -229.643411) (xy 283.561272 -229.643411)
			(xy 283.561272 -229.590113) (xy 283.569215 -229.537409) (xy 283.584925 -229.486479) (xy 283.608051 -229.438458)
			(xy 283.638075 -229.394421) (xy 283.674327 -229.35535) (xy 283.715998 -229.322119) (xy 283.762156 -229.29547)
			(xy 283.81177 -229.275998) (xy 283.863732 -229.264138) (xy 283.916882 -229.260155) (xy 283.970032 -229.264138)
			(xy 284.021994 -229.275998) (xy 284.071608 -229.29547) (xy 284.117766 -229.322119) (xy 284.159437 -229.35535)
			(xy 284.195689 -229.394421) (xy 284.225713 -229.438458) (xy 284.248839 -229.486479) (xy 284.264549 -229.537409)
			(xy 284.272492 -229.590113) (xy 284.27299 -229.616762) (xy 284.272492 -229.643411) (xy 298.648872 -229.643411)
			(xy 298.648872 -229.590113) (xy 298.656815 -229.537409) (xy 298.672525 -229.486479) (xy 298.695651 -229.438458)
			(xy 298.725675 -229.394421) (xy 298.761927 -229.35535) (xy 298.803598 -229.322119) (xy 298.849756 -229.29547)
			(xy 298.89937 -229.275998) (xy 298.951332 -229.264138) (xy 299.004482 -229.260155) (xy 299.057632 -229.264138)
			(xy 299.109594 -229.275998) (xy 299.159208 -229.29547) (xy 299.205366 -229.322119) (xy 299.247037 -229.35535)
			(xy 299.283289 -229.394421) (xy 299.313313 -229.438458) (xy 299.336439 -229.486479) (xy 299.352149 -229.537409)
			(xy 299.360092 -229.590113) (xy 299.36059 -229.616762) (xy 299.360092 -229.643411) (xy 299.352149 -229.696115)
			(xy 299.336439 -229.747045) (xy 299.313313 -229.795066) (xy 299.283289 -229.839103) (xy 299.247037 -229.878174)
			(xy 299.205366 -229.911405) (xy 299.159208 -229.938054) (xy 299.109594 -229.957526) (xy 299.057632 -229.969386)
			(xy 299.004482 -229.97337) (xy 298.951332 -229.969386) (xy 298.89937 -229.957526) (xy 298.849756 -229.938054)
			(xy 298.803598 -229.911405) (xy 298.761927 -229.878174) (xy 298.725675 -229.839103) (xy 298.695651 -229.795066)
			(xy 298.672525 -229.747045) (xy 298.656815 -229.696115) (xy 298.648872 -229.643411) (xy 284.272492 -229.643411)
			(xy 284.264549 -229.696115) (xy 284.248839 -229.747045) (xy 284.225713 -229.795066) (xy 284.195689 -229.839103)
			(xy 284.159437 -229.878174) (xy 284.117766 -229.911405) (xy 284.071608 -229.938054) (xy 284.021994 -229.957526)
			(xy 283.970032 -229.969386) (xy 283.916882 -229.97337) (xy 283.863732 -229.969386) (xy 283.81177 -229.957526)
			(xy 283.762156 -229.938054) (xy 283.715998 -229.911405) (xy 283.674327 -229.878174) (xy 283.638075 -229.839103)
			(xy 283.608051 -229.795066) (xy 283.584925 -229.747045) (xy 283.569215 -229.696115) (xy 283.561272 -229.643411)
			(xy 269.184892 -229.643411) (xy 269.176949 -229.696115) (xy 269.161239 -229.747045) (xy 269.138113 -229.795066)
			(xy 269.108089 -229.839103) (xy 269.071837 -229.878174) (xy 269.030166 -229.911405) (xy 268.984008 -229.938054)
			(xy 268.934394 -229.957526) (xy 268.882432 -229.969386) (xy 268.829282 -229.97337) (xy 268.776132 -229.969386)
			(xy 268.72417 -229.957526) (xy 268.674556 -229.938054) (xy 268.628398 -229.911405) (xy 268.586727 -229.878174)
			(xy 268.550475 -229.839103) (xy 268.520451 -229.795066) (xy 268.497325 -229.747045) (xy 268.481615 -229.696115)
			(xy 268.473672 -229.643411) (xy 254.20828 -229.643411) (xy 254.20828 -230.493295) (xy 264.373604 -230.493295)
			(xy 264.373604 -230.439997) (xy 264.381547 -230.387293) (xy 264.397257 -230.336363) (xy 264.420383 -230.288342)
			(xy 264.450407 -230.244305) (xy 264.486659 -230.205234) (xy 264.52833 -230.172003) (xy 264.574488 -230.145354)
			(xy 264.624102 -230.125882) (xy 264.676064 -230.114022) (xy 264.729214 -230.110039) (xy 264.782364 -230.114022)
			(xy 264.834326 -230.125882) (xy 264.88394 -230.145354) (xy 264.930098 -230.172003) (xy 264.971769 -230.205234)
			(xy 265.008021 -230.244305) (xy 265.038045 -230.288342) (xy 265.061171 -230.336363) (xy 265.076881 -230.387293)
			(xy 265.084824 -230.439997) (xy 265.085322 -230.466646) (xy 265.084824 -230.493295) (xy 279.461204 -230.493295)
			(xy 279.461204 -230.439997) (xy 279.469147 -230.387293) (xy 279.484857 -230.336363) (xy 279.507983 -230.288342)
			(xy 279.538007 -230.244305) (xy 279.574259 -230.205234) (xy 279.61593 -230.172003) (xy 279.662088 -230.145354)
			(xy 279.711702 -230.125882) (xy 279.763664 -230.114022) (xy 279.816814 -230.110039) (xy 279.869964 -230.114022)
			(xy 279.921926 -230.125882) (xy 279.97154 -230.145354) (xy 280.017698 -230.172003) (xy 280.059369 -230.205234)
			(xy 280.095621 -230.244305) (xy 280.125645 -230.288342) (xy 280.148771 -230.336363) (xy 280.164481 -230.387293)
			(xy 280.172424 -230.439997) (xy 280.172922 -230.466646) (xy 280.172424 -230.493295) (xy 294.548804 -230.493295)
			(xy 294.548804 -230.439997) (xy 294.556747 -230.387293) (xy 294.572457 -230.336363) (xy 294.595583 -230.288342)
			(xy 294.625607 -230.244305) (xy 294.661859 -230.205234) (xy 294.70353 -230.172003) (xy 294.749688 -230.145354)
			(xy 294.799302 -230.125882) (xy 294.851264 -230.114022) (xy 294.904414 -230.110039) (xy 294.957564 -230.114022)
			(xy 295.009526 -230.125882) (xy 295.05914 -230.145354) (xy 295.105298 -230.172003) (xy 295.146969 -230.205234)
			(xy 295.183221 -230.244305) (xy 295.213245 -230.288342) (xy 295.236371 -230.336363) (xy 295.252081 -230.387293)
			(xy 295.260024 -230.439997) (xy 295.260522 -230.466646) (xy 295.260024 -230.493295) (xy 309.636404 -230.493295)
			(xy 309.636404 -230.439997) (xy 309.644347 -230.387293) (xy 309.660057 -230.336363) (xy 309.683183 -230.288342)
			(xy 309.713207 -230.244305) (xy 309.749459 -230.205234) (xy 309.79113 -230.172003) (xy 309.837288 -230.145354)
			(xy 309.886902 -230.125882) (xy 309.938864 -230.114022) (xy 309.992014 -230.110039) (xy 310.045164 -230.114022)
			(xy 310.097126 -230.125882) (xy 310.14674 -230.145354) (xy 310.192898 -230.172003) (xy 310.234569 -230.205234)
			(xy 310.270821 -230.244305) (xy 310.300845 -230.288342) (xy 310.323971 -230.336363) (xy 310.339681 -230.387293)
			(xy 310.347624 -230.439997) (xy 310.348122 -230.466646) (xy 310.347624 -230.493295) (xy 310.339681 -230.545999)
			(xy 310.323971 -230.596929) (xy 310.300845 -230.64495) (xy 310.270821 -230.688987) (xy 310.234569 -230.728058)
			(xy 310.192898 -230.761289) (xy 310.14674 -230.787938) (xy 310.097126 -230.80741) (xy 310.045164 -230.81927)
			(xy 309.992014 -230.823254) (xy 309.938864 -230.81927) (xy 309.886902 -230.80741) (xy 309.837288 -230.787938)
			(xy 309.79113 -230.761289) (xy 309.749459 -230.728058) (xy 309.713207 -230.688987) (xy 309.683183 -230.64495)
			(xy 309.660057 -230.596929) (xy 309.644347 -230.545999) (xy 309.636404 -230.493295) (xy 295.260024 -230.493295)
			(xy 295.252081 -230.545999) (xy 295.236371 -230.596929) (xy 295.213245 -230.64495) (xy 295.183221 -230.688987)
			(xy 295.146969 -230.728058) (xy 295.105298 -230.761289) (xy 295.05914 -230.787938) (xy 295.009526 -230.80741)
			(xy 294.957564 -230.81927) (xy 294.904414 -230.823254) (xy 294.851264 -230.81927) (xy 294.799302 -230.80741)
			(xy 294.749688 -230.787938) (xy 294.70353 -230.761289) (xy 294.661859 -230.728058) (xy 294.625607 -230.688987)
			(xy 294.595583 -230.64495) (xy 294.572457 -230.596929) (xy 294.556747 -230.545999) (xy 294.548804 -230.493295)
			(xy 280.172424 -230.493295) (xy 280.164481 -230.545999) (xy 280.148771 -230.596929) (xy 280.125645 -230.64495)
			(xy 280.095621 -230.688987) (xy 280.059369 -230.728058) (xy 280.017698 -230.761289) (xy 279.97154 -230.787938)
			(xy 279.921926 -230.80741) (xy 279.869964 -230.81927) (xy 279.816814 -230.823254) (xy 279.763664 -230.81927)
			(xy 279.711702 -230.80741) (xy 279.662088 -230.787938) (xy 279.61593 -230.761289) (xy 279.574259 -230.728058)
			(xy 279.538007 -230.688987) (xy 279.507983 -230.64495) (xy 279.484857 -230.596929) (xy 279.469147 -230.545999)
			(xy 279.461204 -230.493295) (xy 265.084824 -230.493295) (xy 265.076881 -230.545999) (xy 265.061171 -230.596929)
			(xy 265.038045 -230.64495) (xy 265.008021 -230.688987) (xy 264.971769 -230.728058) (xy 264.930098 -230.761289)
			(xy 264.88394 -230.787938) (xy 264.834326 -230.80741) (xy 264.782364 -230.81927) (xy 264.729214 -230.823254)
			(xy 264.676064 -230.81927) (xy 264.624102 -230.80741) (xy 264.574488 -230.787938) (xy 264.52833 -230.761289)
			(xy 264.486659 -230.728058) (xy 264.450407 -230.688987) (xy 264.420383 -230.64495) (xy 264.397257 -230.596929)
			(xy 264.381547 -230.545999) (xy 264.373604 -230.493295) (xy 254.20828 -230.493295) (xy 254.20828 -231.343433)
			(xy 268.473672 -231.343433) (xy 268.473672 -231.290135) (xy 268.481615 -231.237431) (xy 268.497325 -231.186501)
			(xy 268.520451 -231.13848) (xy 268.550475 -231.094443) (xy 268.586727 -231.055372) (xy 268.628398 -231.022141)
			(xy 268.674556 -230.995492) (xy 268.72417 -230.97602) (xy 268.776132 -230.96416) (xy 268.829282 -230.960177)
			(xy 268.882432 -230.96416) (xy 268.934394 -230.97602) (xy 268.984008 -230.995492) (xy 269.030166 -231.022141)
			(xy 269.071837 -231.055372) (xy 269.108089 -231.094443) (xy 269.138113 -231.13848) (xy 269.161239 -231.186501)
			(xy 269.176949 -231.237431) (xy 269.184892 -231.290135) (xy 269.18539 -231.316784) (xy 269.184892 -231.343433)
			(xy 283.561272 -231.343433) (xy 283.561272 -231.290135) (xy 283.569215 -231.237431) (xy 283.584925 -231.186501)
			(xy 283.608051 -231.13848) (xy 283.638075 -231.094443) (xy 283.674327 -231.055372) (xy 283.715998 -231.022141)
			(xy 283.762156 -230.995492) (xy 283.81177 -230.97602) (xy 283.863732 -230.96416) (xy 283.916882 -230.960177)
			(xy 283.970032 -230.96416) (xy 284.021994 -230.97602) (xy 284.071608 -230.995492) (xy 284.117766 -231.022141)
			(xy 284.159437 -231.055372) (xy 284.195689 -231.094443) (xy 284.225713 -231.13848) (xy 284.248839 -231.186501)
			(xy 284.264549 -231.237431) (xy 284.272492 -231.290135) (xy 284.27299 -231.316784) (xy 284.272492 -231.343433)
			(xy 298.648872 -231.343433) (xy 298.648872 -231.290135) (xy 298.656815 -231.237431) (xy 298.672525 -231.186501)
			(xy 298.695651 -231.13848) (xy 298.725675 -231.094443) (xy 298.761927 -231.055372) (xy 298.803598 -231.022141)
			(xy 298.849756 -230.995492) (xy 298.89937 -230.97602) (xy 298.951332 -230.96416) (xy 299.004482 -230.960177)
			(xy 299.057632 -230.96416) (xy 299.109594 -230.97602) (xy 299.159208 -230.995492) (xy 299.205366 -231.022141)
			(xy 299.247037 -231.055372) (xy 299.283289 -231.094443) (xy 299.313313 -231.13848) (xy 299.336439 -231.186501)
			(xy 299.352149 -231.237431) (xy 299.360092 -231.290135) (xy 299.36059 -231.316784) (xy 299.360092 -231.343433)
			(xy 299.352149 -231.396137) (xy 299.336439 -231.447067) (xy 299.313313 -231.495088) (xy 299.283289 -231.539125)
			(xy 299.247037 -231.578196) (xy 299.205366 -231.611427) (xy 299.159208 -231.638076) (xy 299.109594 -231.657548)
			(xy 299.057632 -231.669408) (xy 299.004482 -231.673392) (xy 298.951332 -231.669408) (xy 298.89937 -231.657548)
			(xy 298.849756 -231.638076) (xy 298.803598 -231.611427) (xy 298.761927 -231.578196) (xy 298.725675 -231.539125)
			(xy 298.695651 -231.495088) (xy 298.672525 -231.447067) (xy 298.656815 -231.396137) (xy 298.648872 -231.343433)
			(xy 284.272492 -231.343433) (xy 284.264549 -231.396137) (xy 284.248839 -231.447067) (xy 284.225713 -231.495088)
			(xy 284.195689 -231.539125) (xy 284.159437 -231.578196) (xy 284.117766 -231.611427) (xy 284.071608 -231.638076)
			(xy 284.021994 -231.657548) (xy 283.970032 -231.669408) (xy 283.916882 -231.673392) (xy 283.863732 -231.669408)
			(xy 283.81177 -231.657548) (xy 283.762156 -231.638076) (xy 283.715998 -231.611427) (xy 283.674327 -231.578196)
			(xy 283.638075 -231.539125) (xy 283.608051 -231.495088) (xy 283.584925 -231.447067) (xy 283.569215 -231.396137)
			(xy 283.561272 -231.343433) (xy 269.184892 -231.343433) (xy 269.176949 -231.396137) (xy 269.161239 -231.447067)
			(xy 269.138113 -231.495088) (xy 269.108089 -231.539125) (xy 269.071837 -231.578196) (xy 269.030166 -231.611427)
			(xy 268.984008 -231.638076) (xy 268.934394 -231.657548) (xy 268.882432 -231.669408) (xy 268.829282 -231.673392)
			(xy 268.776132 -231.669408) (xy 268.72417 -231.657548) (xy 268.674556 -231.638076) (xy 268.628398 -231.611427)
			(xy 268.586727 -231.578196) (xy 268.550475 -231.539125) (xy 268.520451 -231.495088) (xy 268.497325 -231.447067)
			(xy 268.481615 -231.396137) (xy 268.473672 -231.343433) (xy 254.20828 -231.343433) (xy 254.20828 -232.193317)
			(xy 264.373604 -232.193317) (xy 264.373604 -232.140019) (xy 264.381547 -232.087315) (xy 264.397257 -232.036385)
			(xy 264.420383 -231.988364) (xy 264.450407 -231.944327) (xy 264.486659 -231.905256) (xy 264.52833 -231.872025)
			(xy 264.574488 -231.845376) (xy 264.624102 -231.825904) (xy 264.676064 -231.814044) (xy 264.729214 -231.810061)
			(xy 264.782364 -231.814044) (xy 264.834326 -231.825904) (xy 264.88394 -231.845376) (xy 264.930098 -231.872025)
			(xy 264.971769 -231.905256) (xy 265.008021 -231.944327) (xy 265.038045 -231.988364) (xy 265.061171 -232.036385)
			(xy 265.076881 -232.087315) (xy 265.084824 -232.140019) (xy 265.085322 -232.166668) (xy 265.084824 -232.193317)
			(xy 279.461204 -232.193317) (xy 279.461204 -232.140019) (xy 279.469147 -232.087315) (xy 279.484857 -232.036385)
			(xy 279.507983 -231.988364) (xy 279.538007 -231.944327) (xy 279.574259 -231.905256) (xy 279.61593 -231.872025)
			(xy 279.662088 -231.845376) (xy 279.711702 -231.825904) (xy 279.763664 -231.814044) (xy 279.816814 -231.810061)
			(xy 279.869964 -231.814044) (xy 279.921926 -231.825904) (xy 279.97154 -231.845376) (xy 280.017698 -231.872025)
			(xy 280.059369 -231.905256) (xy 280.095621 -231.944327) (xy 280.125645 -231.988364) (xy 280.148771 -232.036385)
			(xy 280.164481 -232.087315) (xy 280.172424 -232.140019) (xy 280.172922 -232.166668) (xy 280.172424 -232.193317)
			(xy 294.548804 -232.193317) (xy 294.548804 -232.140019) (xy 294.556747 -232.087315) (xy 294.572457 -232.036385)
			(xy 294.595583 -231.988364) (xy 294.625607 -231.944327) (xy 294.661859 -231.905256) (xy 294.70353 -231.872025)
			(xy 294.749688 -231.845376) (xy 294.799302 -231.825904) (xy 294.851264 -231.814044) (xy 294.904414 -231.810061)
			(xy 294.957564 -231.814044) (xy 295.009526 -231.825904) (xy 295.05914 -231.845376) (xy 295.105298 -231.872025)
			(xy 295.146969 -231.905256) (xy 295.183221 -231.944327) (xy 295.213245 -231.988364) (xy 295.236371 -232.036385)
			(xy 295.252081 -232.087315) (xy 295.260024 -232.140019) (xy 295.260522 -232.166668) (xy 295.260024 -232.193317)
			(xy 309.636404 -232.193317) (xy 309.636404 -232.140019) (xy 309.644347 -232.087315) (xy 309.660057 -232.036385)
			(xy 309.683183 -231.988364) (xy 309.713207 -231.944327) (xy 309.749459 -231.905256) (xy 309.79113 -231.872025)
			(xy 309.837288 -231.845376) (xy 309.886902 -231.825904) (xy 309.938864 -231.814044) (xy 309.992014 -231.810061)
			(xy 310.045164 -231.814044) (xy 310.097126 -231.825904) (xy 310.14674 -231.845376) (xy 310.192898 -231.872025)
			(xy 310.234569 -231.905256) (xy 310.270821 -231.944327) (xy 310.300845 -231.988364) (xy 310.323971 -232.036385)
			(xy 310.339681 -232.087315) (xy 310.347624 -232.140019) (xy 310.348122 -232.166668) (xy 310.347624 -232.193317)
			(xy 310.339681 -232.246021) (xy 310.323971 -232.296951) (xy 310.300845 -232.344972) (xy 310.270821 -232.389009)
			(xy 310.234569 -232.42808) (xy 310.192898 -232.461311) (xy 310.14674 -232.48796) (xy 310.097126 -232.507432)
			(xy 310.045164 -232.519292) (xy 309.992014 -232.523276) (xy 309.938864 -232.519292) (xy 309.886902 -232.507432)
			(xy 309.837288 -232.48796) (xy 309.79113 -232.461311) (xy 309.749459 -232.42808) (xy 309.713207 -232.389009)
			(xy 309.683183 -232.344972) (xy 309.660057 -232.296951) (xy 309.644347 -232.246021) (xy 309.636404 -232.193317)
			(xy 295.260024 -232.193317) (xy 295.252081 -232.246021) (xy 295.236371 -232.296951) (xy 295.213245 -232.344972)
			(xy 295.183221 -232.389009) (xy 295.146969 -232.42808) (xy 295.105298 -232.461311) (xy 295.05914 -232.48796)
			(xy 295.009526 -232.507432) (xy 294.957564 -232.519292) (xy 294.904414 -232.523276) (xy 294.851264 -232.519292)
			(xy 294.799302 -232.507432) (xy 294.749688 -232.48796) (xy 294.70353 -232.461311) (xy 294.661859 -232.42808)
			(xy 294.625607 -232.389009) (xy 294.595583 -232.344972) (xy 294.572457 -232.296951) (xy 294.556747 -232.246021)
			(xy 294.548804 -232.193317) (xy 280.172424 -232.193317) (xy 280.164481 -232.246021) (xy 280.148771 -232.296951)
			(xy 280.125645 -232.344972) (xy 280.095621 -232.389009) (xy 280.059369 -232.42808) (xy 280.017698 -232.461311)
			(xy 279.97154 -232.48796) (xy 279.921926 -232.507432) (xy 279.869964 -232.519292) (xy 279.816814 -232.523276)
			(xy 279.763664 -232.519292) (xy 279.711702 -232.507432) (xy 279.662088 -232.48796) (xy 279.61593 -232.461311)
			(xy 279.574259 -232.42808) (xy 279.538007 -232.389009) (xy 279.507983 -232.344972) (xy 279.484857 -232.296951)
			(xy 279.469147 -232.246021) (xy 279.461204 -232.193317) (xy 265.084824 -232.193317) (xy 265.076881 -232.246021)
			(xy 265.061171 -232.296951) (xy 265.038045 -232.344972) (xy 265.008021 -232.389009) (xy 264.971769 -232.42808)
			(xy 264.930098 -232.461311) (xy 264.88394 -232.48796) (xy 264.834326 -232.507432) (xy 264.782364 -232.519292)
			(xy 264.729214 -232.523276) (xy 264.676064 -232.519292) (xy 264.624102 -232.507432) (xy 264.574488 -232.48796)
			(xy 264.52833 -232.461311) (xy 264.486659 -232.42808) (xy 264.450407 -232.389009) (xy 264.420383 -232.344972)
			(xy 264.397257 -232.296951) (xy 264.381547 -232.246021) (xy 264.373604 -232.193317) (xy 254.20828 -232.193317)
			(xy 254.20828 -233.043455) (xy 268.473672 -233.043455) (xy 268.473672 -232.990157) (xy 268.481615 -232.937453)
			(xy 268.497325 -232.886523) (xy 268.520451 -232.838502) (xy 268.550475 -232.794465) (xy 268.586727 -232.755394)
			(xy 268.628398 -232.722163) (xy 268.674556 -232.695514) (xy 268.72417 -232.676042) (xy 268.776132 -232.664182)
			(xy 268.829282 -232.660199) (xy 268.882432 -232.664182) (xy 268.934394 -232.676042) (xy 268.984008 -232.695514)
			(xy 269.030166 -232.722163) (xy 269.071837 -232.755394) (xy 269.108089 -232.794465) (xy 269.138113 -232.838502)
			(xy 269.161239 -232.886523) (xy 269.176949 -232.937453) (xy 269.184892 -232.990157) (xy 269.18539 -233.016806)
			(xy 269.184892 -233.043455) (xy 283.561272 -233.043455) (xy 283.561272 -232.990157) (xy 283.569215 -232.937453)
			(xy 283.584925 -232.886523) (xy 283.608051 -232.838502) (xy 283.638075 -232.794465) (xy 283.674327 -232.755394)
			(xy 283.715998 -232.722163) (xy 283.762156 -232.695514) (xy 283.81177 -232.676042) (xy 283.863732 -232.664182)
			(xy 283.916882 -232.660199) (xy 283.970032 -232.664182) (xy 284.021994 -232.676042) (xy 284.071608 -232.695514)
			(xy 284.117766 -232.722163) (xy 284.159437 -232.755394) (xy 284.195689 -232.794465) (xy 284.225713 -232.838502)
			(xy 284.248839 -232.886523) (xy 284.264549 -232.937453) (xy 284.272492 -232.990157) (xy 284.27299 -233.016806)
			(xy 284.272492 -233.043455) (xy 298.648872 -233.043455) (xy 298.648872 -232.990157) (xy 298.656815 -232.937453)
			(xy 298.672525 -232.886523) (xy 298.695651 -232.838502) (xy 298.725675 -232.794465) (xy 298.761927 -232.755394)
			(xy 298.803598 -232.722163) (xy 298.849756 -232.695514) (xy 298.89937 -232.676042) (xy 298.951332 -232.664182)
			(xy 299.004482 -232.660199) (xy 299.057632 -232.664182) (xy 299.109594 -232.676042) (xy 299.159208 -232.695514)
			(xy 299.205366 -232.722163) (xy 299.247037 -232.755394) (xy 299.283289 -232.794465) (xy 299.313313 -232.838502)
			(xy 299.336439 -232.886523) (xy 299.352149 -232.937453) (xy 299.360092 -232.990157) (xy 299.36059 -233.016806)
			(xy 299.360092 -233.043455) (xy 299.352149 -233.096159) (xy 299.336439 -233.147089) (xy 299.313313 -233.19511)
			(xy 299.283289 -233.239147) (xy 299.247037 -233.278218) (xy 299.205366 -233.311449) (xy 299.159208 -233.338098)
			(xy 299.109594 -233.35757) (xy 299.057632 -233.36943) (xy 299.004482 -233.373414) (xy 298.951332 -233.36943)
			(xy 298.89937 -233.35757) (xy 298.849756 -233.338098) (xy 298.803598 -233.311449) (xy 298.761927 -233.278218)
			(xy 298.725675 -233.239147) (xy 298.695651 -233.19511) (xy 298.672525 -233.147089) (xy 298.656815 -233.096159)
			(xy 298.648872 -233.043455) (xy 284.272492 -233.043455) (xy 284.264549 -233.096159) (xy 284.248839 -233.147089)
			(xy 284.225713 -233.19511) (xy 284.195689 -233.239147) (xy 284.159437 -233.278218) (xy 284.117766 -233.311449)
			(xy 284.071608 -233.338098) (xy 284.021994 -233.35757) (xy 283.970032 -233.36943) (xy 283.916882 -233.373414)
			(xy 283.863732 -233.36943) (xy 283.81177 -233.35757) (xy 283.762156 -233.338098) (xy 283.715998 -233.311449)
			(xy 283.674327 -233.278218) (xy 283.638075 -233.239147) (xy 283.608051 -233.19511) (xy 283.584925 -233.147089)
			(xy 283.569215 -233.096159) (xy 283.561272 -233.043455) (xy 269.184892 -233.043455) (xy 269.176949 -233.096159)
			(xy 269.161239 -233.147089) (xy 269.138113 -233.19511) (xy 269.108089 -233.239147) (xy 269.071837 -233.278218)
			(xy 269.030166 -233.311449) (xy 268.984008 -233.338098) (xy 268.934394 -233.35757) (xy 268.882432 -233.36943)
			(xy 268.829282 -233.373414) (xy 268.776132 -233.36943) (xy 268.72417 -233.35757) (xy 268.674556 -233.338098)
			(xy 268.628398 -233.311449) (xy 268.586727 -233.278218) (xy 268.550475 -233.239147) (xy 268.520451 -233.19511)
			(xy 268.497325 -233.147089) (xy 268.481615 -233.096159) (xy 268.473672 -233.043455) (xy 254.20828 -233.043455)
			(xy 254.20828 -233.893339) (xy 264.373604 -233.893339) (xy 264.373604 -233.840041) (xy 264.381547 -233.787337)
			(xy 264.397257 -233.736407) (xy 264.420383 -233.688386) (xy 264.450407 -233.644349) (xy 264.486659 -233.605278)
			(xy 264.52833 -233.572047) (xy 264.574488 -233.545398) (xy 264.624102 -233.525926) (xy 264.676064 -233.514066)
			(xy 264.729214 -233.510083) (xy 264.782364 -233.514066) (xy 264.834326 -233.525926) (xy 264.88394 -233.545398)
			(xy 264.930098 -233.572047) (xy 264.971769 -233.605278) (xy 265.008021 -233.644349) (xy 265.038045 -233.688386)
			(xy 265.061171 -233.736407) (xy 265.076881 -233.787337) (xy 265.084824 -233.840041) (xy 265.085322 -233.86669)
			(xy 265.084824 -233.893339) (xy 279.461204 -233.893339) (xy 279.461204 -233.840041) (xy 279.469147 -233.787337)
			(xy 279.484857 -233.736407) (xy 279.507983 -233.688386) (xy 279.538007 -233.644349) (xy 279.574259 -233.605278)
			(xy 279.61593 -233.572047) (xy 279.662088 -233.545398) (xy 279.711702 -233.525926) (xy 279.763664 -233.514066)
			(xy 279.816814 -233.510083) (xy 279.869964 -233.514066) (xy 279.921926 -233.525926) (xy 279.97154 -233.545398)
			(xy 280.017698 -233.572047) (xy 280.059369 -233.605278) (xy 280.095621 -233.644349) (xy 280.125645 -233.688386)
			(xy 280.148771 -233.736407) (xy 280.164481 -233.787337) (xy 280.172424 -233.840041) (xy 280.172922 -233.86669)
			(xy 280.172424 -233.893339) (xy 294.548804 -233.893339) (xy 294.548804 -233.840041) (xy 294.556747 -233.787337)
			(xy 294.572457 -233.736407) (xy 294.595583 -233.688386) (xy 294.625607 -233.644349) (xy 294.661859 -233.605278)
			(xy 294.70353 -233.572047) (xy 294.749688 -233.545398) (xy 294.799302 -233.525926) (xy 294.851264 -233.514066)
			(xy 294.904414 -233.510083) (xy 294.957564 -233.514066) (xy 295.009526 -233.525926) (xy 295.05914 -233.545398)
			(xy 295.105298 -233.572047) (xy 295.146969 -233.605278) (xy 295.183221 -233.644349) (xy 295.213245 -233.688386)
			(xy 295.236371 -233.736407) (xy 295.252081 -233.787337) (xy 295.260024 -233.840041) (xy 295.260522 -233.86669)
			(xy 295.260024 -233.893339) (xy 295.252081 -233.946043) (xy 295.236371 -233.996973) (xy 295.213245 -234.044994)
			(xy 295.183221 -234.089031) (xy 295.146969 -234.128102) (xy 295.105298 -234.161333) (xy 295.05914 -234.187982)
			(xy 295.009526 -234.207454) (xy 294.957564 -234.219314) (xy 294.904414 -234.223298) (xy 294.851264 -234.219314)
			(xy 294.799302 -234.207454) (xy 294.749688 -234.187982) (xy 294.70353 -234.161333) (xy 294.661859 -234.128102)
			(xy 294.625607 -234.089031) (xy 294.595583 -234.044994) (xy 294.572457 -233.996973) (xy 294.556747 -233.946043)
			(xy 294.548804 -233.893339) (xy 280.172424 -233.893339) (xy 280.164481 -233.946043) (xy 280.148771 -233.996973)
			(xy 280.125645 -234.044994) (xy 280.095621 -234.089031) (xy 280.059369 -234.128102) (xy 280.017698 -234.161333)
			(xy 279.97154 -234.187982) (xy 279.921926 -234.207454) (xy 279.869964 -234.219314) (xy 279.816814 -234.223298)
			(xy 279.763664 -234.219314) (xy 279.711702 -234.207454) (xy 279.662088 -234.187982) (xy 279.61593 -234.161333)
			(xy 279.574259 -234.128102) (xy 279.538007 -234.089031) (xy 279.507983 -234.044994) (xy 279.484857 -233.996973)
			(xy 279.469147 -233.946043) (xy 279.461204 -233.893339) (xy 265.084824 -233.893339) (xy 265.076881 -233.946043)
			(xy 265.061171 -233.996973) (xy 265.038045 -234.044994) (xy 265.008021 -234.089031) (xy 264.971769 -234.128102)
			(xy 264.930098 -234.161333) (xy 264.88394 -234.187982) (xy 264.834326 -234.207454) (xy 264.782364 -234.219314)
			(xy 264.729214 -234.223298) (xy 264.676064 -234.219314) (xy 264.624102 -234.207454) (xy 264.574488 -234.187982)
			(xy 264.52833 -234.161333) (xy 264.486659 -234.128102) (xy 264.450407 -234.089031) (xy 264.420383 -234.044994)
			(xy 264.397257 -233.996973) (xy 264.381547 -233.946043) (xy 264.373604 -233.893339) (xy 254.20828 -233.893339)
			(xy 254.20828 -234.743223) (xy 268.473672 -234.743223) (xy 268.473672 -234.689925) (xy 268.481615 -234.637221)
			(xy 268.497325 -234.586291) (xy 268.520451 -234.53827) (xy 268.550475 -234.494233) (xy 268.586727 -234.455162)
			(xy 268.628398 -234.421931) (xy 268.674556 -234.395282) (xy 268.72417 -234.37581) (xy 268.776132 -234.36395)
			(xy 268.829282 -234.359967) (xy 268.882432 -234.36395) (xy 268.934394 -234.37581) (xy 268.984008 -234.395282)
			(xy 269.030166 -234.421931) (xy 269.071837 -234.455162) (xy 269.108089 -234.494233) (xy 269.138113 -234.53827)
			(xy 269.161239 -234.586291) (xy 269.176949 -234.637221) (xy 269.184892 -234.689925) (xy 269.18539 -234.716574)
			(xy 269.184892 -234.743223) (xy 283.561272 -234.743223) (xy 283.561272 -234.689925) (xy 283.569215 -234.637221)
			(xy 283.584925 -234.586291) (xy 283.608051 -234.53827) (xy 283.638075 -234.494233) (xy 283.674327 -234.455162)
			(xy 283.715998 -234.421931) (xy 283.762156 -234.395282) (xy 283.81177 -234.37581) (xy 283.863732 -234.36395)
			(xy 283.916882 -234.359967) (xy 283.970032 -234.36395) (xy 284.021994 -234.37581) (xy 284.071608 -234.395282)
			(xy 284.117766 -234.421931) (xy 284.159437 -234.455162) (xy 284.195689 -234.494233) (xy 284.225713 -234.53827)
			(xy 284.248839 -234.586291) (xy 284.264549 -234.637221) (xy 284.272492 -234.689925) (xy 284.27299 -234.716574)
			(xy 284.272492 -234.743223) (xy 298.648872 -234.743223) (xy 298.648872 -234.689925) (xy 298.656815 -234.637221)
			(xy 298.672525 -234.586291) (xy 298.695651 -234.53827) (xy 298.725675 -234.494233) (xy 298.761927 -234.455162)
			(xy 298.803598 -234.421931) (xy 298.849756 -234.395282) (xy 298.89937 -234.37581) (xy 298.951332 -234.36395)
			(xy 299.004482 -234.359967) (xy 299.057632 -234.36395) (xy 299.109594 -234.37581) (xy 299.159208 -234.395282)
			(xy 299.205366 -234.421931) (xy 299.247037 -234.455162) (xy 299.283289 -234.494233) (xy 299.313313 -234.53827)
			(xy 299.336439 -234.586291) (xy 299.352149 -234.637221) (xy 299.360092 -234.689925) (xy 299.36059 -234.716574)
			(xy 299.360092 -234.743223) (xy 299.352149 -234.795927) (xy 299.336439 -234.846857) (xy 299.313313 -234.894878)
			(xy 299.283289 -234.938915) (xy 299.247037 -234.977986) (xy 299.205366 -235.011217) (xy 299.159208 -235.037866)
			(xy 299.109594 -235.057338) (xy 299.057632 -235.069198) (xy 299.004482 -235.073182) (xy 298.951332 -235.069198)
			(xy 298.89937 -235.057338) (xy 298.849756 -235.037866) (xy 298.803598 -235.011217) (xy 298.761927 -234.977986)
			(xy 298.725675 -234.938915) (xy 298.695651 -234.894878) (xy 298.672525 -234.846857) (xy 298.656815 -234.795927)
			(xy 298.648872 -234.743223) (xy 284.272492 -234.743223) (xy 284.264549 -234.795927) (xy 284.248839 -234.846857)
			(xy 284.225713 -234.894878) (xy 284.195689 -234.938915) (xy 284.159437 -234.977986) (xy 284.117766 -235.011217)
			(xy 284.071608 -235.037866) (xy 284.021994 -235.057338) (xy 283.970032 -235.069198) (xy 283.916882 -235.073182)
			(xy 283.863732 -235.069198) (xy 283.81177 -235.057338) (xy 283.762156 -235.037866) (xy 283.715998 -235.011217)
			(xy 283.674327 -234.977986) (xy 283.638075 -234.938915) (xy 283.608051 -234.894878) (xy 283.584925 -234.846857)
			(xy 283.569215 -234.795927) (xy 283.561272 -234.743223) (xy 269.184892 -234.743223) (xy 269.176949 -234.795927)
			(xy 269.161239 -234.846857) (xy 269.138113 -234.894878) (xy 269.108089 -234.938915) (xy 269.071837 -234.977986)
			(xy 269.030166 -235.011217) (xy 268.984008 -235.037866) (xy 268.934394 -235.057338) (xy 268.882432 -235.069198)
			(xy 268.829282 -235.073182) (xy 268.776132 -235.069198) (xy 268.72417 -235.057338) (xy 268.674556 -235.037866)
			(xy 268.628398 -235.011217) (xy 268.586727 -234.977986) (xy 268.550475 -234.938915) (xy 268.520451 -234.894878)
			(xy 268.497325 -234.846857) (xy 268.481615 -234.795927) (xy 268.473672 -234.743223) (xy 254.20828 -234.743223)
			(xy 254.20828 -235.593361) (xy 264.373604 -235.593361) (xy 264.373604 -235.540063) (xy 264.381547 -235.487359)
			(xy 264.397257 -235.436429) (xy 264.420383 -235.388408) (xy 264.450407 -235.344371) (xy 264.486659 -235.3053)
			(xy 264.52833 -235.272069) (xy 264.574488 -235.24542) (xy 264.624102 -235.225948) (xy 264.676064 -235.214088)
			(xy 264.729214 -235.210105) (xy 264.782364 -235.214088) (xy 264.834326 -235.225948) (xy 264.88394 -235.24542)
			(xy 264.930098 -235.272069) (xy 264.971769 -235.3053) (xy 265.008021 -235.344371) (xy 265.038045 -235.388408)
			(xy 265.061171 -235.436429) (xy 265.076881 -235.487359) (xy 265.084824 -235.540063) (xy 265.085322 -235.566712)
			(xy 265.084824 -235.593361) (xy 279.461204 -235.593361) (xy 279.461204 -235.540063) (xy 279.469147 -235.487359)
			(xy 279.484857 -235.436429) (xy 279.507983 -235.388408) (xy 279.538007 -235.344371) (xy 279.574259 -235.3053)
			(xy 279.61593 -235.272069) (xy 279.662088 -235.24542) (xy 279.711702 -235.225948) (xy 279.763664 -235.214088)
			(xy 279.816814 -235.210105) (xy 279.869964 -235.214088) (xy 279.921926 -235.225948) (xy 279.97154 -235.24542)
			(xy 280.017698 -235.272069) (xy 280.059369 -235.3053) (xy 280.095621 -235.344371) (xy 280.125645 -235.388408)
			(xy 280.148771 -235.436429) (xy 280.164481 -235.487359) (xy 280.172424 -235.540063) (xy 280.172922 -235.566712)
			(xy 280.172424 -235.593361) (xy 294.548804 -235.593361) (xy 294.548804 -235.540063) (xy 294.556747 -235.487359)
			(xy 294.572457 -235.436429) (xy 294.595583 -235.388408) (xy 294.625607 -235.344371) (xy 294.661859 -235.3053)
			(xy 294.70353 -235.272069) (xy 294.749688 -235.24542) (xy 294.799302 -235.225948) (xy 294.851264 -235.214088)
			(xy 294.904414 -235.210105) (xy 294.957564 -235.214088) (xy 295.009526 -235.225948) (xy 295.05914 -235.24542)
			(xy 295.105298 -235.272069) (xy 295.146969 -235.3053) (xy 295.183221 -235.344371) (xy 295.213245 -235.388408)
			(xy 295.236371 -235.436429) (xy 295.252081 -235.487359) (xy 295.260024 -235.540063) (xy 295.260522 -235.566712)
			(xy 295.260024 -235.593361) (xy 295.252081 -235.646065) (xy 295.236371 -235.696995) (xy 295.213245 -235.745016)
			(xy 295.183221 -235.789053) (xy 295.146969 -235.828124) (xy 295.105298 -235.861355) (xy 295.05914 -235.888004)
			(xy 295.009526 -235.907476) (xy 294.957564 -235.919336) (xy 294.904414 -235.92332) (xy 294.851264 -235.919336)
			(xy 294.799302 -235.907476) (xy 294.749688 -235.888004) (xy 294.70353 -235.861355) (xy 294.661859 -235.828124)
			(xy 294.625607 -235.789053) (xy 294.595583 -235.745016) (xy 294.572457 -235.696995) (xy 294.556747 -235.646065)
			(xy 294.548804 -235.593361) (xy 280.172424 -235.593361) (xy 280.164481 -235.646065) (xy 280.148771 -235.696995)
			(xy 280.125645 -235.745016) (xy 280.095621 -235.789053) (xy 280.059369 -235.828124) (xy 280.017698 -235.861355)
			(xy 279.97154 -235.888004) (xy 279.921926 -235.907476) (xy 279.869964 -235.919336) (xy 279.816814 -235.92332)
			(xy 279.763664 -235.919336) (xy 279.711702 -235.907476) (xy 279.662088 -235.888004) (xy 279.61593 -235.861355)
			(xy 279.574259 -235.828124) (xy 279.538007 -235.789053) (xy 279.507983 -235.745016) (xy 279.484857 -235.696995)
			(xy 279.469147 -235.646065) (xy 279.461204 -235.593361) (xy 265.084824 -235.593361) (xy 265.076881 -235.646065)
			(xy 265.061171 -235.696995) (xy 265.038045 -235.745016) (xy 265.008021 -235.789053) (xy 264.971769 -235.828124)
			(xy 264.930098 -235.861355) (xy 264.88394 -235.888004) (xy 264.834326 -235.907476) (xy 264.782364 -235.919336)
			(xy 264.729214 -235.92332) (xy 264.676064 -235.919336) (xy 264.624102 -235.907476) (xy 264.574488 -235.888004)
			(xy 264.52833 -235.861355) (xy 264.486659 -235.828124) (xy 264.450407 -235.789053) (xy 264.420383 -235.745016)
			(xy 264.397257 -235.696995) (xy 264.381547 -235.646065) (xy 264.373604 -235.593361) (xy 254.20828 -235.593361)
			(xy 254.20828 -236.443245) (xy 268.473672 -236.443245) (xy 268.473672 -236.389947) (xy 268.481615 -236.337243)
			(xy 268.497325 -236.286313) (xy 268.520451 -236.238292) (xy 268.550475 -236.194255) (xy 268.586727 -236.155184)
			(xy 268.628398 -236.121953) (xy 268.674556 -236.095304) (xy 268.72417 -236.075832) (xy 268.776132 -236.063972)
			(xy 268.829282 -236.059989) (xy 268.882432 -236.063972) (xy 268.934394 -236.075832) (xy 268.984008 -236.095304)
			(xy 269.030166 -236.121953) (xy 269.071837 -236.155184) (xy 269.108089 -236.194255) (xy 269.138113 -236.238292)
			(xy 269.161239 -236.286313) (xy 269.176949 -236.337243) (xy 269.184892 -236.389947) (xy 269.18539 -236.416596)
			(xy 269.184892 -236.443245) (xy 283.561272 -236.443245) (xy 283.561272 -236.389947) (xy 283.569215 -236.337243)
			(xy 283.584925 -236.286313) (xy 283.608051 -236.238292) (xy 283.638075 -236.194255) (xy 283.674327 -236.155184)
			(xy 283.715998 -236.121953) (xy 283.762156 -236.095304) (xy 283.81177 -236.075832) (xy 283.863732 -236.063972)
			(xy 283.916882 -236.059989) (xy 283.970032 -236.063972) (xy 284.021994 -236.075832) (xy 284.071608 -236.095304)
			(xy 284.117766 -236.121953) (xy 284.159437 -236.155184) (xy 284.195689 -236.194255) (xy 284.225713 -236.238292)
			(xy 284.248839 -236.286313) (xy 284.264549 -236.337243) (xy 284.272492 -236.389947) (xy 284.27299 -236.416596)
			(xy 284.272492 -236.443245) (xy 298.648872 -236.443245) (xy 298.648872 -236.389947) (xy 298.656815 -236.337243)
			(xy 298.672525 -236.286313) (xy 298.695651 -236.238292) (xy 298.725675 -236.194255) (xy 298.761927 -236.155184)
			(xy 298.803598 -236.121953) (xy 298.849756 -236.095304) (xy 298.89937 -236.075832) (xy 298.951332 -236.063972)
			(xy 299.004482 -236.059989) (xy 299.057632 -236.063972) (xy 299.109594 -236.075832) (xy 299.159208 -236.095304)
			(xy 299.205366 -236.121953) (xy 299.247037 -236.155184) (xy 299.283289 -236.194255) (xy 299.313313 -236.238292)
			(xy 299.336439 -236.286313) (xy 299.352149 -236.337243) (xy 299.360092 -236.389947) (xy 299.36059 -236.416596)
			(xy 299.360092 -236.443245) (xy 299.352149 -236.495949) (xy 299.336439 -236.546879) (xy 299.313313 -236.5949)
			(xy 299.283289 -236.638937) (xy 299.247037 -236.678008) (xy 299.205366 -236.711239) (xy 299.159208 -236.737888)
			(xy 299.109594 -236.75736) (xy 299.057632 -236.76922) (xy 299.004482 -236.773204) (xy 298.951332 -236.76922)
			(xy 298.89937 -236.75736) (xy 298.849756 -236.737888) (xy 298.803598 -236.711239) (xy 298.761927 -236.678008)
			(xy 298.725675 -236.638937) (xy 298.695651 -236.5949) (xy 298.672525 -236.546879) (xy 298.656815 -236.495949)
			(xy 298.648872 -236.443245) (xy 284.272492 -236.443245) (xy 284.264549 -236.495949) (xy 284.248839 -236.546879)
			(xy 284.225713 -236.5949) (xy 284.195689 -236.638937) (xy 284.159437 -236.678008) (xy 284.117766 -236.711239)
			(xy 284.071608 -236.737888) (xy 284.021994 -236.75736) (xy 283.970032 -236.76922) (xy 283.916882 -236.773204)
			(xy 283.863732 -236.76922) (xy 283.81177 -236.75736) (xy 283.762156 -236.737888) (xy 283.715998 -236.711239)
			(xy 283.674327 -236.678008) (xy 283.638075 -236.638937) (xy 283.608051 -236.5949) (xy 283.584925 -236.546879)
			(xy 283.569215 -236.495949) (xy 283.561272 -236.443245) (xy 269.184892 -236.443245) (xy 269.176949 -236.495949)
			(xy 269.161239 -236.546879) (xy 269.138113 -236.5949) (xy 269.108089 -236.638937) (xy 269.071837 -236.678008)
			(xy 269.030166 -236.711239) (xy 268.984008 -236.737888) (xy 268.934394 -236.75736) (xy 268.882432 -236.76922)
			(xy 268.829282 -236.773204) (xy 268.776132 -236.76922) (xy 268.72417 -236.75736) (xy 268.674556 -236.737888)
			(xy 268.628398 -236.711239) (xy 268.586727 -236.678008) (xy 268.550475 -236.638937) (xy 268.520451 -236.5949)
			(xy 268.497325 -236.546879) (xy 268.481615 -236.495949) (xy 268.473672 -236.443245) (xy 254.20828 -236.443245)
			(xy 254.20828 -237.293383) (xy 264.373604 -237.293383) (xy 264.373604 -237.240085) (xy 264.381547 -237.187381)
			(xy 264.397257 -237.136451) (xy 264.420383 -237.08843) (xy 264.450407 -237.044393) (xy 264.486659 -237.005322)
			(xy 264.52833 -236.972091) (xy 264.574488 -236.945442) (xy 264.624102 -236.92597) (xy 264.676064 -236.91411)
			(xy 264.729214 -236.910127) (xy 264.782364 -236.91411) (xy 264.834326 -236.92597) (xy 264.88394 -236.945442)
			(xy 264.930098 -236.972091) (xy 264.971769 -237.005322) (xy 265.008021 -237.044393) (xy 265.038045 -237.08843)
			(xy 265.061171 -237.136451) (xy 265.076881 -237.187381) (xy 265.084824 -237.240085) (xy 265.085322 -237.266734)
			(xy 265.084824 -237.293383) (xy 268.473672 -237.293383) (xy 268.473672 -237.240085) (xy 268.481615 -237.187381)
			(xy 268.497325 -237.136451) (xy 268.520451 -237.08843) (xy 268.550475 -237.044393) (xy 268.586727 -237.005322)
			(xy 268.628398 -236.972091) (xy 268.674556 -236.945442) (xy 268.72417 -236.92597) (xy 268.776132 -236.91411)
			(xy 268.829282 -236.910127) (xy 268.882432 -236.91411) (xy 268.934394 -236.92597) (xy 268.984008 -236.945442)
			(xy 269.030166 -236.972091) (xy 269.071837 -237.005322) (xy 269.108089 -237.044393) (xy 269.138113 -237.08843)
			(xy 269.161239 -237.136451) (xy 269.176949 -237.187381) (xy 269.184892 -237.240085) (xy 269.18539 -237.266734)
			(xy 269.184892 -237.293383) (xy 279.461204 -237.293383) (xy 279.461204 -237.240085) (xy 279.469147 -237.187381)
			(xy 279.484857 -237.136451) (xy 279.507983 -237.08843) (xy 279.538007 -237.044393) (xy 279.574259 -237.005322)
			(xy 279.61593 -236.972091) (xy 279.662088 -236.945442) (xy 279.711702 -236.92597) (xy 279.763664 -236.91411)
			(xy 279.816814 -236.910127) (xy 279.869964 -236.91411) (xy 279.921926 -236.92597) (xy 279.97154 -236.945442)
			(xy 280.017698 -236.972091) (xy 280.059369 -237.005322) (xy 280.095621 -237.044393) (xy 280.125645 -237.08843)
			(xy 280.148771 -237.136451) (xy 280.164481 -237.187381) (xy 280.172424 -237.240085) (xy 280.172922 -237.266734)
			(xy 280.172424 -237.293383) (xy 283.561272 -237.293383) (xy 283.561272 -237.240085) (xy 283.569215 -237.187381)
			(xy 283.584925 -237.136451) (xy 283.608051 -237.08843) (xy 283.638075 -237.044393) (xy 283.674327 -237.005322)
			(xy 283.715998 -236.972091) (xy 283.762156 -236.945442) (xy 283.81177 -236.92597) (xy 283.863732 -236.91411)
			(xy 283.916882 -236.910127) (xy 283.970032 -236.91411) (xy 284.021994 -236.92597) (xy 284.071608 -236.945442)
			(xy 284.117766 -236.972091) (xy 284.159437 -237.005322) (xy 284.195689 -237.044393) (xy 284.225713 -237.08843)
			(xy 284.248839 -237.136451) (xy 284.264549 -237.187381) (xy 284.272492 -237.240085) (xy 284.27299 -237.266734)
			(xy 284.272492 -237.293383) (xy 294.548804 -237.293383) (xy 294.548804 -237.240085) (xy 294.556747 -237.187381)
			(xy 294.572457 -237.136451) (xy 294.595583 -237.08843) (xy 294.625607 -237.044393) (xy 294.661859 -237.005322)
			(xy 294.70353 -236.972091) (xy 294.749688 -236.945442) (xy 294.799302 -236.92597) (xy 294.851264 -236.91411)
			(xy 294.904414 -236.910127) (xy 294.957564 -236.91411) (xy 295.009526 -236.92597) (xy 295.05914 -236.945442)
			(xy 295.105298 -236.972091) (xy 295.146969 -237.005322) (xy 295.183221 -237.044393) (xy 295.213245 -237.08843)
			(xy 295.236371 -237.136451) (xy 295.252081 -237.187381) (xy 295.260024 -237.240085) (xy 295.260522 -237.266734)
			(xy 295.260024 -237.293383) (xy 298.648872 -237.293383) (xy 298.648872 -237.240085) (xy 298.656815 -237.187381)
			(xy 298.672525 -237.136451) (xy 298.695651 -237.08843) (xy 298.725675 -237.044393) (xy 298.761927 -237.005322)
			(xy 298.803598 -236.972091) (xy 298.849756 -236.945442) (xy 298.89937 -236.92597) (xy 298.951332 -236.91411)
			(xy 299.004482 -236.910127) (xy 299.057632 -236.91411) (xy 299.109594 -236.92597) (xy 299.159208 -236.945442)
			(xy 299.205366 -236.972091) (xy 299.247037 -237.005322) (xy 299.283289 -237.044393) (xy 299.313313 -237.08843)
			(xy 299.336439 -237.136451) (xy 299.352149 -237.187381) (xy 299.360092 -237.240085) (xy 299.36059 -237.266734)
			(xy 299.360092 -237.293383) (xy 299.352149 -237.346087) (xy 299.336439 -237.397017) (xy 299.313313 -237.445038)
			(xy 299.283289 -237.489075) (xy 299.247037 -237.528146) (xy 299.205366 -237.561377) (xy 299.159208 -237.588026)
			(xy 299.109594 -237.607498) (xy 299.057632 -237.619358) (xy 299.004482 -237.623342) (xy 298.951332 -237.619358)
			(xy 298.89937 -237.607498) (xy 298.849756 -237.588026) (xy 298.803598 -237.561377) (xy 298.761927 -237.528146)
			(xy 298.725675 -237.489075) (xy 298.695651 -237.445038) (xy 298.672525 -237.397017) (xy 298.656815 -237.346087)
			(xy 298.648872 -237.293383) (xy 295.260024 -237.293383) (xy 295.252081 -237.346087) (xy 295.236371 -237.397017)
			(xy 295.213245 -237.445038) (xy 295.183221 -237.489075) (xy 295.146969 -237.528146) (xy 295.105298 -237.561377)
			(xy 295.05914 -237.588026) (xy 295.009526 -237.607498) (xy 294.957564 -237.619358) (xy 294.904414 -237.623342)
			(xy 294.851264 -237.619358) (xy 294.799302 -237.607498) (xy 294.749688 -237.588026) (xy 294.70353 -237.561377)
			(xy 294.661859 -237.528146) (xy 294.625607 -237.489075) (xy 294.595583 -237.445038) (xy 294.572457 -237.397017)
			(xy 294.556747 -237.346087) (xy 294.548804 -237.293383) (xy 284.272492 -237.293383) (xy 284.264549 -237.346087)
			(xy 284.248839 -237.397017) (xy 284.225713 -237.445038) (xy 284.195689 -237.489075) (xy 284.159437 -237.528146)
			(xy 284.117766 -237.561377) (xy 284.071608 -237.588026) (xy 284.021994 -237.607498) (xy 283.970032 -237.619358)
			(xy 283.916882 -237.623342) (xy 283.863732 -237.619358) (xy 283.81177 -237.607498) (xy 283.762156 -237.588026)
			(xy 283.715998 -237.561377) (xy 283.674327 -237.528146) (xy 283.638075 -237.489075) (xy 283.608051 -237.445038)
			(xy 283.584925 -237.397017) (xy 283.569215 -237.346087) (xy 283.561272 -237.293383) (xy 280.172424 -237.293383)
			(xy 280.164481 -237.346087) (xy 280.148771 -237.397017) (xy 280.125645 -237.445038) (xy 280.095621 -237.489075)
			(xy 280.059369 -237.528146) (xy 280.017698 -237.561377) (xy 279.97154 -237.588026) (xy 279.921926 -237.607498)
			(xy 279.869964 -237.619358) (xy 279.816814 -237.623342) (xy 279.763664 -237.619358) (xy 279.711702 -237.607498)
			(xy 279.662088 -237.588026) (xy 279.61593 -237.561377) (xy 279.574259 -237.528146) (xy 279.538007 -237.489075)
			(xy 279.507983 -237.445038) (xy 279.484857 -237.397017) (xy 279.469147 -237.346087) (xy 279.461204 -237.293383)
			(xy 269.184892 -237.293383) (xy 269.176949 -237.346087) (xy 269.161239 -237.397017) (xy 269.138113 -237.445038)
			(xy 269.108089 -237.489075) (xy 269.071837 -237.528146) (xy 269.030166 -237.561377) (xy 268.984008 -237.588026)
			(xy 268.934394 -237.607498) (xy 268.882432 -237.619358) (xy 268.829282 -237.623342) (xy 268.776132 -237.619358)
			(xy 268.72417 -237.607498) (xy 268.674556 -237.588026) (xy 268.628398 -237.561377) (xy 268.586727 -237.528146)
			(xy 268.550475 -237.489075) (xy 268.520451 -237.445038) (xy 268.497325 -237.397017) (xy 268.481615 -237.346087)
			(xy 268.473672 -237.293383) (xy 265.084824 -237.293383) (xy 265.076881 -237.346087) (xy 265.061171 -237.397017)
			(xy 265.038045 -237.445038) (xy 265.008021 -237.489075) (xy 264.971769 -237.528146) (xy 264.930098 -237.561377)
			(xy 264.88394 -237.588026) (xy 264.834326 -237.607498) (xy 264.782364 -237.619358) (xy 264.729214 -237.623342)
			(xy 264.676064 -237.619358) (xy 264.624102 -237.607498) (xy 264.574488 -237.588026) (xy 264.52833 -237.561377)
			(xy 264.486659 -237.528146) (xy 264.450407 -237.489075) (xy 264.420383 -237.445038) (xy 264.397257 -237.397017)
			(xy 264.381547 -237.346087) (xy 264.373604 -237.293383) (xy 254.20828 -237.293383) (xy 254.20828 -238.143267)
			(xy 264.373604 -238.143267) (xy 264.373604 -238.089969) (xy 264.381547 -238.037265) (xy 264.397257 -237.986335)
			(xy 264.420383 -237.938314) (xy 264.450407 -237.894277) (xy 264.486659 -237.855206) (xy 264.52833 -237.821975)
			(xy 264.574488 -237.795326) (xy 264.624102 -237.775854) (xy 264.676064 -237.763994) (xy 264.729214 -237.760011)
			(xy 264.782364 -237.763994) (xy 264.834326 -237.775854) (xy 264.88394 -237.795326) (xy 264.930098 -237.821975)
			(xy 264.971769 -237.855206) (xy 265.008021 -237.894277) (xy 265.038045 -237.938314) (xy 265.061171 -237.986335)
			(xy 265.076881 -238.037265) (xy 265.084824 -238.089969) (xy 265.085322 -238.116618) (xy 265.084824 -238.143267)
			(xy 279.461204 -238.143267) (xy 279.461204 -238.089969) (xy 279.469147 -238.037265) (xy 279.484857 -237.986335)
			(xy 279.507983 -237.938314) (xy 279.538007 -237.894277) (xy 279.574259 -237.855206) (xy 279.61593 -237.821975)
			(xy 279.662088 -237.795326) (xy 279.711702 -237.775854) (xy 279.763664 -237.763994) (xy 279.816814 -237.760011)
			(xy 279.869964 -237.763994) (xy 279.921926 -237.775854) (xy 279.97154 -237.795326) (xy 280.017698 -237.821975)
			(xy 280.059369 -237.855206) (xy 280.095621 -237.894277) (xy 280.125645 -237.938314) (xy 280.148771 -237.986335)
			(xy 280.164481 -238.037265) (xy 280.172424 -238.089969) (xy 280.172922 -238.116618) (xy 280.172424 -238.143267)
			(xy 294.548804 -238.143267) (xy 294.548804 -238.089969) (xy 294.556747 -238.037265) (xy 294.572457 -237.986335)
			(xy 294.595583 -237.938314) (xy 294.625607 -237.894277) (xy 294.661859 -237.855206) (xy 294.70353 -237.821975)
			(xy 294.749688 -237.795326) (xy 294.799302 -237.775854) (xy 294.851264 -237.763994) (xy 294.904414 -237.760011)
			(xy 294.957564 -237.763994) (xy 295.009526 -237.775854) (xy 295.05914 -237.795326) (xy 295.105298 -237.821975)
			(xy 295.146969 -237.855206) (xy 295.183221 -237.894277) (xy 295.213245 -237.938314) (xy 295.236371 -237.986335)
			(xy 295.252081 -238.037265) (xy 295.260024 -238.089969) (xy 295.260522 -238.116618) (xy 295.260024 -238.143267)
			(xy 295.252081 -238.195971) (xy 295.236371 -238.246901) (xy 295.213245 -238.294922) (xy 295.183221 -238.338959)
			(xy 295.146969 -238.37803) (xy 295.105298 -238.411261) (xy 295.05914 -238.43791) (xy 295.009526 -238.457382)
			(xy 294.957564 -238.469242) (xy 294.904414 -238.473226) (xy 294.851264 -238.469242) (xy 294.799302 -238.457382)
			(xy 294.749688 -238.43791) (xy 294.70353 -238.411261) (xy 294.661859 -238.37803) (xy 294.625607 -238.338959)
			(xy 294.595583 -238.294922) (xy 294.572457 -238.246901) (xy 294.556747 -238.195971) (xy 294.548804 -238.143267)
			(xy 280.172424 -238.143267) (xy 280.164481 -238.195971) (xy 280.148771 -238.246901) (xy 280.125645 -238.294922)
			(xy 280.095621 -238.338959) (xy 280.059369 -238.37803) (xy 280.017698 -238.411261) (xy 279.97154 -238.43791)
			(xy 279.921926 -238.457382) (xy 279.869964 -238.469242) (xy 279.816814 -238.473226) (xy 279.763664 -238.469242)
			(xy 279.711702 -238.457382) (xy 279.662088 -238.43791) (xy 279.61593 -238.411261) (xy 279.574259 -238.37803)
			(xy 279.538007 -238.338959) (xy 279.507983 -238.294922) (xy 279.484857 -238.246901) (xy 279.469147 -238.195971)
			(xy 279.461204 -238.143267) (xy 265.084824 -238.143267) (xy 265.076881 -238.195971) (xy 265.061171 -238.246901)
			(xy 265.038045 -238.294922) (xy 265.008021 -238.338959) (xy 264.971769 -238.37803) (xy 264.930098 -238.411261)
			(xy 264.88394 -238.43791) (xy 264.834326 -238.457382) (xy 264.782364 -238.469242) (xy 264.729214 -238.473226)
			(xy 264.676064 -238.469242) (xy 264.624102 -238.457382) (xy 264.574488 -238.43791) (xy 264.52833 -238.411261)
			(xy 264.486659 -238.37803) (xy 264.450407 -238.338959) (xy 264.420383 -238.294922) (xy 264.397257 -238.246901)
			(xy 264.381547 -238.195971) (xy 264.373604 -238.143267) (xy 254.20828 -238.143267) (xy 254.20828 -238.993405)
			(xy 268.473672 -238.993405) (xy 268.473672 -238.940107) (xy 268.481615 -238.887403) (xy 268.497325 -238.836473)
			(xy 268.520451 -238.788452) (xy 268.550475 -238.744415) (xy 268.586727 -238.705344) (xy 268.628398 -238.672113)
			(xy 268.674556 -238.645464) (xy 268.72417 -238.625992) (xy 268.776132 -238.614132) (xy 268.829282 -238.610149)
			(xy 268.882432 -238.614132) (xy 268.934394 -238.625992) (xy 268.984008 -238.645464) (xy 269.030166 -238.672113)
			(xy 269.071837 -238.705344) (xy 269.108089 -238.744415) (xy 269.138113 -238.788452) (xy 269.161239 -238.836473)
			(xy 269.176949 -238.887403) (xy 269.184892 -238.940107) (xy 269.18539 -238.966756) (xy 269.184892 -238.993405)
			(xy 283.561272 -238.993405) (xy 283.561272 -238.940107) (xy 283.569215 -238.887403) (xy 283.584925 -238.836473)
			(xy 283.608051 -238.788452) (xy 283.638075 -238.744415) (xy 283.674327 -238.705344) (xy 283.715998 -238.672113)
			(xy 283.762156 -238.645464) (xy 283.81177 -238.625992) (xy 283.863732 -238.614132) (xy 283.916882 -238.610149)
			(xy 283.970032 -238.614132) (xy 284.021994 -238.625992) (xy 284.071608 -238.645464) (xy 284.117766 -238.672113)
			(xy 284.159437 -238.705344) (xy 284.195689 -238.744415) (xy 284.225713 -238.788452) (xy 284.248839 -238.836473)
			(xy 284.264549 -238.887403) (xy 284.272492 -238.940107) (xy 284.27299 -238.966756) (xy 284.272492 -238.993405)
			(xy 298.648872 -238.993405) (xy 298.648872 -238.940107) (xy 298.656815 -238.887403) (xy 298.672525 -238.836473)
			(xy 298.695651 -238.788452) (xy 298.725675 -238.744415) (xy 298.761927 -238.705344) (xy 298.803598 -238.672113)
			(xy 298.849756 -238.645464) (xy 298.89937 -238.625992) (xy 298.951332 -238.614132) (xy 299.004482 -238.610149)
			(xy 299.057632 -238.614132) (xy 299.109594 -238.625992) (xy 299.159208 -238.645464) (xy 299.205366 -238.672113)
			(xy 299.247037 -238.705344) (xy 299.283289 -238.744415) (xy 299.313313 -238.788452) (xy 299.336439 -238.836473)
			(xy 299.352149 -238.887403) (xy 299.360092 -238.940107) (xy 299.36059 -238.966756) (xy 299.360092 -238.993405)
			(xy 299.352149 -239.046109) (xy 299.336439 -239.097039) (xy 299.313313 -239.14506) (xy 299.283289 -239.189097)
			(xy 299.247037 -239.228168) (xy 299.205366 -239.261399) (xy 299.159208 -239.288048) (xy 299.109594 -239.30752)
			(xy 299.057632 -239.31938) (xy 299.004482 -239.323364) (xy 298.951332 -239.31938) (xy 298.89937 -239.30752)
			(xy 298.849756 -239.288048) (xy 298.803598 -239.261399) (xy 298.761927 -239.228168) (xy 298.725675 -239.189097)
			(xy 298.695651 -239.14506) (xy 298.672525 -239.097039) (xy 298.656815 -239.046109) (xy 298.648872 -238.993405)
			(xy 284.272492 -238.993405) (xy 284.264549 -239.046109) (xy 284.248839 -239.097039) (xy 284.225713 -239.14506)
			(xy 284.195689 -239.189097) (xy 284.159437 -239.228168) (xy 284.117766 -239.261399) (xy 284.071608 -239.288048)
			(xy 284.021994 -239.30752) (xy 283.970032 -239.31938) (xy 283.916882 -239.323364) (xy 283.863732 -239.31938)
			(xy 283.81177 -239.30752) (xy 283.762156 -239.288048) (xy 283.715998 -239.261399) (xy 283.674327 -239.228168)
			(xy 283.638075 -239.189097) (xy 283.608051 -239.14506) (xy 283.584925 -239.097039) (xy 283.569215 -239.046109)
			(xy 283.561272 -238.993405) (xy 269.184892 -238.993405) (xy 269.176949 -239.046109) (xy 269.161239 -239.097039)
			(xy 269.138113 -239.14506) (xy 269.108089 -239.189097) (xy 269.071837 -239.228168) (xy 269.030166 -239.261399)
			(xy 268.984008 -239.288048) (xy 268.934394 -239.30752) (xy 268.882432 -239.31938) (xy 268.829282 -239.323364)
			(xy 268.776132 -239.31938) (xy 268.72417 -239.30752) (xy 268.674556 -239.288048) (xy 268.628398 -239.261399)
			(xy 268.586727 -239.228168) (xy 268.550475 -239.189097) (xy 268.520451 -239.14506) (xy 268.497325 -239.097039)
			(xy 268.481615 -239.046109) (xy 268.473672 -238.993405) (xy 254.20828 -238.993405) (xy 254.20828 -239.843289)
			(xy 264.373604 -239.843289) (xy 264.373604 -239.789991) (xy 264.381547 -239.737287) (xy 264.397257 -239.686357)
			(xy 264.420383 -239.638336) (xy 264.450407 -239.594299) (xy 264.486659 -239.555228) (xy 264.52833 -239.521997)
			(xy 264.574488 -239.495348) (xy 264.624102 -239.475876) (xy 264.676064 -239.464016) (xy 264.729214 -239.460033)
			(xy 264.782364 -239.464016) (xy 264.834326 -239.475876) (xy 264.88394 -239.495348) (xy 264.930098 -239.521997)
			(xy 264.971769 -239.555228) (xy 265.008021 -239.594299) (xy 265.038045 -239.638336) (xy 265.061171 -239.686357)
			(xy 265.076881 -239.737287) (xy 265.084824 -239.789991) (xy 265.085322 -239.81664) (xy 265.084824 -239.843289)
			(xy 279.461204 -239.843289) (xy 279.461204 -239.789991) (xy 279.469147 -239.737287) (xy 279.484857 -239.686357)
			(xy 279.507983 -239.638336) (xy 279.538007 -239.594299) (xy 279.574259 -239.555228) (xy 279.61593 -239.521997)
			(xy 279.662088 -239.495348) (xy 279.711702 -239.475876) (xy 279.763664 -239.464016) (xy 279.816814 -239.460033)
			(xy 279.869964 -239.464016) (xy 279.921926 -239.475876) (xy 279.97154 -239.495348) (xy 280.017698 -239.521997)
			(xy 280.059369 -239.555228) (xy 280.095621 -239.594299) (xy 280.125645 -239.638336) (xy 280.148771 -239.686357)
			(xy 280.164481 -239.737287) (xy 280.172424 -239.789991) (xy 280.172922 -239.81664) (xy 280.172424 -239.843289)
			(xy 294.548804 -239.843289) (xy 294.548804 -239.789991) (xy 294.556747 -239.737287) (xy 294.572457 -239.686357)
			(xy 294.595583 -239.638336) (xy 294.625607 -239.594299) (xy 294.661859 -239.555228) (xy 294.70353 -239.521997)
			(xy 294.749688 -239.495348) (xy 294.799302 -239.475876) (xy 294.851264 -239.464016) (xy 294.904414 -239.460033)
			(xy 294.957564 -239.464016) (xy 295.009526 -239.475876) (xy 295.05914 -239.495348) (xy 295.105298 -239.521997)
			(xy 295.146969 -239.555228) (xy 295.183221 -239.594299) (xy 295.213245 -239.638336) (xy 295.236371 -239.686357)
			(xy 295.252081 -239.737287) (xy 295.260024 -239.789991) (xy 295.260522 -239.81664) (xy 295.260024 -239.843289)
			(xy 295.252081 -239.895993) (xy 295.236371 -239.946923) (xy 295.213245 -239.994944) (xy 295.183221 -240.038981)
			(xy 295.146969 -240.078052) (xy 295.105298 -240.111283) (xy 295.05914 -240.137932) (xy 295.009526 -240.157404)
			(xy 294.957564 -240.169264) (xy 294.904414 -240.173248) (xy 294.851264 -240.169264) (xy 294.799302 -240.157404)
			(xy 294.749688 -240.137932) (xy 294.70353 -240.111283) (xy 294.661859 -240.078052) (xy 294.625607 -240.038981)
			(xy 294.595583 -239.994944) (xy 294.572457 -239.946923) (xy 294.556747 -239.895993) (xy 294.548804 -239.843289)
			(xy 280.172424 -239.843289) (xy 280.164481 -239.895993) (xy 280.148771 -239.946923) (xy 280.125645 -239.994944)
			(xy 280.095621 -240.038981) (xy 280.059369 -240.078052) (xy 280.017698 -240.111283) (xy 279.97154 -240.137932)
			(xy 279.921926 -240.157404) (xy 279.869964 -240.169264) (xy 279.816814 -240.173248) (xy 279.763664 -240.169264)
			(xy 279.711702 -240.157404) (xy 279.662088 -240.137932) (xy 279.61593 -240.111283) (xy 279.574259 -240.078052)
			(xy 279.538007 -240.038981) (xy 279.507983 -239.994944) (xy 279.484857 -239.946923) (xy 279.469147 -239.895993)
			(xy 279.461204 -239.843289) (xy 265.084824 -239.843289) (xy 265.076881 -239.895993) (xy 265.061171 -239.946923)
			(xy 265.038045 -239.994944) (xy 265.008021 -240.038981) (xy 264.971769 -240.078052) (xy 264.930098 -240.111283)
			(xy 264.88394 -240.137932) (xy 264.834326 -240.157404) (xy 264.782364 -240.169264) (xy 264.729214 -240.173248)
			(xy 264.676064 -240.169264) (xy 264.624102 -240.157404) (xy 264.574488 -240.137932) (xy 264.52833 -240.111283)
			(xy 264.486659 -240.078052) (xy 264.450407 -240.038981) (xy 264.420383 -239.994944) (xy 264.397257 -239.946923)
			(xy 264.381547 -239.895993) (xy 264.373604 -239.843289) (xy 254.20828 -239.843289) (xy 254.20828 -240.693427)
			(xy 268.473672 -240.693427) (xy 268.473672 -240.640129) (xy 268.481615 -240.587425) (xy 268.497325 -240.536495)
			(xy 268.520451 -240.488474) (xy 268.550475 -240.444437) (xy 268.586727 -240.405366) (xy 268.628398 -240.372135)
			(xy 268.674556 -240.345486) (xy 268.72417 -240.326014) (xy 268.776132 -240.314154) (xy 268.829282 -240.310171)
			(xy 268.882432 -240.314154) (xy 268.934394 -240.326014) (xy 268.984008 -240.345486) (xy 269.030166 -240.372135)
			(xy 269.071837 -240.405366) (xy 269.108089 -240.444437) (xy 269.138113 -240.488474) (xy 269.161239 -240.536495)
			(xy 269.176949 -240.587425) (xy 269.184892 -240.640129) (xy 269.18539 -240.666778) (xy 269.184892 -240.693427)
			(xy 283.561272 -240.693427) (xy 283.561272 -240.640129) (xy 283.569215 -240.587425) (xy 283.584925 -240.536495)
			(xy 283.608051 -240.488474) (xy 283.638075 -240.444437) (xy 283.674327 -240.405366) (xy 283.715998 -240.372135)
			(xy 283.762156 -240.345486) (xy 283.81177 -240.326014) (xy 283.863732 -240.314154) (xy 283.916882 -240.310171)
			(xy 283.970032 -240.314154) (xy 284.021994 -240.326014) (xy 284.071608 -240.345486) (xy 284.117766 -240.372135)
			(xy 284.159437 -240.405366) (xy 284.195689 -240.444437) (xy 284.225713 -240.488474) (xy 284.248839 -240.536495)
			(xy 284.264549 -240.587425) (xy 284.272492 -240.640129) (xy 284.27299 -240.666778) (xy 284.272492 -240.693427)
			(xy 298.648872 -240.693427) (xy 298.648872 -240.640129) (xy 298.656815 -240.587425) (xy 298.672525 -240.536495)
			(xy 298.695651 -240.488474) (xy 298.725675 -240.444437) (xy 298.761927 -240.405366) (xy 298.803598 -240.372135)
			(xy 298.849756 -240.345486) (xy 298.89937 -240.326014) (xy 298.951332 -240.314154) (xy 299.004482 -240.310171)
			(xy 299.057632 -240.314154) (xy 299.109594 -240.326014) (xy 299.159208 -240.345486) (xy 299.205366 -240.372135)
			(xy 299.247037 -240.405366) (xy 299.283289 -240.444437) (xy 299.313313 -240.488474) (xy 299.336439 -240.536495)
			(xy 299.352149 -240.587425) (xy 299.360092 -240.640129) (xy 299.36059 -240.666778) (xy 299.360092 -240.693427)
			(xy 299.352149 -240.746131) (xy 299.336439 -240.797061) (xy 299.313313 -240.845082) (xy 299.283289 -240.889119)
			(xy 299.247037 -240.92819) (xy 299.205366 -240.961421) (xy 299.159208 -240.98807) (xy 299.109594 -241.007542)
			(xy 299.057632 -241.019402) (xy 299.004482 -241.023386) (xy 298.951332 -241.019402) (xy 298.89937 -241.007542)
			(xy 298.849756 -240.98807) (xy 298.803598 -240.961421) (xy 298.761927 -240.92819) (xy 298.725675 -240.889119)
			(xy 298.695651 -240.845082) (xy 298.672525 -240.797061) (xy 298.656815 -240.746131) (xy 298.648872 -240.693427)
			(xy 284.272492 -240.693427) (xy 284.264549 -240.746131) (xy 284.248839 -240.797061) (xy 284.225713 -240.845082)
			(xy 284.195689 -240.889119) (xy 284.159437 -240.92819) (xy 284.117766 -240.961421) (xy 284.071608 -240.98807)
			(xy 284.021994 -241.007542) (xy 283.970032 -241.019402) (xy 283.916882 -241.023386) (xy 283.863732 -241.019402)
			(xy 283.81177 -241.007542) (xy 283.762156 -240.98807) (xy 283.715998 -240.961421) (xy 283.674327 -240.92819)
			(xy 283.638075 -240.889119) (xy 283.608051 -240.845082) (xy 283.584925 -240.797061) (xy 283.569215 -240.746131)
			(xy 283.561272 -240.693427) (xy 269.184892 -240.693427) (xy 269.176949 -240.746131) (xy 269.161239 -240.797061)
			(xy 269.138113 -240.845082) (xy 269.108089 -240.889119) (xy 269.071837 -240.92819) (xy 269.030166 -240.961421)
			(xy 268.984008 -240.98807) (xy 268.934394 -241.007542) (xy 268.882432 -241.019402) (xy 268.829282 -241.023386)
			(xy 268.776132 -241.019402) (xy 268.72417 -241.007542) (xy 268.674556 -240.98807) (xy 268.628398 -240.961421)
			(xy 268.586727 -240.92819) (xy 268.550475 -240.889119) (xy 268.520451 -240.845082) (xy 268.497325 -240.797061)
			(xy 268.481615 -240.746131) (xy 268.473672 -240.693427) (xy 254.20828 -240.693427) (xy 254.20828 -241.543311)
			(xy 264.373604 -241.543311) (xy 264.373604 -241.490013) (xy 264.381547 -241.437309) (xy 264.397257 -241.386379)
			(xy 264.420383 -241.338358) (xy 264.450407 -241.294321) (xy 264.486659 -241.25525) (xy 264.52833 -241.222019)
			(xy 264.574488 -241.19537) (xy 264.624102 -241.175898) (xy 264.676064 -241.164038) (xy 264.729214 -241.160055)
			(xy 264.782364 -241.164038) (xy 264.834326 -241.175898) (xy 264.88394 -241.19537) (xy 264.930098 -241.222019)
			(xy 264.971769 -241.25525) (xy 265.008021 -241.294321) (xy 265.038045 -241.338358) (xy 265.061171 -241.386379)
			(xy 265.076881 -241.437309) (xy 265.084824 -241.490013) (xy 265.085322 -241.516662) (xy 265.084824 -241.543311)
			(xy 279.461204 -241.543311) (xy 279.461204 -241.490013) (xy 279.469147 -241.437309) (xy 279.484857 -241.386379)
			(xy 279.507983 -241.338358) (xy 279.538007 -241.294321) (xy 279.574259 -241.25525) (xy 279.61593 -241.222019)
			(xy 279.662088 -241.19537) (xy 279.711702 -241.175898) (xy 279.763664 -241.164038) (xy 279.816814 -241.160055)
			(xy 279.869964 -241.164038) (xy 279.921926 -241.175898) (xy 279.97154 -241.19537) (xy 280.017698 -241.222019)
			(xy 280.059369 -241.25525) (xy 280.095621 -241.294321) (xy 280.125645 -241.338358) (xy 280.148771 -241.386379)
			(xy 280.164481 -241.437309) (xy 280.172424 -241.490013) (xy 280.172922 -241.516662) (xy 280.172424 -241.543311)
			(xy 294.548804 -241.543311) (xy 294.548804 -241.490013) (xy 294.556747 -241.437309) (xy 294.572457 -241.386379)
			(xy 294.595583 -241.338358) (xy 294.625607 -241.294321) (xy 294.661859 -241.25525) (xy 294.70353 -241.222019)
			(xy 294.749688 -241.19537) (xy 294.799302 -241.175898) (xy 294.851264 -241.164038) (xy 294.904414 -241.160055)
			(xy 294.957564 -241.164038) (xy 295.009526 -241.175898) (xy 295.05914 -241.19537) (xy 295.105298 -241.222019)
			(xy 295.146969 -241.25525) (xy 295.183221 -241.294321) (xy 295.213245 -241.338358) (xy 295.236371 -241.386379)
			(xy 295.252081 -241.437309) (xy 295.260024 -241.490013) (xy 295.260522 -241.516662) (xy 295.260024 -241.543311)
			(xy 295.252081 -241.596015) (xy 295.236371 -241.646945) (xy 295.213245 -241.694966) (xy 295.183221 -241.739003)
			(xy 295.146969 -241.778074) (xy 295.105298 -241.811305) (xy 295.05914 -241.837954) (xy 295.009526 -241.857426)
			(xy 294.957564 -241.869286) (xy 294.904414 -241.87327) (xy 294.851264 -241.869286) (xy 294.799302 -241.857426)
			(xy 294.749688 -241.837954) (xy 294.70353 -241.811305) (xy 294.661859 -241.778074) (xy 294.625607 -241.739003)
			(xy 294.595583 -241.694966) (xy 294.572457 -241.646945) (xy 294.556747 -241.596015) (xy 294.548804 -241.543311)
			(xy 280.172424 -241.543311) (xy 280.164481 -241.596015) (xy 280.148771 -241.646945) (xy 280.125645 -241.694966)
			(xy 280.095621 -241.739003) (xy 280.059369 -241.778074) (xy 280.017698 -241.811305) (xy 279.97154 -241.837954)
			(xy 279.921926 -241.857426) (xy 279.869964 -241.869286) (xy 279.816814 -241.87327) (xy 279.763664 -241.869286)
			(xy 279.711702 -241.857426) (xy 279.662088 -241.837954) (xy 279.61593 -241.811305) (xy 279.574259 -241.778074)
			(xy 279.538007 -241.739003) (xy 279.507983 -241.694966) (xy 279.484857 -241.646945) (xy 279.469147 -241.596015)
			(xy 279.461204 -241.543311) (xy 265.084824 -241.543311) (xy 265.076881 -241.596015) (xy 265.061171 -241.646945)
			(xy 265.038045 -241.694966) (xy 265.008021 -241.739003) (xy 264.971769 -241.778074) (xy 264.930098 -241.811305)
			(xy 264.88394 -241.837954) (xy 264.834326 -241.857426) (xy 264.782364 -241.869286) (xy 264.729214 -241.87327)
			(xy 264.676064 -241.869286) (xy 264.624102 -241.857426) (xy 264.574488 -241.837954) (xy 264.52833 -241.811305)
			(xy 264.486659 -241.778074) (xy 264.450407 -241.739003) (xy 264.420383 -241.694966) (xy 264.397257 -241.646945)
			(xy 264.381547 -241.596015) (xy 264.373604 -241.543311) (xy 254.20828 -241.543311) (xy 254.20828 -242.393449)
			(xy 260.929872 -242.393449) (xy 260.929872 -242.340151) (xy 260.937815 -242.287447) (xy 260.953525 -242.236517)
			(xy 260.976651 -242.188496) (xy 261.006675 -242.144459) (xy 261.042927 -242.105388) (xy 261.084598 -242.072157)
			(xy 261.130756 -242.045508) (xy 261.18037 -242.026036) (xy 261.232332 -242.014176) (xy 261.285482 -242.010193)
			(xy 261.338632 -242.014176) (xy 261.390594 -242.026036) (xy 261.440208 -242.045508) (xy 261.486366 -242.072157)
			(xy 261.528037 -242.105388) (xy 261.564289 -242.144459) (xy 261.594313 -242.188496) (xy 261.617439 -242.236517)
			(xy 261.633149 -242.287447) (xy 261.641092 -242.340151) (xy 261.64159 -242.3668) (xy 261.641092 -242.393449)
			(xy 268.473672 -242.393449) (xy 268.473672 -242.340151) (xy 268.481615 -242.287447) (xy 268.497325 -242.236517)
			(xy 268.520451 -242.188496) (xy 268.550475 -242.144459) (xy 268.586727 -242.105388) (xy 268.628398 -242.072157)
			(xy 268.674556 -242.045508) (xy 268.72417 -242.026036) (xy 268.776132 -242.014176) (xy 268.829282 -242.010193)
			(xy 268.882432 -242.014176) (xy 268.934394 -242.026036) (xy 268.984008 -242.045508) (xy 269.030166 -242.072157)
			(xy 269.071837 -242.105388) (xy 269.108089 -242.144459) (xy 269.138113 -242.188496) (xy 269.161239 -242.236517)
			(xy 269.176949 -242.287447) (xy 269.184892 -242.340151) (xy 269.18539 -242.3668) (xy 269.184892 -242.393449)
			(xy 276.017472 -242.393449) (xy 276.017472 -242.340151) (xy 276.025415 -242.287447) (xy 276.041125 -242.236517)
			(xy 276.064251 -242.188496) (xy 276.094275 -242.144459) (xy 276.130527 -242.105388) (xy 276.172198 -242.072157)
			(xy 276.218356 -242.045508) (xy 276.26797 -242.026036) (xy 276.319932 -242.014176) (xy 276.373082 -242.010193)
			(xy 276.426232 -242.014176) (xy 276.478194 -242.026036) (xy 276.527808 -242.045508) (xy 276.573966 -242.072157)
			(xy 276.615637 -242.105388) (xy 276.651889 -242.144459) (xy 276.681913 -242.188496) (xy 276.705039 -242.236517)
			(xy 276.720749 -242.287447) (xy 276.728692 -242.340151) (xy 276.72919 -242.3668) (xy 276.728692 -242.393449)
			(xy 283.561272 -242.393449) (xy 283.561272 -242.340151) (xy 283.569215 -242.287447) (xy 283.584925 -242.236517)
			(xy 283.608051 -242.188496) (xy 283.638075 -242.144459) (xy 283.674327 -242.105388) (xy 283.715998 -242.072157)
			(xy 283.762156 -242.045508) (xy 283.81177 -242.026036) (xy 283.863732 -242.014176) (xy 283.916882 -242.010193)
			(xy 283.970032 -242.014176) (xy 284.021994 -242.026036) (xy 284.071608 -242.045508) (xy 284.117766 -242.072157)
			(xy 284.159437 -242.105388) (xy 284.195689 -242.144459) (xy 284.225713 -242.188496) (xy 284.248839 -242.236517)
			(xy 284.264549 -242.287447) (xy 284.272492 -242.340151) (xy 284.27299 -242.3668) (xy 284.272492 -242.393449)
			(xy 291.105072 -242.393449) (xy 291.105072 -242.340151) (xy 291.113015 -242.287447) (xy 291.128725 -242.236517)
			(xy 291.151851 -242.188496) (xy 291.181875 -242.144459) (xy 291.218127 -242.105388) (xy 291.259798 -242.072157)
			(xy 291.305956 -242.045508) (xy 291.35557 -242.026036) (xy 291.407532 -242.014176) (xy 291.460682 -242.010193)
			(xy 291.513832 -242.014176) (xy 291.565794 -242.026036) (xy 291.615408 -242.045508) (xy 291.661566 -242.072157)
			(xy 291.703237 -242.105388) (xy 291.739489 -242.144459) (xy 291.769513 -242.188496) (xy 291.792639 -242.236517)
			(xy 291.808349 -242.287447) (xy 291.816292 -242.340151) (xy 291.81679 -242.3668) (xy 291.816292 -242.393449)
			(xy 298.648872 -242.393449) (xy 298.648872 -242.340151) (xy 298.656815 -242.287447) (xy 298.672525 -242.236517)
			(xy 298.695651 -242.188496) (xy 298.725675 -242.144459) (xy 298.761927 -242.105388) (xy 298.803598 -242.072157)
			(xy 298.849756 -242.045508) (xy 298.89937 -242.026036) (xy 298.951332 -242.014176) (xy 299.004482 -242.010193)
			(xy 299.057632 -242.014176) (xy 299.109594 -242.026036) (xy 299.159208 -242.045508) (xy 299.205366 -242.072157)
			(xy 299.247037 -242.105388) (xy 299.283289 -242.144459) (xy 299.313313 -242.188496) (xy 299.336439 -242.236517)
			(xy 299.352149 -242.287447) (xy 299.360092 -242.340151) (xy 299.36059 -242.3668) (xy 299.360092 -242.393449)
			(xy 303.982872 -242.393449) (xy 303.982872 -242.340151) (xy 303.990815 -242.287447) (xy 304.006525 -242.236517)
			(xy 304.029651 -242.188496) (xy 304.059675 -242.144459) (xy 304.095927 -242.105388) (xy 304.137598 -242.072157)
			(xy 304.183756 -242.045508) (xy 304.23337 -242.026036) (xy 304.285332 -242.014176) (xy 304.338482 -242.010193)
			(xy 304.391632 -242.014176) (xy 304.443594 -242.026036) (xy 304.493208 -242.045508) (xy 304.539366 -242.072157)
			(xy 304.581037 -242.105388) (xy 304.617289 -242.144459) (xy 304.647313 -242.188496) (xy 304.670439 -242.236517)
			(xy 304.686149 -242.287447) (xy 304.694092 -242.340151) (xy 304.69459 -242.3668) (xy 304.694092 -242.393449)
			(xy 311.526672 -242.393449) (xy 311.526672 -242.340151) (xy 311.534615 -242.287447) (xy 311.550325 -242.236517)
			(xy 311.573451 -242.188496) (xy 311.603475 -242.144459) (xy 311.639727 -242.105388) (xy 311.681398 -242.072157)
			(xy 311.727556 -242.045508) (xy 311.77717 -242.026036) (xy 311.829132 -242.014176) (xy 311.882282 -242.010193)
			(xy 311.935432 -242.014176) (xy 311.987394 -242.026036) (xy 312.037008 -242.045508) (xy 312.083166 -242.072157)
			(xy 312.124837 -242.105388) (xy 312.161089 -242.144459) (xy 312.191113 -242.188496) (xy 312.214239 -242.236517)
			(xy 312.229949 -242.287447) (xy 312.237892 -242.340151) (xy 312.23839 -242.3668) (xy 312.237892 -242.393449)
			(xy 312.229949 -242.446153) (xy 312.214239 -242.497083) (xy 312.191113 -242.545104) (xy 312.161089 -242.589141)
			(xy 312.124837 -242.628212) (xy 312.083166 -242.661443) (xy 312.037008 -242.688092) (xy 311.987394 -242.707564)
			(xy 311.935432 -242.719424) (xy 311.882282 -242.723408) (xy 311.829132 -242.719424) (xy 311.77717 -242.707564)
			(xy 311.727556 -242.688092) (xy 311.681398 -242.661443) (xy 311.639727 -242.628212) (xy 311.603475 -242.589141)
			(xy 311.573451 -242.545104) (xy 311.550325 -242.497083) (xy 311.534615 -242.446153) (xy 311.526672 -242.393449)
			(xy 304.694092 -242.393449) (xy 304.686149 -242.446153) (xy 304.670439 -242.497083) (xy 304.647313 -242.545104)
			(xy 304.617289 -242.589141) (xy 304.581037 -242.628212) (xy 304.539366 -242.661443) (xy 304.493208 -242.688092)
			(xy 304.443594 -242.707564) (xy 304.391632 -242.719424) (xy 304.338482 -242.723408) (xy 304.285332 -242.719424)
			(xy 304.23337 -242.707564) (xy 304.183756 -242.688092) (xy 304.137598 -242.661443) (xy 304.095927 -242.628212)
			(xy 304.059675 -242.589141) (xy 304.029651 -242.545104) (xy 304.006525 -242.497083) (xy 303.990815 -242.446153)
			(xy 303.982872 -242.393449) (xy 299.360092 -242.393449) (xy 299.352149 -242.446153) (xy 299.336439 -242.497083)
			(xy 299.313313 -242.545104) (xy 299.283289 -242.589141) (xy 299.247037 -242.628212) (xy 299.205366 -242.661443)
			(xy 299.159208 -242.688092) (xy 299.109594 -242.707564) (xy 299.057632 -242.719424) (xy 299.004482 -242.723408)
			(xy 298.951332 -242.719424) (xy 298.89937 -242.707564) (xy 298.849756 -242.688092) (xy 298.803598 -242.661443)
			(xy 298.761927 -242.628212) (xy 298.725675 -242.589141) (xy 298.695651 -242.545104) (xy 298.672525 -242.497083)
			(xy 298.656815 -242.446153) (xy 298.648872 -242.393449) (xy 291.816292 -242.393449) (xy 291.808349 -242.446153)
			(xy 291.792639 -242.497083) (xy 291.769513 -242.545104) (xy 291.739489 -242.589141) (xy 291.703237 -242.628212)
			(xy 291.661566 -242.661443) (xy 291.615408 -242.688092) (xy 291.565794 -242.707564) (xy 291.513832 -242.719424)
			(xy 291.460682 -242.723408) (xy 291.407532 -242.719424) (xy 291.35557 -242.707564) (xy 291.305956 -242.688092)
			(xy 291.259798 -242.661443) (xy 291.218127 -242.628212) (xy 291.181875 -242.589141) (xy 291.151851 -242.545104)
			(xy 291.128725 -242.497083) (xy 291.113015 -242.446153) (xy 291.105072 -242.393449) (xy 284.272492 -242.393449)
			(xy 284.264549 -242.446153) (xy 284.248839 -242.497083) (xy 284.225713 -242.545104) (xy 284.195689 -242.589141)
			(xy 284.159437 -242.628212) (xy 284.117766 -242.661443) (xy 284.071608 -242.688092) (xy 284.021994 -242.707564)
			(xy 283.970032 -242.719424) (xy 283.916882 -242.723408) (xy 283.863732 -242.719424) (xy 283.81177 -242.707564)
			(xy 283.762156 -242.688092) (xy 283.715998 -242.661443) (xy 283.674327 -242.628212) (xy 283.638075 -242.589141)
			(xy 283.608051 -242.545104) (xy 283.584925 -242.497083) (xy 283.569215 -242.446153) (xy 283.561272 -242.393449)
			(xy 276.728692 -242.393449) (xy 276.720749 -242.446153) (xy 276.705039 -242.497083) (xy 276.681913 -242.545104)
			(xy 276.651889 -242.589141) (xy 276.615637 -242.628212) (xy 276.573966 -242.661443) (xy 276.527808 -242.688092)
			(xy 276.478194 -242.707564) (xy 276.426232 -242.719424) (xy 276.373082 -242.723408) (xy 276.319932 -242.719424)
			(xy 276.26797 -242.707564) (xy 276.218356 -242.688092) (xy 276.172198 -242.661443) (xy 276.130527 -242.628212)
			(xy 276.094275 -242.589141) (xy 276.064251 -242.545104) (xy 276.041125 -242.497083) (xy 276.025415 -242.446153)
			(xy 276.017472 -242.393449) (xy 269.184892 -242.393449) (xy 269.176949 -242.446153) (xy 269.161239 -242.497083)
			(xy 269.138113 -242.545104) (xy 269.108089 -242.589141) (xy 269.071837 -242.628212) (xy 269.030166 -242.661443)
			(xy 268.984008 -242.688092) (xy 268.934394 -242.707564) (xy 268.882432 -242.719424) (xy 268.829282 -242.723408)
			(xy 268.776132 -242.719424) (xy 268.72417 -242.707564) (xy 268.674556 -242.688092) (xy 268.628398 -242.661443)
			(xy 268.586727 -242.628212) (xy 268.550475 -242.589141) (xy 268.520451 -242.545104) (xy 268.497325 -242.497083)
			(xy 268.481615 -242.446153) (xy 268.473672 -242.393449) (xy 261.641092 -242.393449) (xy 261.633149 -242.446153)
			(xy 261.617439 -242.497083) (xy 261.594313 -242.545104) (xy 261.564289 -242.589141) (xy 261.528037 -242.628212)
			(xy 261.486366 -242.661443) (xy 261.440208 -242.688092) (xy 261.390594 -242.707564) (xy 261.338632 -242.719424)
			(xy 261.285482 -242.723408) (xy 261.232332 -242.719424) (xy 261.18037 -242.707564) (xy 261.130756 -242.688092)
			(xy 261.084598 -242.661443) (xy 261.042927 -242.628212) (xy 261.006675 -242.589141) (xy 260.976651 -242.545104)
			(xy 260.953525 -242.497083) (xy 260.937815 -242.446153) (xy 260.929872 -242.393449) (xy 254.20828 -242.393449)
			(xy 254.20828 -243.243333) (xy 256.829804 -243.243333) (xy 256.829804 -243.190035) (xy 256.837747 -243.137331)
			(xy 256.853457 -243.086401) (xy 256.876583 -243.03838) (xy 256.906607 -242.994343) (xy 256.942859 -242.955272)
			(xy 256.98453 -242.922041) (xy 257.030688 -242.895392) (xy 257.080302 -242.87592) (xy 257.132264 -242.86406)
			(xy 257.185414 -242.860077) (xy 257.238564 -242.86406) (xy 257.290526 -242.87592) (xy 257.34014 -242.895392)
			(xy 257.386298 -242.922041) (xy 257.427969 -242.955272) (xy 257.464221 -242.994343) (xy 257.494245 -243.03838)
			(xy 257.517371 -243.086401) (xy 257.533081 -243.137331) (xy 257.541024 -243.190035) (xy 257.541522 -243.216684)
			(xy 257.541024 -243.243333) (xy 260.929872 -243.243333) (xy 260.929872 -243.190035) (xy 260.937815 -243.137331)
			(xy 260.953525 -243.086401) (xy 260.976651 -243.03838) (xy 261.006675 -242.994343) (xy 261.042927 -242.955272)
			(xy 261.084598 -242.922041) (xy 261.130756 -242.895392) (xy 261.18037 -242.87592) (xy 261.232332 -242.86406)
			(xy 261.285482 -242.860077) (xy 261.338632 -242.86406) (xy 261.390594 -242.87592) (xy 261.440208 -242.895392)
			(xy 261.486366 -242.922041) (xy 261.528037 -242.955272) (xy 261.564289 -242.994343) (xy 261.594313 -243.03838)
			(xy 261.617439 -243.086401) (xy 261.633149 -243.137331) (xy 261.641092 -243.190035) (xy 261.64159 -243.216684)
			(xy 261.641092 -243.243333) (xy 264.373604 -243.243333) (xy 264.373604 -243.190035) (xy 264.381547 -243.137331)
			(xy 264.397257 -243.086401) (xy 264.420383 -243.03838) (xy 264.450407 -242.994343) (xy 264.486659 -242.955272)
			(xy 264.52833 -242.922041) (xy 264.574488 -242.895392) (xy 264.624102 -242.87592) (xy 264.676064 -242.86406)
			(xy 264.729214 -242.860077) (xy 264.782364 -242.86406) (xy 264.834326 -242.87592) (xy 264.88394 -242.895392)
			(xy 264.930098 -242.922041) (xy 264.971769 -242.955272) (xy 265.008021 -242.994343) (xy 265.038045 -243.03838)
			(xy 265.061171 -243.086401) (xy 265.076881 -243.137331) (xy 265.084824 -243.190035) (xy 265.085322 -243.216684)
			(xy 265.084824 -243.243333) (xy 268.473672 -243.243333) (xy 268.473672 -243.190035) (xy 268.481615 -243.137331)
			(xy 268.497325 -243.086401) (xy 268.520451 -243.03838) (xy 268.550475 -242.994343) (xy 268.586727 -242.955272)
			(xy 268.628398 -242.922041) (xy 268.674556 -242.895392) (xy 268.72417 -242.87592) (xy 268.776132 -242.86406)
			(xy 268.829282 -242.860077) (xy 268.882432 -242.86406) (xy 268.934394 -242.87592) (xy 268.984008 -242.895392)
			(xy 269.030166 -242.922041) (xy 269.071837 -242.955272) (xy 269.108089 -242.994343) (xy 269.138113 -243.03838)
			(xy 269.161239 -243.086401) (xy 269.176949 -243.137331) (xy 269.184892 -243.190035) (xy 269.18539 -243.216684)
			(xy 269.184892 -243.243333) (xy 271.917404 -243.243333) (xy 271.917404 -243.190035) (xy 271.925347 -243.137331)
			(xy 271.941057 -243.086401) (xy 271.964183 -243.03838) (xy 271.994207 -242.994343) (xy 272.030459 -242.955272)
			(xy 272.07213 -242.922041) (xy 272.118288 -242.895392) (xy 272.167902 -242.87592) (xy 272.219864 -242.86406)
			(xy 272.273014 -242.860077) (xy 272.326164 -242.86406) (xy 272.378126 -242.87592) (xy 272.42774 -242.895392)
			(xy 272.473898 -242.922041) (xy 272.515569 -242.955272) (xy 272.551821 -242.994343) (xy 272.581845 -243.03838)
			(xy 272.604971 -243.086401) (xy 272.620681 -243.137331) (xy 272.628624 -243.190035) (xy 272.629122 -243.216684)
			(xy 272.628624 -243.243333) (xy 276.017472 -243.243333) (xy 276.017472 -243.190035) (xy 276.025415 -243.137331)
			(xy 276.041125 -243.086401) (xy 276.064251 -243.03838) (xy 276.094275 -242.994343) (xy 276.130527 -242.955272)
			(xy 276.172198 -242.922041) (xy 276.218356 -242.895392) (xy 276.26797 -242.87592) (xy 276.319932 -242.86406)
			(xy 276.373082 -242.860077) (xy 276.426232 -242.86406) (xy 276.478194 -242.87592) (xy 276.527808 -242.895392)
			(xy 276.573966 -242.922041) (xy 276.615637 -242.955272) (xy 276.651889 -242.994343) (xy 276.681913 -243.03838)
			(xy 276.705039 -243.086401) (xy 276.720749 -243.137331) (xy 276.728692 -243.190035) (xy 276.72919 -243.216684)
			(xy 276.728692 -243.243333) (xy 279.461204 -243.243333) (xy 279.461204 -243.190035) (xy 279.469147 -243.137331)
			(xy 279.484857 -243.086401) (xy 279.507983 -243.03838) (xy 279.538007 -242.994343) (xy 279.574259 -242.955272)
			(xy 279.61593 -242.922041) (xy 279.662088 -242.895392) (xy 279.711702 -242.87592) (xy 279.763664 -242.86406)
			(xy 279.816814 -242.860077) (xy 279.869964 -242.86406) (xy 279.921926 -242.87592) (xy 279.97154 -242.895392)
			(xy 280.017698 -242.922041) (xy 280.059369 -242.955272) (xy 280.095621 -242.994343) (xy 280.125645 -243.03838)
			(xy 280.148771 -243.086401) (xy 280.164481 -243.137331) (xy 280.172424 -243.190035) (xy 280.172922 -243.216684)
			(xy 280.172424 -243.243333) (xy 283.561272 -243.243333) (xy 283.561272 -243.190035) (xy 283.569215 -243.137331)
			(xy 283.584925 -243.086401) (xy 283.608051 -243.03838) (xy 283.638075 -242.994343) (xy 283.674327 -242.955272)
			(xy 283.715998 -242.922041) (xy 283.762156 -242.895392) (xy 283.81177 -242.87592) (xy 283.863732 -242.86406)
			(xy 283.916882 -242.860077) (xy 283.970032 -242.86406) (xy 284.021994 -242.87592) (xy 284.071608 -242.895392)
			(xy 284.117766 -242.922041) (xy 284.159437 -242.955272) (xy 284.195689 -242.994343) (xy 284.225713 -243.03838)
			(xy 284.248839 -243.086401) (xy 284.264549 -243.137331) (xy 284.272492 -243.190035) (xy 284.27299 -243.216684)
			(xy 284.272492 -243.243333) (xy 287.005004 -243.243333) (xy 287.005004 -243.190035) (xy 287.012947 -243.137331)
			(xy 287.028657 -243.086401) (xy 287.051783 -243.03838) (xy 287.081807 -242.994343) (xy 287.118059 -242.955272)
			(xy 287.15973 -242.922041) (xy 287.205888 -242.895392) (xy 287.255502 -242.87592) (xy 287.307464 -242.86406)
			(xy 287.360614 -242.860077) (xy 287.413764 -242.86406) (xy 287.465726 -242.87592) (xy 287.51534 -242.895392)
			(xy 287.561498 -242.922041) (xy 287.603169 -242.955272) (xy 287.639421 -242.994343) (xy 287.669445 -243.03838)
			(xy 287.692571 -243.086401) (xy 287.708281 -243.137331) (xy 287.716224 -243.190035) (xy 287.716722 -243.216684)
			(xy 287.716224 -243.243333) (xy 291.105072 -243.243333) (xy 291.105072 -243.190035) (xy 291.113015 -243.137331)
			(xy 291.128725 -243.086401) (xy 291.151851 -243.03838) (xy 291.181875 -242.994343) (xy 291.218127 -242.955272)
			(xy 291.259798 -242.922041) (xy 291.305956 -242.895392) (xy 291.35557 -242.87592) (xy 291.407532 -242.86406)
			(xy 291.460682 -242.860077) (xy 291.513832 -242.86406) (xy 291.565794 -242.87592) (xy 291.615408 -242.895392)
			(xy 291.661566 -242.922041) (xy 291.703237 -242.955272) (xy 291.739489 -242.994343) (xy 291.769513 -243.03838)
			(xy 291.792639 -243.086401) (xy 291.808349 -243.137331) (xy 291.816292 -243.190035) (xy 291.81679 -243.216684)
			(xy 291.816292 -243.243333) (xy 294.548804 -243.243333) (xy 294.548804 -243.190035) (xy 294.556747 -243.137331)
			(xy 294.572457 -243.086401) (xy 294.595583 -243.03838) (xy 294.625607 -242.994343) (xy 294.661859 -242.955272)
			(xy 294.70353 -242.922041) (xy 294.749688 -242.895392) (xy 294.799302 -242.87592) (xy 294.851264 -242.86406)
			(xy 294.904414 -242.860077) (xy 294.957564 -242.86406) (xy 295.009526 -242.87592) (xy 295.05914 -242.895392)
			(xy 295.105298 -242.922041) (xy 295.146969 -242.955272) (xy 295.183221 -242.994343) (xy 295.213245 -243.03838)
			(xy 295.236371 -243.086401) (xy 295.252081 -243.137331) (xy 295.260024 -243.190035) (xy 295.260522 -243.216684)
			(xy 295.260024 -243.243333) (xy 298.648872 -243.243333) (xy 298.648872 -243.190035) (xy 298.656815 -243.137331)
			(xy 298.672525 -243.086401) (xy 298.695651 -243.03838) (xy 298.725675 -242.994343) (xy 298.761927 -242.955272)
			(xy 298.803598 -242.922041) (xy 298.849756 -242.895392) (xy 298.89937 -242.87592) (xy 298.951332 -242.86406)
			(xy 299.004482 -242.860077) (xy 299.057632 -242.86406) (xy 299.109594 -242.87592) (xy 299.159208 -242.895392)
			(xy 299.205366 -242.922041) (xy 299.247037 -242.955272) (xy 299.283289 -242.994343) (xy 299.313313 -243.03838)
			(xy 299.336439 -243.086401) (xy 299.352149 -243.137331) (xy 299.360092 -243.190035) (xy 299.36059 -243.216684)
			(xy 299.360092 -243.243333) (xy 302.092604 -243.243333) (xy 302.092604 -243.190035) (xy 302.100547 -243.137331)
			(xy 302.116257 -243.086401) (xy 302.139383 -243.03838) (xy 302.169407 -242.994343) (xy 302.205659 -242.955272)
			(xy 302.24733 -242.922041) (xy 302.293488 -242.895392) (xy 302.343102 -242.87592) (xy 302.395064 -242.86406)
			(xy 302.448214 -242.860077) (xy 302.501364 -242.86406) (xy 302.553326 -242.87592) (xy 302.60294 -242.895392)
			(xy 302.649098 -242.922041) (xy 302.690769 -242.955272) (xy 302.727021 -242.994343) (xy 302.757045 -243.03838)
			(xy 302.780171 -243.086401) (xy 302.795881 -243.137331) (xy 302.803824 -243.190035) (xy 302.804322 -243.216684)
			(xy 302.803824 -243.243333) (xy 303.982872 -243.243333) (xy 303.982872 -243.190035) (xy 303.990815 -243.137331)
			(xy 304.006525 -243.086401) (xy 304.029651 -243.03838) (xy 304.059675 -242.994343) (xy 304.095927 -242.955272)
			(xy 304.137598 -242.922041) (xy 304.183756 -242.895392) (xy 304.23337 -242.87592) (xy 304.285332 -242.86406)
			(xy 304.338482 -242.860077) (xy 304.391632 -242.86406) (xy 304.443594 -242.87592) (xy 304.493208 -242.895392)
			(xy 304.539366 -242.922041) (xy 304.581037 -242.955272) (xy 304.617289 -242.994343) (xy 304.647313 -243.03838)
			(xy 304.670439 -243.086401) (xy 304.686149 -243.137331) (xy 304.694092 -243.190035) (xy 304.69459 -243.216684)
			(xy 304.694092 -243.243333) (xy 309.636404 -243.243333) (xy 309.636404 -243.190035) (xy 309.644347 -243.137331)
			(xy 309.660057 -243.086401) (xy 309.683183 -243.03838) (xy 309.713207 -242.994343) (xy 309.749459 -242.955272)
			(xy 309.79113 -242.922041) (xy 309.837288 -242.895392) (xy 309.886902 -242.87592) (xy 309.938864 -242.86406)
			(xy 309.992014 -242.860077) (xy 310.045164 -242.86406) (xy 310.097126 -242.87592) (xy 310.14674 -242.895392)
			(xy 310.192898 -242.922041) (xy 310.234569 -242.955272) (xy 310.270821 -242.994343) (xy 310.300845 -243.03838)
			(xy 310.323971 -243.086401) (xy 310.339681 -243.137331) (xy 310.347624 -243.190035) (xy 310.348122 -243.216684)
			(xy 310.347624 -243.243333) (xy 311.526672 -243.243333) (xy 311.526672 -243.190035) (xy 311.534615 -243.137331)
			(xy 311.550325 -243.086401) (xy 311.573451 -243.03838) (xy 311.603475 -242.994343) (xy 311.639727 -242.955272)
			(xy 311.681398 -242.922041) (xy 311.727556 -242.895392) (xy 311.77717 -242.87592) (xy 311.829132 -242.86406)
			(xy 311.882282 -242.860077) (xy 311.935432 -242.86406) (xy 311.987394 -242.87592) (xy 312.037008 -242.895392)
			(xy 312.083166 -242.922041) (xy 312.124837 -242.955272) (xy 312.161089 -242.994343) (xy 312.191113 -243.03838)
			(xy 312.214239 -243.086401) (xy 312.229949 -243.137331) (xy 312.237892 -243.190035) (xy 312.23839 -243.216684)
			(xy 312.237892 -243.243333) (xy 312.229949 -243.296037) (xy 312.214239 -243.346967) (xy 312.191113 -243.394988)
			(xy 312.161089 -243.439025) (xy 312.124837 -243.478096) (xy 312.083166 -243.511327) (xy 312.037008 -243.537976)
			(xy 311.987394 -243.557448) (xy 311.935432 -243.569308) (xy 311.882282 -243.573292) (xy 311.829132 -243.569308)
			(xy 311.77717 -243.557448) (xy 311.727556 -243.537976) (xy 311.681398 -243.511327) (xy 311.639727 -243.478096)
			(xy 311.603475 -243.439025) (xy 311.573451 -243.394988) (xy 311.550325 -243.346967) (xy 311.534615 -243.296037)
			(xy 311.526672 -243.243333) (xy 310.347624 -243.243333) (xy 310.339681 -243.296037) (xy 310.323971 -243.346967)
			(xy 310.300845 -243.394988) (xy 310.270821 -243.439025) (xy 310.234569 -243.478096) (xy 310.192898 -243.511327)
			(xy 310.14674 -243.537976) (xy 310.097126 -243.557448) (xy 310.045164 -243.569308) (xy 309.992014 -243.573292)
			(xy 309.938864 -243.569308) (xy 309.886902 -243.557448) (xy 309.837288 -243.537976) (xy 309.79113 -243.511327)
			(xy 309.749459 -243.478096) (xy 309.713207 -243.439025) (xy 309.683183 -243.394988) (xy 309.660057 -243.346967)
			(xy 309.644347 -243.296037) (xy 309.636404 -243.243333) (xy 304.694092 -243.243333) (xy 304.686149 -243.296037)
			(xy 304.670439 -243.346967) (xy 304.647313 -243.394988) (xy 304.617289 -243.439025) (xy 304.581037 -243.478096)
			(xy 304.539366 -243.511327) (xy 304.493208 -243.537976) (xy 304.443594 -243.557448) (xy 304.391632 -243.569308)
			(xy 304.338482 -243.573292) (xy 304.285332 -243.569308) (xy 304.23337 -243.557448) (xy 304.183756 -243.537976)
			(xy 304.137598 -243.511327) (xy 304.095927 -243.478096) (xy 304.059675 -243.439025) (xy 304.029651 -243.394988)
			(xy 304.006525 -243.346967) (xy 303.990815 -243.296037) (xy 303.982872 -243.243333) (xy 302.803824 -243.243333)
			(xy 302.795881 -243.296037) (xy 302.780171 -243.346967) (xy 302.757045 -243.394988) (xy 302.727021 -243.439025)
			(xy 302.690769 -243.478096) (xy 302.649098 -243.511327) (xy 302.60294 -243.537976) (xy 302.553326 -243.557448)
			(xy 302.501364 -243.569308) (xy 302.448214 -243.573292) (xy 302.395064 -243.569308) (xy 302.343102 -243.557448)
			(xy 302.293488 -243.537976) (xy 302.24733 -243.511327) (xy 302.205659 -243.478096) (xy 302.169407 -243.439025)
			(xy 302.139383 -243.394988) (xy 302.116257 -243.346967) (xy 302.100547 -243.296037) (xy 302.092604 -243.243333)
			(xy 299.360092 -243.243333) (xy 299.352149 -243.296037) (xy 299.336439 -243.346967) (xy 299.313313 -243.394988)
			(xy 299.283289 -243.439025) (xy 299.247037 -243.478096) (xy 299.205366 -243.511327) (xy 299.159208 -243.537976)
			(xy 299.109594 -243.557448) (xy 299.057632 -243.569308) (xy 299.004482 -243.573292) (xy 298.951332 -243.569308)
			(xy 298.89937 -243.557448) (xy 298.849756 -243.537976) (xy 298.803598 -243.511327) (xy 298.761927 -243.478096)
			(xy 298.725675 -243.439025) (xy 298.695651 -243.394988) (xy 298.672525 -243.346967) (xy 298.656815 -243.296037)
			(xy 298.648872 -243.243333) (xy 295.260024 -243.243333) (xy 295.252081 -243.296037) (xy 295.236371 -243.346967)
			(xy 295.213245 -243.394988) (xy 295.183221 -243.439025) (xy 295.146969 -243.478096) (xy 295.105298 -243.511327)
			(xy 295.05914 -243.537976) (xy 295.009526 -243.557448) (xy 294.957564 -243.569308) (xy 294.904414 -243.573292)
			(xy 294.851264 -243.569308) (xy 294.799302 -243.557448) (xy 294.749688 -243.537976) (xy 294.70353 -243.511327)
			(xy 294.661859 -243.478096) (xy 294.625607 -243.439025) (xy 294.595583 -243.394988) (xy 294.572457 -243.346967)
			(xy 294.556747 -243.296037) (xy 294.548804 -243.243333) (xy 291.816292 -243.243333) (xy 291.808349 -243.296037)
			(xy 291.792639 -243.346967) (xy 291.769513 -243.394988) (xy 291.739489 -243.439025) (xy 291.703237 -243.478096)
			(xy 291.661566 -243.511327) (xy 291.615408 -243.537976) (xy 291.565794 -243.557448) (xy 291.513832 -243.569308)
			(xy 291.460682 -243.573292) (xy 291.407532 -243.569308) (xy 291.35557 -243.557448) (xy 291.305956 -243.537976)
			(xy 291.259798 -243.511327) (xy 291.218127 -243.478096) (xy 291.181875 -243.439025) (xy 291.151851 -243.394988)
			(xy 291.128725 -243.346967) (xy 291.113015 -243.296037) (xy 291.105072 -243.243333) (xy 287.716224 -243.243333)
			(xy 287.708281 -243.296037) (xy 287.692571 -243.346967) (xy 287.669445 -243.394988) (xy 287.639421 -243.439025)
			(xy 287.603169 -243.478096) (xy 287.561498 -243.511327) (xy 287.51534 -243.537976) (xy 287.465726 -243.557448)
			(xy 287.413764 -243.569308) (xy 287.360614 -243.573292) (xy 287.307464 -243.569308) (xy 287.255502 -243.557448)
			(xy 287.205888 -243.537976) (xy 287.15973 -243.511327) (xy 287.118059 -243.478096) (xy 287.081807 -243.439025)
			(xy 287.051783 -243.394988) (xy 287.028657 -243.346967) (xy 287.012947 -243.296037) (xy 287.005004 -243.243333)
			(xy 284.272492 -243.243333) (xy 284.264549 -243.296037) (xy 284.248839 -243.346967) (xy 284.225713 -243.394988)
			(xy 284.195689 -243.439025) (xy 284.159437 -243.478096) (xy 284.117766 -243.511327) (xy 284.071608 -243.537976)
			(xy 284.021994 -243.557448) (xy 283.970032 -243.569308) (xy 283.916882 -243.573292) (xy 283.863732 -243.569308)
			(xy 283.81177 -243.557448) (xy 283.762156 -243.537976) (xy 283.715998 -243.511327) (xy 283.674327 -243.478096)
			(xy 283.638075 -243.439025) (xy 283.608051 -243.394988) (xy 283.584925 -243.346967) (xy 283.569215 -243.296037)
			(xy 283.561272 -243.243333) (xy 280.172424 -243.243333) (xy 280.164481 -243.296037) (xy 280.148771 -243.346967)
			(xy 280.125645 -243.394988) (xy 280.095621 -243.439025) (xy 280.059369 -243.478096) (xy 280.017698 -243.511327)
			(xy 279.97154 -243.537976) (xy 279.921926 -243.557448) (xy 279.869964 -243.569308) (xy 279.816814 -243.573292)
			(xy 279.763664 -243.569308) (xy 279.711702 -243.557448) (xy 279.662088 -243.537976) (xy 279.61593 -243.511327)
			(xy 279.574259 -243.478096) (xy 279.538007 -243.439025) (xy 279.507983 -243.394988) (xy 279.484857 -243.346967)
			(xy 279.469147 -243.296037) (xy 279.461204 -243.243333) (xy 276.728692 -243.243333) (xy 276.720749 -243.296037)
			(xy 276.705039 -243.346967) (xy 276.681913 -243.394988) (xy 276.651889 -243.439025) (xy 276.615637 -243.478096)
			(xy 276.573966 -243.511327) (xy 276.527808 -243.537976) (xy 276.478194 -243.557448) (xy 276.426232 -243.569308)
			(xy 276.373082 -243.573292) (xy 276.319932 -243.569308) (xy 276.26797 -243.557448) (xy 276.218356 -243.537976)
			(xy 276.172198 -243.511327) (xy 276.130527 -243.478096) (xy 276.094275 -243.439025) (xy 276.064251 -243.394988)
			(xy 276.041125 -243.346967) (xy 276.025415 -243.296037) (xy 276.017472 -243.243333) (xy 272.628624 -243.243333)
			(xy 272.620681 -243.296037) (xy 272.604971 -243.346967) (xy 272.581845 -243.394988) (xy 272.551821 -243.439025)
			(xy 272.515569 -243.478096) (xy 272.473898 -243.511327) (xy 272.42774 -243.537976) (xy 272.378126 -243.557448)
			(xy 272.326164 -243.569308) (xy 272.273014 -243.573292) (xy 272.219864 -243.569308) (xy 272.167902 -243.557448)
			(xy 272.118288 -243.537976) (xy 272.07213 -243.511327) (xy 272.030459 -243.478096) (xy 271.994207 -243.439025)
			(xy 271.964183 -243.394988) (xy 271.941057 -243.346967) (xy 271.925347 -243.296037) (xy 271.917404 -243.243333)
			(xy 269.184892 -243.243333) (xy 269.176949 -243.296037) (xy 269.161239 -243.346967) (xy 269.138113 -243.394988)
			(xy 269.108089 -243.439025) (xy 269.071837 -243.478096) (xy 269.030166 -243.511327) (xy 268.984008 -243.537976)
			(xy 268.934394 -243.557448) (xy 268.882432 -243.569308) (xy 268.829282 -243.573292) (xy 268.776132 -243.569308)
			(xy 268.72417 -243.557448) (xy 268.674556 -243.537976) (xy 268.628398 -243.511327) (xy 268.586727 -243.478096)
			(xy 268.550475 -243.439025) (xy 268.520451 -243.394988) (xy 268.497325 -243.346967) (xy 268.481615 -243.296037)
			(xy 268.473672 -243.243333) (xy 265.084824 -243.243333) (xy 265.076881 -243.296037) (xy 265.061171 -243.346967)
			(xy 265.038045 -243.394988) (xy 265.008021 -243.439025) (xy 264.971769 -243.478096) (xy 264.930098 -243.511327)
			(xy 264.88394 -243.537976) (xy 264.834326 -243.557448) (xy 264.782364 -243.569308) (xy 264.729214 -243.573292)
			(xy 264.676064 -243.569308) (xy 264.624102 -243.557448) (xy 264.574488 -243.537976) (xy 264.52833 -243.511327)
			(xy 264.486659 -243.478096) (xy 264.450407 -243.439025) (xy 264.420383 -243.394988) (xy 264.397257 -243.346967)
			(xy 264.381547 -243.296037) (xy 264.373604 -243.243333) (xy 261.641092 -243.243333) (xy 261.633149 -243.296037)
			(xy 261.617439 -243.346967) (xy 261.594313 -243.394988) (xy 261.564289 -243.439025) (xy 261.528037 -243.478096)
			(xy 261.486366 -243.511327) (xy 261.440208 -243.537976) (xy 261.390594 -243.557448) (xy 261.338632 -243.569308)
			(xy 261.285482 -243.573292) (xy 261.232332 -243.569308) (xy 261.18037 -243.557448) (xy 261.130756 -243.537976)
			(xy 261.084598 -243.511327) (xy 261.042927 -243.478096) (xy 261.006675 -243.439025) (xy 260.976651 -243.394988)
			(xy 260.953525 -243.346967) (xy 260.937815 -243.296037) (xy 260.929872 -243.243333) (xy 257.541024 -243.243333)
			(xy 257.533081 -243.296037) (xy 257.517371 -243.346967) (xy 257.494245 -243.394988) (xy 257.464221 -243.439025)
			(xy 257.427969 -243.478096) (xy 257.386298 -243.511327) (xy 257.34014 -243.537976) (xy 257.290526 -243.557448)
			(xy 257.238564 -243.569308) (xy 257.185414 -243.573292) (xy 257.132264 -243.569308) (xy 257.080302 -243.557448)
			(xy 257.030688 -243.537976) (xy 256.98453 -243.511327) (xy 256.942859 -243.478096) (xy 256.906607 -243.439025)
			(xy 256.876583 -243.394988) (xy 256.853457 -243.346967) (xy 256.837747 -243.296037) (xy 256.829804 -243.243333)
			(xy 254.20828 -243.243333) (xy 254.20828 -244.093217) (xy 256.829804 -244.093217) (xy 256.829804 -244.039919)
			(xy 256.837747 -243.987215) (xy 256.853457 -243.936285) (xy 256.876583 -243.888264) (xy 256.906607 -243.844227)
			(xy 256.942859 -243.805156) (xy 256.98453 -243.771925) (xy 257.030688 -243.745276) (xy 257.080302 -243.725804)
			(xy 257.132264 -243.713944) (xy 257.185414 -243.709961) (xy 257.238564 -243.713944) (xy 257.290526 -243.725804)
			(xy 257.34014 -243.745276) (xy 257.386298 -243.771925) (xy 257.427969 -243.805156) (xy 257.464221 -243.844227)
			(xy 257.494245 -243.888264) (xy 257.517371 -243.936285) (xy 257.533081 -243.987215) (xy 257.541024 -244.039919)
			(xy 257.541522 -244.066568) (xy 257.541024 -244.093217) (xy 264.373604 -244.093217) (xy 264.373604 -244.039919)
			(xy 264.381547 -243.987215) (xy 264.397257 -243.936285) (xy 264.420383 -243.888264) (xy 264.450407 -243.844227)
			(xy 264.486659 -243.805156) (xy 264.52833 -243.771925) (xy 264.574488 -243.745276) (xy 264.624102 -243.725804)
			(xy 264.676064 -243.713944) (xy 264.729214 -243.709961) (xy 264.782364 -243.713944) (xy 264.834326 -243.725804)
			(xy 264.88394 -243.745276) (xy 264.930098 -243.771925) (xy 264.971769 -243.805156) (xy 265.008021 -243.844227)
			(xy 265.038045 -243.888264) (xy 265.061171 -243.936285) (xy 265.076881 -243.987215) (xy 265.084824 -244.039919)
			(xy 265.085322 -244.066568) (xy 265.084824 -244.093217) (xy 271.917404 -244.093217) (xy 271.917404 -244.039919)
			(xy 271.925347 -243.987215) (xy 271.941057 -243.936285) (xy 271.964183 -243.888264) (xy 271.994207 -243.844227)
			(xy 272.030459 -243.805156) (xy 272.07213 -243.771925) (xy 272.118288 -243.745276) (xy 272.167902 -243.725804)
			(xy 272.219864 -243.713944) (xy 272.273014 -243.709961) (xy 272.326164 -243.713944) (xy 272.378126 -243.725804)
			(xy 272.42774 -243.745276) (xy 272.473898 -243.771925) (xy 272.515569 -243.805156) (xy 272.551821 -243.844227)
			(xy 272.581845 -243.888264) (xy 272.604971 -243.936285) (xy 272.620681 -243.987215) (xy 272.628624 -244.039919)
			(xy 272.629122 -244.066568) (xy 272.628624 -244.093217) (xy 279.461204 -244.093217) (xy 279.461204 -244.039919)
			(xy 279.469147 -243.987215) (xy 279.484857 -243.936285) (xy 279.507983 -243.888264) (xy 279.538007 -243.844227)
			(xy 279.574259 -243.805156) (xy 279.61593 -243.771925) (xy 279.662088 -243.745276) (xy 279.711702 -243.725804)
			(xy 279.763664 -243.713944) (xy 279.816814 -243.709961) (xy 279.869964 -243.713944) (xy 279.921926 -243.725804)
			(xy 279.97154 -243.745276) (xy 280.017698 -243.771925) (xy 280.059369 -243.805156) (xy 280.095621 -243.844227)
			(xy 280.125645 -243.888264) (xy 280.148771 -243.936285) (xy 280.164481 -243.987215) (xy 280.172424 -244.039919)
			(xy 280.172922 -244.066568) (xy 280.172424 -244.093217) (xy 287.005004 -244.093217) (xy 287.005004 -244.039919)
			(xy 287.012947 -243.987215) (xy 287.028657 -243.936285) (xy 287.051783 -243.888264) (xy 287.081807 -243.844227)
			(xy 287.118059 -243.805156) (xy 287.15973 -243.771925) (xy 287.205888 -243.745276) (xy 287.255502 -243.725804)
			(xy 287.307464 -243.713944) (xy 287.360614 -243.709961) (xy 287.413764 -243.713944) (xy 287.465726 -243.725804)
			(xy 287.51534 -243.745276) (xy 287.561498 -243.771925) (xy 287.603169 -243.805156) (xy 287.639421 -243.844227)
			(xy 287.669445 -243.888264) (xy 287.692571 -243.936285) (xy 287.708281 -243.987215) (xy 287.716224 -244.039919)
			(xy 287.716722 -244.066568) (xy 287.716224 -244.093217) (xy 294.548804 -244.093217) (xy 294.548804 -244.039919)
			(xy 294.556747 -243.987215) (xy 294.572457 -243.936285) (xy 294.595583 -243.888264) (xy 294.625607 -243.844227)
			(xy 294.661859 -243.805156) (xy 294.70353 -243.771925) (xy 294.749688 -243.745276) (xy 294.799302 -243.725804)
			(xy 294.851264 -243.713944) (xy 294.904414 -243.709961) (xy 294.957564 -243.713944) (xy 295.009526 -243.725804)
			(xy 295.05914 -243.745276) (xy 295.105298 -243.771925) (xy 295.146969 -243.805156) (xy 295.183221 -243.844227)
			(xy 295.213245 -243.888264) (xy 295.236371 -243.936285) (xy 295.252081 -243.987215) (xy 295.260024 -244.039919)
			(xy 295.260522 -244.066568) (xy 295.260024 -244.093217) (xy 302.092604 -244.093217) (xy 302.092604 -244.039919)
			(xy 302.100547 -243.987215) (xy 302.116257 -243.936285) (xy 302.139383 -243.888264) (xy 302.169407 -243.844227)
			(xy 302.205659 -243.805156) (xy 302.24733 -243.771925) (xy 302.293488 -243.745276) (xy 302.343102 -243.725804)
			(xy 302.395064 -243.713944) (xy 302.448214 -243.709961) (xy 302.501364 -243.713944) (xy 302.553326 -243.725804)
			(xy 302.60294 -243.745276) (xy 302.649098 -243.771925) (xy 302.690769 -243.805156) (xy 302.727021 -243.844227)
			(xy 302.757045 -243.888264) (xy 302.780171 -243.936285) (xy 302.795881 -243.987215) (xy 302.803824 -244.039919)
			(xy 302.804322 -244.066568) (xy 302.803824 -244.093217) (xy 309.636404 -244.093217) (xy 309.636404 -244.039919)
			(xy 309.644347 -243.987215) (xy 309.660057 -243.936285) (xy 309.683183 -243.888264) (xy 309.713207 -243.844227)
			(xy 309.749459 -243.805156) (xy 309.79113 -243.771925) (xy 309.837288 -243.745276) (xy 309.886902 -243.725804)
			(xy 309.938864 -243.713944) (xy 309.992014 -243.709961) (xy 310.045164 -243.713944) (xy 310.097126 -243.725804)
			(xy 310.14674 -243.745276) (xy 310.192898 -243.771925) (xy 310.234569 -243.805156) (xy 310.270821 -243.844227)
			(xy 310.300845 -243.888264) (xy 310.323971 -243.936285) (xy 310.339681 -243.987215) (xy 310.347624 -244.039919)
			(xy 310.348122 -244.066568) (xy 310.347624 -244.093217) (xy 310.339681 -244.145921) (xy 310.323971 -244.196851)
			(xy 310.300845 -244.244872) (xy 310.270821 -244.288909) (xy 310.234569 -244.32798) (xy 310.192898 -244.361211)
			(xy 310.14674 -244.38786) (xy 310.097126 -244.407332) (xy 310.045164 -244.419192) (xy 309.992014 -244.423176)
			(xy 309.938864 -244.419192) (xy 309.886902 -244.407332) (xy 309.837288 -244.38786) (xy 309.79113 -244.361211)
			(xy 309.749459 -244.32798) (xy 309.713207 -244.288909) (xy 309.683183 -244.244872) (xy 309.660057 -244.196851)
			(xy 309.644347 -244.145921) (xy 309.636404 -244.093217) (xy 302.803824 -244.093217) (xy 302.795881 -244.145921)
			(xy 302.780171 -244.196851) (xy 302.757045 -244.244872) (xy 302.727021 -244.288909) (xy 302.690769 -244.32798)
			(xy 302.649098 -244.361211) (xy 302.60294 -244.38786) (xy 302.553326 -244.407332) (xy 302.501364 -244.419192)
			(xy 302.448214 -244.423176) (xy 302.395064 -244.419192) (xy 302.343102 -244.407332) (xy 302.293488 -244.38786)
			(xy 302.24733 -244.361211) (xy 302.205659 -244.32798) (xy 302.169407 -244.288909) (xy 302.139383 -244.244872)
			(xy 302.116257 -244.196851) (xy 302.100547 -244.145921) (xy 302.092604 -244.093217) (xy 295.260024 -244.093217)
			(xy 295.252081 -244.145921) (xy 295.236371 -244.196851) (xy 295.213245 -244.244872) (xy 295.183221 -244.288909)
			(xy 295.146969 -244.32798) (xy 295.105298 -244.361211) (xy 295.05914 -244.38786) (xy 295.009526 -244.407332)
			(xy 294.957564 -244.419192) (xy 294.904414 -244.423176) (xy 294.851264 -244.419192) (xy 294.799302 -244.407332)
			(xy 294.749688 -244.38786) (xy 294.70353 -244.361211) (xy 294.661859 -244.32798) (xy 294.625607 -244.288909)
			(xy 294.595583 -244.244872) (xy 294.572457 -244.196851) (xy 294.556747 -244.145921) (xy 294.548804 -244.093217)
			(xy 287.716224 -244.093217) (xy 287.708281 -244.145921) (xy 287.692571 -244.196851) (xy 287.669445 -244.244872)
			(xy 287.639421 -244.288909) (xy 287.603169 -244.32798) (xy 287.561498 -244.361211) (xy 287.51534 -244.38786)
			(xy 287.465726 -244.407332) (xy 287.413764 -244.419192) (xy 287.360614 -244.423176) (xy 287.307464 -244.419192)
			(xy 287.255502 -244.407332) (xy 287.205888 -244.38786) (xy 287.15973 -244.361211) (xy 287.118059 -244.32798)
			(xy 287.081807 -244.288909) (xy 287.051783 -244.244872) (xy 287.028657 -244.196851) (xy 287.012947 -244.145921)
			(xy 287.005004 -244.093217) (xy 280.172424 -244.093217) (xy 280.164481 -244.145921) (xy 280.148771 -244.196851)
			(xy 280.125645 -244.244872) (xy 280.095621 -244.288909) (xy 280.059369 -244.32798) (xy 280.017698 -244.361211)
			(xy 279.97154 -244.38786) (xy 279.921926 -244.407332) (xy 279.869964 -244.419192) (xy 279.816814 -244.423176)
			(xy 279.763664 -244.419192) (xy 279.711702 -244.407332) (xy 279.662088 -244.38786) (xy 279.61593 -244.361211)
			(xy 279.574259 -244.32798) (xy 279.538007 -244.288909) (xy 279.507983 -244.244872) (xy 279.484857 -244.196851)
			(xy 279.469147 -244.145921) (xy 279.461204 -244.093217) (xy 272.628624 -244.093217) (xy 272.620681 -244.145921)
			(xy 272.604971 -244.196851) (xy 272.581845 -244.244872) (xy 272.551821 -244.288909) (xy 272.515569 -244.32798)
			(xy 272.473898 -244.361211) (xy 272.42774 -244.38786) (xy 272.378126 -244.407332) (xy 272.326164 -244.419192)
			(xy 272.273014 -244.423176) (xy 272.219864 -244.419192) (xy 272.167902 -244.407332) (xy 272.118288 -244.38786)
			(xy 272.07213 -244.361211) (xy 272.030459 -244.32798) (xy 271.994207 -244.288909) (xy 271.964183 -244.244872)
			(xy 271.941057 -244.196851) (xy 271.925347 -244.145921) (xy 271.917404 -244.093217) (xy 265.084824 -244.093217)
			(xy 265.076881 -244.145921) (xy 265.061171 -244.196851) (xy 265.038045 -244.244872) (xy 265.008021 -244.288909)
			(xy 264.971769 -244.32798) (xy 264.930098 -244.361211) (xy 264.88394 -244.38786) (xy 264.834326 -244.407332)
			(xy 264.782364 -244.419192) (xy 264.729214 -244.423176) (xy 264.676064 -244.419192) (xy 264.624102 -244.407332)
			(xy 264.574488 -244.38786) (xy 264.52833 -244.361211) (xy 264.486659 -244.32798) (xy 264.450407 -244.288909)
			(xy 264.420383 -244.244872) (xy 264.397257 -244.196851) (xy 264.381547 -244.145921) (xy 264.373604 -244.093217)
			(xy 257.541024 -244.093217) (xy 257.533081 -244.145921) (xy 257.517371 -244.196851) (xy 257.494245 -244.244872)
			(xy 257.464221 -244.288909) (xy 257.427969 -244.32798) (xy 257.386298 -244.361211) (xy 257.34014 -244.38786)
			(xy 257.290526 -244.407332) (xy 257.238564 -244.419192) (xy 257.185414 -244.423176) (xy 257.132264 -244.419192)
			(xy 257.080302 -244.407332) (xy 257.030688 -244.38786) (xy 256.98453 -244.361211) (xy 256.942859 -244.32798)
			(xy 256.906607 -244.288909) (xy 256.876583 -244.244872) (xy 256.853457 -244.196851) (xy 256.837747 -244.145921)
			(xy 256.829804 -244.093217) (xy 254.20828 -244.093217) (xy 254.20828 -244.943355) (xy 260.929872 -244.943355)
			(xy 260.929872 -244.890057) (xy 260.937815 -244.837353) (xy 260.953525 -244.786423) (xy 260.976651 -244.738402)
			(xy 261.006675 -244.694365) (xy 261.042927 -244.655294) (xy 261.084598 -244.622063) (xy 261.130756 -244.595414)
			(xy 261.18037 -244.575942) (xy 261.232332 -244.564082) (xy 261.285482 -244.560099) (xy 261.338632 -244.564082)
			(xy 261.390594 -244.575942) (xy 261.440208 -244.595414) (xy 261.486366 -244.622063) (xy 261.528037 -244.655294)
			(xy 261.564289 -244.694365) (xy 261.594313 -244.738402) (xy 261.617439 -244.786423) (xy 261.633149 -244.837353)
			(xy 261.641092 -244.890057) (xy 261.64159 -244.916706) (xy 261.641092 -244.943355) (xy 268.473672 -244.943355)
			(xy 268.473672 -244.890057) (xy 268.481615 -244.837353) (xy 268.497325 -244.786423) (xy 268.520451 -244.738402)
			(xy 268.550475 -244.694365) (xy 268.586727 -244.655294) (xy 268.628398 -244.622063) (xy 268.674556 -244.595414)
			(xy 268.72417 -244.575942) (xy 268.776132 -244.564082) (xy 268.829282 -244.560099) (xy 268.882432 -244.564082)
			(xy 268.934394 -244.575942) (xy 268.984008 -244.595414) (xy 269.030166 -244.622063) (xy 269.071837 -244.655294)
			(xy 269.108089 -244.694365) (xy 269.138113 -244.738402) (xy 269.161239 -244.786423) (xy 269.176949 -244.837353)
			(xy 269.184892 -244.890057) (xy 269.18539 -244.916706) (xy 269.184892 -244.943355) (xy 276.017472 -244.943355)
			(xy 276.017472 -244.890057) (xy 276.025415 -244.837353) (xy 276.041125 -244.786423) (xy 276.064251 -244.738402)
			(xy 276.094275 -244.694365) (xy 276.130527 -244.655294) (xy 276.172198 -244.622063) (xy 276.218356 -244.595414)
			(xy 276.26797 -244.575942) (xy 276.319932 -244.564082) (xy 276.373082 -244.560099) (xy 276.426232 -244.564082)
			(xy 276.478194 -244.575942) (xy 276.527808 -244.595414) (xy 276.573966 -244.622063) (xy 276.615637 -244.655294)
			(xy 276.651889 -244.694365) (xy 276.681913 -244.738402) (xy 276.705039 -244.786423) (xy 276.720749 -244.837353)
			(xy 276.728692 -244.890057) (xy 276.72919 -244.916706) (xy 276.728692 -244.943355) (xy 283.561272 -244.943355)
			(xy 283.561272 -244.890057) (xy 283.569215 -244.837353) (xy 283.584925 -244.786423) (xy 283.608051 -244.738402)
			(xy 283.638075 -244.694365) (xy 283.674327 -244.655294) (xy 283.715998 -244.622063) (xy 283.762156 -244.595414)
			(xy 283.81177 -244.575942) (xy 283.863732 -244.564082) (xy 283.916882 -244.560099) (xy 283.970032 -244.564082)
			(xy 284.021994 -244.575942) (xy 284.071608 -244.595414) (xy 284.117766 -244.622063) (xy 284.159437 -244.655294)
			(xy 284.195689 -244.694365) (xy 284.225713 -244.738402) (xy 284.248839 -244.786423) (xy 284.264549 -244.837353)
			(xy 284.272492 -244.890057) (xy 284.27299 -244.916706) (xy 284.272492 -244.943355) (xy 291.105072 -244.943355)
			(xy 291.105072 -244.890057) (xy 291.113015 -244.837353) (xy 291.128725 -244.786423) (xy 291.151851 -244.738402)
			(xy 291.181875 -244.694365) (xy 291.218127 -244.655294) (xy 291.259798 -244.622063) (xy 291.305956 -244.595414)
			(xy 291.35557 -244.575942) (xy 291.407532 -244.564082) (xy 291.460682 -244.560099) (xy 291.513832 -244.564082)
			(xy 291.565794 -244.575942) (xy 291.615408 -244.595414) (xy 291.661566 -244.622063) (xy 291.703237 -244.655294)
			(xy 291.739489 -244.694365) (xy 291.769513 -244.738402) (xy 291.792639 -244.786423) (xy 291.808349 -244.837353)
			(xy 291.816292 -244.890057) (xy 291.81679 -244.916706) (xy 291.816292 -244.943355) (xy 298.648872 -244.943355)
			(xy 298.648872 -244.890057) (xy 298.656815 -244.837353) (xy 298.672525 -244.786423) (xy 298.695651 -244.738402)
			(xy 298.725675 -244.694365) (xy 298.761927 -244.655294) (xy 298.803598 -244.622063) (xy 298.849756 -244.595414)
			(xy 298.89937 -244.575942) (xy 298.951332 -244.564082) (xy 299.004482 -244.560099) (xy 299.057632 -244.564082)
			(xy 299.109594 -244.575942) (xy 299.159208 -244.595414) (xy 299.205366 -244.622063) (xy 299.247037 -244.655294)
			(xy 299.283289 -244.694365) (xy 299.313313 -244.738402) (xy 299.336439 -244.786423) (xy 299.352149 -244.837353)
			(xy 299.360092 -244.890057) (xy 299.36059 -244.916706) (xy 299.360092 -244.943355) (xy 299.352149 -244.996059)
			(xy 299.336439 -245.046989) (xy 299.313313 -245.09501) (xy 299.283289 -245.139047) (xy 299.247037 -245.178118)
			(xy 299.205366 -245.211349) (xy 299.159208 -245.237998) (xy 299.109594 -245.25747) (xy 299.057632 -245.26933)
			(xy 299.004482 -245.273314) (xy 298.951332 -245.26933) (xy 298.89937 -245.25747) (xy 298.849756 -245.237998)
			(xy 298.803598 -245.211349) (xy 298.761927 -245.178118) (xy 298.725675 -245.139047) (xy 298.695651 -245.09501)
			(xy 298.672525 -245.046989) (xy 298.656815 -244.996059) (xy 298.648872 -244.943355) (xy 291.816292 -244.943355)
			(xy 291.808349 -244.996059) (xy 291.792639 -245.046989) (xy 291.769513 -245.09501) (xy 291.739489 -245.139047)
			(xy 291.703237 -245.178118) (xy 291.661566 -245.211349) (xy 291.615408 -245.237998) (xy 291.565794 -245.25747)
			(xy 291.513832 -245.26933) (xy 291.460682 -245.273314) (xy 291.407532 -245.26933) (xy 291.35557 -245.25747)
			(xy 291.305956 -245.237998) (xy 291.259798 -245.211349) (xy 291.218127 -245.178118) (xy 291.181875 -245.139047)
			(xy 291.151851 -245.09501) (xy 291.128725 -245.046989) (xy 291.113015 -244.996059) (xy 291.105072 -244.943355)
			(xy 284.272492 -244.943355) (xy 284.264549 -244.996059) (xy 284.248839 -245.046989) (xy 284.225713 -245.09501)
			(xy 284.195689 -245.139047) (xy 284.159437 -245.178118) (xy 284.117766 -245.211349) (xy 284.071608 -245.237998)
			(xy 284.021994 -245.25747) (xy 283.970032 -245.26933) (xy 283.916882 -245.273314) (xy 283.863732 -245.26933)
			(xy 283.81177 -245.25747) (xy 283.762156 -245.237998) (xy 283.715998 -245.211349) (xy 283.674327 -245.178118)
			(xy 283.638075 -245.139047) (xy 283.608051 -245.09501) (xy 283.584925 -245.046989) (xy 283.569215 -244.996059)
			(xy 283.561272 -244.943355) (xy 276.728692 -244.943355) (xy 276.720749 -244.996059) (xy 276.705039 -245.046989)
			(xy 276.681913 -245.09501) (xy 276.651889 -245.139047) (xy 276.615637 -245.178118) (xy 276.573966 -245.211349)
			(xy 276.527808 -245.237998) (xy 276.478194 -245.25747) (xy 276.426232 -245.26933) (xy 276.373082 -245.273314)
			(xy 276.319932 -245.26933) (xy 276.26797 -245.25747) (xy 276.218356 -245.237998) (xy 276.172198 -245.211349)
			(xy 276.130527 -245.178118) (xy 276.094275 -245.139047) (xy 276.064251 -245.09501) (xy 276.041125 -245.046989)
			(xy 276.025415 -244.996059) (xy 276.017472 -244.943355) (xy 269.184892 -244.943355) (xy 269.176949 -244.996059)
			(xy 269.161239 -245.046989) (xy 269.138113 -245.09501) (xy 269.108089 -245.139047) (xy 269.071837 -245.178118)
			(xy 269.030166 -245.211349) (xy 268.984008 -245.237998) (xy 268.934394 -245.25747) (xy 268.882432 -245.26933)
			(xy 268.829282 -245.273314) (xy 268.776132 -245.26933) (xy 268.72417 -245.25747) (xy 268.674556 -245.237998)
			(xy 268.628398 -245.211349) (xy 268.586727 -245.178118) (xy 268.550475 -245.139047) (xy 268.520451 -245.09501)
			(xy 268.497325 -245.046989) (xy 268.481615 -244.996059) (xy 268.473672 -244.943355) (xy 261.641092 -244.943355)
			(xy 261.633149 -244.996059) (xy 261.617439 -245.046989) (xy 261.594313 -245.09501) (xy 261.564289 -245.139047)
			(xy 261.528037 -245.178118) (xy 261.486366 -245.211349) (xy 261.440208 -245.237998) (xy 261.390594 -245.25747)
			(xy 261.338632 -245.26933) (xy 261.285482 -245.273314) (xy 261.232332 -245.26933) (xy 261.18037 -245.25747)
			(xy 261.130756 -245.237998) (xy 261.084598 -245.211349) (xy 261.042927 -245.178118) (xy 261.006675 -245.139047)
			(xy 260.976651 -245.09501) (xy 260.953525 -245.046989) (xy 260.937815 -244.996059) (xy 260.929872 -244.943355)
			(xy 254.20828 -244.943355) (xy 254.20828 -245.793239) (xy 256.829804 -245.793239) (xy 256.829804 -245.739941)
			(xy 256.837747 -245.687237) (xy 256.853457 -245.636307) (xy 256.876583 -245.588286) (xy 256.906607 -245.544249)
			(xy 256.942859 -245.505178) (xy 256.98453 -245.471947) (xy 257.030688 -245.445298) (xy 257.080302 -245.425826)
			(xy 257.132264 -245.413966) (xy 257.185414 -245.409983) (xy 257.238564 -245.413966) (xy 257.290526 -245.425826)
			(xy 257.34014 -245.445298) (xy 257.386298 -245.471947) (xy 257.427969 -245.505178) (xy 257.464221 -245.544249)
			(xy 257.494245 -245.588286) (xy 257.517371 -245.636307) (xy 257.533081 -245.687237) (xy 257.541024 -245.739941)
			(xy 257.541522 -245.76659) (xy 257.541024 -245.793239) (xy 264.373604 -245.793239) (xy 264.373604 -245.739941)
			(xy 264.381547 -245.687237) (xy 264.397257 -245.636307) (xy 264.420383 -245.588286) (xy 264.450407 -245.544249)
			(xy 264.486659 -245.505178) (xy 264.52833 -245.471947) (xy 264.574488 -245.445298) (xy 264.624102 -245.425826)
			(xy 264.676064 -245.413966) (xy 264.729214 -245.409983) (xy 264.782364 -245.413966) (xy 264.834326 -245.425826)
			(xy 264.88394 -245.445298) (xy 264.930098 -245.471947) (xy 264.971769 -245.505178) (xy 265.008021 -245.544249)
			(xy 265.038045 -245.588286) (xy 265.061171 -245.636307) (xy 265.076881 -245.687237) (xy 265.084824 -245.739941)
			(xy 265.085322 -245.76659) (xy 265.084824 -245.793239) (xy 271.917404 -245.793239) (xy 271.917404 -245.739941)
			(xy 271.925347 -245.687237) (xy 271.941057 -245.636307) (xy 271.964183 -245.588286) (xy 271.994207 -245.544249)
			(xy 272.030459 -245.505178) (xy 272.07213 -245.471947) (xy 272.118288 -245.445298) (xy 272.167902 -245.425826)
			(xy 272.219864 -245.413966) (xy 272.273014 -245.409983) (xy 272.326164 -245.413966) (xy 272.378126 -245.425826)
			(xy 272.42774 -245.445298) (xy 272.473898 -245.471947) (xy 272.515569 -245.505178) (xy 272.551821 -245.544249)
			(xy 272.581845 -245.588286) (xy 272.604971 -245.636307) (xy 272.620681 -245.687237) (xy 272.628624 -245.739941)
			(xy 272.629122 -245.76659) (xy 272.628624 -245.793239) (xy 279.461204 -245.793239) (xy 279.461204 -245.739941)
			(xy 279.469147 -245.687237) (xy 279.484857 -245.636307) (xy 279.507983 -245.588286) (xy 279.538007 -245.544249)
			(xy 279.574259 -245.505178) (xy 279.61593 -245.471947) (xy 279.662088 -245.445298) (xy 279.711702 -245.425826)
			(xy 279.763664 -245.413966) (xy 279.816814 -245.409983) (xy 279.869964 -245.413966) (xy 279.921926 -245.425826)
			(xy 279.97154 -245.445298) (xy 280.017698 -245.471947) (xy 280.059369 -245.505178) (xy 280.095621 -245.544249)
			(xy 280.125645 -245.588286) (xy 280.148771 -245.636307) (xy 280.164481 -245.687237) (xy 280.172424 -245.739941)
			(xy 280.172922 -245.76659) (xy 280.172424 -245.793239) (xy 287.005004 -245.793239) (xy 287.005004 -245.739941)
			(xy 287.012947 -245.687237) (xy 287.028657 -245.636307) (xy 287.051783 -245.588286) (xy 287.081807 -245.544249)
			(xy 287.118059 -245.505178) (xy 287.15973 -245.471947) (xy 287.205888 -245.445298) (xy 287.255502 -245.425826)
			(xy 287.307464 -245.413966) (xy 287.360614 -245.409983) (xy 287.413764 -245.413966) (xy 287.465726 -245.425826)
			(xy 287.51534 -245.445298) (xy 287.561498 -245.471947) (xy 287.603169 -245.505178) (xy 287.639421 -245.544249)
			(xy 287.669445 -245.588286) (xy 287.692571 -245.636307) (xy 287.708281 -245.687237) (xy 287.716224 -245.739941)
			(xy 287.716722 -245.76659) (xy 287.716224 -245.793239) (xy 294.548804 -245.793239) (xy 294.548804 -245.739941)
			(xy 294.556747 -245.687237) (xy 294.572457 -245.636307) (xy 294.595583 -245.588286) (xy 294.625607 -245.544249)
			(xy 294.661859 -245.505178) (xy 294.70353 -245.471947) (xy 294.749688 -245.445298) (xy 294.799302 -245.425826)
			(xy 294.851264 -245.413966) (xy 294.904414 -245.409983) (xy 294.957564 -245.413966) (xy 295.009526 -245.425826)
			(xy 295.05914 -245.445298) (xy 295.105298 -245.471947) (xy 295.146969 -245.505178) (xy 295.183221 -245.544249)
			(xy 295.213245 -245.588286) (xy 295.236371 -245.636307) (xy 295.252081 -245.687237) (xy 295.260024 -245.739941)
			(xy 295.260522 -245.76659) (xy 295.260024 -245.793239) (xy 295.252081 -245.845943) (xy 295.236371 -245.896873)
			(xy 295.213245 -245.944894) (xy 295.183221 -245.988931) (xy 295.146969 -246.028002) (xy 295.105298 -246.061233)
			(xy 295.05914 -246.087882) (xy 295.009526 -246.107354) (xy 294.957564 -246.119214) (xy 294.904414 -246.123198)
			(xy 294.851264 -246.119214) (xy 294.799302 -246.107354) (xy 294.749688 -246.087882) (xy 294.70353 -246.061233)
			(xy 294.661859 -246.028002) (xy 294.625607 -245.988931) (xy 294.595583 -245.944894) (xy 294.572457 -245.896873)
			(xy 294.556747 -245.845943) (xy 294.548804 -245.793239) (xy 287.716224 -245.793239) (xy 287.708281 -245.845943)
			(xy 287.692571 -245.896873) (xy 287.669445 -245.944894) (xy 287.639421 -245.988931) (xy 287.603169 -246.028002)
			(xy 287.561498 -246.061233) (xy 287.51534 -246.087882) (xy 287.465726 -246.107354) (xy 287.413764 -246.119214)
			(xy 287.360614 -246.123198) (xy 287.307464 -246.119214) (xy 287.255502 -246.107354) (xy 287.205888 -246.087882)
			(xy 287.15973 -246.061233) (xy 287.118059 -246.028002) (xy 287.081807 -245.988931) (xy 287.051783 -245.944894)
			(xy 287.028657 -245.896873) (xy 287.012947 -245.845943) (xy 287.005004 -245.793239) (xy 280.172424 -245.793239)
			(xy 280.164481 -245.845943) (xy 280.148771 -245.896873) (xy 280.125645 -245.944894) (xy 280.095621 -245.988931)
			(xy 280.059369 -246.028002) (xy 280.017698 -246.061233) (xy 279.97154 -246.087882) (xy 279.921926 -246.107354)
			(xy 279.869964 -246.119214) (xy 279.816814 -246.123198) (xy 279.763664 -246.119214) (xy 279.711702 -246.107354)
			(xy 279.662088 -246.087882) (xy 279.61593 -246.061233) (xy 279.574259 -246.028002) (xy 279.538007 -245.988931)
			(xy 279.507983 -245.944894) (xy 279.484857 -245.896873) (xy 279.469147 -245.845943) (xy 279.461204 -245.793239)
			(xy 272.628624 -245.793239) (xy 272.620681 -245.845943) (xy 272.604971 -245.896873) (xy 272.581845 -245.944894)
			(xy 272.551821 -245.988931) (xy 272.515569 -246.028002) (xy 272.473898 -246.061233) (xy 272.42774 -246.087882)
			(xy 272.378126 -246.107354) (xy 272.326164 -246.119214) (xy 272.273014 -246.123198) (xy 272.219864 -246.119214)
			(xy 272.167902 -246.107354) (xy 272.118288 -246.087882) (xy 272.07213 -246.061233) (xy 272.030459 -246.028002)
			(xy 271.994207 -245.988931) (xy 271.964183 -245.944894) (xy 271.941057 -245.896873) (xy 271.925347 -245.845943)
			(xy 271.917404 -245.793239) (xy 265.084824 -245.793239) (xy 265.076881 -245.845943) (xy 265.061171 -245.896873)
			(xy 265.038045 -245.944894) (xy 265.008021 -245.988931) (xy 264.971769 -246.028002) (xy 264.930098 -246.061233)
			(xy 264.88394 -246.087882) (xy 264.834326 -246.107354) (xy 264.782364 -246.119214) (xy 264.729214 -246.123198)
			(xy 264.676064 -246.119214) (xy 264.624102 -246.107354) (xy 264.574488 -246.087882) (xy 264.52833 -246.061233)
			(xy 264.486659 -246.028002) (xy 264.450407 -245.988931) (xy 264.420383 -245.944894) (xy 264.397257 -245.896873)
			(xy 264.381547 -245.845943) (xy 264.373604 -245.793239) (xy 257.541024 -245.793239) (xy 257.533081 -245.845943)
			(xy 257.517371 -245.896873) (xy 257.494245 -245.944894) (xy 257.464221 -245.988931) (xy 257.427969 -246.028002)
			(xy 257.386298 -246.061233) (xy 257.34014 -246.087882) (xy 257.290526 -246.107354) (xy 257.238564 -246.119214)
			(xy 257.185414 -246.123198) (xy 257.132264 -246.119214) (xy 257.080302 -246.107354) (xy 257.030688 -246.087882)
			(xy 256.98453 -246.061233) (xy 256.942859 -246.028002) (xy 256.906607 -245.988931) (xy 256.876583 -245.944894)
			(xy 256.853457 -245.896873) (xy 256.837747 -245.845943) (xy 256.829804 -245.793239) (xy 254.20828 -245.793239)
			(xy 254.20828 -246.643377) (xy 268.473672 -246.643377) (xy 268.473672 -246.590079) (xy 268.481615 -246.537375)
			(xy 268.497325 -246.486445) (xy 268.520451 -246.438424) (xy 268.550475 -246.394387) (xy 268.586727 -246.355316)
			(xy 268.628398 -246.322085) (xy 268.674556 -246.295436) (xy 268.72417 -246.275964) (xy 268.776132 -246.264104)
			(xy 268.829282 -246.260121) (xy 268.882432 -246.264104) (xy 268.934394 -246.275964) (xy 268.984008 -246.295436)
			(xy 269.030166 -246.322085) (xy 269.071837 -246.355316) (xy 269.108089 -246.394387) (xy 269.138113 -246.438424)
			(xy 269.161239 -246.486445) (xy 269.176949 -246.537375) (xy 269.184892 -246.590079) (xy 269.18539 -246.616728)
			(xy 269.184892 -246.643377) (xy 283.561272 -246.643377) (xy 283.561272 -246.590079) (xy 283.569215 -246.537375)
			(xy 283.584925 -246.486445) (xy 283.608051 -246.438424) (xy 283.638075 -246.394387) (xy 283.674327 -246.355316)
			(xy 283.715998 -246.322085) (xy 283.762156 -246.295436) (xy 283.81177 -246.275964) (xy 283.863732 -246.264104)
			(xy 283.916882 -246.260121) (xy 283.970032 -246.264104) (xy 284.021994 -246.275964) (xy 284.071608 -246.295436)
			(xy 284.117766 -246.322085) (xy 284.159437 -246.355316) (xy 284.195689 -246.394387) (xy 284.225713 -246.438424)
			(xy 284.248839 -246.486445) (xy 284.264549 -246.537375) (xy 284.272492 -246.590079) (xy 284.27299 -246.616728)
			(xy 284.272492 -246.643377) (xy 298.648872 -246.643377) (xy 298.648872 -246.590079) (xy 298.656815 -246.537375)
			(xy 298.672525 -246.486445) (xy 298.695651 -246.438424) (xy 298.725675 -246.394387) (xy 298.761927 -246.355316)
			(xy 298.803598 -246.322085) (xy 298.849756 -246.295436) (xy 298.89937 -246.275964) (xy 298.951332 -246.264104)
			(xy 299.004482 -246.260121) (xy 299.057632 -246.264104) (xy 299.109594 -246.275964) (xy 299.159208 -246.295436)
			(xy 299.205366 -246.322085) (xy 299.247037 -246.355316) (xy 299.283289 -246.394387) (xy 299.313313 -246.438424)
			(xy 299.336439 -246.486445) (xy 299.352149 -246.537375) (xy 299.360092 -246.590079) (xy 299.36059 -246.616728)
			(xy 299.360092 -246.643377) (xy 299.352149 -246.696081) (xy 299.336439 -246.747011) (xy 299.313313 -246.795032)
			(xy 299.283289 -246.839069) (xy 299.247037 -246.87814) (xy 299.205366 -246.911371) (xy 299.159208 -246.93802)
			(xy 299.109594 -246.957492) (xy 299.057632 -246.969352) (xy 299.004482 -246.973336) (xy 298.951332 -246.969352)
			(xy 298.89937 -246.957492) (xy 298.849756 -246.93802) (xy 298.803598 -246.911371) (xy 298.761927 -246.87814)
			(xy 298.725675 -246.839069) (xy 298.695651 -246.795032) (xy 298.672525 -246.747011) (xy 298.656815 -246.696081)
			(xy 298.648872 -246.643377) (xy 284.272492 -246.643377) (xy 284.264549 -246.696081) (xy 284.248839 -246.747011)
			(xy 284.225713 -246.795032) (xy 284.195689 -246.839069) (xy 284.159437 -246.87814) (xy 284.117766 -246.911371)
			(xy 284.071608 -246.93802) (xy 284.021994 -246.957492) (xy 283.970032 -246.969352) (xy 283.916882 -246.973336)
			(xy 283.863732 -246.969352) (xy 283.81177 -246.957492) (xy 283.762156 -246.93802) (xy 283.715998 -246.911371)
			(xy 283.674327 -246.87814) (xy 283.638075 -246.839069) (xy 283.608051 -246.795032) (xy 283.584925 -246.747011)
			(xy 283.569215 -246.696081) (xy 283.561272 -246.643377) (xy 269.184892 -246.643377) (xy 269.176949 -246.696081)
			(xy 269.161239 -246.747011) (xy 269.138113 -246.795032) (xy 269.108089 -246.839069) (xy 269.071837 -246.87814)
			(xy 269.030166 -246.911371) (xy 268.984008 -246.93802) (xy 268.934394 -246.957492) (xy 268.882432 -246.969352)
			(xy 268.829282 -246.973336) (xy 268.776132 -246.969352) (xy 268.72417 -246.957492) (xy 268.674556 -246.93802)
			(xy 268.628398 -246.911371) (xy 268.586727 -246.87814) (xy 268.550475 -246.839069) (xy 268.520451 -246.795032)
			(xy 268.497325 -246.747011) (xy 268.481615 -246.696081) (xy 268.473672 -246.643377) (xy 254.20828 -246.643377)
			(xy 254.20828 -247.493261) (xy 264.373604 -247.493261) (xy 264.373604 -247.439963) (xy 264.381547 -247.387259)
			(xy 264.397257 -247.336329) (xy 264.420383 -247.288308) (xy 264.450407 -247.244271) (xy 264.486659 -247.2052)
			(xy 264.52833 -247.171969) (xy 264.574488 -247.14532) (xy 264.624102 -247.125848) (xy 264.676064 -247.113988)
			(xy 264.729214 -247.110005) (xy 264.782364 -247.113988) (xy 264.834326 -247.125848) (xy 264.88394 -247.14532)
			(xy 264.930098 -247.171969) (xy 264.971769 -247.2052) (xy 265.008021 -247.244271) (xy 265.038045 -247.288308)
			(xy 265.061171 -247.336329) (xy 265.076881 -247.387259) (xy 265.084824 -247.439963) (xy 265.085322 -247.466612)
			(xy 265.084824 -247.493261) (xy 279.461204 -247.493261) (xy 279.461204 -247.439963) (xy 279.469147 -247.387259)
			(xy 279.484857 -247.336329) (xy 279.507983 -247.288308) (xy 279.538007 -247.244271) (xy 279.574259 -247.2052)
			(xy 279.61593 -247.171969) (xy 279.662088 -247.14532) (xy 279.711702 -247.125848) (xy 279.763664 -247.113988)
			(xy 279.816814 -247.110005) (xy 279.869964 -247.113988) (xy 279.921926 -247.125848) (xy 279.97154 -247.14532)
			(xy 280.017698 -247.171969) (xy 280.059369 -247.2052) (xy 280.095621 -247.244271) (xy 280.125645 -247.288308)
			(xy 280.148771 -247.336329) (xy 280.164481 -247.387259) (xy 280.172424 -247.439963) (xy 280.172922 -247.466612)
			(xy 280.172424 -247.493261) (xy 294.548804 -247.493261) (xy 294.548804 -247.439963) (xy 294.556747 -247.387259)
			(xy 294.572457 -247.336329) (xy 294.595583 -247.288308) (xy 294.625607 -247.244271) (xy 294.661859 -247.2052)
			(xy 294.70353 -247.171969) (xy 294.749688 -247.14532) (xy 294.799302 -247.125848) (xy 294.851264 -247.113988)
			(xy 294.904414 -247.110005) (xy 294.957564 -247.113988) (xy 295.009526 -247.125848) (xy 295.05914 -247.14532)
			(xy 295.105298 -247.171969) (xy 295.146969 -247.2052) (xy 295.183221 -247.244271) (xy 295.213245 -247.288308)
			(xy 295.236371 -247.336329) (xy 295.252081 -247.387259) (xy 295.260024 -247.439963) (xy 295.260522 -247.466612)
			(xy 295.260024 -247.493261) (xy 295.252081 -247.545965) (xy 295.236371 -247.596895) (xy 295.213245 -247.644916)
			(xy 295.183221 -247.688953) (xy 295.146969 -247.728024) (xy 295.105298 -247.761255) (xy 295.05914 -247.787904)
			(xy 295.009526 -247.807376) (xy 294.957564 -247.819236) (xy 294.904414 -247.82322) (xy 294.851264 -247.819236)
			(xy 294.799302 -247.807376) (xy 294.749688 -247.787904) (xy 294.70353 -247.761255) (xy 294.661859 -247.728024)
			(xy 294.625607 -247.688953) (xy 294.595583 -247.644916) (xy 294.572457 -247.596895) (xy 294.556747 -247.545965)
			(xy 294.548804 -247.493261) (xy 280.172424 -247.493261) (xy 280.164481 -247.545965) (xy 280.148771 -247.596895)
			(xy 280.125645 -247.644916) (xy 280.095621 -247.688953) (xy 280.059369 -247.728024) (xy 280.017698 -247.761255)
			(xy 279.97154 -247.787904) (xy 279.921926 -247.807376) (xy 279.869964 -247.819236) (xy 279.816814 -247.82322)
			(xy 279.763664 -247.819236) (xy 279.711702 -247.807376) (xy 279.662088 -247.787904) (xy 279.61593 -247.761255)
			(xy 279.574259 -247.728024) (xy 279.538007 -247.688953) (xy 279.507983 -247.644916) (xy 279.484857 -247.596895)
			(xy 279.469147 -247.545965) (xy 279.461204 -247.493261) (xy 265.084824 -247.493261) (xy 265.076881 -247.545965)
			(xy 265.061171 -247.596895) (xy 265.038045 -247.644916) (xy 265.008021 -247.688953) (xy 264.971769 -247.728024)
			(xy 264.930098 -247.761255) (xy 264.88394 -247.787904) (xy 264.834326 -247.807376) (xy 264.782364 -247.819236)
			(xy 264.729214 -247.82322) (xy 264.676064 -247.819236) (xy 264.624102 -247.807376) (xy 264.574488 -247.787904)
			(xy 264.52833 -247.761255) (xy 264.486659 -247.728024) (xy 264.450407 -247.688953) (xy 264.420383 -247.644916)
			(xy 264.397257 -247.596895) (xy 264.381547 -247.545965) (xy 264.373604 -247.493261) (xy 254.20828 -247.493261)
			(xy 254.20828 -248.343399) (xy 268.473672 -248.343399) (xy 268.473672 -248.290101) (xy 268.481615 -248.237397)
			(xy 268.497325 -248.186467) (xy 268.520451 -248.138446) (xy 268.550475 -248.094409) (xy 268.586727 -248.055338)
			(xy 268.628398 -248.022107) (xy 268.674556 -247.995458) (xy 268.72417 -247.975986) (xy 268.776132 -247.964126)
			(xy 268.829282 -247.960143) (xy 268.882432 -247.964126) (xy 268.934394 -247.975986) (xy 268.984008 -247.995458)
			(xy 269.030166 -248.022107) (xy 269.071837 -248.055338) (xy 269.108089 -248.094409) (xy 269.138113 -248.138446)
			(xy 269.161239 -248.186467) (xy 269.176949 -248.237397) (xy 269.184892 -248.290101) (xy 269.18539 -248.31675)
			(xy 269.184892 -248.343399) (xy 283.561272 -248.343399) (xy 283.561272 -248.290101) (xy 283.569215 -248.237397)
			(xy 283.584925 -248.186467) (xy 283.608051 -248.138446) (xy 283.638075 -248.094409) (xy 283.674327 -248.055338)
			(xy 283.715998 -248.022107) (xy 283.762156 -247.995458) (xy 283.81177 -247.975986) (xy 283.863732 -247.964126)
			(xy 283.916882 -247.960143) (xy 283.970032 -247.964126) (xy 284.021994 -247.975986) (xy 284.071608 -247.995458)
			(xy 284.117766 -248.022107) (xy 284.159437 -248.055338) (xy 284.195689 -248.094409) (xy 284.225713 -248.138446)
			(xy 284.248839 -248.186467) (xy 284.264549 -248.237397) (xy 284.272492 -248.290101) (xy 284.27299 -248.31675)
			(xy 284.272492 -248.343399) (xy 298.648872 -248.343399) (xy 298.648872 -248.290101) (xy 298.656815 -248.237397)
			(xy 298.672525 -248.186467) (xy 298.695651 -248.138446) (xy 298.725675 -248.094409) (xy 298.761927 -248.055338)
			(xy 298.803598 -248.022107) (xy 298.849756 -247.995458) (xy 298.89937 -247.975986) (xy 298.951332 -247.964126)
			(xy 299.004482 -247.960143) (xy 299.057632 -247.964126) (xy 299.109594 -247.975986) (xy 299.159208 -247.995458)
			(xy 299.205366 -248.022107) (xy 299.247037 -248.055338) (xy 299.283289 -248.094409) (xy 299.313313 -248.138446)
			(xy 299.336439 -248.186467) (xy 299.352149 -248.237397) (xy 299.360092 -248.290101) (xy 299.36059 -248.31675)
			(xy 299.360092 -248.343399) (xy 299.352149 -248.396103) (xy 299.336439 -248.447033) (xy 299.313313 -248.495054)
			(xy 299.283289 -248.539091) (xy 299.247037 -248.578162) (xy 299.205366 -248.611393) (xy 299.159208 -248.638042)
			(xy 299.109594 -248.657514) (xy 299.057632 -248.669374) (xy 299.004482 -248.673358) (xy 298.951332 -248.669374)
			(xy 298.89937 -248.657514) (xy 298.849756 -248.638042) (xy 298.803598 -248.611393) (xy 298.761927 -248.578162)
			(xy 298.725675 -248.539091) (xy 298.695651 -248.495054) (xy 298.672525 -248.447033) (xy 298.656815 -248.396103)
			(xy 298.648872 -248.343399) (xy 284.272492 -248.343399) (xy 284.264549 -248.396103) (xy 284.248839 -248.447033)
			(xy 284.225713 -248.495054) (xy 284.195689 -248.539091) (xy 284.159437 -248.578162) (xy 284.117766 -248.611393)
			(xy 284.071608 -248.638042) (xy 284.021994 -248.657514) (xy 283.970032 -248.669374) (xy 283.916882 -248.673358)
			(xy 283.863732 -248.669374) (xy 283.81177 -248.657514) (xy 283.762156 -248.638042) (xy 283.715998 -248.611393)
			(xy 283.674327 -248.578162) (xy 283.638075 -248.539091) (xy 283.608051 -248.495054) (xy 283.584925 -248.447033)
			(xy 283.569215 -248.396103) (xy 283.561272 -248.343399) (xy 269.184892 -248.343399) (xy 269.176949 -248.396103)
			(xy 269.161239 -248.447033) (xy 269.138113 -248.495054) (xy 269.108089 -248.539091) (xy 269.071837 -248.578162)
			(xy 269.030166 -248.611393) (xy 268.984008 -248.638042) (xy 268.934394 -248.657514) (xy 268.882432 -248.669374)
			(xy 268.829282 -248.673358) (xy 268.776132 -248.669374) (xy 268.72417 -248.657514) (xy 268.674556 -248.638042)
			(xy 268.628398 -248.611393) (xy 268.586727 -248.578162) (xy 268.550475 -248.539091) (xy 268.520451 -248.495054)
			(xy 268.497325 -248.447033) (xy 268.481615 -248.396103) (xy 268.473672 -248.343399) (xy 254.20828 -248.343399)
			(xy 254.20828 -249.193283) (xy 264.373604 -249.193283) (xy 264.373604 -249.139985) (xy 264.381547 -249.087281)
			(xy 264.397257 -249.036351) (xy 264.420383 -248.98833) (xy 264.450407 -248.944293) (xy 264.486659 -248.905222)
			(xy 264.52833 -248.871991) (xy 264.574488 -248.845342) (xy 264.624102 -248.82587) (xy 264.676064 -248.81401)
			(xy 264.729214 -248.810027) (xy 264.782364 -248.81401) (xy 264.834326 -248.82587) (xy 264.88394 -248.845342)
			(xy 264.930098 -248.871991) (xy 264.971769 -248.905222) (xy 265.008021 -248.944293) (xy 265.038045 -248.98833)
			(xy 265.061171 -249.036351) (xy 265.076881 -249.087281) (xy 265.084824 -249.139985) (xy 265.085322 -249.166634)
			(xy 265.084824 -249.193283) (xy 279.461204 -249.193283) (xy 279.461204 -249.139985) (xy 279.469147 -249.087281)
			(xy 279.484857 -249.036351) (xy 279.507983 -248.98833) (xy 279.538007 -248.944293) (xy 279.574259 -248.905222)
			(xy 279.61593 -248.871991) (xy 279.662088 -248.845342) (xy 279.711702 -248.82587) (xy 279.763664 -248.81401)
			(xy 279.816814 -248.810027) (xy 279.869964 -248.81401) (xy 279.921926 -248.82587) (xy 279.97154 -248.845342)
			(xy 280.017698 -248.871991) (xy 280.059369 -248.905222) (xy 280.095621 -248.944293) (xy 280.125645 -248.98833)
			(xy 280.148771 -249.036351) (xy 280.164481 -249.087281) (xy 280.172424 -249.139985) (xy 280.172922 -249.166634)
			(xy 280.172424 -249.193283) (xy 294.548804 -249.193283) (xy 294.548804 -249.139985) (xy 294.556747 -249.087281)
			(xy 294.572457 -249.036351) (xy 294.595583 -248.98833) (xy 294.625607 -248.944293) (xy 294.661859 -248.905222)
			(xy 294.70353 -248.871991) (xy 294.749688 -248.845342) (xy 294.799302 -248.82587) (xy 294.851264 -248.81401)
			(xy 294.904414 -248.810027) (xy 294.957564 -248.81401) (xy 295.009526 -248.82587) (xy 295.05914 -248.845342)
			(xy 295.105298 -248.871991) (xy 295.146969 -248.905222) (xy 295.183221 -248.944293) (xy 295.213245 -248.98833)
			(xy 295.236371 -249.036351) (xy 295.252081 -249.087281) (xy 295.260024 -249.139985) (xy 295.260522 -249.166634)
			(xy 295.260024 -249.193283) (xy 295.252081 -249.245987) (xy 295.236371 -249.296917) (xy 295.213245 -249.344938)
			(xy 295.183221 -249.388975) (xy 295.146969 -249.428046) (xy 295.105298 -249.461277) (xy 295.05914 -249.487926)
			(xy 295.009526 -249.507398) (xy 294.957564 -249.519258) (xy 294.904414 -249.523242) (xy 294.851264 -249.519258)
			(xy 294.799302 -249.507398) (xy 294.749688 -249.487926) (xy 294.70353 -249.461277) (xy 294.661859 -249.428046)
			(xy 294.625607 -249.388975) (xy 294.595583 -249.344938) (xy 294.572457 -249.296917) (xy 294.556747 -249.245987)
			(xy 294.548804 -249.193283) (xy 280.172424 -249.193283) (xy 280.164481 -249.245987) (xy 280.148771 -249.296917)
			(xy 280.125645 -249.344938) (xy 280.095621 -249.388975) (xy 280.059369 -249.428046) (xy 280.017698 -249.461277)
			(xy 279.97154 -249.487926) (xy 279.921926 -249.507398) (xy 279.869964 -249.519258) (xy 279.816814 -249.523242)
			(xy 279.763664 -249.519258) (xy 279.711702 -249.507398) (xy 279.662088 -249.487926) (xy 279.61593 -249.461277)
			(xy 279.574259 -249.428046) (xy 279.538007 -249.388975) (xy 279.507983 -249.344938) (xy 279.484857 -249.296917)
			(xy 279.469147 -249.245987) (xy 279.461204 -249.193283) (xy 265.084824 -249.193283) (xy 265.076881 -249.245987)
			(xy 265.061171 -249.296917) (xy 265.038045 -249.344938) (xy 265.008021 -249.388975) (xy 264.971769 -249.428046)
			(xy 264.930098 -249.461277) (xy 264.88394 -249.487926) (xy 264.834326 -249.507398) (xy 264.782364 -249.519258)
			(xy 264.729214 -249.523242) (xy 264.676064 -249.519258) (xy 264.624102 -249.507398) (xy 264.574488 -249.487926)
			(xy 264.52833 -249.461277) (xy 264.486659 -249.428046) (xy 264.450407 -249.388975) (xy 264.420383 -249.344938)
			(xy 264.397257 -249.296917) (xy 264.381547 -249.245987) (xy 264.373604 -249.193283) (xy 254.20828 -249.193283)
			(xy 254.20828 -250.043421) (xy 268.473672 -250.043421) (xy 268.473672 -249.990123) (xy 268.481615 -249.937419)
			(xy 268.497325 -249.886489) (xy 268.520451 -249.838468) (xy 268.550475 -249.794431) (xy 268.586727 -249.75536)
			(xy 268.628398 -249.722129) (xy 268.674556 -249.69548) (xy 268.72417 -249.676008) (xy 268.776132 -249.664148)
			(xy 268.829282 -249.660165) (xy 268.882432 -249.664148) (xy 268.934394 -249.676008) (xy 268.984008 -249.69548)
			(xy 269.030166 -249.722129) (xy 269.071837 -249.75536) (xy 269.108089 -249.794431) (xy 269.138113 -249.838468)
			(xy 269.161239 -249.886489) (xy 269.176949 -249.937419) (xy 269.184892 -249.990123) (xy 269.18539 -250.016772)
			(xy 269.184892 -250.043421) (xy 283.561272 -250.043421) (xy 283.561272 -249.990123) (xy 283.569215 -249.937419)
			(xy 283.584925 -249.886489) (xy 283.608051 -249.838468) (xy 283.638075 -249.794431) (xy 283.674327 -249.75536)
			(xy 283.715998 -249.722129) (xy 283.762156 -249.69548) (xy 283.81177 -249.676008) (xy 283.863732 -249.664148)
			(xy 283.916882 -249.660165) (xy 283.970032 -249.664148) (xy 284.021994 -249.676008) (xy 284.071608 -249.69548)
			(xy 284.117766 -249.722129) (xy 284.159437 -249.75536) (xy 284.195689 -249.794431) (xy 284.225713 -249.838468)
			(xy 284.248839 -249.886489) (xy 284.264549 -249.937419) (xy 284.272492 -249.990123) (xy 284.27299 -250.016772)
			(xy 284.272492 -250.043421) (xy 298.648872 -250.043421) (xy 298.648872 -249.990123) (xy 298.656815 -249.937419)
			(xy 298.672525 -249.886489) (xy 298.695651 -249.838468) (xy 298.725675 -249.794431) (xy 298.761927 -249.75536)
			(xy 298.803598 -249.722129) (xy 298.849756 -249.69548) (xy 298.89937 -249.676008) (xy 298.951332 -249.664148)
			(xy 299.004482 -249.660165) (xy 299.057632 -249.664148) (xy 299.109594 -249.676008) (xy 299.159208 -249.69548)
			(xy 299.205366 -249.722129) (xy 299.247037 -249.75536) (xy 299.283289 -249.794431) (xy 299.313313 -249.838468)
			(xy 299.336439 -249.886489) (xy 299.352149 -249.937419) (xy 299.360092 -249.990123) (xy 299.36059 -250.016772)
			(xy 299.360092 -250.043421) (xy 299.352149 -250.096125) (xy 299.336439 -250.147055) (xy 299.313313 -250.195076)
			(xy 299.283289 -250.239113) (xy 299.247037 -250.278184) (xy 299.205366 -250.311415) (xy 299.159208 -250.338064)
			(xy 299.109594 -250.357536) (xy 299.057632 -250.369396) (xy 299.004482 -250.37338) (xy 298.951332 -250.369396)
			(xy 298.89937 -250.357536) (xy 298.849756 -250.338064) (xy 298.803598 -250.311415) (xy 298.761927 -250.278184)
			(xy 298.725675 -250.239113) (xy 298.695651 -250.195076) (xy 298.672525 -250.147055) (xy 298.656815 -250.096125)
			(xy 298.648872 -250.043421) (xy 284.272492 -250.043421) (xy 284.264549 -250.096125) (xy 284.248839 -250.147055)
			(xy 284.225713 -250.195076) (xy 284.195689 -250.239113) (xy 284.159437 -250.278184) (xy 284.117766 -250.311415)
			(xy 284.071608 -250.338064) (xy 284.021994 -250.357536) (xy 283.970032 -250.369396) (xy 283.916882 -250.37338)
			(xy 283.863732 -250.369396) (xy 283.81177 -250.357536) (xy 283.762156 -250.338064) (xy 283.715998 -250.311415)
			(xy 283.674327 -250.278184) (xy 283.638075 -250.239113) (xy 283.608051 -250.195076) (xy 283.584925 -250.147055)
			(xy 283.569215 -250.096125) (xy 283.561272 -250.043421) (xy 269.184892 -250.043421) (xy 269.176949 -250.096125)
			(xy 269.161239 -250.147055) (xy 269.138113 -250.195076) (xy 269.108089 -250.239113) (xy 269.071837 -250.278184)
			(xy 269.030166 -250.311415) (xy 268.984008 -250.338064) (xy 268.934394 -250.357536) (xy 268.882432 -250.369396)
			(xy 268.829282 -250.37338) (xy 268.776132 -250.369396) (xy 268.72417 -250.357536) (xy 268.674556 -250.338064)
			(xy 268.628398 -250.311415) (xy 268.586727 -250.278184) (xy 268.550475 -250.239113) (xy 268.520451 -250.195076)
			(xy 268.497325 -250.147055) (xy 268.481615 -250.096125) (xy 268.473672 -250.043421) (xy 254.20828 -250.043421)
			(xy 254.20828 -250.893305) (xy 264.373604 -250.893305) (xy 264.373604 -250.840007) (xy 264.381547 -250.787303)
			(xy 264.397257 -250.736373) (xy 264.420383 -250.688352) (xy 264.450407 -250.644315) (xy 264.486659 -250.605244)
			(xy 264.52833 -250.572013) (xy 264.574488 -250.545364) (xy 264.624102 -250.525892) (xy 264.676064 -250.514032)
			(xy 264.729214 -250.510049) (xy 264.782364 -250.514032) (xy 264.834326 -250.525892) (xy 264.88394 -250.545364)
			(xy 264.930098 -250.572013) (xy 264.971769 -250.605244) (xy 265.008021 -250.644315) (xy 265.038045 -250.688352)
			(xy 265.061171 -250.736373) (xy 265.076881 -250.787303) (xy 265.084824 -250.840007) (xy 265.085322 -250.866656)
			(xy 265.084824 -250.893305) (xy 279.461204 -250.893305) (xy 279.461204 -250.840007) (xy 279.469147 -250.787303)
			(xy 279.484857 -250.736373) (xy 279.507983 -250.688352) (xy 279.538007 -250.644315) (xy 279.574259 -250.605244)
			(xy 279.61593 -250.572013) (xy 279.662088 -250.545364) (xy 279.711702 -250.525892) (xy 279.763664 -250.514032)
			(xy 279.816814 -250.510049) (xy 279.869964 -250.514032) (xy 279.921926 -250.525892) (xy 279.97154 -250.545364)
			(xy 280.017698 -250.572013) (xy 280.059369 -250.605244) (xy 280.095621 -250.644315) (xy 280.125645 -250.688352)
			(xy 280.148771 -250.736373) (xy 280.164481 -250.787303) (xy 280.172424 -250.840007) (xy 280.172922 -250.866656)
			(xy 280.172424 -250.893305) (xy 294.548804 -250.893305) (xy 294.548804 -250.840007) (xy 294.556747 -250.787303)
			(xy 294.572457 -250.736373) (xy 294.595583 -250.688352) (xy 294.625607 -250.644315) (xy 294.661859 -250.605244)
			(xy 294.70353 -250.572013) (xy 294.749688 -250.545364) (xy 294.799302 -250.525892) (xy 294.851264 -250.514032)
			(xy 294.904414 -250.510049) (xy 294.957564 -250.514032) (xy 295.009526 -250.525892) (xy 295.05914 -250.545364)
			(xy 295.105298 -250.572013) (xy 295.146969 -250.605244) (xy 295.183221 -250.644315) (xy 295.213245 -250.688352)
			(xy 295.236371 -250.736373) (xy 295.252081 -250.787303) (xy 295.260024 -250.840007) (xy 295.260522 -250.866656)
			(xy 295.260024 -250.893305) (xy 295.252081 -250.946009) (xy 295.236371 -250.996939) (xy 295.213245 -251.04496)
			(xy 295.183221 -251.088997) (xy 295.146969 -251.128068) (xy 295.105298 -251.161299) (xy 295.05914 -251.187948)
			(xy 295.009526 -251.20742) (xy 294.957564 -251.21928) (xy 294.904414 -251.223264) (xy 294.851264 -251.21928)
			(xy 294.799302 -251.20742) (xy 294.749688 -251.187948) (xy 294.70353 -251.161299) (xy 294.661859 -251.128068)
			(xy 294.625607 -251.088997) (xy 294.595583 -251.04496) (xy 294.572457 -250.996939) (xy 294.556747 -250.946009)
			(xy 294.548804 -250.893305) (xy 280.172424 -250.893305) (xy 280.164481 -250.946009) (xy 280.148771 -250.996939)
			(xy 280.125645 -251.04496) (xy 280.095621 -251.088997) (xy 280.059369 -251.128068) (xy 280.017698 -251.161299)
			(xy 279.97154 -251.187948) (xy 279.921926 -251.20742) (xy 279.869964 -251.21928) (xy 279.816814 -251.223264)
			(xy 279.763664 -251.21928) (xy 279.711702 -251.20742) (xy 279.662088 -251.187948) (xy 279.61593 -251.161299)
			(xy 279.574259 -251.128068) (xy 279.538007 -251.088997) (xy 279.507983 -251.04496) (xy 279.484857 -250.996939)
			(xy 279.469147 -250.946009) (xy 279.461204 -250.893305) (xy 265.084824 -250.893305) (xy 265.076881 -250.946009)
			(xy 265.061171 -250.996939) (xy 265.038045 -251.04496) (xy 265.008021 -251.088997) (xy 264.971769 -251.128068)
			(xy 264.930098 -251.161299) (xy 264.88394 -251.187948) (xy 264.834326 -251.20742) (xy 264.782364 -251.21928)
			(xy 264.729214 -251.223264) (xy 264.676064 -251.21928) (xy 264.624102 -251.20742) (xy 264.574488 -251.187948)
			(xy 264.52833 -251.161299) (xy 264.486659 -251.128068) (xy 264.450407 -251.088997) (xy 264.420383 -251.04496)
			(xy 264.397257 -250.996939) (xy 264.381547 -250.946009) (xy 264.373604 -250.893305) (xy 254.20828 -250.893305)
			(xy 254.20828 -251.743443) (xy 268.473672 -251.743443) (xy 268.473672 -251.690145) (xy 268.481615 -251.637441)
			(xy 268.497325 -251.586511) (xy 268.520451 -251.53849) (xy 268.550475 -251.494453) (xy 268.586727 -251.455382)
			(xy 268.628398 -251.422151) (xy 268.674556 -251.395502) (xy 268.72417 -251.37603) (xy 268.776132 -251.36417)
			(xy 268.829282 -251.360187) (xy 268.882432 -251.36417) (xy 268.934394 -251.37603) (xy 268.984008 -251.395502)
			(xy 269.030166 -251.422151) (xy 269.071837 -251.455382) (xy 269.108089 -251.494453) (xy 269.138113 -251.53849)
			(xy 269.161239 -251.586511) (xy 269.176949 -251.637441) (xy 269.184892 -251.690145) (xy 269.18539 -251.716794)
			(xy 269.184892 -251.743443) (xy 283.561272 -251.743443) (xy 283.561272 -251.690145) (xy 283.569215 -251.637441)
			(xy 283.584925 -251.586511) (xy 283.608051 -251.53849) (xy 283.638075 -251.494453) (xy 283.674327 -251.455382)
			(xy 283.715998 -251.422151) (xy 283.762156 -251.395502) (xy 283.81177 -251.37603) (xy 283.863732 -251.36417)
			(xy 283.916882 -251.360187) (xy 283.970032 -251.36417) (xy 284.021994 -251.37603) (xy 284.071608 -251.395502)
			(xy 284.117766 -251.422151) (xy 284.159437 -251.455382) (xy 284.195689 -251.494453) (xy 284.225713 -251.53849)
			(xy 284.248839 -251.586511) (xy 284.264549 -251.637441) (xy 284.272492 -251.690145) (xy 284.27299 -251.716794)
			(xy 284.272492 -251.743443) (xy 298.648872 -251.743443) (xy 298.648872 -251.690145) (xy 298.656815 -251.637441)
			(xy 298.672525 -251.586511) (xy 298.695651 -251.53849) (xy 298.725675 -251.494453) (xy 298.761927 -251.455382)
			(xy 298.803598 -251.422151) (xy 298.849756 -251.395502) (xy 298.89937 -251.37603) (xy 298.951332 -251.36417)
			(xy 299.004482 -251.360187) (xy 299.057632 -251.36417) (xy 299.109594 -251.37603) (xy 299.159208 -251.395502)
			(xy 299.205366 -251.422151) (xy 299.247037 -251.455382) (xy 299.283289 -251.494453) (xy 299.313313 -251.53849)
			(xy 299.336439 -251.586511) (xy 299.352149 -251.637441) (xy 299.360092 -251.690145) (xy 299.36059 -251.716794)
			(xy 299.360092 -251.743443) (xy 299.352149 -251.796147) (xy 299.336439 -251.847077) (xy 299.313313 -251.895098)
			(xy 299.283289 -251.939135) (xy 299.247037 -251.978206) (xy 299.205366 -252.011437) (xy 299.159208 -252.038086)
			(xy 299.109594 -252.057558) (xy 299.057632 -252.069418) (xy 299.004482 -252.073402) (xy 298.951332 -252.069418)
			(xy 298.89937 -252.057558) (xy 298.849756 -252.038086) (xy 298.803598 -252.011437) (xy 298.761927 -251.978206)
			(xy 298.725675 -251.939135) (xy 298.695651 -251.895098) (xy 298.672525 -251.847077) (xy 298.656815 -251.796147)
			(xy 298.648872 -251.743443) (xy 284.272492 -251.743443) (xy 284.264549 -251.796147) (xy 284.248839 -251.847077)
			(xy 284.225713 -251.895098) (xy 284.195689 -251.939135) (xy 284.159437 -251.978206) (xy 284.117766 -252.011437)
			(xy 284.071608 -252.038086) (xy 284.021994 -252.057558) (xy 283.970032 -252.069418) (xy 283.916882 -252.073402)
			(xy 283.863732 -252.069418) (xy 283.81177 -252.057558) (xy 283.762156 -252.038086) (xy 283.715998 -252.011437)
			(xy 283.674327 -251.978206) (xy 283.638075 -251.939135) (xy 283.608051 -251.895098) (xy 283.584925 -251.847077)
			(xy 283.569215 -251.796147) (xy 283.561272 -251.743443) (xy 269.184892 -251.743443) (xy 269.176949 -251.796147)
			(xy 269.161239 -251.847077) (xy 269.138113 -251.895098) (xy 269.108089 -251.939135) (xy 269.071837 -251.978206)
			(xy 269.030166 -252.011437) (xy 268.984008 -252.038086) (xy 268.934394 -252.057558) (xy 268.882432 -252.069418)
			(xy 268.829282 -252.073402) (xy 268.776132 -252.069418) (xy 268.72417 -252.057558) (xy 268.674556 -252.038086)
			(xy 268.628398 -252.011437) (xy 268.586727 -251.978206) (xy 268.550475 -251.939135) (xy 268.520451 -251.895098)
			(xy 268.497325 -251.847077) (xy 268.481615 -251.796147) (xy 268.473672 -251.743443) (xy 254.20828 -251.743443)
			(xy 254.20828 -252.593327) (xy 258.720072 -252.593327) (xy 258.720072 -252.540029) (xy 258.728015 -252.487325)
			(xy 258.743725 -252.436395) (xy 258.766851 -252.388374) (xy 258.796875 -252.344337) (xy 258.833127 -252.305266)
			(xy 258.874798 -252.272035) (xy 258.920956 -252.245386) (xy 258.97057 -252.225914) (xy 259.022532 -252.214054)
			(xy 259.075682 -252.210071) (xy 259.128832 -252.214054) (xy 259.180794 -252.225914) (xy 259.230408 -252.245386)
			(xy 259.276566 -252.272035) (xy 259.318237 -252.305266) (xy 259.354489 -252.344337) (xy 259.384513 -252.388374)
			(xy 259.407639 -252.436395) (xy 259.423349 -252.487325) (xy 259.431292 -252.540029) (xy 259.43179 -252.566678)
			(xy 259.431292 -252.593327) (xy 264.373604 -252.593327) (xy 264.373604 -252.540029) (xy 264.381547 -252.487325)
			(xy 264.397257 -252.436395) (xy 264.420383 -252.388374) (xy 264.450407 -252.344337) (xy 264.486659 -252.305266)
			(xy 264.52833 -252.272035) (xy 264.574488 -252.245386) (xy 264.624102 -252.225914) (xy 264.676064 -252.214054)
			(xy 264.729214 -252.210071) (xy 264.782364 -252.214054) (xy 264.834326 -252.225914) (xy 264.88394 -252.245386)
			(xy 264.930098 -252.272035) (xy 264.971769 -252.305266) (xy 265.008021 -252.344337) (xy 265.038045 -252.388374)
			(xy 265.061171 -252.436395) (xy 265.076881 -252.487325) (xy 265.084824 -252.540029) (xy 265.085322 -252.566678)
			(xy 265.084824 -252.593327) (xy 268.473672 -252.593327) (xy 268.473672 -252.540029) (xy 268.481615 -252.487325)
			(xy 268.497325 -252.436395) (xy 268.520451 -252.388374) (xy 268.550475 -252.344337) (xy 268.586727 -252.305266)
			(xy 268.628398 -252.272035) (xy 268.674556 -252.245386) (xy 268.72417 -252.225914) (xy 268.776132 -252.214054)
			(xy 268.829282 -252.210071) (xy 268.882432 -252.214054) (xy 268.934394 -252.225914) (xy 268.984008 -252.245386)
			(xy 269.030166 -252.272035) (xy 269.071837 -252.305266) (xy 269.108089 -252.344337) (xy 269.138113 -252.388374)
			(xy 269.161239 -252.436395) (xy 269.176949 -252.487325) (xy 269.184892 -252.540029) (xy 269.18539 -252.566678)
			(xy 269.184892 -252.593327) (xy 273.807672 -252.593327) (xy 273.807672 -252.540029) (xy 273.815615 -252.487325)
			(xy 273.831325 -252.436395) (xy 273.854451 -252.388374) (xy 273.884475 -252.344337) (xy 273.920727 -252.305266)
			(xy 273.962398 -252.272035) (xy 274.008556 -252.245386) (xy 274.05817 -252.225914) (xy 274.110132 -252.214054)
			(xy 274.163282 -252.210071) (xy 274.216432 -252.214054) (xy 274.268394 -252.225914) (xy 274.318008 -252.245386)
			(xy 274.364166 -252.272035) (xy 274.405837 -252.305266) (xy 274.442089 -252.344337) (xy 274.472113 -252.388374)
			(xy 274.495239 -252.436395) (xy 274.510949 -252.487325) (xy 274.518892 -252.540029) (xy 274.51939 -252.566678)
			(xy 274.518892 -252.593327) (xy 279.461204 -252.593327) (xy 279.461204 -252.540029) (xy 279.469147 -252.487325)
			(xy 279.484857 -252.436395) (xy 279.507983 -252.388374) (xy 279.538007 -252.344337) (xy 279.574259 -252.305266)
			(xy 279.61593 -252.272035) (xy 279.662088 -252.245386) (xy 279.711702 -252.225914) (xy 279.763664 -252.214054)
			(xy 279.816814 -252.210071) (xy 279.869964 -252.214054) (xy 279.921926 -252.225914) (xy 279.97154 -252.245386)
			(xy 280.017698 -252.272035) (xy 280.059369 -252.305266) (xy 280.095621 -252.344337) (xy 280.125645 -252.388374)
			(xy 280.148771 -252.436395) (xy 280.164481 -252.487325) (xy 280.172424 -252.540029) (xy 280.172922 -252.566678)
			(xy 280.172424 -252.593327) (xy 283.561272 -252.593327) (xy 283.561272 -252.540029) (xy 283.569215 -252.487325)
			(xy 283.584925 -252.436395) (xy 283.608051 -252.388374) (xy 283.638075 -252.344337) (xy 283.674327 -252.305266)
			(xy 283.715998 -252.272035) (xy 283.762156 -252.245386) (xy 283.81177 -252.225914) (xy 283.863732 -252.214054)
			(xy 283.916882 -252.210071) (xy 283.970032 -252.214054) (xy 284.021994 -252.225914) (xy 284.071608 -252.245386)
			(xy 284.117766 -252.272035) (xy 284.159437 -252.305266) (xy 284.195689 -252.344337) (xy 284.225713 -252.388374)
			(xy 284.248839 -252.436395) (xy 284.264549 -252.487325) (xy 284.272492 -252.540029) (xy 284.27299 -252.566678)
			(xy 284.272492 -252.593327) (xy 288.895272 -252.593327) (xy 288.895272 -252.540029) (xy 288.903215 -252.487325)
			(xy 288.918925 -252.436395) (xy 288.942051 -252.388374) (xy 288.972075 -252.344337) (xy 289.008327 -252.305266)
			(xy 289.049998 -252.272035) (xy 289.096156 -252.245386) (xy 289.14577 -252.225914) (xy 289.197732 -252.214054)
			(xy 289.250882 -252.210071) (xy 289.304032 -252.214054) (xy 289.355994 -252.225914) (xy 289.405608 -252.245386)
			(xy 289.451766 -252.272035) (xy 289.493437 -252.305266) (xy 289.529689 -252.344337) (xy 289.559713 -252.388374)
			(xy 289.582839 -252.436395) (xy 289.598549 -252.487325) (xy 289.606492 -252.540029) (xy 289.60699 -252.566678)
			(xy 289.606492 -252.593327) (xy 294.548804 -252.593327) (xy 294.548804 -252.540029) (xy 294.556747 -252.487325)
			(xy 294.572457 -252.436395) (xy 294.595583 -252.388374) (xy 294.625607 -252.344337) (xy 294.661859 -252.305266)
			(xy 294.70353 -252.272035) (xy 294.749688 -252.245386) (xy 294.799302 -252.225914) (xy 294.851264 -252.214054)
			(xy 294.904414 -252.210071) (xy 294.957564 -252.214054) (xy 295.009526 -252.225914) (xy 295.05914 -252.245386)
			(xy 295.105298 -252.272035) (xy 295.146969 -252.305266) (xy 295.183221 -252.344337) (xy 295.213245 -252.388374)
			(xy 295.236371 -252.436395) (xy 295.252081 -252.487325) (xy 295.260024 -252.540029) (xy 295.260522 -252.566678)
			(xy 295.260024 -252.593327) (xy 298.648872 -252.593327) (xy 298.648872 -252.540029) (xy 298.656815 -252.487325)
			(xy 298.672525 -252.436395) (xy 298.695651 -252.388374) (xy 298.725675 -252.344337) (xy 298.761927 -252.305266)
			(xy 298.803598 -252.272035) (xy 298.849756 -252.245386) (xy 298.89937 -252.225914) (xy 298.951332 -252.214054)
			(xy 299.004482 -252.210071) (xy 299.057632 -252.214054) (xy 299.109594 -252.225914) (xy 299.159208 -252.245386)
			(xy 299.205366 -252.272035) (xy 299.247037 -252.305266) (xy 299.283289 -252.344337) (xy 299.313313 -252.388374)
			(xy 299.336439 -252.436395) (xy 299.352149 -252.487325) (xy 299.360092 -252.540029) (xy 299.36059 -252.566678)
			(xy 299.360092 -252.593327) (xy 303.982872 -252.593327) (xy 303.982872 -252.540029) (xy 303.990815 -252.487325)
			(xy 304.006525 -252.436395) (xy 304.029651 -252.388374) (xy 304.059675 -252.344337) (xy 304.095927 -252.305266)
			(xy 304.137598 -252.272035) (xy 304.183756 -252.245386) (xy 304.23337 -252.225914) (xy 304.285332 -252.214054)
			(xy 304.338482 -252.210071) (xy 304.391632 -252.214054) (xy 304.443594 -252.225914) (xy 304.493208 -252.245386)
			(xy 304.539366 -252.272035) (xy 304.581037 -252.305266) (xy 304.617289 -252.344337) (xy 304.647313 -252.388374)
			(xy 304.670439 -252.436395) (xy 304.686149 -252.487325) (xy 304.694092 -252.540029) (xy 304.69459 -252.566678)
			(xy 304.694092 -252.593327) (xy 311.526672 -252.593327) (xy 311.526672 -252.540029) (xy 311.534615 -252.487325)
			(xy 311.550325 -252.436395) (xy 311.573451 -252.388374) (xy 311.603475 -252.344337) (xy 311.639727 -252.305266)
			(xy 311.681398 -252.272035) (xy 311.727556 -252.245386) (xy 311.77717 -252.225914) (xy 311.829132 -252.214054)
			(xy 311.882282 -252.210071) (xy 311.935432 -252.214054) (xy 311.987394 -252.225914) (xy 312.037008 -252.245386)
			(xy 312.083166 -252.272035) (xy 312.124837 -252.305266) (xy 312.161089 -252.344337) (xy 312.191113 -252.388374)
			(xy 312.214239 -252.436395) (xy 312.229949 -252.487325) (xy 312.237892 -252.540029) (xy 312.23839 -252.566678)
			(xy 312.237892 -252.593327) (xy 312.229949 -252.646031) (xy 312.214239 -252.696961) (xy 312.191113 -252.744982)
			(xy 312.161089 -252.789019) (xy 312.124837 -252.82809) (xy 312.083166 -252.861321) (xy 312.037008 -252.88797)
			(xy 311.987394 -252.907442) (xy 311.935432 -252.919302) (xy 311.882282 -252.923286) (xy 311.829132 -252.919302)
			(xy 311.77717 -252.907442) (xy 311.727556 -252.88797) (xy 311.681398 -252.861321) (xy 311.639727 -252.82809)
			(xy 311.603475 -252.789019) (xy 311.573451 -252.744982) (xy 311.550325 -252.696961) (xy 311.534615 -252.646031)
			(xy 311.526672 -252.593327) (xy 304.694092 -252.593327) (xy 304.686149 -252.646031) (xy 304.670439 -252.696961)
			(xy 304.647313 -252.744982) (xy 304.617289 -252.789019) (xy 304.581037 -252.82809) (xy 304.539366 -252.861321)
			(xy 304.493208 -252.88797) (xy 304.443594 -252.907442) (xy 304.391632 -252.919302) (xy 304.338482 -252.923286)
			(xy 304.285332 -252.919302) (xy 304.23337 -252.907442) (xy 304.183756 -252.88797) (xy 304.137598 -252.861321)
			(xy 304.095927 -252.82809) (xy 304.059675 -252.789019) (xy 304.029651 -252.744982) (xy 304.006525 -252.696961)
			(xy 303.990815 -252.646031) (xy 303.982872 -252.593327) (xy 299.360092 -252.593327) (xy 299.352149 -252.646031)
			(xy 299.336439 -252.696961) (xy 299.313313 -252.744982) (xy 299.283289 -252.789019) (xy 299.247037 -252.82809)
			(xy 299.205366 -252.861321) (xy 299.159208 -252.88797) (xy 299.109594 -252.907442) (xy 299.057632 -252.919302)
			(xy 299.004482 -252.923286) (xy 298.951332 -252.919302) (xy 298.89937 -252.907442) (xy 298.849756 -252.88797)
			(xy 298.803598 -252.861321) (xy 298.761927 -252.82809) (xy 298.725675 -252.789019) (xy 298.695651 -252.744982)
			(xy 298.672525 -252.696961) (xy 298.656815 -252.646031) (xy 298.648872 -252.593327) (xy 295.260024 -252.593327)
			(xy 295.252081 -252.646031) (xy 295.236371 -252.696961) (xy 295.213245 -252.744982) (xy 295.183221 -252.789019)
			(xy 295.146969 -252.82809) (xy 295.105298 -252.861321) (xy 295.05914 -252.88797) (xy 295.009526 -252.907442)
			(xy 294.957564 -252.919302) (xy 294.904414 -252.923286) (xy 294.851264 -252.919302) (xy 294.799302 -252.907442)
			(xy 294.749688 -252.88797) (xy 294.70353 -252.861321) (xy 294.661859 -252.82809) (xy 294.625607 -252.789019)
			(xy 294.595583 -252.744982) (xy 294.572457 -252.696961) (xy 294.556747 -252.646031) (xy 294.548804 -252.593327)
			(xy 289.606492 -252.593327) (xy 289.598549 -252.646031) (xy 289.582839 -252.696961) (xy 289.559713 -252.744982)
			(xy 289.529689 -252.789019) (xy 289.493437 -252.82809) (xy 289.451766 -252.861321) (xy 289.405608 -252.88797)
			(xy 289.355994 -252.907442) (xy 289.304032 -252.919302) (xy 289.250882 -252.923286) (xy 289.197732 -252.919302)
			(xy 289.14577 -252.907442) (xy 289.096156 -252.88797) (xy 289.049998 -252.861321) (xy 289.008327 -252.82809)
			(xy 288.972075 -252.789019) (xy 288.942051 -252.744982) (xy 288.918925 -252.696961) (xy 288.903215 -252.646031)
			(xy 288.895272 -252.593327) (xy 284.272492 -252.593327) (xy 284.264549 -252.646031) (xy 284.248839 -252.696961)
			(xy 284.225713 -252.744982) (xy 284.195689 -252.789019) (xy 284.159437 -252.82809) (xy 284.117766 -252.861321)
			(xy 284.071608 -252.88797) (xy 284.021994 -252.907442) (xy 283.970032 -252.919302) (xy 283.916882 -252.923286)
			(xy 283.863732 -252.919302) (xy 283.81177 -252.907442) (xy 283.762156 -252.88797) (xy 283.715998 -252.861321)
			(xy 283.674327 -252.82809) (xy 283.638075 -252.789019) (xy 283.608051 -252.744982) (xy 283.584925 -252.696961)
			(xy 283.569215 -252.646031) (xy 283.561272 -252.593327) (xy 280.172424 -252.593327) (xy 280.164481 -252.646031)
			(xy 280.148771 -252.696961) (xy 280.125645 -252.744982) (xy 280.095621 -252.789019) (xy 280.059369 -252.82809)
			(xy 280.017698 -252.861321) (xy 279.97154 -252.88797) (xy 279.921926 -252.907442) (xy 279.869964 -252.919302)
			(xy 279.816814 -252.923286) (xy 279.763664 -252.919302) (xy 279.711702 -252.907442) (xy 279.662088 -252.88797)
			(xy 279.61593 -252.861321) (xy 279.574259 -252.82809) (xy 279.538007 -252.789019) (xy 279.507983 -252.744982)
			(xy 279.484857 -252.696961) (xy 279.469147 -252.646031) (xy 279.461204 -252.593327) (xy 274.518892 -252.593327)
			(xy 274.510949 -252.646031) (xy 274.495239 -252.696961) (xy 274.472113 -252.744982) (xy 274.442089 -252.789019)
			(xy 274.405837 -252.82809) (xy 274.364166 -252.861321) (xy 274.318008 -252.88797) (xy 274.268394 -252.907442)
			(xy 274.216432 -252.919302) (xy 274.163282 -252.923286) (xy 274.110132 -252.919302) (xy 274.05817 -252.907442)
			(xy 274.008556 -252.88797) (xy 273.962398 -252.861321) (xy 273.920727 -252.82809) (xy 273.884475 -252.789019)
			(xy 273.854451 -252.744982) (xy 273.831325 -252.696961) (xy 273.815615 -252.646031) (xy 273.807672 -252.593327)
			(xy 269.184892 -252.593327) (xy 269.176949 -252.646031) (xy 269.161239 -252.696961) (xy 269.138113 -252.744982)
			(xy 269.108089 -252.789019) (xy 269.071837 -252.82809) (xy 269.030166 -252.861321) (xy 268.984008 -252.88797)
			(xy 268.934394 -252.907442) (xy 268.882432 -252.919302) (xy 268.829282 -252.923286) (xy 268.776132 -252.919302)
			(xy 268.72417 -252.907442) (xy 268.674556 -252.88797) (xy 268.628398 -252.861321) (xy 268.586727 -252.82809)
			(xy 268.550475 -252.789019) (xy 268.520451 -252.744982) (xy 268.497325 -252.696961) (xy 268.481615 -252.646031)
			(xy 268.473672 -252.593327) (xy 265.084824 -252.593327) (xy 265.076881 -252.646031) (xy 265.061171 -252.696961)
			(xy 265.038045 -252.744982) (xy 265.008021 -252.789019) (xy 264.971769 -252.82809) (xy 264.930098 -252.861321)
			(xy 264.88394 -252.88797) (xy 264.834326 -252.907442) (xy 264.782364 -252.919302) (xy 264.729214 -252.923286)
			(xy 264.676064 -252.919302) (xy 264.624102 -252.907442) (xy 264.574488 -252.88797) (xy 264.52833 -252.861321)
			(xy 264.486659 -252.82809) (xy 264.450407 -252.789019) (xy 264.420383 -252.744982) (xy 264.397257 -252.696961)
			(xy 264.381547 -252.646031) (xy 264.373604 -252.593327) (xy 259.431292 -252.593327) (xy 259.423349 -252.646031)
			(xy 259.407639 -252.696961) (xy 259.384513 -252.744982) (xy 259.354489 -252.789019) (xy 259.318237 -252.82809)
			(xy 259.276566 -252.861321) (xy 259.230408 -252.88797) (xy 259.180794 -252.907442) (xy 259.128832 -252.919302)
			(xy 259.075682 -252.923286) (xy 259.022532 -252.919302) (xy 258.97057 -252.907442) (xy 258.920956 -252.88797)
			(xy 258.874798 -252.861321) (xy 258.833127 -252.82809) (xy 258.796875 -252.789019) (xy 258.766851 -252.744982)
			(xy 258.743725 -252.696961) (xy 258.728015 -252.646031) (xy 258.720072 -252.593327) (xy 254.20828 -252.593327)
			(xy 254.20828 -254.6495) (xy 305.72177 -254.6495) (xy 305.725754 -254.596349) (xy 305.737614 -254.544385)
			(xy 305.757086 -254.494769) (xy 305.783735 -254.448609) (xy 305.816966 -254.406937) (xy 305.856037 -254.370682)
			(xy 305.900075 -254.340656) (xy 305.948096 -254.317528) (xy 305.999027 -254.301815) (xy 306.051732 -254.293869)
			(xy 306.078382 -254.29337) (xy 306.078636 -254.29337) (xy 306.10593 -254.293928) (xy 306.159875 -254.302286)
			(xy 306.211916 -254.318769) (xy 306.260836 -254.342994) (xy 306.30549 -254.374393) (xy 306.325524 -254.392938)
			(xy 306.337146 -254.403335) (xy 306.36508 -254.417159) (xy 306.395882 -254.421915) (xy 306.426684 -254.417159)
			(xy 306.454618 -254.403335) (xy 306.46624 -254.392938) (xy 306.48625 -254.374321) (xy 306.530943 -254.342864)
			(xy 306.579922 -254.318614) (xy 306.632035 -254.302144) (xy 306.686055 -254.29384) (xy 306.713382 -254.29337)
			(xy 306.740702 -254.29391) (xy 306.794702 -254.302245) (xy 306.846798 -254.318722) (xy 306.89577 -254.342955)
			(xy 306.940471 -254.374377) (xy 306.960524 -254.392938) (xy 306.972146 -254.403335) (xy 307.00008 -254.417159)
			(xy 307.030882 -254.421915) (xy 307.061684 -254.417159) (xy 307.089618 -254.403335) (xy 307.10124 -254.392938)
			(xy 307.12125 -254.374321) (xy 307.165943 -254.342864) (xy 307.214922 -254.318614) (xy 307.267035 -254.302144)
			(xy 307.321055 -254.29384) (xy 307.348382 -254.29337) (xy 307.375702 -254.29391) (xy 307.429702 -254.302245)
			(xy 307.481798 -254.318722) (xy 307.53077 -254.342955) (xy 307.575471 -254.374377) (xy 307.595524 -254.392938)
			(xy 307.607146 -254.403335) (xy 307.63508 -254.417159) (xy 307.665882 -254.421915) (xy 307.696684 -254.417159)
			(xy 307.724618 -254.403335) (xy 307.73624 -254.392938) (xy 307.755464 -254.375081) (xy 307.798185 -254.344619)
			(xy 307.844918 -254.320766) (xy 307.894648 -254.304039) (xy 307.92039 -254.298958) (xy 307.933561 -254.296141)
			(xy 307.957888 -254.284605) (xy 307.978361 -254.267118) (xy 307.993558 -254.244893) (xy 308.002426 -254.219471)
			(xy 308.00435 -254.192616) (xy 308.002178 -254.179324) (xy 307.999094 -254.162411) (xy 307.995783 -254.128189)
			(xy 307.995574 -254.110998) (xy 307.996139 -254.083016) (xy 308.004894 -254.02774) (xy 308.022188 -253.974515)
			(xy 308.047594 -253.92465) (xy 308.080489 -253.879373) (xy 308.120061 -253.839799) (xy 308.165336 -253.806903)
			(xy 308.2152 -253.781494) (xy 308.268425 -253.764198) (xy 308.3237 -253.75544) (xy 308.351682 -253.75489)
			(xy 308.381014 -253.755495) (xy 308.438887 -253.765102) (xy 308.494399 -253.784074) (xy 308.546045 -253.811899)
			(xy 308.592425 -253.847821) (xy 308.612794 -253.868936) (xy 308.622804 -253.879069) (xy 308.647183 -253.893779)
			(xy 308.674677 -253.90118) (xy 308.703146 -253.900698) (xy 308.730374 -253.892369) (xy 308.75424 -253.876843)
			(xy 308.763924 -253.866396) (xy 308.780916 -253.847572) (xy 308.819315 -253.81445) (xy 308.862024 -253.78711)
			(xy 308.90818 -253.766107) (xy 308.956849 -253.751864) (xy 309.007047 -253.74467) (xy 309.032402 -253.744222)
			(xy 309.059053 -253.74466) (xy 309.111761 -253.752605) (xy 309.162696 -253.768316) (xy 309.21072 -253.791444)
			(xy 309.254761 -253.82147) (xy 309.293834 -253.857726) (xy 309.327068 -253.8994) (xy 309.35372 -253.945561)
			(xy 309.373193 -253.99518) (xy 309.385054 -254.047146) (xy 309.389038 -254.1003) (xy 309.385054 -254.153454)
			(xy 309.373193 -254.20542) (xy 309.35372 -254.255039) (xy 309.327068 -254.3012) (xy 309.293834 -254.342874)
			(xy 309.254761 -254.37913) (xy 309.21072 -254.409156) (xy 309.162696 -254.432284) (xy 309.111761 -254.447995)
			(xy 309.059053 -254.45594) (xy 309.032402 -254.456438) (xy 309.00307 -254.455835) (xy 308.945197 -254.446226)
			(xy 308.889686 -254.427252) (xy 308.83804 -254.399428) (xy 308.791659 -254.363507) (xy 308.77129 -254.342392)
			(xy 308.761291 -254.33225) (xy 308.736906 -254.317552) (xy 308.709411 -254.310158) (xy 308.680944 -254.310643)
			(xy 308.653717 -254.318969) (xy 308.629847 -254.334489) (xy 308.62016 -254.344932) (xy 308.604044 -254.362845)
			(xy 308.567789 -254.394585) (xy 308.527583 -254.421142) (xy 308.484161 -254.44203) (xy 308.438317 -254.456867)
			(xy 308.414674 -254.461518) (xy 308.401505 -254.464338) (xy 308.377182 -254.475878) (xy 308.356713 -254.493366)
			(xy 308.341517 -254.515589) (xy 308.332647 -254.541008) (xy 308.330717 -254.567861) (xy 308.332886 -254.581152)
			(xy 308.33598 -254.598064) (xy 308.339284 -254.632287) (xy 308.33949 -254.649478) (xy 308.338967 -254.677464)
			(xy 308.330214 -254.732746) (xy 308.31292 -254.785979) (xy 308.287511 -254.83585) (xy 308.254613 -254.881132)
			(xy 308.215035 -254.92071) (xy 308.169754 -254.953609) (xy 308.119882 -254.979019) (xy 308.06665 -254.996313)
			(xy 308.011368 -255.005067) (xy 307.983382 -255.005586) (xy 307.983128 -255.005586) (xy 307.955832 -255.005062)
			(xy 307.901885 -254.996698) (xy 307.849843 -254.980207) (xy 307.800925 -254.955974) (xy 307.756272 -254.924567)
			(xy 307.73624 -254.906018) (xy 307.724618 -254.895621) (xy 307.696684 -254.881797) (xy 307.665882 -254.877041)
			(xy 307.63508 -254.881797) (xy 307.607146 -254.895621) (xy 307.595524 -254.906018) (xy 307.575496 -254.924614)
			(xy 307.530807 -254.956072) (xy 307.481832 -254.980324) (xy 307.429723 -254.9968) (xy 307.375708 -255.005111)
			(xy 307.348382 -255.005586) (xy 307.321061 -255.00508) (xy 307.267058 -254.996739) (xy 307.214961 -254.980255)
			(xy 307.16599 -254.956013) (xy 307.121292 -254.924583) (xy 307.10124 -254.906018) (xy 307.089618 -254.895621)
			(xy 307.061684 -254.881797) (xy 307.030882 -254.877041) (xy 307.00008 -254.881797) (xy 306.972146 -254.895621)
			(xy 306.960524 -254.906018) (xy 306.940496 -254.924614) (xy 306.895807 -254.956072) (xy 306.846832 -254.980324)
			(xy 306.794723 -254.9968) (xy 306.740708 -255.005111) (xy 306.713382 -255.005586) (xy 306.686061 -255.00508)
			(xy 306.632058 -254.996739) (xy 306.579961 -254.980255) (xy 306.53099 -254.956013) (xy 306.486292 -254.924583)
			(xy 306.46624 -254.906018) (xy 306.454618 -254.895621) (xy 306.426684 -254.881797) (xy 306.395882 -254.877041)
			(xy 306.36508 -254.881797) (xy 306.337146 -254.895621) (xy 306.325524 -254.906018) (xy 306.305515 -254.924598)
			(xy 306.260872 -254.956033) (xy 306.21195 -254.980277) (xy 306.159897 -254.996759) (xy 306.105936 -255.005093)
			(xy 306.078636 -255.005586) (xy 306.078382 -255.005586) (xy 306.051732 -255.005131) (xy 305.999027 -254.997185)
			(xy 305.948096 -254.981472) (xy 305.900075 -254.958344) (xy 305.856037 -254.928318) (xy 305.816966 -254.892063)
			(xy 305.783735 -254.850391) (xy 305.757086 -254.804231) (xy 305.737614 -254.754615) (xy 305.725754 -254.702651)
			(xy 305.72177 -254.6495) (xy 254.20828 -254.6495) (xy 254.20828 -259.393415) (xy 260.929872 -259.393415)
			(xy 260.929872 -259.340117) (xy 260.937815 -259.287413) (xy 260.953525 -259.236483) (xy 260.976651 -259.188462)
			(xy 261.006675 -259.144425) (xy 261.042927 -259.105354) (xy 261.084598 -259.072123) (xy 261.130756 -259.045474)
			(xy 261.18037 -259.026002) (xy 261.232332 -259.014142) (xy 261.285482 -259.010159) (xy 261.338632 -259.014142)
			(xy 261.390594 -259.026002) (xy 261.440208 -259.045474) (xy 261.486366 -259.072123) (xy 261.528037 -259.105354)
			(xy 261.564289 -259.144425) (xy 261.594313 -259.188462) (xy 261.617439 -259.236483) (xy 261.633149 -259.287413)
			(xy 261.641092 -259.340117) (xy 261.64159 -259.366766) (xy 261.641092 -259.393415) (xy 264.373604 -259.393415)
			(xy 264.373604 -259.340117) (xy 264.381547 -259.287413) (xy 264.397257 -259.236483) (xy 264.420383 -259.188462)
			(xy 264.450407 -259.144425) (xy 264.486659 -259.105354) (xy 264.52833 -259.072123) (xy 264.574488 -259.045474)
			(xy 264.624102 -259.026002) (xy 264.676064 -259.014142) (xy 264.729214 -259.010159) (xy 264.782364 -259.014142)
			(xy 264.834326 -259.026002) (xy 264.88394 -259.045474) (xy 264.930098 -259.072123) (xy 264.971769 -259.105354)
			(xy 265.008021 -259.144425) (xy 265.038045 -259.188462) (xy 265.061171 -259.236483) (xy 265.076881 -259.287413)
			(xy 265.084824 -259.340117) (xy 265.085322 -259.366766) (xy 265.084824 -259.393415) (xy 268.473672 -259.393415)
			(xy 268.473672 -259.340117) (xy 268.481615 -259.287413) (xy 268.497325 -259.236483) (xy 268.520451 -259.188462)
			(xy 268.550475 -259.144425) (xy 268.586727 -259.105354) (xy 268.628398 -259.072123) (xy 268.674556 -259.045474)
			(xy 268.72417 -259.026002) (xy 268.776132 -259.014142) (xy 268.829282 -259.010159) (xy 268.882432 -259.014142)
			(xy 268.934394 -259.026002) (xy 268.984008 -259.045474) (xy 269.030166 -259.072123) (xy 269.071837 -259.105354)
			(xy 269.108089 -259.144425) (xy 269.138113 -259.188462) (xy 269.161239 -259.236483) (xy 269.176949 -259.287413)
			(xy 269.184892 -259.340117) (xy 269.18539 -259.366766) (xy 269.184892 -259.393415) (xy 276.017472 -259.393415)
			(xy 276.017472 -259.340117) (xy 276.025415 -259.287413) (xy 276.041125 -259.236483) (xy 276.064251 -259.188462)
			(xy 276.094275 -259.144425) (xy 276.130527 -259.105354) (xy 276.172198 -259.072123) (xy 276.218356 -259.045474)
			(xy 276.26797 -259.026002) (xy 276.319932 -259.014142) (xy 276.373082 -259.010159) (xy 276.426232 -259.014142)
			(xy 276.478194 -259.026002) (xy 276.527808 -259.045474) (xy 276.573966 -259.072123) (xy 276.615637 -259.105354)
			(xy 276.651889 -259.144425) (xy 276.681913 -259.188462) (xy 276.705039 -259.236483) (xy 276.720749 -259.287413)
			(xy 276.728692 -259.340117) (xy 276.72919 -259.366766) (xy 276.728692 -259.393415) (xy 279.461204 -259.393415)
			(xy 279.461204 -259.340117) (xy 279.469147 -259.287413) (xy 279.484857 -259.236483) (xy 279.507983 -259.188462)
			(xy 279.538007 -259.144425) (xy 279.574259 -259.105354) (xy 279.61593 -259.072123) (xy 279.662088 -259.045474)
			(xy 279.711702 -259.026002) (xy 279.763664 -259.014142) (xy 279.816814 -259.010159) (xy 279.869964 -259.014142)
			(xy 279.921926 -259.026002) (xy 279.97154 -259.045474) (xy 280.017698 -259.072123) (xy 280.059369 -259.105354)
			(xy 280.095621 -259.144425) (xy 280.125645 -259.188462) (xy 280.148771 -259.236483) (xy 280.164481 -259.287413)
			(xy 280.172424 -259.340117) (xy 280.172922 -259.366766) (xy 280.172424 -259.393415) (xy 283.561272 -259.393415)
			(xy 283.561272 -259.340117) (xy 283.569215 -259.287413) (xy 283.584925 -259.236483) (xy 283.608051 -259.188462)
			(xy 283.638075 -259.144425) (xy 283.674327 -259.105354) (xy 283.715998 -259.072123) (xy 283.762156 -259.045474)
			(xy 283.81177 -259.026002) (xy 283.863732 -259.014142) (xy 283.916882 -259.010159) (xy 283.970032 -259.014142)
			(xy 284.021994 -259.026002) (xy 284.071608 -259.045474) (xy 284.117766 -259.072123) (xy 284.159437 -259.105354)
			(xy 284.195689 -259.144425) (xy 284.225713 -259.188462) (xy 284.248839 -259.236483) (xy 284.264549 -259.287413)
			(xy 284.272492 -259.340117) (xy 284.27299 -259.366766) (xy 284.272492 -259.393415) (xy 291.105072 -259.393415)
			(xy 291.105072 -259.340117) (xy 291.113015 -259.287413) (xy 291.128725 -259.236483) (xy 291.151851 -259.188462)
			(xy 291.181875 -259.144425) (xy 291.218127 -259.105354) (xy 291.259798 -259.072123) (xy 291.305956 -259.045474)
			(xy 291.35557 -259.026002) (xy 291.407532 -259.014142) (xy 291.460682 -259.010159) (xy 291.513832 -259.014142)
			(xy 291.565794 -259.026002) (xy 291.615408 -259.045474) (xy 291.661566 -259.072123) (xy 291.703237 -259.105354)
			(xy 291.739489 -259.144425) (xy 291.769513 -259.188462) (xy 291.792639 -259.236483) (xy 291.808349 -259.287413)
			(xy 291.816292 -259.340117) (xy 291.81679 -259.366766) (xy 291.816292 -259.393415) (xy 294.548804 -259.393415)
			(xy 294.548804 -259.340117) (xy 294.556747 -259.287413) (xy 294.572457 -259.236483) (xy 294.595583 -259.188462)
			(xy 294.625607 -259.144425) (xy 294.661859 -259.105354) (xy 294.70353 -259.072123) (xy 294.749688 -259.045474)
			(xy 294.799302 -259.026002) (xy 294.851264 -259.014142) (xy 294.904414 -259.010159) (xy 294.957564 -259.014142)
			(xy 295.009526 -259.026002) (xy 295.05914 -259.045474) (xy 295.105298 -259.072123) (xy 295.146969 -259.105354)
			(xy 295.183221 -259.144425) (xy 295.213245 -259.188462) (xy 295.236371 -259.236483) (xy 295.252081 -259.287413)
			(xy 295.260024 -259.340117) (xy 295.260522 -259.366766) (xy 295.260024 -259.393415) (xy 298.674272 -259.393415)
			(xy 298.674272 -259.340117) (xy 298.682215 -259.287413) (xy 298.697925 -259.236483) (xy 298.721051 -259.188462)
			(xy 298.751075 -259.144425) (xy 298.787327 -259.105354) (xy 298.828998 -259.072123) (xy 298.875156 -259.045474)
			(xy 298.92477 -259.026002) (xy 298.976732 -259.014142) (xy 299.029882 -259.010159) (xy 299.083032 -259.014142)
			(xy 299.134994 -259.026002) (xy 299.184608 -259.045474) (xy 299.230766 -259.072123) (xy 299.272437 -259.105354)
			(xy 299.308689 -259.144425) (xy 299.338713 -259.188462) (xy 299.361839 -259.236483) (xy 299.377549 -259.287413)
			(xy 299.385492 -259.340117) (xy 299.38599 -259.366766) (xy 299.385492 -259.393415) (xy 299.377549 -259.446119)
			(xy 299.361839 -259.497049) (xy 299.338713 -259.54507) (xy 299.308689 -259.589107) (xy 299.272437 -259.628178)
			(xy 299.230766 -259.661409) (xy 299.184608 -259.688058) (xy 299.134994 -259.70753) (xy 299.083032 -259.71939)
			(xy 299.029882 -259.723374) (xy 298.976732 -259.71939) (xy 298.92477 -259.70753) (xy 298.875156 -259.688058)
			(xy 298.828998 -259.661409) (xy 298.787327 -259.628178) (xy 298.751075 -259.589107) (xy 298.721051 -259.54507)
			(xy 298.697925 -259.497049) (xy 298.682215 -259.446119) (xy 298.674272 -259.393415) (xy 295.260024 -259.393415)
			(xy 295.252081 -259.446119) (xy 295.236371 -259.497049) (xy 295.213245 -259.54507) (xy 295.183221 -259.589107)
			(xy 295.146969 -259.628178) (xy 295.105298 -259.661409) (xy 295.05914 -259.688058) (xy 295.009526 -259.70753)
			(xy 294.957564 -259.71939) (xy 294.904414 -259.723374) (xy 294.851264 -259.71939) (xy 294.799302 -259.70753)
			(xy 294.749688 -259.688058) (xy 294.70353 -259.661409) (xy 294.661859 -259.628178) (xy 294.625607 -259.589107)
			(xy 294.595583 -259.54507) (xy 294.572457 -259.497049) (xy 294.556747 -259.446119) (xy 294.548804 -259.393415)
			(xy 291.816292 -259.393415) (xy 291.808349 -259.446119) (xy 291.792639 -259.497049) (xy 291.769513 -259.54507)
			(xy 291.739489 -259.589107) (xy 291.703237 -259.628178) (xy 291.661566 -259.661409) (xy 291.615408 -259.688058)
			(xy 291.565794 -259.70753) (xy 291.513832 -259.71939) (xy 291.460682 -259.723374) (xy 291.407532 -259.71939)
			(xy 291.35557 -259.70753) (xy 291.305956 -259.688058) (xy 291.259798 -259.661409) (xy 291.218127 -259.628178)
			(xy 291.181875 -259.589107) (xy 291.151851 -259.54507) (xy 291.128725 -259.497049) (xy 291.113015 -259.446119)
			(xy 291.105072 -259.393415) (xy 284.272492 -259.393415) (xy 284.264549 -259.446119) (xy 284.248839 -259.497049)
			(xy 284.225713 -259.54507) (xy 284.195689 -259.589107) (xy 284.159437 -259.628178) (xy 284.117766 -259.661409)
			(xy 284.071608 -259.688058) (xy 284.021994 -259.70753) (xy 283.970032 -259.71939) (xy 283.916882 -259.723374)
			(xy 283.863732 -259.71939) (xy 283.81177 -259.70753) (xy 283.762156 -259.688058) (xy 283.715998 -259.661409)
			(xy 283.674327 -259.628178) (xy 283.638075 -259.589107) (xy 283.608051 -259.54507) (xy 283.584925 -259.497049)
			(xy 283.569215 -259.446119) (xy 283.561272 -259.393415) (xy 280.172424 -259.393415) (xy 280.164481 -259.446119)
			(xy 280.148771 -259.497049) (xy 280.125645 -259.54507) (xy 280.095621 -259.589107) (xy 280.059369 -259.628178)
			(xy 280.017698 -259.661409) (xy 279.97154 -259.688058) (xy 279.921926 -259.70753) (xy 279.869964 -259.71939)
			(xy 279.816814 -259.723374) (xy 279.763664 -259.71939) (xy 279.711702 -259.70753) (xy 279.662088 -259.688058)
			(xy 279.61593 -259.661409) (xy 279.574259 -259.628178) (xy 279.538007 -259.589107) (xy 279.507983 -259.54507)
			(xy 279.484857 -259.497049) (xy 279.469147 -259.446119) (xy 279.461204 -259.393415) (xy 276.728692 -259.393415)
			(xy 276.720749 -259.446119) (xy 276.705039 -259.497049) (xy 276.681913 -259.54507) (xy 276.651889 -259.589107)
			(xy 276.615637 -259.628178) (xy 276.573966 -259.661409) (xy 276.527808 -259.688058) (xy 276.478194 -259.70753)
			(xy 276.426232 -259.71939) (xy 276.373082 -259.723374) (xy 276.319932 -259.71939) (xy 276.26797 -259.70753)
			(xy 276.218356 -259.688058) (xy 276.172198 -259.661409) (xy 276.130527 -259.628178) (xy 276.094275 -259.589107)
			(xy 276.064251 -259.54507) (xy 276.041125 -259.497049) (xy 276.025415 -259.446119) (xy 276.017472 -259.393415)
			(xy 269.184892 -259.393415) (xy 269.176949 -259.446119) (xy 269.161239 -259.497049) (xy 269.138113 -259.54507)
			(xy 269.108089 -259.589107) (xy 269.071837 -259.628178) (xy 269.030166 -259.661409) (xy 268.984008 -259.688058)
			(xy 268.934394 -259.70753) (xy 268.882432 -259.71939) (xy 268.829282 -259.723374) (xy 268.776132 -259.71939)
			(xy 268.72417 -259.70753) (xy 268.674556 -259.688058) (xy 268.628398 -259.661409) (xy 268.586727 -259.628178)
			(xy 268.550475 -259.589107) (xy 268.520451 -259.54507) (xy 268.497325 -259.497049) (xy 268.481615 -259.446119)
			(xy 268.473672 -259.393415) (xy 265.084824 -259.393415) (xy 265.076881 -259.446119) (xy 265.061171 -259.497049)
			(xy 265.038045 -259.54507) (xy 265.008021 -259.589107) (xy 264.971769 -259.628178) (xy 264.930098 -259.661409)
			(xy 264.88394 -259.688058) (xy 264.834326 -259.70753) (xy 264.782364 -259.71939) (xy 264.729214 -259.723374)
			(xy 264.676064 -259.71939) (xy 264.624102 -259.70753) (xy 264.574488 -259.688058) (xy 264.52833 -259.661409)
			(xy 264.486659 -259.628178) (xy 264.450407 -259.589107) (xy 264.420383 -259.54507) (xy 264.397257 -259.497049)
			(xy 264.381547 -259.446119) (xy 264.373604 -259.393415) (xy 261.641092 -259.393415) (xy 261.633149 -259.446119)
			(xy 261.617439 -259.497049) (xy 261.594313 -259.54507) (xy 261.564289 -259.589107) (xy 261.528037 -259.628178)
			(xy 261.486366 -259.661409) (xy 261.440208 -259.688058) (xy 261.390594 -259.70753) (xy 261.338632 -259.71939)
			(xy 261.285482 -259.723374) (xy 261.232332 -259.71939) (xy 261.18037 -259.70753) (xy 261.130756 -259.688058)
			(xy 261.084598 -259.661409) (xy 261.042927 -259.628178) (xy 261.006675 -259.589107) (xy 260.976651 -259.54507)
			(xy 260.953525 -259.497049) (xy 260.937815 -259.446119) (xy 260.929872 -259.393415) (xy 254.20828 -259.393415)
			(xy 254.20828 -260.243299) (xy 260.929872 -260.243299) (xy 260.929872 -260.190001) (xy 260.937815 -260.137297)
			(xy 260.953525 -260.086367) (xy 260.976651 -260.038346) (xy 261.006675 -259.994309) (xy 261.042927 -259.955238)
			(xy 261.084598 -259.922007) (xy 261.130756 -259.895358) (xy 261.18037 -259.875886) (xy 261.232332 -259.864026)
			(xy 261.285482 -259.860043) (xy 261.338632 -259.864026) (xy 261.390594 -259.875886) (xy 261.440208 -259.895358)
			(xy 261.486366 -259.922007) (xy 261.528037 -259.955238) (xy 261.564289 -259.994309) (xy 261.594313 -260.038346)
			(xy 261.617439 -260.086367) (xy 261.633149 -260.137297) (xy 261.641092 -260.190001) (xy 261.64159 -260.21665)
			(xy 261.641092 -260.243299) (xy 268.473672 -260.243299) (xy 268.473672 -260.190001) (xy 268.481615 -260.137297)
			(xy 268.497325 -260.086367) (xy 268.520451 -260.038346) (xy 268.550475 -259.994309) (xy 268.586727 -259.955238)
			(xy 268.628398 -259.922007) (xy 268.674556 -259.895358) (xy 268.72417 -259.875886) (xy 268.776132 -259.864026)
			(xy 268.829282 -259.860043) (xy 268.882432 -259.864026) (xy 268.934394 -259.875886) (xy 268.984008 -259.895358)
			(xy 269.030166 -259.922007) (xy 269.071837 -259.955238) (xy 269.108089 -259.994309) (xy 269.138113 -260.038346)
			(xy 269.161239 -260.086367) (xy 269.176949 -260.137297) (xy 269.184892 -260.190001) (xy 269.18539 -260.21665)
			(xy 269.184892 -260.243299) (xy 276.017472 -260.243299) (xy 276.017472 -260.190001) (xy 276.025415 -260.137297)
			(xy 276.041125 -260.086367) (xy 276.064251 -260.038346) (xy 276.094275 -259.994309) (xy 276.130527 -259.955238)
			(xy 276.172198 -259.922007) (xy 276.218356 -259.895358) (xy 276.26797 -259.875886) (xy 276.319932 -259.864026)
			(xy 276.373082 -259.860043) (xy 276.426232 -259.864026) (xy 276.478194 -259.875886) (xy 276.527808 -259.895358)
			(xy 276.573966 -259.922007) (xy 276.615637 -259.955238) (xy 276.651889 -259.994309) (xy 276.681913 -260.038346)
			(xy 276.705039 -260.086367) (xy 276.720749 -260.137297) (xy 276.728692 -260.190001) (xy 276.72919 -260.21665)
			(xy 276.728692 -260.243299) (xy 283.561272 -260.243299) (xy 283.561272 -260.190001) (xy 283.569215 -260.137297)
			(xy 283.584925 -260.086367) (xy 283.608051 -260.038346) (xy 283.638075 -259.994309) (xy 283.674327 -259.955238)
			(xy 283.715998 -259.922007) (xy 283.762156 -259.895358) (xy 283.81177 -259.875886) (xy 283.863732 -259.864026)
			(xy 283.916882 -259.860043) (xy 283.970032 -259.864026) (xy 284.021994 -259.875886) (xy 284.071608 -259.895358)
			(xy 284.117766 -259.922007) (xy 284.159437 -259.955238) (xy 284.195689 -259.994309) (xy 284.225713 -260.038346)
			(xy 284.248839 -260.086367) (xy 284.264549 -260.137297) (xy 284.272492 -260.190001) (xy 284.27299 -260.21665)
			(xy 284.272492 -260.243299) (xy 291.105072 -260.243299) (xy 291.105072 -260.190001) (xy 291.113015 -260.137297)
			(xy 291.128725 -260.086367) (xy 291.151851 -260.038346) (xy 291.181875 -259.994309) (xy 291.218127 -259.955238)
			(xy 291.259798 -259.922007) (xy 291.305956 -259.895358) (xy 291.35557 -259.875886) (xy 291.407532 -259.864026)
			(xy 291.460682 -259.860043) (xy 291.513832 -259.864026) (xy 291.565794 -259.875886) (xy 291.615408 -259.895358)
			(xy 291.661566 -259.922007) (xy 291.703237 -259.955238) (xy 291.739489 -259.994309) (xy 291.769513 -260.038346)
			(xy 291.792639 -260.086367) (xy 291.808349 -260.137297) (xy 291.816292 -260.190001) (xy 291.81679 -260.21665)
			(xy 291.816292 -260.243299) (xy 298.674272 -260.243299) (xy 298.674272 -260.190001) (xy 298.682215 -260.137297)
			(xy 298.697925 -260.086367) (xy 298.721051 -260.038346) (xy 298.751075 -259.994309) (xy 298.787327 -259.955238)
			(xy 298.828998 -259.922007) (xy 298.875156 -259.895358) (xy 298.92477 -259.875886) (xy 298.976732 -259.864026)
			(xy 299.029882 -259.860043) (xy 299.083032 -259.864026) (xy 299.134994 -259.875886) (xy 299.184608 -259.895358)
			(xy 299.230766 -259.922007) (xy 299.272437 -259.955238) (xy 299.308689 -259.994309) (xy 299.338713 -260.038346)
			(xy 299.361839 -260.086367) (xy 299.377549 -260.137297) (xy 299.385492 -260.190001) (xy 299.38599 -260.21665)
			(xy 299.385492 -260.243299) (xy 299.377549 -260.296003) (xy 299.361839 -260.346933) (xy 299.338713 -260.394954)
			(xy 299.308689 -260.438991) (xy 299.272437 -260.478062) (xy 299.230766 -260.511293) (xy 299.184608 -260.537942)
			(xy 299.134994 -260.557414) (xy 299.083032 -260.569274) (xy 299.029882 -260.573258) (xy 298.976732 -260.569274)
			(xy 298.92477 -260.557414) (xy 298.875156 -260.537942) (xy 298.828998 -260.511293) (xy 298.787327 -260.478062)
			(xy 298.751075 -260.438991) (xy 298.721051 -260.394954) (xy 298.697925 -260.346933) (xy 298.682215 -260.296003)
			(xy 298.674272 -260.243299) (xy 291.816292 -260.243299) (xy 291.808349 -260.296003) (xy 291.792639 -260.346933)
			(xy 291.769513 -260.394954) (xy 291.739489 -260.438991) (xy 291.703237 -260.478062) (xy 291.661566 -260.511293)
			(xy 291.615408 -260.537942) (xy 291.565794 -260.557414) (xy 291.513832 -260.569274) (xy 291.460682 -260.573258)
			(xy 291.407532 -260.569274) (xy 291.35557 -260.557414) (xy 291.305956 -260.537942) (xy 291.259798 -260.511293)
			(xy 291.218127 -260.478062) (xy 291.181875 -260.438991) (xy 291.151851 -260.394954) (xy 291.128725 -260.346933)
			(xy 291.113015 -260.296003) (xy 291.105072 -260.243299) (xy 284.272492 -260.243299) (xy 284.264549 -260.296003)
			(xy 284.248839 -260.346933) (xy 284.225713 -260.394954) (xy 284.195689 -260.438991) (xy 284.159437 -260.478062)
			(xy 284.117766 -260.511293) (xy 284.071608 -260.537942) (xy 284.021994 -260.557414) (xy 283.970032 -260.569274)
			(xy 283.916882 -260.573258) (xy 283.863732 -260.569274) (xy 283.81177 -260.557414) (xy 283.762156 -260.537942)
			(xy 283.715998 -260.511293) (xy 283.674327 -260.478062) (xy 283.638075 -260.438991) (xy 283.608051 -260.394954)
			(xy 283.584925 -260.346933) (xy 283.569215 -260.296003) (xy 283.561272 -260.243299) (xy 276.728692 -260.243299)
			(xy 276.720749 -260.296003) (xy 276.705039 -260.346933) (xy 276.681913 -260.394954) (xy 276.651889 -260.438991)
			(xy 276.615637 -260.478062) (xy 276.573966 -260.511293) (xy 276.527808 -260.537942) (xy 276.478194 -260.557414)
			(xy 276.426232 -260.569274) (xy 276.373082 -260.573258) (xy 276.319932 -260.569274) (xy 276.26797 -260.557414)
			(xy 276.218356 -260.537942) (xy 276.172198 -260.511293) (xy 276.130527 -260.478062) (xy 276.094275 -260.438991)
			(xy 276.064251 -260.394954) (xy 276.041125 -260.346933) (xy 276.025415 -260.296003) (xy 276.017472 -260.243299)
			(xy 269.184892 -260.243299) (xy 269.176949 -260.296003) (xy 269.161239 -260.346933) (xy 269.138113 -260.394954)
			(xy 269.108089 -260.438991) (xy 269.071837 -260.478062) (xy 269.030166 -260.511293) (xy 268.984008 -260.537942)
			(xy 268.934394 -260.557414) (xy 268.882432 -260.569274) (xy 268.829282 -260.573258) (xy 268.776132 -260.569274)
			(xy 268.72417 -260.557414) (xy 268.674556 -260.537942) (xy 268.628398 -260.511293) (xy 268.586727 -260.478062)
			(xy 268.550475 -260.438991) (xy 268.520451 -260.394954) (xy 268.497325 -260.346933) (xy 268.481615 -260.296003)
			(xy 268.473672 -260.243299) (xy 261.641092 -260.243299) (xy 261.633149 -260.296003) (xy 261.617439 -260.346933)
			(xy 261.594313 -260.394954) (xy 261.564289 -260.438991) (xy 261.528037 -260.478062) (xy 261.486366 -260.511293)
			(xy 261.440208 -260.537942) (xy 261.390594 -260.557414) (xy 261.338632 -260.569274) (xy 261.285482 -260.573258)
			(xy 261.232332 -260.569274) (xy 261.18037 -260.557414) (xy 261.130756 -260.537942) (xy 261.084598 -260.511293)
			(xy 261.042927 -260.478062) (xy 261.006675 -260.438991) (xy 260.976651 -260.394954) (xy 260.953525 -260.346933)
			(xy 260.937815 -260.296003) (xy 260.929872 -260.243299) (xy 254.20828 -260.243299) (xy 254.20828 -261.093437)
			(xy 264.373604 -261.093437) (xy 264.373604 -261.040139) (xy 264.381547 -260.987435) (xy 264.397257 -260.936505)
			(xy 264.420383 -260.888484) (xy 264.450407 -260.844447) (xy 264.486659 -260.805376) (xy 264.52833 -260.772145)
			(xy 264.574488 -260.745496) (xy 264.624102 -260.726024) (xy 264.676064 -260.714164) (xy 264.729214 -260.710181)
			(xy 264.782364 -260.714164) (xy 264.834326 -260.726024) (xy 264.88394 -260.745496) (xy 264.930098 -260.772145)
			(xy 264.971769 -260.805376) (xy 265.008021 -260.844447) (xy 265.038045 -260.888484) (xy 265.061171 -260.936505)
			(xy 265.076881 -260.987435) (xy 265.084824 -261.040139) (xy 265.085322 -261.066788) (xy 265.084824 -261.093437)
			(xy 279.461204 -261.093437) (xy 279.461204 -261.040139) (xy 279.469147 -260.987435) (xy 279.484857 -260.936505)
			(xy 279.507983 -260.888484) (xy 279.538007 -260.844447) (xy 279.574259 -260.805376) (xy 279.61593 -260.772145)
			(xy 279.662088 -260.745496) (xy 279.711702 -260.726024) (xy 279.763664 -260.714164) (xy 279.816814 -260.710181)
			(xy 279.869964 -260.714164) (xy 279.921926 -260.726024) (xy 279.97154 -260.745496) (xy 280.017698 -260.772145)
			(xy 280.059369 -260.805376) (xy 280.095621 -260.844447) (xy 280.125645 -260.888484) (xy 280.148771 -260.936505)
			(xy 280.164481 -260.987435) (xy 280.172424 -261.040139) (xy 280.172922 -261.066788) (xy 280.172424 -261.093437)
			(xy 294.548804 -261.093437) (xy 294.548804 -261.040139) (xy 294.556747 -260.987435) (xy 294.572457 -260.936505)
			(xy 294.595583 -260.888484) (xy 294.625607 -260.844447) (xy 294.661859 -260.805376) (xy 294.70353 -260.772145)
			(xy 294.749688 -260.745496) (xy 294.799302 -260.726024) (xy 294.851264 -260.714164) (xy 294.904414 -260.710181)
			(xy 294.957564 -260.714164) (xy 295.009526 -260.726024) (xy 295.05914 -260.745496) (xy 295.105298 -260.772145)
			(xy 295.146969 -260.805376) (xy 295.183221 -260.844447) (xy 295.213245 -260.888484) (xy 295.236371 -260.936505)
			(xy 295.252081 -260.987435) (xy 295.260024 -261.040139) (xy 295.260522 -261.066788) (xy 295.260024 -261.093437)
			(xy 295.252081 -261.146141) (xy 295.236371 -261.197071) (xy 295.213245 -261.245092) (xy 295.183221 -261.289129)
			(xy 295.146969 -261.3282) (xy 295.105298 -261.361431) (xy 295.05914 -261.38808) (xy 295.009526 -261.407552)
			(xy 294.957564 -261.419412) (xy 294.904414 -261.423396) (xy 294.851264 -261.419412) (xy 294.799302 -261.407552)
			(xy 294.749688 -261.38808) (xy 294.70353 -261.361431) (xy 294.661859 -261.3282) (xy 294.625607 -261.289129)
			(xy 294.595583 -261.245092) (xy 294.572457 -261.197071) (xy 294.556747 -261.146141) (xy 294.548804 -261.093437)
			(xy 280.172424 -261.093437) (xy 280.164481 -261.146141) (xy 280.148771 -261.197071) (xy 280.125645 -261.245092)
			(xy 280.095621 -261.289129) (xy 280.059369 -261.3282) (xy 280.017698 -261.361431) (xy 279.97154 -261.38808)
			(xy 279.921926 -261.407552) (xy 279.869964 -261.419412) (xy 279.816814 -261.423396) (xy 279.763664 -261.419412)
			(xy 279.711702 -261.407552) (xy 279.662088 -261.38808) (xy 279.61593 -261.361431) (xy 279.574259 -261.3282)
			(xy 279.538007 -261.289129) (xy 279.507983 -261.245092) (xy 279.484857 -261.197071) (xy 279.469147 -261.146141)
			(xy 279.461204 -261.093437) (xy 265.084824 -261.093437) (xy 265.076881 -261.146141) (xy 265.061171 -261.197071)
			(xy 265.038045 -261.245092) (xy 265.008021 -261.289129) (xy 264.971769 -261.3282) (xy 264.930098 -261.361431)
			(xy 264.88394 -261.38808) (xy 264.834326 -261.407552) (xy 264.782364 -261.419412) (xy 264.729214 -261.423396)
			(xy 264.676064 -261.419412) (xy 264.624102 -261.407552) (xy 264.574488 -261.38808) (xy 264.52833 -261.361431)
			(xy 264.486659 -261.3282) (xy 264.450407 -261.289129) (xy 264.420383 -261.245092) (xy 264.397257 -261.197071)
			(xy 264.381547 -261.146141) (xy 264.373604 -261.093437) (xy 254.20828 -261.093437) (xy 254.20828 -261.943321)
			(xy 268.473672 -261.943321) (xy 268.473672 -261.890023) (xy 268.481615 -261.837319) (xy 268.497325 -261.786389)
			(xy 268.520451 -261.738368) (xy 268.550475 -261.694331) (xy 268.586727 -261.65526) (xy 268.628398 -261.622029)
			(xy 268.674556 -261.59538) (xy 268.72417 -261.575908) (xy 268.776132 -261.564048) (xy 268.829282 -261.560065)
			(xy 268.882432 -261.564048) (xy 268.934394 -261.575908) (xy 268.984008 -261.59538) (xy 269.030166 -261.622029)
			(xy 269.071837 -261.65526) (xy 269.108089 -261.694331) (xy 269.138113 -261.738368) (xy 269.161239 -261.786389)
			(xy 269.176949 -261.837319) (xy 269.184892 -261.890023) (xy 269.18539 -261.916672) (xy 269.184892 -261.943321)
			(xy 283.561272 -261.943321) (xy 283.561272 -261.890023) (xy 283.569215 -261.837319) (xy 283.584925 -261.786389)
			(xy 283.608051 -261.738368) (xy 283.638075 -261.694331) (xy 283.674327 -261.65526) (xy 283.715998 -261.622029)
			(xy 283.762156 -261.59538) (xy 283.81177 -261.575908) (xy 283.863732 -261.564048) (xy 283.916882 -261.560065)
			(xy 283.970032 -261.564048) (xy 284.021994 -261.575908) (xy 284.071608 -261.59538) (xy 284.117766 -261.622029)
			(xy 284.159437 -261.65526) (xy 284.195689 -261.694331) (xy 284.225713 -261.738368) (xy 284.248839 -261.786389)
			(xy 284.264549 -261.837319) (xy 284.272492 -261.890023) (xy 284.27299 -261.916672) (xy 284.272492 -261.943321)
			(xy 298.674272 -261.943321) (xy 298.674272 -261.890023) (xy 298.682215 -261.837319) (xy 298.697925 -261.786389)
			(xy 298.721051 -261.738368) (xy 298.751075 -261.694331) (xy 298.787327 -261.65526) (xy 298.828998 -261.622029)
			(xy 298.875156 -261.59538) (xy 298.92477 -261.575908) (xy 298.976732 -261.564048) (xy 299.029882 -261.560065)
			(xy 299.083032 -261.564048) (xy 299.134994 -261.575908) (xy 299.184608 -261.59538) (xy 299.230766 -261.622029)
			(xy 299.272437 -261.65526) (xy 299.308689 -261.694331) (xy 299.338713 -261.738368) (xy 299.361839 -261.786389)
			(xy 299.377549 -261.837319) (xy 299.385492 -261.890023) (xy 299.38599 -261.916672) (xy 299.385492 -261.943321)
			(xy 299.377549 -261.996025) (xy 299.361839 -262.046955) (xy 299.338713 -262.094976) (xy 299.308689 -262.139013)
			(xy 299.272437 -262.178084) (xy 299.230766 -262.211315) (xy 299.184608 -262.237964) (xy 299.134994 -262.257436)
			(xy 299.083032 -262.269296) (xy 299.029882 -262.27328) (xy 298.976732 -262.269296) (xy 298.92477 -262.257436)
			(xy 298.875156 -262.237964) (xy 298.828998 -262.211315) (xy 298.787327 -262.178084) (xy 298.751075 -262.139013)
			(xy 298.721051 -262.094976) (xy 298.697925 -262.046955) (xy 298.682215 -261.996025) (xy 298.674272 -261.943321)
			(xy 284.272492 -261.943321) (xy 284.264549 -261.996025) (xy 284.248839 -262.046955) (xy 284.225713 -262.094976)
			(xy 284.195689 -262.139013) (xy 284.159437 -262.178084) (xy 284.117766 -262.211315) (xy 284.071608 -262.237964)
			(xy 284.021994 -262.257436) (xy 283.970032 -262.269296) (xy 283.916882 -262.27328) (xy 283.863732 -262.269296)
			(xy 283.81177 -262.257436) (xy 283.762156 -262.237964) (xy 283.715998 -262.211315) (xy 283.674327 -262.178084)
			(xy 283.638075 -262.139013) (xy 283.608051 -262.094976) (xy 283.584925 -262.046955) (xy 283.569215 -261.996025)
			(xy 283.561272 -261.943321) (xy 269.184892 -261.943321) (xy 269.176949 -261.996025) (xy 269.161239 -262.046955)
			(xy 269.138113 -262.094976) (xy 269.108089 -262.139013) (xy 269.071837 -262.178084) (xy 269.030166 -262.211315)
			(xy 268.984008 -262.237964) (xy 268.934394 -262.257436) (xy 268.882432 -262.269296) (xy 268.829282 -262.27328)
			(xy 268.776132 -262.269296) (xy 268.72417 -262.257436) (xy 268.674556 -262.237964) (xy 268.628398 -262.211315)
			(xy 268.586727 -262.178084) (xy 268.550475 -262.139013) (xy 268.520451 -262.094976) (xy 268.497325 -262.046955)
			(xy 268.481615 -261.996025) (xy 268.473672 -261.943321) (xy 254.20828 -261.943321) (xy 254.20828 -262.793459)
			(xy 264.373604 -262.793459) (xy 264.373604 -262.740161) (xy 264.381547 -262.687457) (xy 264.397257 -262.636527)
			(xy 264.420383 -262.588506) (xy 264.450407 -262.544469) (xy 264.486659 -262.505398) (xy 264.52833 -262.472167)
			(xy 264.574488 -262.445518) (xy 264.624102 -262.426046) (xy 264.676064 -262.414186) (xy 264.729214 -262.410203)
			(xy 264.782364 -262.414186) (xy 264.834326 -262.426046) (xy 264.88394 -262.445518) (xy 264.930098 -262.472167)
			(xy 264.971769 -262.505398) (xy 265.008021 -262.544469) (xy 265.038045 -262.588506) (xy 265.061171 -262.636527)
			(xy 265.076881 -262.687457) (xy 265.084824 -262.740161) (xy 265.085322 -262.76681) (xy 265.084824 -262.793459)
			(xy 279.461204 -262.793459) (xy 279.461204 -262.740161) (xy 279.469147 -262.687457) (xy 279.484857 -262.636527)
			(xy 279.507983 -262.588506) (xy 279.538007 -262.544469) (xy 279.574259 -262.505398) (xy 279.61593 -262.472167)
			(xy 279.662088 -262.445518) (xy 279.711702 -262.426046) (xy 279.763664 -262.414186) (xy 279.816814 -262.410203)
			(xy 279.869964 -262.414186) (xy 279.921926 -262.426046) (xy 279.97154 -262.445518) (xy 280.017698 -262.472167)
			(xy 280.059369 -262.505398) (xy 280.095621 -262.544469) (xy 280.125645 -262.588506) (xy 280.148771 -262.636527)
			(xy 280.164481 -262.687457) (xy 280.172424 -262.740161) (xy 280.172922 -262.76681) (xy 280.172424 -262.793459)
			(xy 294.548804 -262.793459) (xy 294.548804 -262.740161) (xy 294.556747 -262.687457) (xy 294.572457 -262.636527)
			(xy 294.595583 -262.588506) (xy 294.625607 -262.544469) (xy 294.661859 -262.505398) (xy 294.70353 -262.472167)
			(xy 294.749688 -262.445518) (xy 294.799302 -262.426046) (xy 294.851264 -262.414186) (xy 294.904414 -262.410203)
			(xy 294.957564 -262.414186) (xy 295.009526 -262.426046) (xy 295.05914 -262.445518) (xy 295.105298 -262.472167)
			(xy 295.146969 -262.505398) (xy 295.183221 -262.544469) (xy 295.213245 -262.588506) (xy 295.236371 -262.636527)
			(xy 295.252081 -262.687457) (xy 295.260024 -262.740161) (xy 295.260522 -262.76681) (xy 295.260024 -262.793459)
			(xy 295.252081 -262.846163) (xy 295.236371 -262.897093) (xy 295.213245 -262.945114) (xy 295.183221 -262.989151)
			(xy 295.146969 -263.028222) (xy 295.105298 -263.061453) (xy 295.05914 -263.088102) (xy 295.009526 -263.107574)
			(xy 294.957564 -263.119434) (xy 294.904414 -263.123418) (xy 294.851264 -263.119434) (xy 294.799302 -263.107574)
			(xy 294.749688 -263.088102) (xy 294.70353 -263.061453) (xy 294.661859 -263.028222) (xy 294.625607 -262.989151)
			(xy 294.595583 -262.945114) (xy 294.572457 -262.897093) (xy 294.556747 -262.846163) (xy 294.548804 -262.793459)
			(xy 280.172424 -262.793459) (xy 280.164481 -262.846163) (xy 280.148771 -262.897093) (xy 280.125645 -262.945114)
			(xy 280.095621 -262.989151) (xy 280.059369 -263.028222) (xy 280.017698 -263.061453) (xy 279.97154 -263.088102)
			(xy 279.921926 -263.107574) (xy 279.869964 -263.119434) (xy 279.816814 -263.123418) (xy 279.763664 -263.119434)
			(xy 279.711702 -263.107574) (xy 279.662088 -263.088102) (xy 279.61593 -263.061453) (xy 279.574259 -263.028222)
			(xy 279.538007 -262.989151) (xy 279.507983 -262.945114) (xy 279.484857 -262.897093) (xy 279.469147 -262.846163)
			(xy 279.461204 -262.793459) (xy 265.084824 -262.793459) (xy 265.076881 -262.846163) (xy 265.061171 -262.897093)
			(xy 265.038045 -262.945114) (xy 265.008021 -262.989151) (xy 264.971769 -263.028222) (xy 264.930098 -263.061453)
			(xy 264.88394 -263.088102) (xy 264.834326 -263.107574) (xy 264.782364 -263.119434) (xy 264.729214 -263.123418)
			(xy 264.676064 -263.119434) (xy 264.624102 -263.107574) (xy 264.574488 -263.088102) (xy 264.52833 -263.061453)
			(xy 264.486659 -263.028222) (xy 264.450407 -262.989151) (xy 264.420383 -262.945114) (xy 264.397257 -262.897093)
			(xy 264.381547 -262.846163) (xy 264.373604 -262.793459) (xy 254.20828 -262.793459) (xy 254.20828 -263.643343)
			(xy 268.473672 -263.643343) (xy 268.473672 -263.590045) (xy 268.481615 -263.537341) (xy 268.497325 -263.486411)
			(xy 268.520451 -263.43839) (xy 268.550475 -263.394353) (xy 268.586727 -263.355282) (xy 268.628398 -263.322051)
			(xy 268.674556 -263.295402) (xy 268.72417 -263.27593) (xy 268.776132 -263.26407) (xy 268.829282 -263.260087)
			(xy 268.882432 -263.26407) (xy 268.934394 -263.27593) (xy 268.984008 -263.295402) (xy 269.030166 -263.322051)
			(xy 269.071837 -263.355282) (xy 269.108089 -263.394353) (xy 269.138113 -263.43839) (xy 269.161239 -263.486411)
			(xy 269.176949 -263.537341) (xy 269.184892 -263.590045) (xy 269.18539 -263.616694) (xy 269.184892 -263.643343)
			(xy 283.561272 -263.643343) (xy 283.561272 -263.590045) (xy 283.569215 -263.537341) (xy 283.584925 -263.486411)
			(xy 283.608051 -263.43839) (xy 283.638075 -263.394353) (xy 283.674327 -263.355282) (xy 283.715998 -263.322051)
			(xy 283.762156 -263.295402) (xy 283.81177 -263.27593) (xy 283.863732 -263.26407) (xy 283.916882 -263.260087)
			(xy 283.970032 -263.26407) (xy 284.021994 -263.27593) (xy 284.071608 -263.295402) (xy 284.117766 -263.322051)
			(xy 284.159437 -263.355282) (xy 284.195689 -263.394353) (xy 284.225713 -263.43839) (xy 284.248839 -263.486411)
			(xy 284.264549 -263.537341) (xy 284.272492 -263.590045) (xy 284.27299 -263.616694) (xy 284.272492 -263.643343)
			(xy 298.674272 -263.643343) (xy 298.674272 -263.590045) (xy 298.682215 -263.537341) (xy 298.697925 -263.486411)
			(xy 298.721051 -263.43839) (xy 298.751075 -263.394353) (xy 298.787327 -263.355282) (xy 298.828998 -263.322051)
			(xy 298.875156 -263.295402) (xy 298.92477 -263.27593) (xy 298.976732 -263.26407) (xy 299.029882 -263.260087)
			(xy 299.083032 -263.26407) (xy 299.134994 -263.27593) (xy 299.184608 -263.295402) (xy 299.230766 -263.322051)
			(xy 299.272437 -263.355282) (xy 299.308689 -263.394353) (xy 299.338713 -263.43839) (xy 299.361839 -263.486411)
			(xy 299.377549 -263.537341) (xy 299.385492 -263.590045) (xy 299.38599 -263.616694) (xy 299.385492 -263.643343)
			(xy 299.377549 -263.696047) (xy 299.361839 -263.746977) (xy 299.338713 -263.794998) (xy 299.308689 -263.839035)
			(xy 299.272437 -263.878106) (xy 299.230766 -263.911337) (xy 299.184608 -263.937986) (xy 299.134994 -263.957458)
			(xy 299.083032 -263.969318) (xy 299.029882 -263.973302) (xy 298.976732 -263.969318) (xy 298.92477 -263.957458)
			(xy 298.875156 -263.937986) (xy 298.828998 -263.911337) (xy 298.787327 -263.878106) (xy 298.751075 -263.839035)
			(xy 298.721051 -263.794998) (xy 298.697925 -263.746977) (xy 298.682215 -263.696047) (xy 298.674272 -263.643343)
			(xy 284.272492 -263.643343) (xy 284.264549 -263.696047) (xy 284.248839 -263.746977) (xy 284.225713 -263.794998)
			(xy 284.195689 -263.839035) (xy 284.159437 -263.878106) (xy 284.117766 -263.911337) (xy 284.071608 -263.937986)
			(xy 284.021994 -263.957458) (xy 283.970032 -263.969318) (xy 283.916882 -263.973302) (xy 283.863732 -263.969318)
			(xy 283.81177 -263.957458) (xy 283.762156 -263.937986) (xy 283.715998 -263.911337) (xy 283.674327 -263.878106)
			(xy 283.638075 -263.839035) (xy 283.608051 -263.794998) (xy 283.584925 -263.746977) (xy 283.569215 -263.696047)
			(xy 283.561272 -263.643343) (xy 269.184892 -263.643343) (xy 269.176949 -263.696047) (xy 269.161239 -263.746977)
			(xy 269.138113 -263.794998) (xy 269.108089 -263.839035) (xy 269.071837 -263.878106) (xy 269.030166 -263.911337)
			(xy 268.984008 -263.937986) (xy 268.934394 -263.957458) (xy 268.882432 -263.969318) (xy 268.829282 -263.973302)
			(xy 268.776132 -263.969318) (xy 268.72417 -263.957458) (xy 268.674556 -263.937986) (xy 268.628398 -263.911337)
			(xy 268.586727 -263.878106) (xy 268.550475 -263.839035) (xy 268.520451 -263.794998) (xy 268.497325 -263.746977)
			(xy 268.481615 -263.696047) (xy 268.473672 -263.643343) (xy 254.20828 -263.643343) (xy 254.20828 -264.493227)
			(xy 264.373604 -264.493227) (xy 264.373604 -264.439929) (xy 264.381547 -264.387225) (xy 264.397257 -264.336295)
			(xy 264.420383 -264.288274) (xy 264.450407 -264.244237) (xy 264.486659 -264.205166) (xy 264.52833 -264.171935)
			(xy 264.574488 -264.145286) (xy 264.624102 -264.125814) (xy 264.676064 -264.113954) (xy 264.729214 -264.109971)
			(xy 264.782364 -264.113954) (xy 264.834326 -264.125814) (xy 264.88394 -264.145286) (xy 264.930098 -264.171935)
			(xy 264.971769 -264.205166) (xy 265.008021 -264.244237) (xy 265.038045 -264.288274) (xy 265.061171 -264.336295)
			(xy 265.076881 -264.387225) (xy 265.084824 -264.439929) (xy 265.085322 -264.466578) (xy 265.084824 -264.493227)
			(xy 279.461204 -264.493227) (xy 279.461204 -264.439929) (xy 279.469147 -264.387225) (xy 279.484857 -264.336295)
			(xy 279.507983 -264.288274) (xy 279.538007 -264.244237) (xy 279.574259 -264.205166) (xy 279.61593 -264.171935)
			(xy 279.662088 -264.145286) (xy 279.711702 -264.125814) (xy 279.763664 -264.113954) (xy 279.816814 -264.109971)
			(xy 279.869964 -264.113954) (xy 279.921926 -264.125814) (xy 279.97154 -264.145286) (xy 280.017698 -264.171935)
			(xy 280.059369 -264.205166) (xy 280.095621 -264.244237) (xy 280.125645 -264.288274) (xy 280.148771 -264.336295)
			(xy 280.164481 -264.387225) (xy 280.172424 -264.439929) (xy 280.172922 -264.466578) (xy 280.172424 -264.493227)
			(xy 294.548804 -264.493227) (xy 294.548804 -264.439929) (xy 294.556747 -264.387225) (xy 294.572457 -264.336295)
			(xy 294.595583 -264.288274) (xy 294.625607 -264.244237) (xy 294.661859 -264.205166) (xy 294.70353 -264.171935)
			(xy 294.749688 -264.145286) (xy 294.799302 -264.125814) (xy 294.851264 -264.113954) (xy 294.904414 -264.109971)
			(xy 294.957564 -264.113954) (xy 295.009526 -264.125814) (xy 295.05914 -264.145286) (xy 295.105298 -264.171935)
			(xy 295.146969 -264.205166) (xy 295.183221 -264.244237) (xy 295.213245 -264.288274) (xy 295.236371 -264.336295)
			(xy 295.252081 -264.387225) (xy 295.260024 -264.439929) (xy 295.260522 -264.466578) (xy 295.260024 -264.493227)
			(xy 295.252081 -264.545931) (xy 295.236371 -264.596861) (xy 295.213245 -264.644882) (xy 295.183221 -264.688919)
			(xy 295.146969 -264.72799) (xy 295.105298 -264.761221) (xy 295.05914 -264.78787) (xy 295.009526 -264.807342)
			(xy 294.957564 -264.819202) (xy 294.904414 -264.823186) (xy 294.851264 -264.819202) (xy 294.799302 -264.807342)
			(xy 294.749688 -264.78787) (xy 294.70353 -264.761221) (xy 294.661859 -264.72799) (xy 294.625607 -264.688919)
			(xy 294.595583 -264.644882) (xy 294.572457 -264.596861) (xy 294.556747 -264.545931) (xy 294.548804 -264.493227)
			(xy 280.172424 -264.493227) (xy 280.164481 -264.545931) (xy 280.148771 -264.596861) (xy 280.125645 -264.644882)
			(xy 280.095621 -264.688919) (xy 280.059369 -264.72799) (xy 280.017698 -264.761221) (xy 279.97154 -264.78787)
			(xy 279.921926 -264.807342) (xy 279.869964 -264.819202) (xy 279.816814 -264.823186) (xy 279.763664 -264.819202)
			(xy 279.711702 -264.807342) (xy 279.662088 -264.78787) (xy 279.61593 -264.761221) (xy 279.574259 -264.72799)
			(xy 279.538007 -264.688919) (xy 279.507983 -264.644882) (xy 279.484857 -264.596861) (xy 279.469147 -264.545931)
			(xy 279.461204 -264.493227) (xy 265.084824 -264.493227) (xy 265.076881 -264.545931) (xy 265.061171 -264.596861)
			(xy 265.038045 -264.644882) (xy 265.008021 -264.688919) (xy 264.971769 -264.72799) (xy 264.930098 -264.761221)
			(xy 264.88394 -264.78787) (xy 264.834326 -264.807342) (xy 264.782364 -264.819202) (xy 264.729214 -264.823186)
			(xy 264.676064 -264.819202) (xy 264.624102 -264.807342) (xy 264.574488 -264.78787) (xy 264.52833 -264.761221)
			(xy 264.486659 -264.72799) (xy 264.450407 -264.688919) (xy 264.420383 -264.644882) (xy 264.397257 -264.596861)
			(xy 264.381547 -264.545931) (xy 264.373604 -264.493227) (xy 254.20828 -264.493227) (xy 254.20828 -265.343365)
			(xy 268.473672 -265.343365) (xy 268.473672 -265.290067) (xy 268.481615 -265.237363) (xy 268.497325 -265.186433)
			(xy 268.520451 -265.138412) (xy 268.550475 -265.094375) (xy 268.586727 -265.055304) (xy 268.628398 -265.022073)
			(xy 268.674556 -264.995424) (xy 268.72417 -264.975952) (xy 268.776132 -264.964092) (xy 268.829282 -264.960109)
			(xy 268.882432 -264.964092) (xy 268.934394 -264.975952) (xy 268.984008 -264.995424) (xy 269.030166 -265.022073)
			(xy 269.071837 -265.055304) (xy 269.108089 -265.094375) (xy 269.138113 -265.138412) (xy 269.161239 -265.186433)
			(xy 269.176949 -265.237363) (xy 269.184892 -265.290067) (xy 269.18539 -265.316716) (xy 269.184892 -265.343365)
			(xy 283.561272 -265.343365) (xy 283.561272 -265.290067) (xy 283.569215 -265.237363) (xy 283.584925 -265.186433)
			(xy 283.608051 -265.138412) (xy 283.638075 -265.094375) (xy 283.674327 -265.055304) (xy 283.715998 -265.022073)
			(xy 283.762156 -264.995424) (xy 283.81177 -264.975952) (xy 283.863732 -264.964092) (xy 283.916882 -264.960109)
			(xy 283.970032 -264.964092) (xy 284.021994 -264.975952) (xy 284.071608 -264.995424) (xy 284.117766 -265.022073)
			(xy 284.159437 -265.055304) (xy 284.195689 -265.094375) (xy 284.225713 -265.138412) (xy 284.248839 -265.186433)
			(xy 284.264549 -265.237363) (xy 284.272492 -265.290067) (xy 284.27299 -265.316716) (xy 284.272492 -265.343365)
			(xy 298.674272 -265.343365) (xy 298.674272 -265.290067) (xy 298.682215 -265.237363) (xy 298.697925 -265.186433)
			(xy 298.721051 -265.138412) (xy 298.751075 -265.094375) (xy 298.787327 -265.055304) (xy 298.828998 -265.022073)
			(xy 298.875156 -264.995424) (xy 298.92477 -264.975952) (xy 298.976732 -264.964092) (xy 299.029882 -264.960109)
			(xy 299.083032 -264.964092) (xy 299.134994 -264.975952) (xy 299.184608 -264.995424) (xy 299.230766 -265.022073)
			(xy 299.272437 -265.055304) (xy 299.308689 -265.094375) (xy 299.338713 -265.138412) (xy 299.361839 -265.186433)
			(xy 299.377549 -265.237363) (xy 299.385492 -265.290067) (xy 299.38599 -265.316716) (xy 299.385492 -265.343365)
			(xy 299.377549 -265.396069) (xy 299.361839 -265.446999) (xy 299.338713 -265.49502) (xy 299.308689 -265.539057)
			(xy 299.272437 -265.578128) (xy 299.230766 -265.611359) (xy 299.184608 -265.638008) (xy 299.134994 -265.65748)
			(xy 299.083032 -265.66934) (xy 299.029882 -265.673324) (xy 298.976732 -265.66934) (xy 298.92477 -265.65748)
			(xy 298.875156 -265.638008) (xy 298.828998 -265.611359) (xy 298.787327 -265.578128) (xy 298.751075 -265.539057)
			(xy 298.721051 -265.49502) (xy 298.697925 -265.446999) (xy 298.682215 -265.396069) (xy 298.674272 -265.343365)
			(xy 284.272492 -265.343365) (xy 284.264549 -265.396069) (xy 284.248839 -265.446999) (xy 284.225713 -265.49502)
			(xy 284.195689 -265.539057) (xy 284.159437 -265.578128) (xy 284.117766 -265.611359) (xy 284.071608 -265.638008)
			(xy 284.021994 -265.65748) (xy 283.970032 -265.66934) (xy 283.916882 -265.673324) (xy 283.863732 -265.66934)
			(xy 283.81177 -265.65748) (xy 283.762156 -265.638008) (xy 283.715998 -265.611359) (xy 283.674327 -265.578128)
			(xy 283.638075 -265.539057) (xy 283.608051 -265.49502) (xy 283.584925 -265.446999) (xy 283.569215 -265.396069)
			(xy 283.561272 -265.343365) (xy 269.184892 -265.343365) (xy 269.176949 -265.396069) (xy 269.161239 -265.446999)
			(xy 269.138113 -265.49502) (xy 269.108089 -265.539057) (xy 269.071837 -265.578128) (xy 269.030166 -265.611359)
			(xy 268.984008 -265.638008) (xy 268.934394 -265.65748) (xy 268.882432 -265.66934) (xy 268.829282 -265.673324)
			(xy 268.776132 -265.66934) (xy 268.72417 -265.65748) (xy 268.674556 -265.638008) (xy 268.628398 -265.611359)
			(xy 268.586727 -265.578128) (xy 268.550475 -265.539057) (xy 268.520451 -265.49502) (xy 268.497325 -265.446999)
			(xy 268.481615 -265.396069) (xy 268.473672 -265.343365) (xy 254.20828 -265.343365) (xy 254.20828 -266.193249)
			(xy 264.373604 -266.193249) (xy 264.373604 -266.139951) (xy 264.381547 -266.087247) (xy 264.397257 -266.036317)
			(xy 264.420383 -265.988296) (xy 264.450407 -265.944259) (xy 264.486659 -265.905188) (xy 264.52833 -265.871957)
			(xy 264.574488 -265.845308) (xy 264.624102 -265.825836) (xy 264.676064 -265.813976) (xy 264.729214 -265.809993)
			(xy 264.782364 -265.813976) (xy 264.834326 -265.825836) (xy 264.88394 -265.845308) (xy 264.930098 -265.871957)
			(xy 264.971769 -265.905188) (xy 265.008021 -265.944259) (xy 265.038045 -265.988296) (xy 265.061171 -266.036317)
			(xy 265.076881 -266.087247) (xy 265.084824 -266.139951) (xy 265.085322 -266.1666) (xy 265.084824 -266.193249)
			(xy 279.461204 -266.193249) (xy 279.461204 -266.139951) (xy 279.469147 -266.087247) (xy 279.484857 -266.036317)
			(xy 279.507983 -265.988296) (xy 279.538007 -265.944259) (xy 279.574259 -265.905188) (xy 279.61593 -265.871957)
			(xy 279.662088 -265.845308) (xy 279.711702 -265.825836) (xy 279.763664 -265.813976) (xy 279.816814 -265.809993)
			(xy 279.869964 -265.813976) (xy 279.921926 -265.825836) (xy 279.97154 -265.845308) (xy 280.017698 -265.871957)
			(xy 280.059369 -265.905188) (xy 280.095621 -265.944259) (xy 280.125645 -265.988296) (xy 280.148771 -266.036317)
			(xy 280.164481 -266.087247) (xy 280.172424 -266.139951) (xy 280.172922 -266.1666) (xy 280.172424 -266.193249)
			(xy 294.548804 -266.193249) (xy 294.548804 -266.139951) (xy 294.556747 -266.087247) (xy 294.572457 -266.036317)
			(xy 294.595583 -265.988296) (xy 294.625607 -265.944259) (xy 294.661859 -265.905188) (xy 294.70353 -265.871957)
			(xy 294.749688 -265.845308) (xy 294.799302 -265.825836) (xy 294.851264 -265.813976) (xy 294.904414 -265.809993)
			(xy 294.957564 -265.813976) (xy 295.009526 -265.825836) (xy 295.05914 -265.845308) (xy 295.105298 -265.871957)
			(xy 295.146969 -265.905188) (xy 295.183221 -265.944259) (xy 295.213245 -265.988296) (xy 295.236371 -266.036317)
			(xy 295.252081 -266.087247) (xy 295.260024 -266.139951) (xy 295.260522 -266.1666) (xy 295.260024 -266.193249)
			(xy 295.252081 -266.245953) (xy 295.236371 -266.296883) (xy 295.213245 -266.344904) (xy 295.183221 -266.388941)
			(xy 295.146969 -266.428012) (xy 295.105298 -266.461243) (xy 295.05914 -266.487892) (xy 295.009526 -266.507364)
			(xy 294.957564 -266.519224) (xy 294.904414 -266.523208) (xy 294.851264 -266.519224) (xy 294.799302 -266.507364)
			(xy 294.749688 -266.487892) (xy 294.70353 -266.461243) (xy 294.661859 -266.428012) (xy 294.625607 -266.388941)
			(xy 294.595583 -266.344904) (xy 294.572457 -266.296883) (xy 294.556747 -266.245953) (xy 294.548804 -266.193249)
			(xy 280.172424 -266.193249) (xy 280.164481 -266.245953) (xy 280.148771 -266.296883) (xy 280.125645 -266.344904)
			(xy 280.095621 -266.388941) (xy 280.059369 -266.428012) (xy 280.017698 -266.461243) (xy 279.97154 -266.487892)
			(xy 279.921926 -266.507364) (xy 279.869964 -266.519224) (xy 279.816814 -266.523208) (xy 279.763664 -266.519224)
			(xy 279.711702 -266.507364) (xy 279.662088 -266.487892) (xy 279.61593 -266.461243) (xy 279.574259 -266.428012)
			(xy 279.538007 -266.388941) (xy 279.507983 -266.344904) (xy 279.484857 -266.296883) (xy 279.469147 -266.245953)
			(xy 279.461204 -266.193249) (xy 265.084824 -266.193249) (xy 265.076881 -266.245953) (xy 265.061171 -266.296883)
			(xy 265.038045 -266.344904) (xy 265.008021 -266.388941) (xy 264.971769 -266.428012) (xy 264.930098 -266.461243)
			(xy 264.88394 -266.487892) (xy 264.834326 -266.507364) (xy 264.782364 -266.519224) (xy 264.729214 -266.523208)
			(xy 264.676064 -266.519224) (xy 264.624102 -266.507364) (xy 264.574488 -266.487892) (xy 264.52833 -266.461243)
			(xy 264.486659 -266.428012) (xy 264.450407 -266.388941) (xy 264.420383 -266.344904) (xy 264.397257 -266.296883)
			(xy 264.381547 -266.245953) (xy 264.373604 -266.193249) (xy 254.20828 -266.193249) (xy 254.20828 -267.043387)
			(xy 260.929872 -267.043387) (xy 260.929872 -266.990089) (xy 260.937815 -266.937385) (xy 260.953525 -266.886455)
			(xy 260.976651 -266.838434) (xy 261.006675 -266.794397) (xy 261.042927 -266.755326) (xy 261.084598 -266.722095)
			(xy 261.130756 -266.695446) (xy 261.18037 -266.675974) (xy 261.232332 -266.664114) (xy 261.285482 -266.660131)
			(xy 261.338632 -266.664114) (xy 261.390594 -266.675974) (xy 261.440208 -266.695446) (xy 261.486366 -266.722095)
			(xy 261.528037 -266.755326) (xy 261.564289 -266.794397) (xy 261.594313 -266.838434) (xy 261.617439 -266.886455)
			(xy 261.633149 -266.937385) (xy 261.641092 -266.990089) (xy 261.64159 -267.016738) (xy 261.641092 -267.043387)
			(xy 268.473672 -267.043387) (xy 268.473672 -266.990089) (xy 268.481615 -266.937385) (xy 268.497325 -266.886455)
			(xy 268.520451 -266.838434) (xy 268.550475 -266.794397) (xy 268.586727 -266.755326) (xy 268.628398 -266.722095)
			(xy 268.674556 -266.695446) (xy 268.72417 -266.675974) (xy 268.776132 -266.664114) (xy 268.829282 -266.660131)
			(xy 268.882432 -266.664114) (xy 268.934394 -266.675974) (xy 268.984008 -266.695446) (xy 269.030166 -266.722095)
			(xy 269.071837 -266.755326) (xy 269.108089 -266.794397) (xy 269.138113 -266.838434) (xy 269.161239 -266.886455)
			(xy 269.176949 -266.937385) (xy 269.184892 -266.990089) (xy 269.18539 -267.016738) (xy 269.184892 -267.043387)
			(xy 276.017472 -267.043387) (xy 276.017472 -266.990089) (xy 276.025415 -266.937385) (xy 276.041125 -266.886455)
			(xy 276.064251 -266.838434) (xy 276.094275 -266.794397) (xy 276.130527 -266.755326) (xy 276.172198 -266.722095)
			(xy 276.218356 -266.695446) (xy 276.26797 -266.675974) (xy 276.319932 -266.664114) (xy 276.373082 -266.660131)
			(xy 276.426232 -266.664114) (xy 276.478194 -266.675974) (xy 276.527808 -266.695446) (xy 276.573966 -266.722095)
			(xy 276.615637 -266.755326) (xy 276.651889 -266.794397) (xy 276.681913 -266.838434) (xy 276.705039 -266.886455)
			(xy 276.720749 -266.937385) (xy 276.728692 -266.990089) (xy 276.72919 -267.016738) (xy 276.728692 -267.043387)
			(xy 283.561272 -267.043387) (xy 283.561272 -266.990089) (xy 283.569215 -266.937385) (xy 283.584925 -266.886455)
			(xy 283.608051 -266.838434) (xy 283.638075 -266.794397) (xy 283.674327 -266.755326) (xy 283.715998 -266.722095)
			(xy 283.762156 -266.695446) (xy 283.81177 -266.675974) (xy 283.863732 -266.664114) (xy 283.916882 -266.660131)
			(xy 283.970032 -266.664114) (xy 284.021994 -266.675974) (xy 284.071608 -266.695446) (xy 284.117766 -266.722095)
			(xy 284.159437 -266.755326) (xy 284.195689 -266.794397) (xy 284.225713 -266.838434) (xy 284.248839 -266.886455)
			(xy 284.264549 -266.937385) (xy 284.272492 -266.990089) (xy 284.27299 -267.016738) (xy 284.272492 -267.043387)
			(xy 291.105072 -267.043387) (xy 291.105072 -266.990089) (xy 291.113015 -266.937385) (xy 291.128725 -266.886455)
			(xy 291.151851 -266.838434) (xy 291.181875 -266.794397) (xy 291.218127 -266.755326) (xy 291.259798 -266.722095)
			(xy 291.305956 -266.695446) (xy 291.35557 -266.675974) (xy 291.407532 -266.664114) (xy 291.460682 -266.660131)
			(xy 291.513832 -266.664114) (xy 291.565794 -266.675974) (xy 291.615408 -266.695446) (xy 291.661566 -266.722095)
			(xy 291.703237 -266.755326) (xy 291.739489 -266.794397) (xy 291.769513 -266.838434) (xy 291.792639 -266.886455)
			(xy 291.808349 -266.937385) (xy 291.816292 -266.990089) (xy 291.81679 -267.016738) (xy 291.816292 -267.043387)
			(xy 298.674272 -267.043387) (xy 298.674272 -266.990089) (xy 298.682215 -266.937385) (xy 298.697925 -266.886455)
			(xy 298.721051 -266.838434) (xy 298.751075 -266.794397) (xy 298.787327 -266.755326) (xy 298.828998 -266.722095)
			(xy 298.875156 -266.695446) (xy 298.92477 -266.675974) (xy 298.976732 -266.664114) (xy 299.029882 -266.660131)
			(xy 299.083032 -266.664114) (xy 299.134994 -266.675974) (xy 299.184608 -266.695446) (xy 299.230766 -266.722095)
			(xy 299.272437 -266.755326) (xy 299.308689 -266.794397) (xy 299.338713 -266.838434) (xy 299.361839 -266.886455)
			(xy 299.377549 -266.937385) (xy 299.385492 -266.990089) (xy 299.38599 -267.016738) (xy 299.385492 -267.043387)
			(xy 299.377549 -267.096091) (xy 299.361839 -267.147021) (xy 299.338713 -267.195042) (xy 299.308689 -267.239079)
			(xy 299.272437 -267.27815) (xy 299.230766 -267.311381) (xy 299.184608 -267.33803) (xy 299.134994 -267.357502)
			(xy 299.083032 -267.369362) (xy 299.029882 -267.373346) (xy 298.976732 -267.369362) (xy 298.92477 -267.357502)
			(xy 298.875156 -267.33803) (xy 298.828998 -267.311381) (xy 298.787327 -267.27815) (xy 298.751075 -267.239079)
			(xy 298.721051 -267.195042) (xy 298.697925 -267.147021) (xy 298.682215 -267.096091) (xy 298.674272 -267.043387)
			(xy 291.816292 -267.043387) (xy 291.808349 -267.096091) (xy 291.792639 -267.147021) (xy 291.769513 -267.195042)
			(xy 291.739489 -267.239079) (xy 291.703237 -267.27815) (xy 291.661566 -267.311381) (xy 291.615408 -267.33803)
			(xy 291.565794 -267.357502) (xy 291.513832 -267.369362) (xy 291.460682 -267.373346) (xy 291.407532 -267.369362)
			(xy 291.35557 -267.357502) (xy 291.305956 -267.33803) (xy 291.259798 -267.311381) (xy 291.218127 -267.27815)
			(xy 291.181875 -267.239079) (xy 291.151851 -267.195042) (xy 291.128725 -267.147021) (xy 291.113015 -267.096091)
			(xy 291.105072 -267.043387) (xy 284.272492 -267.043387) (xy 284.264549 -267.096091) (xy 284.248839 -267.147021)
			(xy 284.225713 -267.195042) (xy 284.195689 -267.239079) (xy 284.159437 -267.27815) (xy 284.117766 -267.311381)
			(xy 284.071608 -267.33803) (xy 284.021994 -267.357502) (xy 283.970032 -267.369362) (xy 283.916882 -267.373346)
			(xy 283.863732 -267.369362) (xy 283.81177 -267.357502) (xy 283.762156 -267.33803) (xy 283.715998 -267.311381)
			(xy 283.674327 -267.27815) (xy 283.638075 -267.239079) (xy 283.608051 -267.195042) (xy 283.584925 -267.147021)
			(xy 283.569215 -267.096091) (xy 283.561272 -267.043387) (xy 276.728692 -267.043387) (xy 276.720749 -267.096091)
			(xy 276.705039 -267.147021) (xy 276.681913 -267.195042) (xy 276.651889 -267.239079) (xy 276.615637 -267.27815)
			(xy 276.573966 -267.311381) (xy 276.527808 -267.33803) (xy 276.478194 -267.357502) (xy 276.426232 -267.369362)
			(xy 276.373082 -267.373346) (xy 276.319932 -267.369362) (xy 276.26797 -267.357502) (xy 276.218356 -267.33803)
			(xy 276.172198 -267.311381) (xy 276.130527 -267.27815) (xy 276.094275 -267.239079) (xy 276.064251 -267.195042)
			(xy 276.041125 -267.147021) (xy 276.025415 -267.096091) (xy 276.017472 -267.043387) (xy 269.184892 -267.043387)
			(xy 269.176949 -267.096091) (xy 269.161239 -267.147021) (xy 269.138113 -267.195042) (xy 269.108089 -267.239079)
			(xy 269.071837 -267.27815) (xy 269.030166 -267.311381) (xy 268.984008 -267.33803) (xy 268.934394 -267.357502)
			(xy 268.882432 -267.369362) (xy 268.829282 -267.373346) (xy 268.776132 -267.369362) (xy 268.72417 -267.357502)
			(xy 268.674556 -267.33803) (xy 268.628398 -267.311381) (xy 268.586727 -267.27815) (xy 268.550475 -267.239079)
			(xy 268.520451 -267.195042) (xy 268.497325 -267.147021) (xy 268.481615 -267.096091) (xy 268.473672 -267.043387)
			(xy 261.641092 -267.043387) (xy 261.633149 -267.096091) (xy 261.617439 -267.147021) (xy 261.594313 -267.195042)
			(xy 261.564289 -267.239079) (xy 261.528037 -267.27815) (xy 261.486366 -267.311381) (xy 261.440208 -267.33803)
			(xy 261.390594 -267.357502) (xy 261.338632 -267.369362) (xy 261.285482 -267.373346) (xy 261.232332 -267.369362)
			(xy 261.18037 -267.357502) (xy 261.130756 -267.33803) (xy 261.084598 -267.311381) (xy 261.042927 -267.27815)
			(xy 261.006675 -267.239079) (xy 260.976651 -267.195042) (xy 260.953525 -267.147021) (xy 260.937815 -267.096091)
			(xy 260.929872 -267.043387) (xy 254.20828 -267.043387) (xy 254.20828 -267.893271) (xy 256.829804 -267.893271)
			(xy 256.829804 -267.839973) (xy 256.837747 -267.787269) (xy 256.853457 -267.736339) (xy 256.876583 -267.688318)
			(xy 256.906607 -267.644281) (xy 256.942859 -267.60521) (xy 256.98453 -267.571979) (xy 257.030688 -267.54533)
			(xy 257.080302 -267.525858) (xy 257.132264 -267.513998) (xy 257.185414 -267.510015) (xy 257.238564 -267.513998)
			(xy 257.290526 -267.525858) (xy 257.34014 -267.54533) (xy 257.386298 -267.571979) (xy 257.427969 -267.60521)
			(xy 257.464221 -267.644281) (xy 257.494245 -267.688318) (xy 257.517371 -267.736339) (xy 257.533081 -267.787269)
			(xy 257.541024 -267.839973) (xy 257.541522 -267.866622) (xy 257.541024 -267.893271) (xy 264.373604 -267.893271)
			(xy 264.373604 -267.839973) (xy 264.381547 -267.787269) (xy 264.397257 -267.736339) (xy 264.420383 -267.688318)
			(xy 264.450407 -267.644281) (xy 264.486659 -267.60521) (xy 264.52833 -267.571979) (xy 264.574488 -267.54533)
			(xy 264.624102 -267.525858) (xy 264.676064 -267.513998) (xy 264.729214 -267.510015) (xy 264.782364 -267.513998)
			(xy 264.834326 -267.525858) (xy 264.88394 -267.54533) (xy 264.930098 -267.571979) (xy 264.971769 -267.60521)
			(xy 265.008021 -267.644281) (xy 265.038045 -267.688318) (xy 265.061171 -267.736339) (xy 265.076881 -267.787269)
			(xy 265.084824 -267.839973) (xy 265.085322 -267.866622) (xy 265.084824 -267.893271) (xy 271.917404 -267.893271)
			(xy 271.917404 -267.839973) (xy 271.925347 -267.787269) (xy 271.941057 -267.736339) (xy 271.964183 -267.688318)
			(xy 271.994207 -267.644281) (xy 272.030459 -267.60521) (xy 272.07213 -267.571979) (xy 272.118288 -267.54533)
			(xy 272.167902 -267.525858) (xy 272.219864 -267.513998) (xy 272.273014 -267.510015) (xy 272.326164 -267.513998)
			(xy 272.378126 -267.525858) (xy 272.42774 -267.54533) (xy 272.473898 -267.571979) (xy 272.515569 -267.60521)
			(xy 272.551821 -267.644281) (xy 272.581845 -267.688318) (xy 272.604971 -267.736339) (xy 272.620681 -267.787269)
			(xy 272.628624 -267.839973) (xy 272.629122 -267.866622) (xy 272.628624 -267.893271) (xy 279.461204 -267.893271)
			(xy 279.461204 -267.839973) (xy 279.469147 -267.787269) (xy 279.484857 -267.736339) (xy 279.507983 -267.688318)
			(xy 279.538007 -267.644281) (xy 279.574259 -267.60521) (xy 279.61593 -267.571979) (xy 279.662088 -267.54533)
			(xy 279.711702 -267.525858) (xy 279.763664 -267.513998) (xy 279.816814 -267.510015) (xy 279.869964 -267.513998)
			(xy 279.921926 -267.525858) (xy 279.97154 -267.54533) (xy 280.017698 -267.571979) (xy 280.059369 -267.60521)
			(xy 280.095621 -267.644281) (xy 280.125645 -267.688318) (xy 280.148771 -267.736339) (xy 280.164481 -267.787269)
			(xy 280.172424 -267.839973) (xy 280.172922 -267.866622) (xy 280.172424 -267.893271) (xy 287.005004 -267.893271)
			(xy 287.005004 -267.839973) (xy 287.012947 -267.787269) (xy 287.028657 -267.736339) (xy 287.051783 -267.688318)
			(xy 287.081807 -267.644281) (xy 287.118059 -267.60521) (xy 287.15973 -267.571979) (xy 287.205888 -267.54533)
			(xy 287.255502 -267.525858) (xy 287.307464 -267.513998) (xy 287.360614 -267.510015) (xy 287.413764 -267.513998)
			(xy 287.465726 -267.525858) (xy 287.51534 -267.54533) (xy 287.561498 -267.571979) (xy 287.603169 -267.60521)
			(xy 287.639421 -267.644281) (xy 287.669445 -267.688318) (xy 287.692571 -267.736339) (xy 287.708281 -267.787269)
			(xy 287.716224 -267.839973) (xy 287.716722 -267.866622) (xy 287.716224 -267.893271) (xy 294.548804 -267.893271)
			(xy 294.548804 -267.839973) (xy 294.556747 -267.787269) (xy 294.572457 -267.736339) (xy 294.595583 -267.688318)
			(xy 294.625607 -267.644281) (xy 294.661859 -267.60521) (xy 294.70353 -267.571979) (xy 294.749688 -267.54533)
			(xy 294.799302 -267.525858) (xy 294.851264 -267.513998) (xy 294.904414 -267.510015) (xy 294.957564 -267.513998)
			(xy 295.009526 -267.525858) (xy 295.05914 -267.54533) (xy 295.105298 -267.571979) (xy 295.146969 -267.60521)
			(xy 295.183221 -267.644281) (xy 295.213245 -267.688318) (xy 295.236371 -267.736339) (xy 295.252081 -267.787269)
			(xy 295.260024 -267.839973) (xy 295.260522 -267.866622) (xy 295.260024 -267.893271) (xy 295.252081 -267.945975)
			(xy 295.236371 -267.996905) (xy 295.213245 -268.044926) (xy 295.183221 -268.088963) (xy 295.146969 -268.128034)
			(xy 295.105298 -268.161265) (xy 295.05914 -268.187914) (xy 295.009526 -268.207386) (xy 294.957564 -268.219246)
			(xy 294.904414 -268.22323) (xy 294.851264 -268.219246) (xy 294.799302 -268.207386) (xy 294.749688 -268.187914)
			(xy 294.70353 -268.161265) (xy 294.661859 -268.128034) (xy 294.625607 -268.088963) (xy 294.595583 -268.044926)
			(xy 294.572457 -267.996905) (xy 294.556747 -267.945975) (xy 294.548804 -267.893271) (xy 287.716224 -267.893271)
			(xy 287.708281 -267.945975) (xy 287.692571 -267.996905) (xy 287.669445 -268.044926) (xy 287.639421 -268.088963)
			(xy 287.603169 -268.128034) (xy 287.561498 -268.161265) (xy 287.51534 -268.187914) (xy 287.465726 -268.207386)
			(xy 287.413764 -268.219246) (xy 287.360614 -268.22323) (xy 287.307464 -268.219246) (xy 287.255502 -268.207386)
			(xy 287.205888 -268.187914) (xy 287.15973 -268.161265) (xy 287.118059 -268.128034) (xy 287.081807 -268.088963)
			(xy 287.051783 -268.044926) (xy 287.028657 -267.996905) (xy 287.012947 -267.945975) (xy 287.005004 -267.893271)
			(xy 280.172424 -267.893271) (xy 280.164481 -267.945975) (xy 280.148771 -267.996905) (xy 280.125645 -268.044926)
			(xy 280.095621 -268.088963) (xy 280.059369 -268.128034) (xy 280.017698 -268.161265) (xy 279.97154 -268.187914)
			(xy 279.921926 -268.207386) (xy 279.869964 -268.219246) (xy 279.816814 -268.22323) (xy 279.763664 -268.219246)
			(xy 279.711702 -268.207386) (xy 279.662088 -268.187914) (xy 279.61593 -268.161265) (xy 279.574259 -268.128034)
			(xy 279.538007 -268.088963) (xy 279.507983 -268.044926) (xy 279.484857 -267.996905) (xy 279.469147 -267.945975)
			(xy 279.461204 -267.893271) (xy 272.628624 -267.893271) (xy 272.620681 -267.945975) (xy 272.604971 -267.996905)
			(xy 272.581845 -268.044926) (xy 272.551821 -268.088963) (xy 272.515569 -268.128034) (xy 272.473898 -268.161265)
			(xy 272.42774 -268.187914) (xy 272.378126 -268.207386) (xy 272.326164 -268.219246) (xy 272.273014 -268.22323)
			(xy 272.219864 -268.219246) (xy 272.167902 -268.207386) (xy 272.118288 -268.187914) (xy 272.07213 -268.161265)
			(xy 272.030459 -268.128034) (xy 271.994207 -268.088963) (xy 271.964183 -268.044926) (xy 271.941057 -267.996905)
			(xy 271.925347 -267.945975) (xy 271.917404 -267.893271) (xy 265.084824 -267.893271) (xy 265.076881 -267.945975)
			(xy 265.061171 -267.996905) (xy 265.038045 -268.044926) (xy 265.008021 -268.088963) (xy 264.971769 -268.128034)
			(xy 264.930098 -268.161265) (xy 264.88394 -268.187914) (xy 264.834326 -268.207386) (xy 264.782364 -268.219246)
			(xy 264.729214 -268.22323) (xy 264.676064 -268.219246) (xy 264.624102 -268.207386) (xy 264.574488 -268.187914)
			(xy 264.52833 -268.161265) (xy 264.486659 -268.128034) (xy 264.450407 -268.088963) (xy 264.420383 -268.044926)
			(xy 264.397257 -267.996905) (xy 264.381547 -267.945975) (xy 264.373604 -267.893271) (xy 257.541024 -267.893271)
			(xy 257.533081 -267.945975) (xy 257.517371 -267.996905) (xy 257.494245 -268.044926) (xy 257.464221 -268.088963)
			(xy 257.427969 -268.128034) (xy 257.386298 -268.161265) (xy 257.34014 -268.187914) (xy 257.290526 -268.207386)
			(xy 257.238564 -268.219246) (xy 257.185414 -268.22323) (xy 257.132264 -268.219246) (xy 257.080302 -268.207386)
			(xy 257.030688 -268.187914) (xy 256.98453 -268.161265) (xy 256.942859 -268.128034) (xy 256.906607 -268.088963)
			(xy 256.876583 -268.044926) (xy 256.853457 -267.996905) (xy 256.837747 -267.945975) (xy 256.829804 -267.893271)
			(xy 254.20828 -267.893271) (xy 254.20828 -268.743409) (xy 283.561272 -268.743409) (xy 283.561272 -268.690111)
			(xy 283.569215 -268.637407) (xy 283.584925 -268.586477) (xy 283.608051 -268.538456) (xy 283.638075 -268.494419)
			(xy 283.674327 -268.455348) (xy 283.715998 -268.422117) (xy 283.762156 -268.395468) (xy 283.81177 -268.375996)
			(xy 283.863732 -268.364136) (xy 283.916882 -268.360153) (xy 283.970032 -268.364136) (xy 284.021994 -268.375996)
			(xy 284.071608 -268.395468) (xy 284.117766 -268.422117) (xy 284.159437 -268.455348) (xy 284.195689 -268.494419)
			(xy 284.225713 -268.538456) (xy 284.248839 -268.586477) (xy 284.264549 -268.637407) (xy 284.272492 -268.690111)
			(xy 284.27299 -268.71676) (xy 284.272492 -268.743409) (xy 284.264549 -268.796113) (xy 284.248839 -268.847043)
			(xy 284.225713 -268.895064) (xy 284.195689 -268.939101) (xy 284.159437 -268.978172) (xy 284.117766 -269.011403)
			(xy 284.071608 -269.038052) (xy 284.021994 -269.057524) (xy 283.970032 -269.069384) (xy 283.916882 -269.073368)
			(xy 283.863732 -269.069384) (xy 283.81177 -269.057524) (xy 283.762156 -269.038052) (xy 283.715998 -269.011403)
			(xy 283.674327 -268.978172) (xy 283.638075 -268.939101) (xy 283.608051 -268.895064) (xy 283.584925 -268.847043)
			(xy 283.569215 -268.796113) (xy 283.561272 -268.743409) (xy 254.20828 -268.743409) (xy 254.20828 -269.593293)
			(xy 264.373604 -269.593293) (xy 264.373604 -269.539995) (xy 264.381547 -269.487291) (xy 264.397257 -269.436361)
			(xy 264.420383 -269.38834) (xy 264.450407 -269.344303) (xy 264.486659 -269.305232) (xy 264.52833 -269.272001)
			(xy 264.574488 -269.245352) (xy 264.624102 -269.22588) (xy 264.676064 -269.21402) (xy 264.729214 -269.210037)
			(xy 264.782364 -269.21402) (xy 264.834326 -269.22588) (xy 264.88394 -269.245352) (xy 264.930098 -269.272001)
			(xy 264.971769 -269.305232) (xy 265.008021 -269.344303) (xy 265.038045 -269.38834) (xy 265.061171 -269.436361)
			(xy 265.076881 -269.487291) (xy 265.084824 -269.539995) (xy 265.085322 -269.566644) (xy 265.084824 -269.593293)
			(xy 279.461204 -269.593293) (xy 279.461204 -269.539995) (xy 279.469147 -269.487291) (xy 279.484857 -269.436361)
			(xy 279.507983 -269.38834) (xy 279.538007 -269.344303) (xy 279.574259 -269.305232) (xy 279.61593 -269.272001)
			(xy 279.662088 -269.245352) (xy 279.711702 -269.22588) (xy 279.763664 -269.21402) (xy 279.816814 -269.210037)
			(xy 279.869964 -269.21402) (xy 279.921926 -269.22588) (xy 279.97154 -269.245352) (xy 280.017698 -269.272001)
			(xy 280.059369 -269.305232) (xy 280.095621 -269.344303) (xy 280.125645 -269.38834) (xy 280.148771 -269.436361)
			(xy 280.164481 -269.487291) (xy 280.172424 -269.539995) (xy 280.172922 -269.566644) (xy 280.172424 -269.593293)
			(xy 294.548804 -269.593293) (xy 294.548804 -269.539995) (xy 294.556747 -269.487291) (xy 294.572457 -269.436361)
			(xy 294.595583 -269.38834) (xy 294.625607 -269.344303) (xy 294.661859 -269.305232) (xy 294.70353 -269.272001)
			(xy 294.749688 -269.245352) (xy 294.799302 -269.22588) (xy 294.851264 -269.21402) (xy 294.904414 -269.210037)
			(xy 294.957564 -269.21402) (xy 295.009526 -269.22588) (xy 295.05914 -269.245352) (xy 295.105298 -269.272001)
			(xy 295.146969 -269.305232) (xy 295.183221 -269.344303) (xy 295.213245 -269.38834) (xy 295.236371 -269.436361)
			(xy 295.252081 -269.487291) (xy 295.260024 -269.539995) (xy 295.260522 -269.566644) (xy 295.260024 -269.593293)
			(xy 309.636404 -269.593293) (xy 309.636404 -269.539995) (xy 309.644347 -269.487291) (xy 309.660057 -269.436361)
			(xy 309.683183 -269.38834) (xy 309.713207 -269.344303) (xy 309.749459 -269.305232) (xy 309.79113 -269.272001)
			(xy 309.837288 -269.245352) (xy 309.886902 -269.22588) (xy 309.938864 -269.21402) (xy 309.992014 -269.210037)
			(xy 310.045164 -269.21402) (xy 310.097126 -269.22588) (xy 310.14674 -269.245352) (xy 310.192898 -269.272001)
			(xy 310.234569 -269.305232) (xy 310.270821 -269.344303) (xy 310.300845 -269.38834) (xy 310.323971 -269.436361)
			(xy 310.339681 -269.487291) (xy 310.347624 -269.539995) (xy 310.348122 -269.566644) (xy 310.347624 -269.593293)
			(xy 310.339681 -269.645997) (xy 310.323971 -269.696927) (xy 310.300845 -269.744948) (xy 310.270821 -269.788985)
			(xy 310.234569 -269.828056) (xy 310.192898 -269.861287) (xy 310.14674 -269.887936) (xy 310.097126 -269.907408)
			(xy 310.045164 -269.919268) (xy 309.992014 -269.923252) (xy 309.938864 -269.919268) (xy 309.886902 -269.907408)
			(xy 309.837288 -269.887936) (xy 309.79113 -269.861287) (xy 309.749459 -269.828056) (xy 309.713207 -269.788985)
			(xy 309.683183 -269.744948) (xy 309.660057 -269.696927) (xy 309.644347 -269.645997) (xy 309.636404 -269.593293)
			(xy 295.260024 -269.593293) (xy 295.252081 -269.645997) (xy 295.236371 -269.696927) (xy 295.213245 -269.744948)
			(xy 295.183221 -269.788985) (xy 295.146969 -269.828056) (xy 295.105298 -269.861287) (xy 295.05914 -269.887936)
			(xy 295.009526 -269.907408) (xy 294.957564 -269.919268) (xy 294.904414 -269.923252) (xy 294.851264 -269.919268)
			(xy 294.799302 -269.907408) (xy 294.749688 -269.887936) (xy 294.70353 -269.861287) (xy 294.661859 -269.828056)
			(xy 294.625607 -269.788985) (xy 294.595583 -269.744948) (xy 294.572457 -269.696927) (xy 294.556747 -269.645997)
			(xy 294.548804 -269.593293) (xy 280.172424 -269.593293) (xy 280.164481 -269.645997) (xy 280.148771 -269.696927)
			(xy 280.125645 -269.744948) (xy 280.095621 -269.788985) (xy 280.059369 -269.828056) (xy 280.017698 -269.861287)
			(xy 279.97154 -269.887936) (xy 279.921926 -269.907408) (xy 279.869964 -269.919268) (xy 279.816814 -269.923252)
			(xy 279.763664 -269.919268) (xy 279.711702 -269.907408) (xy 279.662088 -269.887936) (xy 279.61593 -269.861287)
			(xy 279.574259 -269.828056) (xy 279.538007 -269.788985) (xy 279.507983 -269.744948) (xy 279.484857 -269.696927)
			(xy 279.469147 -269.645997) (xy 279.461204 -269.593293) (xy 265.084824 -269.593293) (xy 265.076881 -269.645997)
			(xy 265.061171 -269.696927) (xy 265.038045 -269.744948) (xy 265.008021 -269.788985) (xy 264.971769 -269.828056)
			(xy 264.930098 -269.861287) (xy 264.88394 -269.887936) (xy 264.834326 -269.907408) (xy 264.782364 -269.919268)
			(xy 264.729214 -269.923252) (xy 264.676064 -269.919268) (xy 264.624102 -269.907408) (xy 264.574488 -269.887936)
			(xy 264.52833 -269.861287) (xy 264.486659 -269.828056) (xy 264.450407 -269.788985) (xy 264.420383 -269.744948)
			(xy 264.397257 -269.696927) (xy 264.381547 -269.645997) (xy 264.373604 -269.593293) (xy 254.20828 -269.593293)
			(xy 254.20828 -270.443431) (xy 268.473672 -270.443431) (xy 268.473672 -270.390133) (xy 268.481615 -270.337429)
			(xy 268.497325 -270.286499) (xy 268.520451 -270.238478) (xy 268.550475 -270.194441) (xy 268.586727 -270.15537)
			(xy 268.628398 -270.122139) (xy 268.674556 -270.09549) (xy 268.72417 -270.076018) (xy 268.776132 -270.064158)
			(xy 268.829282 -270.060175) (xy 268.882432 -270.064158) (xy 268.934394 -270.076018) (xy 268.984008 -270.09549)
			(xy 269.030166 -270.122139) (xy 269.071837 -270.15537) (xy 269.108089 -270.194441) (xy 269.138113 -270.238478)
			(xy 269.161239 -270.286499) (xy 269.176949 -270.337429) (xy 269.184892 -270.390133) (xy 269.18539 -270.416782)
			(xy 269.184892 -270.443431) (xy 283.561272 -270.443431) (xy 283.561272 -270.390133) (xy 283.569215 -270.337429)
			(xy 283.584925 -270.286499) (xy 283.608051 -270.238478) (xy 283.638075 -270.194441) (xy 283.674327 -270.15537)
			(xy 283.715998 -270.122139) (xy 283.762156 -270.09549) (xy 283.81177 -270.076018) (xy 283.863732 -270.064158)
			(xy 283.916882 -270.060175) (xy 283.970032 -270.064158) (xy 284.021994 -270.076018) (xy 284.071608 -270.09549)
			(xy 284.117766 -270.122139) (xy 284.159437 -270.15537) (xy 284.195689 -270.194441) (xy 284.225713 -270.238478)
			(xy 284.248839 -270.286499) (xy 284.264549 -270.337429) (xy 284.272492 -270.390133) (xy 284.27299 -270.416782)
			(xy 284.272492 -270.443431) (xy 298.674272 -270.443431) (xy 298.674272 -270.390133) (xy 298.682215 -270.337429)
			(xy 298.697925 -270.286499) (xy 298.721051 -270.238478) (xy 298.751075 -270.194441) (xy 298.787327 -270.15537)
			(xy 298.828998 -270.122139) (xy 298.875156 -270.09549) (xy 298.92477 -270.076018) (xy 298.976732 -270.064158)
			(xy 299.029882 -270.060175) (xy 299.083032 -270.064158) (xy 299.134994 -270.076018) (xy 299.184608 -270.09549)
			(xy 299.230766 -270.122139) (xy 299.272437 -270.15537) (xy 299.308689 -270.194441) (xy 299.338713 -270.238478)
			(xy 299.361839 -270.286499) (xy 299.377549 -270.337429) (xy 299.385492 -270.390133) (xy 299.38599 -270.416782)
			(xy 299.385492 -270.443431) (xy 299.377549 -270.496135) (xy 299.361839 -270.547065) (xy 299.338713 -270.595086)
			(xy 299.308689 -270.639123) (xy 299.272437 -270.678194) (xy 299.230766 -270.711425) (xy 299.184608 -270.738074)
			(xy 299.134994 -270.757546) (xy 299.083032 -270.769406) (xy 299.029882 -270.77339) (xy 298.976732 -270.769406)
			(xy 298.92477 -270.757546) (xy 298.875156 -270.738074) (xy 298.828998 -270.711425) (xy 298.787327 -270.678194)
			(xy 298.751075 -270.639123) (xy 298.721051 -270.595086) (xy 298.697925 -270.547065) (xy 298.682215 -270.496135)
			(xy 298.674272 -270.443431) (xy 284.272492 -270.443431) (xy 284.264549 -270.496135) (xy 284.248839 -270.547065)
			(xy 284.225713 -270.595086) (xy 284.195689 -270.639123) (xy 284.159437 -270.678194) (xy 284.117766 -270.711425)
			(xy 284.071608 -270.738074) (xy 284.021994 -270.757546) (xy 283.970032 -270.769406) (xy 283.916882 -270.77339)
			(xy 283.863732 -270.769406) (xy 283.81177 -270.757546) (xy 283.762156 -270.738074) (xy 283.715998 -270.711425)
			(xy 283.674327 -270.678194) (xy 283.638075 -270.639123) (xy 283.608051 -270.595086) (xy 283.584925 -270.547065)
			(xy 283.569215 -270.496135) (xy 283.561272 -270.443431) (xy 269.184892 -270.443431) (xy 269.176949 -270.496135)
			(xy 269.161239 -270.547065) (xy 269.138113 -270.595086) (xy 269.108089 -270.639123) (xy 269.071837 -270.678194)
			(xy 269.030166 -270.711425) (xy 268.984008 -270.738074) (xy 268.934394 -270.757546) (xy 268.882432 -270.769406)
			(xy 268.829282 -270.77339) (xy 268.776132 -270.769406) (xy 268.72417 -270.757546) (xy 268.674556 -270.738074)
			(xy 268.628398 -270.711425) (xy 268.586727 -270.678194) (xy 268.550475 -270.639123) (xy 268.520451 -270.595086)
			(xy 268.497325 -270.547065) (xy 268.481615 -270.496135) (xy 268.473672 -270.443431) (xy 254.20828 -270.443431)
			(xy 254.20828 -271.293315) (xy 264.373604 -271.293315) (xy 264.373604 -271.240017) (xy 264.381547 -271.187313)
			(xy 264.397257 -271.136383) (xy 264.420383 -271.088362) (xy 264.450407 -271.044325) (xy 264.486659 -271.005254)
			(xy 264.52833 -270.972023) (xy 264.574488 -270.945374) (xy 264.624102 -270.925902) (xy 264.676064 -270.914042)
			(xy 264.729214 -270.910059) (xy 264.782364 -270.914042) (xy 264.834326 -270.925902) (xy 264.88394 -270.945374)
			(xy 264.930098 -270.972023) (xy 264.971769 -271.005254) (xy 265.008021 -271.044325) (xy 265.038045 -271.088362)
			(xy 265.061171 -271.136383) (xy 265.076881 -271.187313) (xy 265.084824 -271.240017) (xy 265.085322 -271.266666)
			(xy 265.084824 -271.293315) (xy 279.461204 -271.293315) (xy 279.461204 -271.240017) (xy 279.469147 -271.187313)
			(xy 279.484857 -271.136383) (xy 279.507983 -271.088362) (xy 279.538007 -271.044325) (xy 279.574259 -271.005254)
			(xy 279.61593 -270.972023) (xy 279.662088 -270.945374) (xy 279.711702 -270.925902) (xy 279.763664 -270.914042)
			(xy 279.816814 -270.910059) (xy 279.869964 -270.914042) (xy 279.921926 -270.925902) (xy 279.97154 -270.945374)
			(xy 280.017698 -270.972023) (xy 280.059369 -271.005254) (xy 280.095621 -271.044325) (xy 280.125645 -271.088362)
			(xy 280.148771 -271.136383) (xy 280.164481 -271.187313) (xy 280.172424 -271.240017) (xy 280.172922 -271.266666)
			(xy 280.172424 -271.293315) (xy 294.548804 -271.293315) (xy 294.548804 -271.240017) (xy 294.556747 -271.187313)
			(xy 294.572457 -271.136383) (xy 294.595583 -271.088362) (xy 294.625607 -271.044325) (xy 294.661859 -271.005254)
			(xy 294.70353 -270.972023) (xy 294.749688 -270.945374) (xy 294.799302 -270.925902) (xy 294.851264 -270.914042)
			(xy 294.904414 -270.910059) (xy 294.957564 -270.914042) (xy 295.009526 -270.925902) (xy 295.05914 -270.945374)
			(xy 295.105298 -270.972023) (xy 295.146969 -271.005254) (xy 295.183221 -271.044325) (xy 295.213245 -271.088362)
			(xy 295.236371 -271.136383) (xy 295.252081 -271.187313) (xy 295.260024 -271.240017) (xy 295.260522 -271.266666)
			(xy 295.260024 -271.293315) (xy 295.252081 -271.346019) (xy 295.236371 -271.396949) (xy 295.213245 -271.44497)
			(xy 295.183221 -271.489007) (xy 295.146969 -271.528078) (xy 295.105298 -271.561309) (xy 295.05914 -271.587958)
			(xy 295.009526 -271.60743) (xy 294.957564 -271.61929) (xy 294.904414 -271.623274) (xy 294.851264 -271.61929)
			(xy 294.799302 -271.60743) (xy 294.749688 -271.587958) (xy 294.70353 -271.561309) (xy 294.661859 -271.528078)
			(xy 294.625607 -271.489007) (xy 294.595583 -271.44497) (xy 294.572457 -271.396949) (xy 294.556747 -271.346019)
			(xy 294.548804 -271.293315) (xy 280.172424 -271.293315) (xy 280.164481 -271.346019) (xy 280.148771 -271.396949)
			(xy 280.125645 -271.44497) (xy 280.095621 -271.489007) (xy 280.059369 -271.528078) (xy 280.017698 -271.561309)
			(xy 279.97154 -271.587958) (xy 279.921926 -271.60743) (xy 279.869964 -271.61929) (xy 279.816814 -271.623274)
			(xy 279.763664 -271.61929) (xy 279.711702 -271.60743) (xy 279.662088 -271.587958) (xy 279.61593 -271.561309)
			(xy 279.574259 -271.528078) (xy 279.538007 -271.489007) (xy 279.507983 -271.44497) (xy 279.484857 -271.396949)
			(xy 279.469147 -271.346019) (xy 279.461204 -271.293315) (xy 265.084824 -271.293315) (xy 265.076881 -271.346019)
			(xy 265.061171 -271.396949) (xy 265.038045 -271.44497) (xy 265.008021 -271.489007) (xy 264.971769 -271.528078)
			(xy 264.930098 -271.561309) (xy 264.88394 -271.587958) (xy 264.834326 -271.60743) (xy 264.782364 -271.61929)
			(xy 264.729214 -271.623274) (xy 264.676064 -271.61929) (xy 264.624102 -271.60743) (xy 264.574488 -271.587958)
			(xy 264.52833 -271.561309) (xy 264.486659 -271.528078) (xy 264.450407 -271.489007) (xy 264.420383 -271.44497)
			(xy 264.397257 -271.396949) (xy 264.381547 -271.346019) (xy 264.373604 -271.293315) (xy 254.20828 -271.293315)
			(xy 254.20828 -272.143453) (xy 268.473672 -272.143453) (xy 268.473672 -272.090155) (xy 268.481615 -272.037451)
			(xy 268.497325 -271.986521) (xy 268.520451 -271.9385) (xy 268.550475 -271.894463) (xy 268.586727 -271.855392)
			(xy 268.628398 -271.822161) (xy 268.674556 -271.795512) (xy 268.72417 -271.77604) (xy 268.776132 -271.76418)
			(xy 268.829282 -271.760197) (xy 268.882432 -271.76418) (xy 268.934394 -271.77604) (xy 268.984008 -271.795512)
			(xy 269.030166 -271.822161) (xy 269.071837 -271.855392) (xy 269.108089 -271.894463) (xy 269.138113 -271.9385)
			(xy 269.161239 -271.986521) (xy 269.176949 -272.037451) (xy 269.184892 -272.090155) (xy 269.18539 -272.116804)
			(xy 269.184892 -272.143453) (xy 283.561272 -272.143453) (xy 283.561272 -272.090155) (xy 283.569215 -272.037451)
			(xy 283.584925 -271.986521) (xy 283.608051 -271.9385) (xy 283.638075 -271.894463) (xy 283.674327 -271.855392)
			(xy 283.715998 -271.822161) (xy 283.762156 -271.795512) (xy 283.81177 -271.77604) (xy 283.863732 -271.76418)
			(xy 283.916882 -271.760197) (xy 283.970032 -271.76418) (xy 284.021994 -271.77604) (xy 284.071608 -271.795512)
			(xy 284.117766 -271.822161) (xy 284.159437 -271.855392) (xy 284.195689 -271.894463) (xy 284.225713 -271.9385)
			(xy 284.248839 -271.986521) (xy 284.264549 -272.037451) (xy 284.272492 -272.090155) (xy 284.27299 -272.116804)
			(xy 284.272492 -272.143453) (xy 298.674272 -272.143453) (xy 298.674272 -272.090155) (xy 298.682215 -272.037451)
			(xy 298.697925 -271.986521) (xy 298.721051 -271.9385) (xy 298.751075 -271.894463) (xy 298.787327 -271.855392)
			(xy 298.828998 -271.822161) (xy 298.875156 -271.795512) (xy 298.92477 -271.77604) (xy 298.976732 -271.76418)
			(xy 299.029882 -271.760197) (xy 299.083032 -271.76418) (xy 299.134994 -271.77604) (xy 299.184608 -271.795512)
			(xy 299.230766 -271.822161) (xy 299.272437 -271.855392) (xy 299.308689 -271.894463) (xy 299.338713 -271.9385)
			(xy 299.361839 -271.986521) (xy 299.377549 -272.037451) (xy 299.385492 -272.090155) (xy 299.38599 -272.116804)
			(xy 299.385492 -272.143453) (xy 299.377549 -272.196157) (xy 299.361839 -272.247087) (xy 299.338713 -272.295108)
			(xy 299.308689 -272.339145) (xy 299.272437 -272.378216) (xy 299.230766 -272.411447) (xy 299.184608 -272.438096)
			(xy 299.134994 -272.457568) (xy 299.083032 -272.469428) (xy 299.029882 -272.473412) (xy 298.976732 -272.469428)
			(xy 298.92477 -272.457568) (xy 298.875156 -272.438096) (xy 298.828998 -272.411447) (xy 298.787327 -272.378216)
			(xy 298.751075 -272.339145) (xy 298.721051 -272.295108) (xy 298.697925 -272.247087) (xy 298.682215 -272.196157)
			(xy 298.674272 -272.143453) (xy 284.272492 -272.143453) (xy 284.264549 -272.196157) (xy 284.248839 -272.247087)
			(xy 284.225713 -272.295108) (xy 284.195689 -272.339145) (xy 284.159437 -272.378216) (xy 284.117766 -272.411447)
			(xy 284.071608 -272.438096) (xy 284.021994 -272.457568) (xy 283.970032 -272.469428) (xy 283.916882 -272.473412)
			(xy 283.863732 -272.469428) (xy 283.81177 -272.457568) (xy 283.762156 -272.438096) (xy 283.715998 -272.411447)
			(xy 283.674327 -272.378216) (xy 283.638075 -272.339145) (xy 283.608051 -272.295108) (xy 283.584925 -272.247087)
			(xy 283.569215 -272.196157) (xy 283.561272 -272.143453) (xy 269.184892 -272.143453) (xy 269.176949 -272.196157)
			(xy 269.161239 -272.247087) (xy 269.138113 -272.295108) (xy 269.108089 -272.339145) (xy 269.071837 -272.378216)
			(xy 269.030166 -272.411447) (xy 268.984008 -272.438096) (xy 268.934394 -272.457568) (xy 268.882432 -272.469428)
			(xy 268.829282 -272.473412) (xy 268.776132 -272.469428) (xy 268.72417 -272.457568) (xy 268.674556 -272.438096)
			(xy 268.628398 -272.411447) (xy 268.586727 -272.378216) (xy 268.550475 -272.339145) (xy 268.520451 -272.295108)
			(xy 268.497325 -272.247087) (xy 268.481615 -272.196157) (xy 268.473672 -272.143453) (xy 254.20828 -272.143453)
			(xy 254.20828 -272.993337) (xy 264.373604 -272.993337) (xy 264.373604 -272.940039) (xy 264.381547 -272.887335)
			(xy 264.397257 -272.836405) (xy 264.420383 -272.788384) (xy 264.450407 -272.744347) (xy 264.486659 -272.705276)
			(xy 264.52833 -272.672045) (xy 264.574488 -272.645396) (xy 264.624102 -272.625924) (xy 264.676064 -272.614064)
			(xy 264.729214 -272.610081) (xy 264.782364 -272.614064) (xy 264.834326 -272.625924) (xy 264.88394 -272.645396)
			(xy 264.930098 -272.672045) (xy 264.971769 -272.705276) (xy 265.008021 -272.744347) (xy 265.038045 -272.788384)
			(xy 265.061171 -272.836405) (xy 265.076881 -272.887335) (xy 265.084824 -272.940039) (xy 265.085322 -272.966688)
			(xy 265.084824 -272.993337) (xy 279.461204 -272.993337) (xy 279.461204 -272.940039) (xy 279.469147 -272.887335)
			(xy 279.484857 -272.836405) (xy 279.507983 -272.788384) (xy 279.538007 -272.744347) (xy 279.574259 -272.705276)
			(xy 279.61593 -272.672045) (xy 279.662088 -272.645396) (xy 279.711702 -272.625924) (xy 279.763664 -272.614064)
			(xy 279.816814 -272.610081) (xy 279.869964 -272.614064) (xy 279.921926 -272.625924) (xy 279.97154 -272.645396)
			(xy 280.017698 -272.672045) (xy 280.059369 -272.705276) (xy 280.095621 -272.744347) (xy 280.125645 -272.788384)
			(xy 280.148771 -272.836405) (xy 280.164481 -272.887335) (xy 280.172424 -272.940039) (xy 280.172922 -272.966688)
			(xy 280.172424 -272.993337) (xy 294.548804 -272.993337) (xy 294.548804 -272.940039) (xy 294.556747 -272.887335)
			(xy 294.572457 -272.836405) (xy 294.595583 -272.788384) (xy 294.625607 -272.744347) (xy 294.661859 -272.705276)
			(xy 294.70353 -272.672045) (xy 294.749688 -272.645396) (xy 294.799302 -272.625924) (xy 294.851264 -272.614064)
			(xy 294.904414 -272.610081) (xy 294.957564 -272.614064) (xy 295.009526 -272.625924) (xy 295.05914 -272.645396)
			(xy 295.105298 -272.672045) (xy 295.146969 -272.705276) (xy 295.183221 -272.744347) (xy 295.213245 -272.788384)
			(xy 295.236371 -272.836405) (xy 295.252081 -272.887335) (xy 295.260024 -272.940039) (xy 295.260522 -272.966688)
			(xy 295.260024 -272.993337) (xy 295.252081 -273.046041) (xy 295.236371 -273.096971) (xy 295.213245 -273.144992)
			(xy 295.183221 -273.189029) (xy 295.146969 -273.2281) (xy 295.105298 -273.261331) (xy 295.05914 -273.28798)
			(xy 295.009526 -273.307452) (xy 294.957564 -273.319312) (xy 294.904414 -273.323296) (xy 294.851264 -273.319312)
			(xy 294.799302 -273.307452) (xy 294.749688 -273.28798) (xy 294.70353 -273.261331) (xy 294.661859 -273.2281)
			(xy 294.625607 -273.189029) (xy 294.595583 -273.144992) (xy 294.572457 -273.096971) (xy 294.556747 -273.046041)
			(xy 294.548804 -272.993337) (xy 280.172424 -272.993337) (xy 280.164481 -273.046041) (xy 280.148771 -273.096971)
			(xy 280.125645 -273.144992) (xy 280.095621 -273.189029) (xy 280.059369 -273.2281) (xy 280.017698 -273.261331)
			(xy 279.97154 -273.28798) (xy 279.921926 -273.307452) (xy 279.869964 -273.319312) (xy 279.816814 -273.323296)
			(xy 279.763664 -273.319312) (xy 279.711702 -273.307452) (xy 279.662088 -273.28798) (xy 279.61593 -273.261331)
			(xy 279.574259 -273.2281) (xy 279.538007 -273.189029) (xy 279.507983 -273.144992) (xy 279.484857 -273.096971)
			(xy 279.469147 -273.046041) (xy 279.461204 -272.993337) (xy 265.084824 -272.993337) (xy 265.076881 -273.046041)
			(xy 265.061171 -273.096971) (xy 265.038045 -273.144992) (xy 265.008021 -273.189029) (xy 264.971769 -273.2281)
			(xy 264.930098 -273.261331) (xy 264.88394 -273.28798) (xy 264.834326 -273.307452) (xy 264.782364 -273.319312)
			(xy 264.729214 -273.323296) (xy 264.676064 -273.319312) (xy 264.624102 -273.307452) (xy 264.574488 -273.28798)
			(xy 264.52833 -273.261331) (xy 264.486659 -273.2281) (xy 264.450407 -273.189029) (xy 264.420383 -273.144992)
			(xy 264.397257 -273.096971) (xy 264.381547 -273.046041) (xy 264.373604 -272.993337) (xy 254.20828 -272.993337)
			(xy 254.20828 -273.843221) (xy 268.473672 -273.843221) (xy 268.473672 -273.789923) (xy 268.481615 -273.737219)
			(xy 268.497325 -273.686289) (xy 268.520451 -273.638268) (xy 268.550475 -273.594231) (xy 268.586727 -273.55516)
			(xy 268.628398 -273.521929) (xy 268.674556 -273.49528) (xy 268.72417 -273.475808) (xy 268.776132 -273.463948)
			(xy 268.829282 -273.459965) (xy 268.882432 -273.463948) (xy 268.934394 -273.475808) (xy 268.984008 -273.49528)
			(xy 269.030166 -273.521929) (xy 269.071837 -273.55516) (xy 269.108089 -273.594231) (xy 269.138113 -273.638268)
			(xy 269.161239 -273.686289) (xy 269.176949 -273.737219) (xy 269.184892 -273.789923) (xy 269.18539 -273.816572)
			(xy 269.184892 -273.843221) (xy 283.561272 -273.843221) (xy 283.561272 -273.789923) (xy 283.569215 -273.737219)
			(xy 283.584925 -273.686289) (xy 283.608051 -273.638268) (xy 283.638075 -273.594231) (xy 283.674327 -273.55516)
			(xy 283.715998 -273.521929) (xy 283.762156 -273.49528) (xy 283.81177 -273.475808) (xy 283.863732 -273.463948)
			(xy 283.916882 -273.459965) (xy 283.970032 -273.463948) (xy 284.021994 -273.475808) (xy 284.071608 -273.49528)
			(xy 284.117766 -273.521929) (xy 284.159437 -273.55516) (xy 284.195689 -273.594231) (xy 284.225713 -273.638268)
			(xy 284.248839 -273.686289) (xy 284.264549 -273.737219) (xy 284.272492 -273.789923) (xy 284.27299 -273.816572)
			(xy 284.272492 -273.843221) (xy 298.674272 -273.843221) (xy 298.674272 -273.789923) (xy 298.682215 -273.737219)
			(xy 298.697925 -273.686289) (xy 298.721051 -273.638268) (xy 298.751075 -273.594231) (xy 298.787327 -273.55516)
			(xy 298.828998 -273.521929) (xy 298.875156 -273.49528) (xy 298.92477 -273.475808) (xy 298.976732 -273.463948)
			(xy 299.029882 -273.459965) (xy 299.083032 -273.463948) (xy 299.134994 -273.475808) (xy 299.184608 -273.49528)
			(xy 299.230766 -273.521929) (xy 299.272437 -273.55516) (xy 299.308689 -273.594231) (xy 299.338713 -273.638268)
			(xy 299.361839 -273.686289) (xy 299.377549 -273.737219) (xy 299.385492 -273.789923) (xy 299.38599 -273.816572)
			(xy 299.385492 -273.843221) (xy 299.377549 -273.895925) (xy 299.361839 -273.946855) (xy 299.338713 -273.994876)
			(xy 299.308689 -274.038913) (xy 299.272437 -274.077984) (xy 299.230766 -274.111215) (xy 299.184608 -274.137864)
			(xy 299.134994 -274.157336) (xy 299.083032 -274.169196) (xy 299.029882 -274.17318) (xy 298.976732 -274.169196)
			(xy 298.92477 -274.157336) (xy 298.875156 -274.137864) (xy 298.828998 -274.111215) (xy 298.787327 -274.077984)
			(xy 298.751075 -274.038913) (xy 298.721051 -273.994876) (xy 298.697925 -273.946855) (xy 298.682215 -273.895925)
			(xy 298.674272 -273.843221) (xy 284.272492 -273.843221) (xy 284.264549 -273.895925) (xy 284.248839 -273.946855)
			(xy 284.225713 -273.994876) (xy 284.195689 -274.038913) (xy 284.159437 -274.077984) (xy 284.117766 -274.111215)
			(xy 284.071608 -274.137864) (xy 284.021994 -274.157336) (xy 283.970032 -274.169196) (xy 283.916882 -274.17318)
			(xy 283.863732 -274.169196) (xy 283.81177 -274.157336) (xy 283.762156 -274.137864) (xy 283.715998 -274.111215)
			(xy 283.674327 -274.077984) (xy 283.638075 -274.038913) (xy 283.608051 -273.994876) (xy 283.584925 -273.946855)
			(xy 283.569215 -273.895925) (xy 283.561272 -273.843221) (xy 269.184892 -273.843221) (xy 269.176949 -273.895925)
			(xy 269.161239 -273.946855) (xy 269.138113 -273.994876) (xy 269.108089 -274.038913) (xy 269.071837 -274.077984)
			(xy 269.030166 -274.111215) (xy 268.984008 -274.137864) (xy 268.934394 -274.157336) (xy 268.882432 -274.169196)
			(xy 268.829282 -274.17318) (xy 268.776132 -274.169196) (xy 268.72417 -274.157336) (xy 268.674556 -274.137864)
			(xy 268.628398 -274.111215) (xy 268.586727 -274.077984) (xy 268.550475 -274.038913) (xy 268.520451 -273.994876)
			(xy 268.497325 -273.946855) (xy 268.481615 -273.895925) (xy 268.473672 -273.843221) (xy 254.20828 -273.843221)
			(xy 254.20828 -274.693359) (xy 264.373604 -274.693359) (xy 264.373604 -274.640061) (xy 264.381547 -274.587357)
			(xy 264.397257 -274.536427) (xy 264.420383 -274.488406) (xy 264.450407 -274.444369) (xy 264.486659 -274.405298)
			(xy 264.52833 -274.372067) (xy 264.574488 -274.345418) (xy 264.624102 -274.325946) (xy 264.676064 -274.314086)
			(xy 264.729214 -274.310103) (xy 264.782364 -274.314086) (xy 264.834326 -274.325946) (xy 264.88394 -274.345418)
			(xy 264.930098 -274.372067) (xy 264.971769 -274.405298) (xy 265.008021 -274.444369) (xy 265.038045 -274.488406)
			(xy 265.061171 -274.536427) (xy 265.076881 -274.587357) (xy 265.084824 -274.640061) (xy 265.085322 -274.66671)
			(xy 265.084824 -274.693359) (xy 268.473672 -274.693359) (xy 268.473672 -274.640061) (xy 268.481615 -274.587357)
			(xy 268.497325 -274.536427) (xy 268.520451 -274.488406) (xy 268.550475 -274.444369) (xy 268.586727 -274.405298)
			(xy 268.628398 -274.372067) (xy 268.674556 -274.345418) (xy 268.72417 -274.325946) (xy 268.776132 -274.314086)
			(xy 268.829282 -274.310103) (xy 268.882432 -274.314086) (xy 268.934394 -274.325946) (xy 268.984008 -274.345418)
			(xy 269.030166 -274.372067) (xy 269.071837 -274.405298) (xy 269.108089 -274.444369) (xy 269.138113 -274.488406)
			(xy 269.161239 -274.536427) (xy 269.176949 -274.587357) (xy 269.184892 -274.640061) (xy 269.18539 -274.66671)
			(xy 269.184892 -274.693359) (xy 279.461204 -274.693359) (xy 279.461204 -274.640061) (xy 279.469147 -274.587357)
			(xy 279.484857 -274.536427) (xy 279.507983 -274.488406) (xy 279.538007 -274.444369) (xy 279.574259 -274.405298)
			(xy 279.61593 -274.372067) (xy 279.662088 -274.345418) (xy 279.711702 -274.325946) (xy 279.763664 -274.314086)
			(xy 279.816814 -274.310103) (xy 279.869964 -274.314086) (xy 279.921926 -274.325946) (xy 279.97154 -274.345418)
			(xy 280.017698 -274.372067) (xy 280.059369 -274.405298) (xy 280.095621 -274.444369) (xy 280.125645 -274.488406)
			(xy 280.148771 -274.536427) (xy 280.164481 -274.587357) (xy 280.172424 -274.640061) (xy 280.172922 -274.66671)
			(xy 280.172424 -274.693359) (xy 283.561272 -274.693359) (xy 283.561272 -274.640061) (xy 283.569215 -274.587357)
			(xy 283.584925 -274.536427) (xy 283.608051 -274.488406) (xy 283.638075 -274.444369) (xy 283.674327 -274.405298)
			(xy 283.715998 -274.372067) (xy 283.762156 -274.345418) (xy 283.81177 -274.325946) (xy 283.863732 -274.314086)
			(xy 283.916882 -274.310103) (xy 283.970032 -274.314086) (xy 284.021994 -274.325946) (xy 284.071608 -274.345418)
			(xy 284.117766 -274.372067) (xy 284.159437 -274.405298) (xy 284.195689 -274.444369) (xy 284.225713 -274.488406)
			(xy 284.248839 -274.536427) (xy 284.264549 -274.587357) (xy 284.272492 -274.640061) (xy 284.27299 -274.66671)
			(xy 284.272492 -274.693359) (xy 294.548804 -274.693359) (xy 294.548804 -274.640061) (xy 294.556747 -274.587357)
			(xy 294.572457 -274.536427) (xy 294.595583 -274.488406) (xy 294.625607 -274.444369) (xy 294.661859 -274.405298)
			(xy 294.70353 -274.372067) (xy 294.749688 -274.345418) (xy 294.799302 -274.325946) (xy 294.851264 -274.314086)
			(xy 294.904414 -274.310103) (xy 294.957564 -274.314086) (xy 295.009526 -274.325946) (xy 295.05914 -274.345418)
			(xy 295.105298 -274.372067) (xy 295.146969 -274.405298) (xy 295.183221 -274.444369) (xy 295.213245 -274.488406)
			(xy 295.236371 -274.536427) (xy 295.252081 -274.587357) (xy 295.260024 -274.640061) (xy 295.260522 -274.66671)
			(xy 295.260024 -274.693359) (xy 295.259986 -274.693613) (xy 298.674272 -274.693613) (xy 298.674272 -274.640315)
			(xy 298.682215 -274.587611) (xy 298.697925 -274.536681) (xy 298.721051 -274.48866) (xy 298.751075 -274.444623)
			(xy 298.787327 -274.405552) (xy 298.828998 -274.372321) (xy 298.875156 -274.345672) (xy 298.92477 -274.3262)
			(xy 298.976732 -274.31434) (xy 299.029882 -274.310357) (xy 299.083032 -274.31434) (xy 299.134994 -274.3262)
			(xy 299.184608 -274.345672) (xy 299.230766 -274.372321) (xy 299.272437 -274.405552) (xy 299.308689 -274.444623)
			(xy 299.338713 -274.48866) (xy 299.361839 -274.536681) (xy 299.377549 -274.587611) (xy 299.385492 -274.640315)
			(xy 299.38599 -274.666964) (xy 299.385492 -274.693613) (xy 299.377549 -274.746317) (xy 299.361839 -274.797247)
			(xy 299.338713 -274.845268) (xy 299.308689 -274.889305) (xy 299.272437 -274.928376) (xy 299.230766 -274.961607)
			(xy 299.184608 -274.988256) (xy 299.134994 -275.007728) (xy 299.083032 -275.019588) (xy 299.029882 -275.023572)
			(xy 298.976732 -275.019588) (xy 298.92477 -275.007728) (xy 298.875156 -274.988256) (xy 298.828998 -274.961607)
			(xy 298.787327 -274.928376) (xy 298.751075 -274.889305) (xy 298.721051 -274.845268) (xy 298.697925 -274.797247)
			(xy 298.682215 -274.746317) (xy 298.674272 -274.693613) (xy 295.259986 -274.693613) (xy 295.252081 -274.746063)
			(xy 295.236371 -274.796993) (xy 295.213245 -274.845014) (xy 295.183221 -274.889051) (xy 295.146969 -274.928122)
			(xy 295.105298 -274.961353) (xy 295.05914 -274.988002) (xy 295.009526 -275.007474) (xy 294.957564 -275.019334)
			(xy 294.904414 -275.023318) (xy 294.851264 -275.019334) (xy 294.799302 -275.007474) (xy 294.749688 -274.988002)
			(xy 294.70353 -274.961353) (xy 294.661859 -274.928122) (xy 294.625607 -274.889051) (xy 294.595583 -274.845014)
			(xy 294.572457 -274.796993) (xy 294.556747 -274.746063) (xy 294.548804 -274.693359) (xy 284.272492 -274.693359)
			(xy 284.264549 -274.746063) (xy 284.248839 -274.796993) (xy 284.225713 -274.845014) (xy 284.195689 -274.889051)
			(xy 284.159437 -274.928122) (xy 284.117766 -274.961353) (xy 284.071608 -274.988002) (xy 284.021994 -275.007474)
			(xy 283.970032 -275.019334) (xy 283.916882 -275.023318) (xy 283.863732 -275.019334) (xy 283.81177 -275.007474)
			(xy 283.762156 -274.988002) (xy 283.715998 -274.961353) (xy 283.674327 -274.928122) (xy 283.638075 -274.889051)
			(xy 283.608051 -274.845014) (xy 283.584925 -274.796993) (xy 283.569215 -274.746063) (xy 283.561272 -274.693359)
			(xy 280.172424 -274.693359) (xy 280.164481 -274.746063) (xy 280.148771 -274.796993) (xy 280.125645 -274.845014)
			(xy 280.095621 -274.889051) (xy 280.059369 -274.928122) (xy 280.017698 -274.961353) (xy 279.97154 -274.988002)
			(xy 279.921926 -275.007474) (xy 279.869964 -275.019334) (xy 279.816814 -275.023318) (xy 279.763664 -275.019334)
			(xy 279.711702 -275.007474) (xy 279.662088 -274.988002) (xy 279.61593 -274.961353) (xy 279.574259 -274.928122)
			(xy 279.538007 -274.889051) (xy 279.507983 -274.845014) (xy 279.484857 -274.796993) (xy 279.469147 -274.746063)
			(xy 279.461204 -274.693359) (xy 269.184892 -274.693359) (xy 269.176949 -274.746063) (xy 269.161239 -274.796993)
			(xy 269.138113 -274.845014) (xy 269.108089 -274.889051) (xy 269.071837 -274.928122) (xy 269.030166 -274.961353)
			(xy 268.984008 -274.988002) (xy 268.934394 -275.007474) (xy 268.882432 -275.019334) (xy 268.829282 -275.023318)
			(xy 268.776132 -275.019334) (xy 268.72417 -275.007474) (xy 268.674556 -274.988002) (xy 268.628398 -274.961353)
			(xy 268.586727 -274.928122) (xy 268.550475 -274.889051) (xy 268.520451 -274.845014) (xy 268.497325 -274.796993)
			(xy 268.481615 -274.746063) (xy 268.473672 -274.693359) (xy 265.084824 -274.693359) (xy 265.076881 -274.746063)
			(xy 265.061171 -274.796993) (xy 265.038045 -274.845014) (xy 265.008021 -274.889051) (xy 264.971769 -274.928122)
			(xy 264.930098 -274.961353) (xy 264.88394 -274.988002) (xy 264.834326 -275.007474) (xy 264.782364 -275.019334)
			(xy 264.729214 -275.023318) (xy 264.676064 -275.019334) (xy 264.624102 -275.007474) (xy 264.574488 -274.988002)
			(xy 264.52833 -274.961353) (xy 264.486659 -274.928122) (xy 264.450407 -274.889051) (xy 264.420383 -274.845014)
			(xy 264.397257 -274.796993) (xy 264.381547 -274.746063) (xy 264.373604 -274.693359) (xy 254.20828 -274.693359)
			(xy 254.20828 -275.543243) (xy 264.373604 -275.543243) (xy 264.373604 -275.489945) (xy 264.381547 -275.437241)
			(xy 264.397257 -275.386311) (xy 264.420383 -275.33829) (xy 264.450407 -275.294253) (xy 264.486659 -275.255182)
			(xy 264.52833 -275.221951) (xy 264.574488 -275.195302) (xy 264.624102 -275.17583) (xy 264.676064 -275.16397)
			(xy 264.729214 -275.159987) (xy 264.782364 -275.16397) (xy 264.834326 -275.17583) (xy 264.88394 -275.195302)
			(xy 264.930098 -275.221951) (xy 264.971769 -275.255182) (xy 265.008021 -275.294253) (xy 265.038045 -275.33829)
			(xy 265.061171 -275.386311) (xy 265.076881 -275.437241) (xy 265.084824 -275.489945) (xy 265.085322 -275.516594)
			(xy 265.084824 -275.543243) (xy 279.461204 -275.543243) (xy 279.461204 -275.489945) (xy 279.469147 -275.437241)
			(xy 279.484857 -275.386311) (xy 279.507983 -275.33829) (xy 279.538007 -275.294253) (xy 279.574259 -275.255182)
			(xy 279.61593 -275.221951) (xy 279.662088 -275.195302) (xy 279.711702 -275.17583) (xy 279.763664 -275.16397)
			(xy 279.816814 -275.159987) (xy 279.869964 -275.16397) (xy 279.921926 -275.17583) (xy 279.97154 -275.195302)
			(xy 280.017698 -275.221951) (xy 280.059369 -275.255182) (xy 280.095621 -275.294253) (xy 280.125645 -275.33829)
			(xy 280.148771 -275.386311) (xy 280.164481 -275.437241) (xy 280.172424 -275.489945) (xy 280.172922 -275.516594)
			(xy 280.172424 -275.543243) (xy 294.548804 -275.543243) (xy 294.548804 -275.489945) (xy 294.556747 -275.437241)
			(xy 294.572457 -275.386311) (xy 294.595583 -275.33829) (xy 294.625607 -275.294253) (xy 294.661859 -275.255182)
			(xy 294.70353 -275.221951) (xy 294.749688 -275.195302) (xy 294.799302 -275.17583) (xy 294.851264 -275.16397)
			(xy 294.904414 -275.159987) (xy 294.957564 -275.16397) (xy 295.009526 -275.17583) (xy 295.05914 -275.195302)
			(xy 295.105298 -275.221951) (xy 295.146969 -275.255182) (xy 295.183221 -275.294253) (xy 295.213245 -275.33829)
			(xy 295.236371 -275.386311) (xy 295.252081 -275.437241) (xy 295.260024 -275.489945) (xy 295.260522 -275.516594)
			(xy 295.260024 -275.543243) (xy 295.252081 -275.595947) (xy 295.236371 -275.646877) (xy 295.213245 -275.694898)
			(xy 295.183221 -275.738935) (xy 295.146969 -275.778006) (xy 295.105298 -275.811237) (xy 295.05914 -275.837886)
			(xy 295.009526 -275.857358) (xy 294.957564 -275.869218) (xy 294.904414 -275.873202) (xy 294.851264 -275.869218)
			(xy 294.799302 -275.857358) (xy 294.749688 -275.837886) (xy 294.70353 -275.811237) (xy 294.661859 -275.778006)
			(xy 294.625607 -275.738935) (xy 294.595583 -275.694898) (xy 294.572457 -275.646877) (xy 294.556747 -275.595947)
			(xy 294.548804 -275.543243) (xy 280.172424 -275.543243) (xy 280.164481 -275.595947) (xy 280.148771 -275.646877)
			(xy 280.125645 -275.694898) (xy 280.095621 -275.738935) (xy 280.059369 -275.778006) (xy 280.017698 -275.811237)
			(xy 279.97154 -275.837886) (xy 279.921926 -275.857358) (xy 279.869964 -275.869218) (xy 279.816814 -275.873202)
			(xy 279.763664 -275.869218) (xy 279.711702 -275.857358) (xy 279.662088 -275.837886) (xy 279.61593 -275.811237)
			(xy 279.574259 -275.778006) (xy 279.538007 -275.738935) (xy 279.507983 -275.694898) (xy 279.484857 -275.646877)
			(xy 279.469147 -275.595947) (xy 279.461204 -275.543243) (xy 265.084824 -275.543243) (xy 265.076881 -275.595947)
			(xy 265.061171 -275.646877) (xy 265.038045 -275.694898) (xy 265.008021 -275.738935) (xy 264.971769 -275.778006)
			(xy 264.930098 -275.811237) (xy 264.88394 -275.837886) (xy 264.834326 -275.857358) (xy 264.782364 -275.869218)
			(xy 264.729214 -275.873202) (xy 264.676064 -275.869218) (xy 264.624102 -275.857358) (xy 264.574488 -275.837886)
			(xy 264.52833 -275.811237) (xy 264.486659 -275.778006) (xy 264.450407 -275.738935) (xy 264.420383 -275.694898)
			(xy 264.397257 -275.646877) (xy 264.381547 -275.595947) (xy 264.373604 -275.543243) (xy 254.20828 -275.543243)
			(xy 254.20828 -276.393381) (xy 268.473672 -276.393381) (xy 268.473672 -276.340083) (xy 268.481615 -276.287379)
			(xy 268.497325 -276.236449) (xy 268.520451 -276.188428) (xy 268.550475 -276.144391) (xy 268.586727 -276.10532)
			(xy 268.628398 -276.072089) (xy 268.674556 -276.04544) (xy 268.72417 -276.025968) (xy 268.776132 -276.014108)
			(xy 268.829282 -276.010125) (xy 268.882432 -276.014108) (xy 268.934394 -276.025968) (xy 268.984008 -276.04544)
			(xy 269.030166 -276.072089) (xy 269.071837 -276.10532) (xy 269.108089 -276.144391) (xy 269.138113 -276.188428)
			(xy 269.161239 -276.236449) (xy 269.176949 -276.287379) (xy 269.184892 -276.340083) (xy 269.18539 -276.366732)
			(xy 269.184892 -276.393381) (xy 283.561272 -276.393381) (xy 283.561272 -276.340083) (xy 283.569215 -276.287379)
			(xy 283.584925 -276.236449) (xy 283.608051 -276.188428) (xy 283.638075 -276.144391) (xy 283.674327 -276.10532)
			(xy 283.715998 -276.072089) (xy 283.762156 -276.04544) (xy 283.81177 -276.025968) (xy 283.863732 -276.014108)
			(xy 283.916882 -276.010125) (xy 283.970032 -276.014108) (xy 284.021994 -276.025968) (xy 284.071608 -276.04544)
			(xy 284.117766 -276.072089) (xy 284.159437 -276.10532) (xy 284.195689 -276.144391) (xy 284.225713 -276.188428)
			(xy 284.248839 -276.236449) (xy 284.264549 -276.287379) (xy 284.272492 -276.340083) (xy 284.27299 -276.366732)
			(xy 284.272492 -276.393381) (xy 284.272454 -276.393635) (xy 298.674272 -276.393635) (xy 298.674272 -276.340337)
			(xy 298.682215 -276.287633) (xy 298.697925 -276.236703) (xy 298.721051 -276.188682) (xy 298.751075 -276.144645)
			(xy 298.787327 -276.105574) (xy 298.828998 -276.072343) (xy 298.875156 -276.045694) (xy 298.92477 -276.026222)
			(xy 298.976732 -276.014362) (xy 299.029882 -276.010379) (xy 299.083032 -276.014362) (xy 299.134994 -276.026222)
			(xy 299.184608 -276.045694) (xy 299.230766 -276.072343) (xy 299.272437 -276.105574) (xy 299.308689 -276.144645)
			(xy 299.338713 -276.188682) (xy 299.361839 -276.236703) (xy 299.377549 -276.287633) (xy 299.385492 -276.340337)
			(xy 299.38599 -276.366986) (xy 299.385492 -276.393635) (xy 299.377549 -276.446339) (xy 299.361839 -276.497269)
			(xy 299.338713 -276.54529) (xy 299.308689 -276.589327) (xy 299.272437 -276.628398) (xy 299.230766 -276.661629)
			(xy 299.184608 -276.688278) (xy 299.134994 -276.70775) (xy 299.083032 -276.71961) (xy 299.029882 -276.723594)
			(xy 298.976732 -276.71961) (xy 298.92477 -276.70775) (xy 298.875156 -276.688278) (xy 298.828998 -276.661629)
			(xy 298.787327 -276.628398) (xy 298.751075 -276.589327) (xy 298.721051 -276.54529) (xy 298.697925 -276.497269)
			(xy 298.682215 -276.446339) (xy 298.674272 -276.393635) (xy 284.272454 -276.393635) (xy 284.264549 -276.446085)
			(xy 284.248839 -276.497015) (xy 284.225713 -276.545036) (xy 284.195689 -276.589073) (xy 284.159437 -276.628144)
			(xy 284.117766 -276.661375) (xy 284.071608 -276.688024) (xy 284.021994 -276.707496) (xy 283.970032 -276.719356)
			(xy 283.916882 -276.72334) (xy 283.863732 -276.719356) (xy 283.81177 -276.707496) (xy 283.762156 -276.688024)
			(xy 283.715998 -276.661375) (xy 283.674327 -276.628144) (xy 283.638075 -276.589073) (xy 283.608051 -276.545036)
			(xy 283.584925 -276.497015) (xy 283.569215 -276.446085) (xy 283.561272 -276.393381) (xy 269.184892 -276.393381)
			(xy 269.176949 -276.446085) (xy 269.161239 -276.497015) (xy 269.138113 -276.545036) (xy 269.108089 -276.589073)
			(xy 269.071837 -276.628144) (xy 269.030166 -276.661375) (xy 268.984008 -276.688024) (xy 268.934394 -276.707496)
			(xy 268.882432 -276.719356) (xy 268.829282 -276.72334) (xy 268.776132 -276.719356) (xy 268.72417 -276.707496)
			(xy 268.674556 -276.688024) (xy 268.628398 -276.661375) (xy 268.586727 -276.628144) (xy 268.550475 -276.589073)
			(xy 268.520451 -276.545036) (xy 268.497325 -276.497015) (xy 268.481615 -276.446085) (xy 268.473672 -276.393381)
			(xy 254.20828 -276.393381) (xy 254.20828 -277.243265) (xy 264.373604 -277.243265) (xy 264.373604 -277.189967)
			(xy 264.381547 -277.137263) (xy 264.397257 -277.086333) (xy 264.420383 -277.038312) (xy 264.450407 -276.994275)
			(xy 264.486659 -276.955204) (xy 264.52833 -276.921973) (xy 264.574488 -276.895324) (xy 264.624102 -276.875852)
			(xy 264.676064 -276.863992) (xy 264.729214 -276.860009) (xy 264.782364 -276.863992) (xy 264.834326 -276.875852)
			(xy 264.88394 -276.895324) (xy 264.930098 -276.921973) (xy 264.971769 -276.955204) (xy 265.008021 -276.994275)
			(xy 265.038045 -277.038312) (xy 265.061171 -277.086333) (xy 265.076881 -277.137263) (xy 265.084824 -277.189967)
			(xy 265.085322 -277.216616) (xy 265.084824 -277.243265) (xy 279.461204 -277.243265) (xy 279.461204 -277.189967)
			(xy 279.469147 -277.137263) (xy 279.484857 -277.086333) (xy 279.507983 -277.038312) (xy 279.538007 -276.994275)
			(xy 279.574259 -276.955204) (xy 279.61593 -276.921973) (xy 279.662088 -276.895324) (xy 279.711702 -276.875852)
			(xy 279.763664 -276.863992) (xy 279.816814 -276.860009) (xy 279.869964 -276.863992) (xy 279.921926 -276.875852)
			(xy 279.97154 -276.895324) (xy 280.017698 -276.921973) (xy 280.059369 -276.955204) (xy 280.095621 -276.994275)
			(xy 280.125645 -277.038312) (xy 280.148771 -277.086333) (xy 280.164481 -277.137263) (xy 280.172424 -277.189967)
			(xy 280.172922 -277.216616) (xy 280.172424 -277.243265) (xy 294.548804 -277.243265) (xy 294.548804 -277.189967)
			(xy 294.556747 -277.137263) (xy 294.572457 -277.086333) (xy 294.595583 -277.038312) (xy 294.625607 -276.994275)
			(xy 294.661859 -276.955204) (xy 294.70353 -276.921973) (xy 294.749688 -276.895324) (xy 294.799302 -276.875852)
			(xy 294.851264 -276.863992) (xy 294.904414 -276.860009) (xy 294.957564 -276.863992) (xy 295.009526 -276.875852)
			(xy 295.05914 -276.895324) (xy 295.105298 -276.921973) (xy 295.146969 -276.955204) (xy 295.183221 -276.994275)
			(xy 295.213245 -277.038312) (xy 295.236371 -277.086333) (xy 295.252081 -277.137263) (xy 295.260024 -277.189967)
			(xy 295.260522 -277.216616) (xy 295.260024 -277.243265) (xy 295.252081 -277.295969) (xy 295.236371 -277.346899)
			(xy 295.213245 -277.39492) (xy 295.183221 -277.438957) (xy 295.146969 -277.478028) (xy 295.105298 -277.511259)
			(xy 295.05914 -277.537908) (xy 295.009526 -277.55738) (xy 294.957564 -277.56924) (xy 294.904414 -277.573224)
			(xy 294.851264 -277.56924) (xy 294.799302 -277.55738) (xy 294.749688 -277.537908) (xy 294.70353 -277.511259)
			(xy 294.661859 -277.478028) (xy 294.625607 -277.438957) (xy 294.595583 -277.39492) (xy 294.572457 -277.346899)
			(xy 294.556747 -277.295969) (xy 294.548804 -277.243265) (xy 280.172424 -277.243265) (xy 280.164481 -277.295969)
			(xy 280.148771 -277.346899) (xy 280.125645 -277.39492) (xy 280.095621 -277.438957) (xy 280.059369 -277.478028)
			(xy 280.017698 -277.511259) (xy 279.97154 -277.537908) (xy 279.921926 -277.55738) (xy 279.869964 -277.56924)
			(xy 279.816814 -277.573224) (xy 279.763664 -277.56924) (xy 279.711702 -277.55738) (xy 279.662088 -277.537908)
			(xy 279.61593 -277.511259) (xy 279.574259 -277.478028) (xy 279.538007 -277.438957) (xy 279.507983 -277.39492)
			(xy 279.484857 -277.346899) (xy 279.469147 -277.295969) (xy 279.461204 -277.243265) (xy 265.084824 -277.243265)
			(xy 265.076881 -277.295969) (xy 265.061171 -277.346899) (xy 265.038045 -277.39492) (xy 265.008021 -277.438957)
			(xy 264.971769 -277.478028) (xy 264.930098 -277.511259) (xy 264.88394 -277.537908) (xy 264.834326 -277.55738)
			(xy 264.782364 -277.56924) (xy 264.729214 -277.573224) (xy 264.676064 -277.56924) (xy 264.624102 -277.55738)
			(xy 264.574488 -277.537908) (xy 264.52833 -277.511259) (xy 264.486659 -277.478028) (xy 264.450407 -277.438957)
			(xy 264.420383 -277.39492) (xy 264.397257 -277.346899) (xy 264.381547 -277.295969) (xy 264.373604 -277.243265)
			(xy 254.20828 -277.243265) (xy 254.20828 -278.093403) (xy 268.473672 -278.093403) (xy 268.473672 -278.040105)
			(xy 268.481615 -277.987401) (xy 268.497325 -277.936471) (xy 268.520451 -277.88845) (xy 268.550475 -277.844413)
			(xy 268.586727 -277.805342) (xy 268.628398 -277.772111) (xy 268.674556 -277.745462) (xy 268.72417 -277.72599)
			(xy 268.776132 -277.71413) (xy 268.829282 -277.710147) (xy 268.882432 -277.71413) (xy 268.934394 -277.72599)
			(xy 268.984008 -277.745462) (xy 269.030166 -277.772111) (xy 269.071837 -277.805342) (xy 269.108089 -277.844413)
			(xy 269.138113 -277.88845) (xy 269.161239 -277.936471) (xy 269.176949 -277.987401) (xy 269.184892 -278.040105)
			(xy 269.18539 -278.066754) (xy 269.184892 -278.093403) (xy 283.561272 -278.093403) (xy 283.561272 -278.040105)
			(xy 283.569215 -277.987401) (xy 283.584925 -277.936471) (xy 283.608051 -277.88845) (xy 283.638075 -277.844413)
			(xy 283.674327 -277.805342) (xy 283.715998 -277.772111) (xy 283.762156 -277.745462) (xy 283.81177 -277.72599)
			(xy 283.863732 -277.71413) (xy 283.916882 -277.710147) (xy 283.970032 -277.71413) (xy 284.021994 -277.72599)
			(xy 284.071608 -277.745462) (xy 284.117766 -277.772111) (xy 284.159437 -277.805342) (xy 284.195689 -277.844413)
			(xy 284.225713 -277.88845) (xy 284.248839 -277.936471) (xy 284.264549 -277.987401) (xy 284.272492 -278.040105)
			(xy 284.27299 -278.066754) (xy 284.272492 -278.093403) (xy 284.272454 -278.093657) (xy 298.674272 -278.093657)
			(xy 298.674272 -278.040359) (xy 298.682215 -277.987655) (xy 298.697925 -277.936725) (xy 298.721051 -277.888704)
			(xy 298.751075 -277.844667) (xy 298.787327 -277.805596) (xy 298.828998 -277.772365) (xy 298.875156 -277.745716)
			(xy 298.92477 -277.726244) (xy 298.976732 -277.714384) (xy 299.029882 -277.710401) (xy 299.083032 -277.714384)
			(xy 299.134994 -277.726244) (xy 299.184608 -277.745716) (xy 299.230766 -277.772365) (xy 299.272437 -277.805596)
			(xy 299.308689 -277.844667) (xy 299.338713 -277.888704) (xy 299.361839 -277.936725) (xy 299.377549 -277.987655)
			(xy 299.385492 -278.040359) (xy 299.38599 -278.067008) (xy 299.385492 -278.093657) (xy 299.377549 -278.146361)
			(xy 299.361839 -278.197291) (xy 299.338713 -278.245312) (xy 299.308689 -278.289349) (xy 299.272437 -278.32842)
			(xy 299.230766 -278.361651) (xy 299.184608 -278.3883) (xy 299.134994 -278.407772) (xy 299.083032 -278.419632)
			(xy 299.029882 -278.423616) (xy 298.976732 -278.419632) (xy 298.92477 -278.407772) (xy 298.875156 -278.3883)
			(xy 298.828998 -278.361651) (xy 298.787327 -278.32842) (xy 298.751075 -278.289349) (xy 298.721051 -278.245312)
			(xy 298.697925 -278.197291) (xy 298.682215 -278.146361) (xy 298.674272 -278.093657) (xy 284.272454 -278.093657)
			(xy 284.264549 -278.146107) (xy 284.248839 -278.197037) (xy 284.225713 -278.245058) (xy 284.195689 -278.289095)
			(xy 284.159437 -278.328166) (xy 284.117766 -278.361397) (xy 284.071608 -278.388046) (xy 284.021994 -278.407518)
			(xy 283.970032 -278.419378) (xy 283.916882 -278.423362) (xy 283.863732 -278.419378) (xy 283.81177 -278.407518)
			(xy 283.762156 -278.388046) (xy 283.715998 -278.361397) (xy 283.674327 -278.328166) (xy 283.638075 -278.289095)
			(xy 283.608051 -278.245058) (xy 283.584925 -278.197037) (xy 283.569215 -278.146107) (xy 283.561272 -278.093403)
			(xy 269.184892 -278.093403) (xy 269.176949 -278.146107) (xy 269.161239 -278.197037) (xy 269.138113 -278.245058)
			(xy 269.108089 -278.289095) (xy 269.071837 -278.328166) (xy 269.030166 -278.361397) (xy 268.984008 -278.388046)
			(xy 268.934394 -278.407518) (xy 268.882432 -278.419378) (xy 268.829282 -278.423362) (xy 268.776132 -278.419378)
			(xy 268.72417 -278.407518) (xy 268.674556 -278.388046) (xy 268.628398 -278.361397) (xy 268.586727 -278.328166)
			(xy 268.550475 -278.289095) (xy 268.520451 -278.245058) (xy 268.497325 -278.197037) (xy 268.481615 -278.146107)
			(xy 268.473672 -278.093403) (xy 254.20828 -278.093403) (xy 254.20828 -278.943287) (xy 264.373604 -278.943287)
			(xy 264.373604 -278.889989) (xy 264.381547 -278.837285) (xy 264.397257 -278.786355) (xy 264.420383 -278.738334)
			(xy 264.450407 -278.694297) (xy 264.486659 -278.655226) (xy 264.52833 -278.621995) (xy 264.574488 -278.595346)
			(xy 264.624102 -278.575874) (xy 264.676064 -278.564014) (xy 264.729214 -278.560031) (xy 264.782364 -278.564014)
			(xy 264.834326 -278.575874) (xy 264.88394 -278.595346) (xy 264.930098 -278.621995) (xy 264.971769 -278.655226)
			(xy 265.008021 -278.694297) (xy 265.038045 -278.738334) (xy 265.061171 -278.786355) (xy 265.076881 -278.837285)
			(xy 265.084824 -278.889989) (xy 265.085322 -278.916638) (xy 265.084824 -278.943287) (xy 279.461204 -278.943287)
			(xy 279.461204 -278.889989) (xy 279.469147 -278.837285) (xy 279.484857 -278.786355) (xy 279.507983 -278.738334)
			(xy 279.538007 -278.694297) (xy 279.574259 -278.655226) (xy 279.61593 -278.621995) (xy 279.662088 -278.595346)
			(xy 279.711702 -278.575874) (xy 279.763664 -278.564014) (xy 279.816814 -278.560031) (xy 279.869964 -278.564014)
			(xy 279.921926 -278.575874) (xy 279.97154 -278.595346) (xy 280.017698 -278.621995) (xy 280.059369 -278.655226)
			(xy 280.095621 -278.694297) (xy 280.125645 -278.738334) (xy 280.148771 -278.786355) (xy 280.164481 -278.837285)
			(xy 280.172424 -278.889989) (xy 280.172922 -278.916638) (xy 280.172424 -278.943287) (xy 294.548804 -278.943287)
			(xy 294.548804 -278.889989) (xy 294.556747 -278.837285) (xy 294.572457 -278.786355) (xy 294.595583 -278.738334)
			(xy 294.625607 -278.694297) (xy 294.661859 -278.655226) (xy 294.70353 -278.621995) (xy 294.749688 -278.595346)
			(xy 294.799302 -278.575874) (xy 294.851264 -278.564014) (xy 294.904414 -278.560031) (xy 294.957564 -278.564014)
			(xy 295.009526 -278.575874) (xy 295.05914 -278.595346) (xy 295.105298 -278.621995) (xy 295.146969 -278.655226)
			(xy 295.183221 -278.694297) (xy 295.213245 -278.738334) (xy 295.236371 -278.786355) (xy 295.252081 -278.837285)
			(xy 295.260024 -278.889989) (xy 295.260522 -278.916638) (xy 295.260024 -278.943287) (xy 295.252081 -278.995991)
			(xy 295.236371 -279.046921) (xy 295.213245 -279.094942) (xy 295.183221 -279.138979) (xy 295.146969 -279.17805)
			(xy 295.105298 -279.211281) (xy 295.05914 -279.23793) (xy 295.009526 -279.257402) (xy 294.957564 -279.269262)
			(xy 294.904414 -279.273246) (xy 294.851264 -279.269262) (xy 294.799302 -279.257402) (xy 294.749688 -279.23793)
			(xy 294.70353 -279.211281) (xy 294.661859 -279.17805) (xy 294.625607 -279.138979) (xy 294.595583 -279.094942)
			(xy 294.572457 -279.046921) (xy 294.556747 -278.995991) (xy 294.548804 -278.943287) (xy 280.172424 -278.943287)
			(xy 280.164481 -278.995991) (xy 280.148771 -279.046921) (xy 280.125645 -279.094942) (xy 280.095621 -279.138979)
			(xy 280.059369 -279.17805) (xy 280.017698 -279.211281) (xy 279.97154 -279.23793) (xy 279.921926 -279.257402)
			(xy 279.869964 -279.269262) (xy 279.816814 -279.273246) (xy 279.763664 -279.269262) (xy 279.711702 -279.257402)
			(xy 279.662088 -279.23793) (xy 279.61593 -279.211281) (xy 279.574259 -279.17805) (xy 279.538007 -279.138979)
			(xy 279.507983 -279.094942) (xy 279.484857 -279.046921) (xy 279.469147 -278.995991) (xy 279.461204 -278.943287)
			(xy 265.084824 -278.943287) (xy 265.076881 -278.995991) (xy 265.061171 -279.046921) (xy 265.038045 -279.094942)
			(xy 265.008021 -279.138979) (xy 264.971769 -279.17805) (xy 264.930098 -279.211281) (xy 264.88394 -279.23793)
			(xy 264.834326 -279.257402) (xy 264.782364 -279.269262) (xy 264.729214 -279.273246) (xy 264.676064 -279.269262)
			(xy 264.624102 -279.257402) (xy 264.574488 -279.23793) (xy 264.52833 -279.211281) (xy 264.486659 -279.17805)
			(xy 264.450407 -279.138979) (xy 264.420383 -279.094942) (xy 264.397257 -279.046921) (xy 264.381547 -278.995991)
			(xy 264.373604 -278.943287) (xy 254.20828 -278.943287) (xy 254.20828 -279.793425) (xy 268.473672 -279.793425)
			(xy 268.473672 -279.740127) (xy 268.481615 -279.687423) (xy 268.497325 -279.636493) (xy 268.520451 -279.588472)
			(xy 268.550475 -279.544435) (xy 268.586727 -279.505364) (xy 268.628398 -279.472133) (xy 268.674556 -279.445484)
			(xy 268.72417 -279.426012) (xy 268.776132 -279.414152) (xy 268.829282 -279.410169) (xy 268.882432 -279.414152)
			(xy 268.934394 -279.426012) (xy 268.984008 -279.445484) (xy 269.030166 -279.472133) (xy 269.071837 -279.505364)
			(xy 269.108089 -279.544435) (xy 269.138113 -279.588472) (xy 269.161239 -279.636493) (xy 269.176949 -279.687423)
			(xy 269.184892 -279.740127) (xy 269.18539 -279.766776) (xy 269.184892 -279.793425) (xy 283.561272 -279.793425)
			(xy 283.561272 -279.740127) (xy 283.569215 -279.687423) (xy 283.584925 -279.636493) (xy 283.608051 -279.588472)
			(xy 283.638075 -279.544435) (xy 283.674327 -279.505364) (xy 283.715998 -279.472133) (xy 283.762156 -279.445484)
			(xy 283.81177 -279.426012) (xy 283.863732 -279.414152) (xy 283.916882 -279.410169) (xy 283.970032 -279.414152)
			(xy 284.021994 -279.426012) (xy 284.071608 -279.445484) (xy 284.117766 -279.472133) (xy 284.159437 -279.505364)
			(xy 284.195689 -279.544435) (xy 284.225713 -279.588472) (xy 284.248839 -279.636493) (xy 284.264549 -279.687423)
			(xy 284.272492 -279.740127) (xy 284.27299 -279.766776) (xy 284.272492 -279.793425) (xy 298.674272 -279.793425)
			(xy 298.674272 -279.740127) (xy 298.682215 -279.687423) (xy 298.697925 -279.636493) (xy 298.721051 -279.588472)
			(xy 298.751075 -279.544435) (xy 298.787327 -279.505364) (xy 298.828998 -279.472133) (xy 298.875156 -279.445484)
			(xy 298.92477 -279.426012) (xy 298.976732 -279.414152) (xy 299.029882 -279.410169) (xy 299.083032 -279.414152)
			(xy 299.134994 -279.426012) (xy 299.184608 -279.445484) (xy 299.230766 -279.472133) (xy 299.272437 -279.505364)
			(xy 299.308689 -279.544435) (xy 299.338713 -279.588472) (xy 299.361839 -279.636493) (xy 299.377549 -279.687423)
			(xy 299.385492 -279.740127) (xy 299.38599 -279.766776) (xy 299.385492 -279.793425) (xy 299.377549 -279.846129)
			(xy 299.361839 -279.897059) (xy 299.338713 -279.94508) (xy 299.308689 -279.989117) (xy 299.272437 -280.028188)
			(xy 299.230766 -280.061419) (xy 299.184608 -280.088068) (xy 299.134994 -280.10754) (xy 299.083032 -280.1194)
			(xy 299.029882 -280.123384) (xy 298.976732 -280.1194) (xy 298.92477 -280.10754) (xy 298.875156 -280.088068)
			(xy 298.828998 -280.061419) (xy 298.787327 -280.028188) (xy 298.751075 -279.989117) (xy 298.721051 -279.94508)
			(xy 298.697925 -279.897059) (xy 298.682215 -279.846129) (xy 298.674272 -279.793425) (xy 284.272492 -279.793425)
			(xy 284.264549 -279.846129) (xy 284.248839 -279.897059) (xy 284.225713 -279.94508) (xy 284.195689 -279.989117)
			(xy 284.159437 -280.028188) (xy 284.117766 -280.061419) (xy 284.071608 -280.088068) (xy 284.021994 -280.10754)
			(xy 283.970032 -280.1194) (xy 283.916882 -280.123384) (xy 283.863732 -280.1194) (xy 283.81177 -280.10754)
			(xy 283.762156 -280.088068) (xy 283.715998 -280.061419) (xy 283.674327 -280.028188) (xy 283.638075 -279.989117)
			(xy 283.608051 -279.94508) (xy 283.584925 -279.897059) (xy 283.569215 -279.846129) (xy 283.561272 -279.793425)
			(xy 269.184892 -279.793425) (xy 269.176949 -279.846129) (xy 269.161239 -279.897059) (xy 269.138113 -279.94508)
			(xy 269.108089 -279.989117) (xy 269.071837 -280.028188) (xy 269.030166 -280.061419) (xy 268.984008 -280.088068)
			(xy 268.934394 -280.10754) (xy 268.882432 -280.1194) (xy 268.829282 -280.123384) (xy 268.776132 -280.1194)
			(xy 268.72417 -280.10754) (xy 268.674556 -280.088068) (xy 268.628398 -280.061419) (xy 268.586727 -280.028188)
			(xy 268.550475 -279.989117) (xy 268.520451 -279.94508) (xy 268.497325 -279.897059) (xy 268.481615 -279.846129)
			(xy 268.473672 -279.793425) (xy 254.20828 -279.793425) (xy 254.20828 -280.643309) (xy 264.373604 -280.643309)
			(xy 264.373604 -280.590011) (xy 264.381547 -280.537307) (xy 264.397257 -280.486377) (xy 264.420383 -280.438356)
			(xy 264.450407 -280.394319) (xy 264.486659 -280.355248) (xy 264.52833 -280.322017) (xy 264.574488 -280.295368)
			(xy 264.624102 -280.275896) (xy 264.676064 -280.264036) (xy 264.729214 -280.260053) (xy 264.782364 -280.264036)
			(xy 264.834326 -280.275896) (xy 264.88394 -280.295368) (xy 264.930098 -280.322017) (xy 264.971769 -280.355248)
			(xy 265.008021 -280.394319) (xy 265.038045 -280.438356) (xy 265.061171 -280.486377) (xy 265.076881 -280.537307)
			(xy 265.084824 -280.590011) (xy 265.085322 -280.61666) (xy 265.084824 -280.643309) (xy 279.461204 -280.643309)
			(xy 279.461204 -280.590011) (xy 279.469147 -280.537307) (xy 279.484857 -280.486377) (xy 279.507983 -280.438356)
			(xy 279.538007 -280.394319) (xy 279.574259 -280.355248) (xy 279.61593 -280.322017) (xy 279.662088 -280.295368)
			(xy 279.711702 -280.275896) (xy 279.763664 -280.264036) (xy 279.816814 -280.260053) (xy 279.869964 -280.264036)
			(xy 279.921926 -280.275896) (xy 279.97154 -280.295368) (xy 280.017698 -280.322017) (xy 280.059369 -280.355248)
			(xy 280.095621 -280.394319) (xy 280.125645 -280.438356) (xy 280.148771 -280.486377) (xy 280.164481 -280.537307)
			(xy 280.172424 -280.590011) (xy 280.172922 -280.61666) (xy 280.172424 -280.643309) (xy 294.548804 -280.643309)
			(xy 294.548804 -280.590011) (xy 294.556747 -280.537307) (xy 294.572457 -280.486377) (xy 294.595583 -280.438356)
			(xy 294.625607 -280.394319) (xy 294.661859 -280.355248) (xy 294.70353 -280.322017) (xy 294.749688 -280.295368)
			(xy 294.799302 -280.275896) (xy 294.851264 -280.264036) (xy 294.904414 -280.260053) (xy 294.957564 -280.264036)
			(xy 295.009526 -280.275896) (xy 295.05914 -280.295368) (xy 295.105298 -280.322017) (xy 295.146969 -280.355248)
			(xy 295.183221 -280.394319) (xy 295.213245 -280.438356) (xy 295.236371 -280.486377) (xy 295.252081 -280.537307)
			(xy 295.260024 -280.590011) (xy 295.260522 -280.61666) (xy 295.260024 -280.643309) (xy 295.252081 -280.696013)
			(xy 295.236371 -280.746943) (xy 295.213245 -280.794964) (xy 295.183221 -280.839001) (xy 295.146969 -280.878072)
			(xy 295.105298 -280.911303) (xy 295.05914 -280.937952) (xy 295.009526 -280.957424) (xy 294.957564 -280.969284)
			(xy 294.904414 -280.973268) (xy 294.851264 -280.969284) (xy 294.799302 -280.957424) (xy 294.749688 -280.937952)
			(xy 294.70353 -280.911303) (xy 294.661859 -280.878072) (xy 294.625607 -280.839001) (xy 294.595583 -280.794964)
			(xy 294.572457 -280.746943) (xy 294.556747 -280.696013) (xy 294.548804 -280.643309) (xy 280.172424 -280.643309)
			(xy 280.164481 -280.696013) (xy 280.148771 -280.746943) (xy 280.125645 -280.794964) (xy 280.095621 -280.839001)
			(xy 280.059369 -280.878072) (xy 280.017698 -280.911303) (xy 279.97154 -280.937952) (xy 279.921926 -280.957424)
			(xy 279.869964 -280.969284) (xy 279.816814 -280.973268) (xy 279.763664 -280.969284) (xy 279.711702 -280.957424)
			(xy 279.662088 -280.937952) (xy 279.61593 -280.911303) (xy 279.574259 -280.878072) (xy 279.538007 -280.839001)
			(xy 279.507983 -280.794964) (xy 279.484857 -280.746943) (xy 279.469147 -280.696013) (xy 279.461204 -280.643309)
			(xy 265.084824 -280.643309) (xy 265.076881 -280.696013) (xy 265.061171 -280.746943) (xy 265.038045 -280.794964)
			(xy 265.008021 -280.839001) (xy 264.971769 -280.878072) (xy 264.930098 -280.911303) (xy 264.88394 -280.937952)
			(xy 264.834326 -280.957424) (xy 264.782364 -280.969284) (xy 264.729214 -280.973268) (xy 264.676064 -280.969284)
			(xy 264.624102 -280.957424) (xy 264.574488 -280.937952) (xy 264.52833 -280.911303) (xy 264.486659 -280.878072)
			(xy 264.450407 -280.839001) (xy 264.420383 -280.794964) (xy 264.397257 -280.746943) (xy 264.381547 -280.696013)
			(xy 264.373604 -280.643309) (xy 254.20828 -280.643309) (xy 254.20828 -281.493447) (xy 268.473672 -281.493447)
			(xy 268.473672 -281.440149) (xy 268.481615 -281.387445) (xy 268.497325 -281.336515) (xy 268.520451 -281.288494)
			(xy 268.550475 -281.244457) (xy 268.586727 -281.205386) (xy 268.628398 -281.172155) (xy 268.674556 -281.145506)
			(xy 268.72417 -281.126034) (xy 268.776132 -281.114174) (xy 268.829282 -281.110191) (xy 268.882432 -281.114174)
			(xy 268.934394 -281.126034) (xy 268.984008 -281.145506) (xy 269.030166 -281.172155) (xy 269.071837 -281.205386)
			(xy 269.108089 -281.244457) (xy 269.138113 -281.288494) (xy 269.161239 -281.336515) (xy 269.176949 -281.387445)
			(xy 269.184892 -281.440149) (xy 269.18539 -281.466798) (xy 269.184892 -281.493447) (xy 283.561272 -281.493447)
			(xy 283.561272 -281.440149) (xy 283.569215 -281.387445) (xy 283.584925 -281.336515) (xy 283.608051 -281.288494)
			(xy 283.638075 -281.244457) (xy 283.674327 -281.205386) (xy 283.715998 -281.172155) (xy 283.762156 -281.145506)
			(xy 283.81177 -281.126034) (xy 283.863732 -281.114174) (xy 283.916882 -281.110191) (xy 283.970032 -281.114174)
			(xy 284.021994 -281.126034) (xy 284.071608 -281.145506) (xy 284.117766 -281.172155) (xy 284.159437 -281.205386)
			(xy 284.195689 -281.244457) (xy 284.225713 -281.288494) (xy 284.248839 -281.336515) (xy 284.264549 -281.387445)
			(xy 284.272492 -281.440149) (xy 284.27299 -281.466798) (xy 284.272492 -281.493447) (xy 298.674272 -281.493447)
			(xy 298.674272 -281.440149) (xy 298.682215 -281.387445) (xy 298.697925 -281.336515) (xy 298.721051 -281.288494)
			(xy 298.751075 -281.244457) (xy 298.787327 -281.205386) (xy 298.828998 -281.172155) (xy 298.875156 -281.145506)
			(xy 298.92477 -281.126034) (xy 298.976732 -281.114174) (xy 299.029882 -281.110191) (xy 299.083032 -281.114174)
			(xy 299.134994 -281.126034) (xy 299.184608 -281.145506) (xy 299.230766 -281.172155) (xy 299.272437 -281.205386)
			(xy 299.308689 -281.244457) (xy 299.338713 -281.288494) (xy 299.361839 -281.336515) (xy 299.377549 -281.387445)
			(xy 299.385492 -281.440149) (xy 299.38599 -281.466798) (xy 299.385492 -281.493447) (xy 299.377549 -281.546151)
			(xy 299.361839 -281.597081) (xy 299.338713 -281.645102) (xy 299.308689 -281.689139) (xy 299.272437 -281.72821)
			(xy 299.230766 -281.761441) (xy 299.184608 -281.78809) (xy 299.134994 -281.807562) (xy 299.083032 -281.819422)
			(xy 299.029882 -281.823406) (xy 298.976732 -281.819422) (xy 298.92477 -281.807562) (xy 298.875156 -281.78809)
			(xy 298.828998 -281.761441) (xy 298.787327 -281.72821) (xy 298.751075 -281.689139) (xy 298.721051 -281.645102)
			(xy 298.697925 -281.597081) (xy 298.682215 -281.546151) (xy 298.674272 -281.493447) (xy 284.272492 -281.493447)
			(xy 284.264549 -281.546151) (xy 284.248839 -281.597081) (xy 284.225713 -281.645102) (xy 284.195689 -281.689139)
			(xy 284.159437 -281.72821) (xy 284.117766 -281.761441) (xy 284.071608 -281.78809) (xy 284.021994 -281.807562)
			(xy 283.970032 -281.819422) (xy 283.916882 -281.823406) (xy 283.863732 -281.819422) (xy 283.81177 -281.807562)
			(xy 283.762156 -281.78809) (xy 283.715998 -281.761441) (xy 283.674327 -281.72821) (xy 283.638075 -281.689139)
			(xy 283.608051 -281.645102) (xy 283.584925 -281.597081) (xy 283.569215 -281.546151) (xy 283.561272 -281.493447)
			(xy 269.184892 -281.493447) (xy 269.176949 -281.546151) (xy 269.161239 -281.597081) (xy 269.138113 -281.645102)
			(xy 269.108089 -281.689139) (xy 269.071837 -281.72821) (xy 269.030166 -281.761441) (xy 268.984008 -281.78809)
			(xy 268.934394 -281.807562) (xy 268.882432 -281.819422) (xy 268.829282 -281.823406) (xy 268.776132 -281.819422)
			(xy 268.72417 -281.807562) (xy 268.674556 -281.78809) (xy 268.628398 -281.761441) (xy 268.586727 -281.72821)
			(xy 268.550475 -281.689139) (xy 268.520451 -281.645102) (xy 268.497325 -281.597081) (xy 268.481615 -281.546151)
			(xy 268.473672 -281.493447) (xy 254.20828 -281.493447) (xy 254.20828 -282.343331) (xy 264.373604 -282.343331)
			(xy 264.373604 -282.290033) (xy 264.381547 -282.237329) (xy 264.397257 -282.186399) (xy 264.420383 -282.138378)
			(xy 264.450407 -282.094341) (xy 264.486659 -282.05527) (xy 264.52833 -282.022039) (xy 264.574488 -281.99539)
			(xy 264.624102 -281.975918) (xy 264.676064 -281.964058) (xy 264.729214 -281.960075) (xy 264.782364 -281.964058)
			(xy 264.834326 -281.975918) (xy 264.88394 -281.99539) (xy 264.930098 -282.022039) (xy 264.971769 -282.05527)
			(xy 265.008021 -282.094341) (xy 265.038045 -282.138378) (xy 265.061171 -282.186399) (xy 265.076881 -282.237329)
			(xy 265.084824 -282.290033) (xy 265.085322 -282.316682) (xy 265.084824 -282.343331) (xy 279.461204 -282.343331)
			(xy 279.461204 -282.290033) (xy 279.469147 -282.237329) (xy 279.484857 -282.186399) (xy 279.507983 -282.138378)
			(xy 279.538007 -282.094341) (xy 279.574259 -282.05527) (xy 279.61593 -282.022039) (xy 279.662088 -281.99539)
			(xy 279.711702 -281.975918) (xy 279.763664 -281.964058) (xy 279.816814 -281.960075) (xy 279.869964 -281.964058)
			(xy 279.921926 -281.975918) (xy 279.97154 -281.99539) (xy 280.017698 -282.022039) (xy 280.059369 -282.05527)
			(xy 280.095621 -282.094341) (xy 280.125645 -282.138378) (xy 280.148771 -282.186399) (xy 280.164481 -282.237329)
			(xy 280.172424 -282.290033) (xy 280.172922 -282.316682) (xy 280.172424 -282.343331) (xy 294.548804 -282.343331)
			(xy 294.548804 -282.290033) (xy 294.556747 -282.237329) (xy 294.572457 -282.186399) (xy 294.595583 -282.138378)
			(xy 294.625607 -282.094341) (xy 294.661859 -282.05527) (xy 294.70353 -282.022039) (xy 294.749688 -281.99539)
			(xy 294.799302 -281.975918) (xy 294.851264 -281.964058) (xy 294.904414 -281.960075) (xy 294.957564 -281.964058)
			(xy 295.009526 -281.975918) (xy 295.05914 -281.99539) (xy 295.105298 -282.022039) (xy 295.146969 -282.05527)
			(xy 295.183221 -282.094341) (xy 295.213245 -282.138378) (xy 295.236371 -282.186399) (xy 295.252081 -282.237329)
			(xy 295.260024 -282.290033) (xy 295.260522 -282.316682) (xy 295.260024 -282.343331) (xy 295.252081 -282.396035)
			(xy 295.236371 -282.446965) (xy 295.213245 -282.494986) (xy 295.183221 -282.539023) (xy 295.146969 -282.578094)
			(xy 295.105298 -282.611325) (xy 295.05914 -282.637974) (xy 295.009526 -282.657446) (xy 294.957564 -282.669306)
			(xy 294.904414 -282.67329) (xy 294.851264 -282.669306) (xy 294.799302 -282.657446) (xy 294.749688 -282.637974)
			(xy 294.70353 -282.611325) (xy 294.661859 -282.578094) (xy 294.625607 -282.539023) (xy 294.595583 -282.494986)
			(xy 294.572457 -282.446965) (xy 294.556747 -282.396035) (xy 294.548804 -282.343331) (xy 280.172424 -282.343331)
			(xy 280.164481 -282.396035) (xy 280.148771 -282.446965) (xy 280.125645 -282.494986) (xy 280.095621 -282.539023)
			(xy 280.059369 -282.578094) (xy 280.017698 -282.611325) (xy 279.97154 -282.637974) (xy 279.921926 -282.657446)
			(xy 279.869964 -282.669306) (xy 279.816814 -282.67329) (xy 279.763664 -282.669306) (xy 279.711702 -282.657446)
			(xy 279.662088 -282.637974) (xy 279.61593 -282.611325) (xy 279.574259 -282.578094) (xy 279.538007 -282.539023)
			(xy 279.507983 -282.494986) (xy 279.484857 -282.446965) (xy 279.469147 -282.396035) (xy 279.461204 -282.343331)
			(xy 265.084824 -282.343331) (xy 265.076881 -282.396035) (xy 265.061171 -282.446965) (xy 265.038045 -282.494986)
			(xy 265.008021 -282.539023) (xy 264.971769 -282.578094) (xy 264.930098 -282.611325) (xy 264.88394 -282.637974)
			(xy 264.834326 -282.657446) (xy 264.782364 -282.669306) (xy 264.729214 -282.67329) (xy 264.676064 -282.669306)
			(xy 264.624102 -282.657446) (xy 264.574488 -282.637974) (xy 264.52833 -282.611325) (xy 264.486659 -282.578094)
			(xy 264.450407 -282.539023) (xy 264.420383 -282.494986) (xy 264.397257 -282.446965) (xy 264.381547 -282.396035)
			(xy 264.373604 -282.343331) (xy 254.20828 -282.343331) (xy 254.20828 -283.193215) (xy 268.473672 -283.193215)
			(xy 268.473672 -283.139917) (xy 268.481615 -283.087213) (xy 268.497325 -283.036283) (xy 268.520451 -282.988262)
			(xy 268.550475 -282.944225) (xy 268.586727 -282.905154) (xy 268.628398 -282.871923) (xy 268.674556 -282.845274)
			(xy 268.72417 -282.825802) (xy 268.776132 -282.813942) (xy 268.829282 -282.809959) (xy 268.882432 -282.813942)
			(xy 268.934394 -282.825802) (xy 268.984008 -282.845274) (xy 269.030166 -282.871923) (xy 269.071837 -282.905154)
			(xy 269.108089 -282.944225) (xy 269.138113 -282.988262) (xy 269.161239 -283.036283) (xy 269.176949 -283.087213)
			(xy 269.184892 -283.139917) (xy 269.18539 -283.166566) (xy 269.184892 -283.193215) (xy 283.561272 -283.193215)
			(xy 283.561272 -283.139917) (xy 283.569215 -283.087213) (xy 283.584925 -283.036283) (xy 283.608051 -282.988262)
			(xy 283.638075 -282.944225) (xy 283.674327 -282.905154) (xy 283.715998 -282.871923) (xy 283.762156 -282.845274)
			(xy 283.81177 -282.825802) (xy 283.863732 -282.813942) (xy 283.916882 -282.809959) (xy 283.970032 -282.813942)
			(xy 284.021994 -282.825802) (xy 284.071608 -282.845274) (xy 284.117766 -282.871923) (xy 284.159437 -282.905154)
			(xy 284.195689 -282.944225) (xy 284.225713 -282.988262) (xy 284.248839 -283.036283) (xy 284.264549 -283.087213)
			(xy 284.272492 -283.139917) (xy 284.27299 -283.166566) (xy 284.272492 -283.193215) (xy 284.272454 -283.193469)
			(xy 298.674272 -283.193469) (xy 298.674272 -283.140171) (xy 298.682215 -283.087467) (xy 298.697925 -283.036537)
			(xy 298.721051 -282.988516) (xy 298.751075 -282.944479) (xy 298.787327 -282.905408) (xy 298.828998 -282.872177)
			(xy 298.875156 -282.845528) (xy 298.92477 -282.826056) (xy 298.976732 -282.814196) (xy 299.029882 -282.810213)
			(xy 299.083032 -282.814196) (xy 299.134994 -282.826056) (xy 299.184608 -282.845528) (xy 299.230766 -282.872177)
			(xy 299.272437 -282.905408) (xy 299.308689 -282.944479) (xy 299.338713 -282.988516) (xy 299.361839 -283.036537)
			(xy 299.377549 -283.087467) (xy 299.385492 -283.140171) (xy 299.38599 -283.16682) (xy 299.385492 -283.193469)
			(xy 299.377549 -283.246173) (xy 299.361839 -283.297103) (xy 299.338713 -283.345124) (xy 299.308689 -283.389161)
			(xy 299.272437 -283.428232) (xy 299.230766 -283.461463) (xy 299.184608 -283.488112) (xy 299.134994 -283.507584)
			(xy 299.083032 -283.519444) (xy 299.029882 -283.523428) (xy 298.976732 -283.519444) (xy 298.92477 -283.507584)
			(xy 298.875156 -283.488112) (xy 298.828998 -283.461463) (xy 298.787327 -283.428232) (xy 298.751075 -283.389161)
			(xy 298.721051 -283.345124) (xy 298.697925 -283.297103) (xy 298.682215 -283.246173) (xy 298.674272 -283.193469)
			(xy 284.272454 -283.193469) (xy 284.264549 -283.245919) (xy 284.248839 -283.296849) (xy 284.225713 -283.34487)
			(xy 284.195689 -283.388907) (xy 284.159437 -283.427978) (xy 284.117766 -283.461209) (xy 284.071608 -283.487858)
			(xy 284.021994 -283.50733) (xy 283.970032 -283.51919) (xy 283.916882 -283.523174) (xy 283.863732 -283.51919)
			(xy 283.81177 -283.50733) (xy 283.762156 -283.487858) (xy 283.715998 -283.461209) (xy 283.674327 -283.427978)
			(xy 283.638075 -283.388907) (xy 283.608051 -283.34487) (xy 283.584925 -283.296849) (xy 283.569215 -283.245919)
			(xy 283.561272 -283.193215) (xy 269.184892 -283.193215) (xy 269.176949 -283.245919) (xy 269.161239 -283.296849)
			(xy 269.138113 -283.34487) (xy 269.108089 -283.388907) (xy 269.071837 -283.427978) (xy 269.030166 -283.461209)
			(xy 268.984008 -283.487858) (xy 268.934394 -283.50733) (xy 268.882432 -283.51919) (xy 268.829282 -283.523174)
			(xy 268.776132 -283.51919) (xy 268.72417 -283.50733) (xy 268.674556 -283.487858) (xy 268.628398 -283.461209)
			(xy 268.586727 -283.427978) (xy 268.550475 -283.388907) (xy 268.520451 -283.34487) (xy 268.497325 -283.296849)
			(xy 268.481615 -283.245919) (xy 268.473672 -283.193215) (xy 254.20828 -283.193215) (xy 254.20828 -284.043353)
			(xy 264.373604 -284.043353) (xy 264.373604 -283.990055) (xy 264.381547 -283.937351) (xy 264.397257 -283.886421)
			(xy 264.420383 -283.8384) (xy 264.450407 -283.794363) (xy 264.486659 -283.755292) (xy 264.52833 -283.722061)
			(xy 264.574488 -283.695412) (xy 264.624102 -283.67594) (xy 264.676064 -283.66408) (xy 264.729214 -283.660097)
			(xy 264.782364 -283.66408) (xy 264.834326 -283.67594) (xy 264.88394 -283.695412) (xy 264.930098 -283.722061)
			(xy 264.971769 -283.755292) (xy 265.008021 -283.794363) (xy 265.038045 -283.8384) (xy 265.061171 -283.886421)
			(xy 265.076881 -283.937351) (xy 265.084824 -283.990055) (xy 265.085322 -284.016704) (xy 265.084824 -284.043353)
			(xy 268.473672 -284.043353) (xy 268.473672 -283.990055) (xy 268.481615 -283.937351) (xy 268.497325 -283.886421)
			(xy 268.520451 -283.8384) (xy 268.550475 -283.794363) (xy 268.586727 -283.755292) (xy 268.628398 -283.722061)
			(xy 268.674556 -283.695412) (xy 268.72417 -283.67594) (xy 268.776132 -283.66408) (xy 268.829282 -283.660097)
			(xy 268.882432 -283.66408) (xy 268.934394 -283.67594) (xy 268.984008 -283.695412) (xy 269.030166 -283.722061)
			(xy 269.071837 -283.755292) (xy 269.108089 -283.794363) (xy 269.138113 -283.8384) (xy 269.161239 -283.886421)
			(xy 269.176949 -283.937351) (xy 269.184892 -283.990055) (xy 269.18539 -284.016704) (xy 269.184892 -284.043353)
			(xy 279.461204 -284.043353) (xy 279.461204 -283.990055) (xy 279.469147 -283.937351) (xy 279.484857 -283.886421)
			(xy 279.507983 -283.8384) (xy 279.538007 -283.794363) (xy 279.574259 -283.755292) (xy 279.61593 -283.722061)
			(xy 279.662088 -283.695412) (xy 279.711702 -283.67594) (xy 279.763664 -283.66408) (xy 279.816814 -283.660097)
			(xy 279.869964 -283.66408) (xy 279.921926 -283.67594) (xy 279.97154 -283.695412) (xy 280.017698 -283.722061)
			(xy 280.059369 -283.755292) (xy 280.095621 -283.794363) (xy 280.125645 -283.8384) (xy 280.148771 -283.886421)
			(xy 280.164481 -283.937351) (xy 280.172424 -283.990055) (xy 280.172922 -284.016704) (xy 280.172424 -284.043353)
			(xy 283.561272 -284.043353) (xy 283.561272 -283.990055) (xy 283.569215 -283.937351) (xy 283.584925 -283.886421)
			(xy 283.608051 -283.8384) (xy 283.638075 -283.794363) (xy 283.674327 -283.755292) (xy 283.715998 -283.722061)
			(xy 283.762156 -283.695412) (xy 283.81177 -283.67594) (xy 283.863732 -283.66408) (xy 283.916882 -283.660097)
			(xy 283.970032 -283.66408) (xy 284.021994 -283.67594) (xy 284.071608 -283.695412) (xy 284.117766 -283.722061)
			(xy 284.159437 -283.755292) (xy 284.195689 -283.794363) (xy 284.225713 -283.8384) (xy 284.248839 -283.886421)
			(xy 284.264549 -283.937351) (xy 284.272492 -283.990055) (xy 284.27299 -284.016704) (xy 284.272492 -284.043353)
			(xy 294.548804 -284.043353) (xy 294.548804 -283.990055) (xy 294.556747 -283.937351) (xy 294.572457 -283.886421)
			(xy 294.595583 -283.8384) (xy 294.625607 -283.794363) (xy 294.661859 -283.755292) (xy 294.70353 -283.722061)
			(xy 294.749688 -283.695412) (xy 294.799302 -283.67594) (xy 294.851264 -283.66408) (xy 294.904414 -283.660097)
			(xy 294.957564 -283.66408) (xy 295.009526 -283.67594) (xy 295.05914 -283.695412) (xy 295.105298 -283.722061)
			(xy 295.146969 -283.755292) (xy 295.183221 -283.794363) (xy 295.213245 -283.8384) (xy 295.236371 -283.886421)
			(xy 295.252081 -283.937351) (xy 295.260024 -283.990055) (xy 295.260522 -284.016704) (xy 295.260024 -284.043353)
			(xy 295.259986 -284.043607) (xy 298.674272 -284.043607) (xy 298.674272 -283.990309) (xy 298.682215 -283.937605)
			(xy 298.697925 -283.886675) (xy 298.721051 -283.838654) (xy 298.751075 -283.794617) (xy 298.787327 -283.755546)
			(xy 298.828998 -283.722315) (xy 298.875156 -283.695666) (xy 298.92477 -283.676194) (xy 298.976732 -283.664334)
			(xy 299.029882 -283.660351) (xy 299.083032 -283.664334) (xy 299.134994 -283.676194) (xy 299.184608 -283.695666)
			(xy 299.230766 -283.722315) (xy 299.272437 -283.755546) (xy 299.308689 -283.794617) (xy 299.338713 -283.838654)
			(xy 299.361839 -283.886675) (xy 299.377549 -283.937605) (xy 299.385492 -283.990309) (xy 299.38599 -284.016958)
			(xy 299.385492 -284.043607) (xy 299.377549 -284.096311) (xy 299.361839 -284.147241) (xy 299.338713 -284.195262)
			(xy 299.308689 -284.239299) (xy 299.272437 -284.27837) (xy 299.230766 -284.311601) (xy 299.184608 -284.33825)
			(xy 299.134994 -284.357722) (xy 299.083032 -284.369582) (xy 299.029882 -284.373566) (xy 298.976732 -284.369582)
			(xy 298.92477 -284.357722) (xy 298.875156 -284.33825) (xy 298.828998 -284.311601) (xy 298.787327 -284.27837)
			(xy 298.751075 -284.239299) (xy 298.721051 -284.195262) (xy 298.697925 -284.147241) (xy 298.682215 -284.096311)
			(xy 298.674272 -284.043607) (xy 295.259986 -284.043607) (xy 295.252081 -284.096057) (xy 295.236371 -284.146987)
			(xy 295.213245 -284.195008) (xy 295.183221 -284.239045) (xy 295.146969 -284.278116) (xy 295.105298 -284.311347)
			(xy 295.05914 -284.337996) (xy 295.009526 -284.357468) (xy 294.957564 -284.369328) (xy 294.904414 -284.373312)
			(xy 294.851264 -284.369328) (xy 294.799302 -284.357468) (xy 294.749688 -284.337996) (xy 294.70353 -284.311347)
			(xy 294.661859 -284.278116) (xy 294.625607 -284.239045) (xy 294.595583 -284.195008) (xy 294.572457 -284.146987)
			(xy 294.556747 -284.096057) (xy 294.548804 -284.043353) (xy 284.272492 -284.043353) (xy 284.264549 -284.096057)
			(xy 284.248839 -284.146987) (xy 284.225713 -284.195008) (xy 284.195689 -284.239045) (xy 284.159437 -284.278116)
			(xy 284.117766 -284.311347) (xy 284.071608 -284.337996) (xy 284.021994 -284.357468) (xy 283.970032 -284.369328)
			(xy 283.916882 -284.373312) (xy 283.863732 -284.369328) (xy 283.81177 -284.357468) (xy 283.762156 -284.337996)
			(xy 283.715998 -284.311347) (xy 283.674327 -284.278116) (xy 283.638075 -284.239045) (xy 283.608051 -284.195008)
			(xy 283.584925 -284.146987) (xy 283.569215 -284.096057) (xy 283.561272 -284.043353) (xy 280.172424 -284.043353)
			(xy 280.164481 -284.096057) (xy 280.148771 -284.146987) (xy 280.125645 -284.195008) (xy 280.095621 -284.239045)
			(xy 280.059369 -284.278116) (xy 280.017698 -284.311347) (xy 279.97154 -284.337996) (xy 279.921926 -284.357468)
			(xy 279.869964 -284.369328) (xy 279.816814 -284.373312) (xy 279.763664 -284.369328) (xy 279.711702 -284.357468)
			(xy 279.662088 -284.337996) (xy 279.61593 -284.311347) (xy 279.574259 -284.278116) (xy 279.538007 -284.239045)
			(xy 279.507983 -284.195008) (xy 279.484857 -284.146987) (xy 279.469147 -284.096057) (xy 279.461204 -284.043353)
			(xy 269.184892 -284.043353) (xy 269.176949 -284.096057) (xy 269.161239 -284.146987) (xy 269.138113 -284.195008)
			(xy 269.108089 -284.239045) (xy 269.071837 -284.278116) (xy 269.030166 -284.311347) (xy 268.984008 -284.337996)
			(xy 268.934394 -284.357468) (xy 268.882432 -284.369328) (xy 268.829282 -284.373312) (xy 268.776132 -284.369328)
			(xy 268.72417 -284.357468) (xy 268.674556 -284.337996) (xy 268.628398 -284.311347) (xy 268.586727 -284.278116)
			(xy 268.550475 -284.239045) (xy 268.520451 -284.195008) (xy 268.497325 -284.146987) (xy 268.481615 -284.096057)
			(xy 268.473672 -284.043353) (xy 265.084824 -284.043353) (xy 265.076881 -284.096057) (xy 265.061171 -284.146987)
			(xy 265.038045 -284.195008) (xy 265.008021 -284.239045) (xy 264.971769 -284.278116) (xy 264.930098 -284.311347)
			(xy 264.88394 -284.337996) (xy 264.834326 -284.357468) (xy 264.782364 -284.369328) (xy 264.729214 -284.373312)
			(xy 264.676064 -284.369328) (xy 264.624102 -284.357468) (xy 264.574488 -284.337996) (xy 264.52833 -284.311347)
			(xy 264.486659 -284.278116) (xy 264.450407 -284.239045) (xy 264.420383 -284.195008) (xy 264.397257 -284.146987)
			(xy 264.381547 -284.096057) (xy 264.373604 -284.043353) (xy 254.20828 -284.043353) (xy 254.20828 -284.893237)
			(xy 264.373604 -284.893237) (xy 264.373604 -284.839939) (xy 264.381547 -284.787235) (xy 264.397257 -284.736305)
			(xy 264.420383 -284.688284) (xy 264.450407 -284.644247) (xy 264.486659 -284.605176) (xy 264.52833 -284.571945)
			(xy 264.574488 -284.545296) (xy 264.624102 -284.525824) (xy 264.676064 -284.513964) (xy 264.729214 -284.509981)
			(xy 264.782364 -284.513964) (xy 264.834326 -284.525824) (xy 264.88394 -284.545296) (xy 264.930098 -284.571945)
			(xy 264.971769 -284.605176) (xy 265.008021 -284.644247) (xy 265.038045 -284.688284) (xy 265.061171 -284.736305)
			(xy 265.076881 -284.787235) (xy 265.084824 -284.839939) (xy 265.085322 -284.866588) (xy 265.084824 -284.893237)
			(xy 279.461204 -284.893237) (xy 279.461204 -284.839939) (xy 279.469147 -284.787235) (xy 279.484857 -284.736305)
			(xy 279.507983 -284.688284) (xy 279.538007 -284.644247) (xy 279.574259 -284.605176) (xy 279.61593 -284.571945)
			(xy 279.662088 -284.545296) (xy 279.711702 -284.525824) (xy 279.763664 -284.513964) (xy 279.816814 -284.509981)
			(xy 279.869964 -284.513964) (xy 279.921926 -284.525824) (xy 279.97154 -284.545296) (xy 280.017698 -284.571945)
			(xy 280.059369 -284.605176) (xy 280.095621 -284.644247) (xy 280.125645 -284.688284) (xy 280.148771 -284.736305)
			(xy 280.164481 -284.787235) (xy 280.172424 -284.839939) (xy 280.172922 -284.866588) (xy 280.172424 -284.893237)
			(xy 294.548804 -284.893237) (xy 294.548804 -284.839939) (xy 294.556747 -284.787235) (xy 294.572457 -284.736305)
			(xy 294.595583 -284.688284) (xy 294.625607 -284.644247) (xy 294.661859 -284.605176) (xy 294.70353 -284.571945)
			(xy 294.749688 -284.545296) (xy 294.799302 -284.525824) (xy 294.851264 -284.513964) (xy 294.904414 -284.509981)
			(xy 294.957564 -284.513964) (xy 295.009526 -284.525824) (xy 295.05914 -284.545296) (xy 295.105298 -284.571945)
			(xy 295.146969 -284.605176) (xy 295.183221 -284.644247) (xy 295.213245 -284.688284) (xy 295.236371 -284.736305)
			(xy 295.252081 -284.787235) (xy 295.260024 -284.839939) (xy 295.260522 -284.866588) (xy 295.260024 -284.893237)
			(xy 295.252081 -284.945941) (xy 295.236371 -284.996871) (xy 295.213245 -285.044892) (xy 295.183221 -285.088929)
			(xy 295.146969 -285.128) (xy 295.105298 -285.161231) (xy 295.05914 -285.18788) (xy 295.009526 -285.207352)
			(xy 294.957564 -285.219212) (xy 294.904414 -285.223196) (xy 294.851264 -285.219212) (xy 294.799302 -285.207352)
			(xy 294.749688 -285.18788) (xy 294.70353 -285.161231) (xy 294.661859 -285.128) (xy 294.625607 -285.088929)
			(xy 294.595583 -285.044892) (xy 294.572457 -284.996871) (xy 294.556747 -284.945941) (xy 294.548804 -284.893237)
			(xy 280.172424 -284.893237) (xy 280.164481 -284.945941) (xy 280.148771 -284.996871) (xy 280.125645 -285.044892)
			(xy 280.095621 -285.088929) (xy 280.059369 -285.128) (xy 280.017698 -285.161231) (xy 279.97154 -285.18788)
			(xy 279.921926 -285.207352) (xy 279.869964 -285.219212) (xy 279.816814 -285.223196) (xy 279.763664 -285.219212)
			(xy 279.711702 -285.207352) (xy 279.662088 -285.18788) (xy 279.61593 -285.161231) (xy 279.574259 -285.128)
			(xy 279.538007 -285.088929) (xy 279.507983 -285.044892) (xy 279.484857 -284.996871) (xy 279.469147 -284.945941)
			(xy 279.461204 -284.893237) (xy 265.084824 -284.893237) (xy 265.076881 -284.945941) (xy 265.061171 -284.996871)
			(xy 265.038045 -285.044892) (xy 265.008021 -285.088929) (xy 264.971769 -285.128) (xy 264.930098 -285.161231)
			(xy 264.88394 -285.18788) (xy 264.834326 -285.207352) (xy 264.782364 -285.219212) (xy 264.729214 -285.223196)
			(xy 264.676064 -285.219212) (xy 264.624102 -285.207352) (xy 264.574488 -285.18788) (xy 264.52833 -285.161231)
			(xy 264.486659 -285.128) (xy 264.450407 -285.088929) (xy 264.420383 -285.044892) (xy 264.397257 -284.996871)
			(xy 264.381547 -284.945941) (xy 264.373604 -284.893237) (xy 254.20828 -284.893237) (xy 254.20828 -285.743375)
			(xy 268.473672 -285.743375) (xy 268.473672 -285.690077) (xy 268.481615 -285.637373) (xy 268.497325 -285.586443)
			(xy 268.520451 -285.538422) (xy 268.550475 -285.494385) (xy 268.586727 -285.455314) (xy 268.628398 -285.422083)
			(xy 268.674556 -285.395434) (xy 268.72417 -285.375962) (xy 268.776132 -285.364102) (xy 268.829282 -285.360119)
			(xy 268.882432 -285.364102) (xy 268.934394 -285.375962) (xy 268.984008 -285.395434) (xy 269.030166 -285.422083)
			(xy 269.071837 -285.455314) (xy 269.108089 -285.494385) (xy 269.138113 -285.538422) (xy 269.161239 -285.586443)
			(xy 269.176949 -285.637373) (xy 269.184892 -285.690077) (xy 269.18539 -285.716726) (xy 269.184892 -285.743375)
			(xy 283.561272 -285.743375) (xy 283.561272 -285.690077) (xy 283.569215 -285.637373) (xy 283.584925 -285.586443)
			(xy 283.608051 -285.538422) (xy 283.638075 -285.494385) (xy 283.674327 -285.455314) (xy 283.715998 -285.422083)
			(xy 283.762156 -285.395434) (xy 283.81177 -285.375962) (xy 283.863732 -285.364102) (xy 283.916882 -285.360119)
			(xy 283.970032 -285.364102) (xy 284.021994 -285.375962) (xy 284.071608 -285.395434) (xy 284.117766 -285.422083)
			(xy 284.159437 -285.455314) (xy 284.195689 -285.494385) (xy 284.225713 -285.538422) (xy 284.248839 -285.586443)
			(xy 284.264549 -285.637373) (xy 284.272492 -285.690077) (xy 284.27299 -285.716726) (xy 284.272492 -285.743375)
			(xy 298.648872 -285.743375) (xy 298.648872 -285.690077) (xy 298.656815 -285.637373) (xy 298.672525 -285.586443)
			(xy 298.695651 -285.538422) (xy 298.725675 -285.494385) (xy 298.761927 -285.455314) (xy 298.803598 -285.422083)
			(xy 298.849756 -285.395434) (xy 298.89937 -285.375962) (xy 298.951332 -285.364102) (xy 299.004482 -285.360119)
			(xy 299.057632 -285.364102) (xy 299.109594 -285.375962) (xy 299.159208 -285.395434) (xy 299.205366 -285.422083)
			(xy 299.247037 -285.455314) (xy 299.283289 -285.494385) (xy 299.313313 -285.538422) (xy 299.336439 -285.586443)
			(xy 299.352149 -285.637373) (xy 299.360092 -285.690077) (xy 299.36059 -285.716726) (xy 299.360092 -285.743375)
			(xy 299.352149 -285.796079) (xy 299.336439 -285.847009) (xy 299.313313 -285.89503) (xy 299.283289 -285.939067)
			(xy 299.247037 -285.978138) (xy 299.205366 -286.011369) (xy 299.159208 -286.038018) (xy 299.109594 -286.05749)
			(xy 299.057632 -286.06935) (xy 299.004482 -286.073334) (xy 298.951332 -286.06935) (xy 298.89937 -286.05749)
			(xy 298.849756 -286.038018) (xy 298.803598 -286.011369) (xy 298.761927 -285.978138) (xy 298.725675 -285.939067)
			(xy 298.695651 -285.89503) (xy 298.672525 -285.847009) (xy 298.656815 -285.796079) (xy 298.648872 -285.743375)
			(xy 284.272492 -285.743375) (xy 284.264549 -285.796079) (xy 284.248839 -285.847009) (xy 284.225713 -285.89503)
			(xy 284.195689 -285.939067) (xy 284.159437 -285.978138) (xy 284.117766 -286.011369) (xy 284.071608 -286.038018)
			(xy 284.021994 -286.05749) (xy 283.970032 -286.06935) (xy 283.916882 -286.073334) (xy 283.863732 -286.06935)
			(xy 283.81177 -286.05749) (xy 283.762156 -286.038018) (xy 283.715998 -286.011369) (xy 283.674327 -285.978138)
			(xy 283.638075 -285.939067) (xy 283.608051 -285.89503) (xy 283.584925 -285.847009) (xy 283.569215 -285.796079)
			(xy 283.561272 -285.743375) (xy 269.184892 -285.743375) (xy 269.176949 -285.796079) (xy 269.161239 -285.847009)
			(xy 269.138113 -285.89503) (xy 269.108089 -285.939067) (xy 269.071837 -285.978138) (xy 269.030166 -286.011369)
			(xy 268.984008 -286.038018) (xy 268.934394 -286.05749) (xy 268.882432 -286.06935) (xy 268.829282 -286.073334)
			(xy 268.776132 -286.06935) (xy 268.72417 -286.05749) (xy 268.674556 -286.038018) (xy 268.628398 -286.011369)
			(xy 268.586727 -285.978138) (xy 268.550475 -285.939067) (xy 268.520451 -285.89503) (xy 268.497325 -285.847009)
			(xy 268.481615 -285.796079) (xy 268.473672 -285.743375) (xy 254.20828 -285.743375) (xy 254.20828 -286.593259)
			(xy 264.373604 -286.593259) (xy 264.373604 -286.539961) (xy 264.381547 -286.487257) (xy 264.397257 -286.436327)
			(xy 264.420383 -286.388306) (xy 264.450407 -286.344269) (xy 264.486659 -286.305198) (xy 264.52833 -286.271967)
			(xy 264.574488 -286.245318) (xy 264.624102 -286.225846) (xy 264.676064 -286.213986) (xy 264.729214 -286.210003)
			(xy 264.782364 -286.213986) (xy 264.834326 -286.225846) (xy 264.88394 -286.245318) (xy 264.930098 -286.271967)
			(xy 264.971769 -286.305198) (xy 265.008021 -286.344269) (xy 265.038045 -286.388306) (xy 265.061171 -286.436327)
			(xy 265.076881 -286.487257) (xy 265.084824 -286.539961) (xy 265.085322 -286.56661) (xy 265.084824 -286.593259)
			(xy 279.461204 -286.593259) (xy 279.461204 -286.539961) (xy 279.469147 -286.487257) (xy 279.484857 -286.436327)
			(xy 279.507983 -286.388306) (xy 279.538007 -286.344269) (xy 279.574259 -286.305198) (xy 279.61593 -286.271967)
			(xy 279.662088 -286.245318) (xy 279.711702 -286.225846) (xy 279.763664 -286.213986) (xy 279.816814 -286.210003)
			(xy 279.869964 -286.213986) (xy 279.921926 -286.225846) (xy 279.97154 -286.245318) (xy 280.017698 -286.271967)
			(xy 280.059369 -286.305198) (xy 280.095621 -286.344269) (xy 280.125645 -286.388306) (xy 280.148771 -286.436327)
			(xy 280.164481 -286.487257) (xy 280.172424 -286.539961) (xy 280.172922 -286.56661) (xy 280.172424 -286.593259)
			(xy 294.548804 -286.593259) (xy 294.548804 -286.539961) (xy 294.556747 -286.487257) (xy 294.572457 -286.436327)
			(xy 294.595583 -286.388306) (xy 294.625607 -286.344269) (xy 294.661859 -286.305198) (xy 294.70353 -286.271967)
			(xy 294.749688 -286.245318) (xy 294.799302 -286.225846) (xy 294.851264 -286.213986) (xy 294.904414 -286.210003)
			(xy 294.957564 -286.213986) (xy 295.009526 -286.225846) (xy 295.05914 -286.245318) (xy 295.105298 -286.271967)
			(xy 295.146969 -286.305198) (xy 295.183221 -286.344269) (xy 295.213245 -286.388306) (xy 295.236371 -286.436327)
			(xy 295.252081 -286.487257) (xy 295.260024 -286.539961) (xy 295.260522 -286.56661) (xy 295.260024 -286.593259)
			(xy 295.252081 -286.645963) (xy 295.236371 -286.696893) (xy 295.213245 -286.744914) (xy 295.183221 -286.788951)
			(xy 295.146969 -286.828022) (xy 295.105298 -286.861253) (xy 295.05914 -286.887902) (xy 295.009526 -286.907374)
			(xy 294.957564 -286.919234) (xy 294.904414 -286.923218) (xy 294.851264 -286.919234) (xy 294.799302 -286.907374)
			(xy 294.749688 -286.887902) (xy 294.70353 -286.861253) (xy 294.661859 -286.828022) (xy 294.625607 -286.788951)
			(xy 294.595583 -286.744914) (xy 294.572457 -286.696893) (xy 294.556747 -286.645963) (xy 294.548804 -286.593259)
			(xy 280.172424 -286.593259) (xy 280.164481 -286.645963) (xy 280.148771 -286.696893) (xy 280.125645 -286.744914)
			(xy 280.095621 -286.788951) (xy 280.059369 -286.828022) (xy 280.017698 -286.861253) (xy 279.97154 -286.887902)
			(xy 279.921926 -286.907374) (xy 279.869964 -286.919234) (xy 279.816814 -286.923218) (xy 279.763664 -286.919234)
			(xy 279.711702 -286.907374) (xy 279.662088 -286.887902) (xy 279.61593 -286.861253) (xy 279.574259 -286.828022)
			(xy 279.538007 -286.788951) (xy 279.507983 -286.744914) (xy 279.484857 -286.696893) (xy 279.469147 -286.645963)
			(xy 279.461204 -286.593259) (xy 265.084824 -286.593259) (xy 265.076881 -286.645963) (xy 265.061171 -286.696893)
			(xy 265.038045 -286.744914) (xy 265.008021 -286.788951) (xy 264.971769 -286.828022) (xy 264.930098 -286.861253)
			(xy 264.88394 -286.887902) (xy 264.834326 -286.907374) (xy 264.782364 -286.919234) (xy 264.729214 -286.923218)
			(xy 264.676064 -286.919234) (xy 264.624102 -286.907374) (xy 264.574488 -286.887902) (xy 264.52833 -286.861253)
			(xy 264.486659 -286.828022) (xy 264.450407 -286.788951) (xy 264.420383 -286.744914) (xy 264.397257 -286.696893)
			(xy 264.381547 -286.645963) (xy 264.373604 -286.593259) (xy 254.20828 -286.593259) (xy 254.20828 -287.443397)
			(xy 268.473672 -287.443397) (xy 268.473672 -287.390099) (xy 268.481615 -287.337395) (xy 268.497325 -287.286465)
			(xy 268.520451 -287.238444) (xy 268.550475 -287.194407) (xy 268.586727 -287.155336) (xy 268.628398 -287.122105)
			(xy 268.674556 -287.095456) (xy 268.72417 -287.075984) (xy 268.776132 -287.064124) (xy 268.829282 -287.060141)
			(xy 268.882432 -287.064124) (xy 268.934394 -287.075984) (xy 268.984008 -287.095456) (xy 269.030166 -287.122105)
			(xy 269.071837 -287.155336) (xy 269.108089 -287.194407) (xy 269.138113 -287.238444) (xy 269.161239 -287.286465)
			(xy 269.176949 -287.337395) (xy 269.184892 -287.390099) (xy 269.18539 -287.416748) (xy 269.184892 -287.443397)
			(xy 283.561272 -287.443397) (xy 283.561272 -287.390099) (xy 283.569215 -287.337395) (xy 283.584925 -287.286465)
			(xy 283.608051 -287.238444) (xy 283.638075 -287.194407) (xy 283.674327 -287.155336) (xy 283.715998 -287.122105)
			(xy 283.762156 -287.095456) (xy 283.81177 -287.075984) (xy 283.863732 -287.064124) (xy 283.916882 -287.060141)
			(xy 283.970032 -287.064124) (xy 284.021994 -287.075984) (xy 284.071608 -287.095456) (xy 284.117766 -287.122105)
			(xy 284.159437 -287.155336) (xy 284.195689 -287.194407) (xy 284.225713 -287.238444) (xy 284.248839 -287.286465)
			(xy 284.264549 -287.337395) (xy 284.272492 -287.390099) (xy 284.27299 -287.416748) (xy 284.272492 -287.443397)
			(xy 298.648872 -287.443397) (xy 298.648872 -287.390099) (xy 298.656815 -287.337395) (xy 298.672525 -287.286465)
			(xy 298.695651 -287.238444) (xy 298.725675 -287.194407) (xy 298.761927 -287.155336) (xy 298.803598 -287.122105)
			(xy 298.849756 -287.095456) (xy 298.89937 -287.075984) (xy 298.951332 -287.064124) (xy 299.004482 -287.060141)
			(xy 299.057632 -287.064124) (xy 299.109594 -287.075984) (xy 299.159208 -287.095456) (xy 299.205366 -287.122105)
			(xy 299.247037 -287.155336) (xy 299.283289 -287.194407) (xy 299.313313 -287.238444) (xy 299.336439 -287.286465)
			(xy 299.352149 -287.337395) (xy 299.360092 -287.390099) (xy 299.36059 -287.416748) (xy 299.360092 -287.443397)
			(xy 299.352149 -287.496101) (xy 299.336439 -287.547031) (xy 299.313313 -287.595052) (xy 299.283289 -287.639089)
			(xy 299.247037 -287.67816) (xy 299.205366 -287.711391) (xy 299.159208 -287.73804) (xy 299.109594 -287.757512)
			(xy 299.057632 -287.769372) (xy 299.004482 -287.773356) (xy 298.951332 -287.769372) (xy 298.89937 -287.757512)
			(xy 298.849756 -287.73804) (xy 298.803598 -287.711391) (xy 298.761927 -287.67816) (xy 298.725675 -287.639089)
			(xy 298.695651 -287.595052) (xy 298.672525 -287.547031) (xy 298.656815 -287.496101) (xy 298.648872 -287.443397)
			(xy 284.272492 -287.443397) (xy 284.264549 -287.496101) (xy 284.248839 -287.547031) (xy 284.225713 -287.595052)
			(xy 284.195689 -287.639089) (xy 284.159437 -287.67816) (xy 284.117766 -287.711391) (xy 284.071608 -287.73804)
			(xy 284.021994 -287.757512) (xy 283.970032 -287.769372) (xy 283.916882 -287.773356) (xy 283.863732 -287.769372)
			(xy 283.81177 -287.757512) (xy 283.762156 -287.73804) (xy 283.715998 -287.711391) (xy 283.674327 -287.67816)
			(xy 283.638075 -287.639089) (xy 283.608051 -287.595052) (xy 283.584925 -287.547031) (xy 283.569215 -287.496101)
			(xy 283.561272 -287.443397) (xy 269.184892 -287.443397) (xy 269.176949 -287.496101) (xy 269.161239 -287.547031)
			(xy 269.138113 -287.595052) (xy 269.108089 -287.639089) (xy 269.071837 -287.67816) (xy 269.030166 -287.711391)
			(xy 268.984008 -287.73804) (xy 268.934394 -287.757512) (xy 268.882432 -287.769372) (xy 268.829282 -287.773356)
			(xy 268.776132 -287.769372) (xy 268.72417 -287.757512) (xy 268.674556 -287.73804) (xy 268.628398 -287.711391)
			(xy 268.586727 -287.67816) (xy 268.550475 -287.639089) (xy 268.520451 -287.595052) (xy 268.497325 -287.547031)
			(xy 268.481615 -287.496101) (xy 268.473672 -287.443397) (xy 254.20828 -287.443397) (xy 254.20828 -288.293281)
			(xy 264.373604 -288.293281) (xy 264.373604 -288.239983) (xy 264.381547 -288.187279) (xy 264.397257 -288.136349)
			(xy 264.420383 -288.088328) (xy 264.450407 -288.044291) (xy 264.486659 -288.00522) (xy 264.52833 -287.971989)
			(xy 264.574488 -287.94534) (xy 264.624102 -287.925868) (xy 264.676064 -287.914008) (xy 264.729214 -287.910025)
			(xy 264.782364 -287.914008) (xy 264.834326 -287.925868) (xy 264.88394 -287.94534) (xy 264.930098 -287.971989)
			(xy 264.971769 -288.00522) (xy 265.008021 -288.044291) (xy 265.038045 -288.088328) (xy 265.061171 -288.136349)
			(xy 265.076881 -288.187279) (xy 265.084824 -288.239983) (xy 265.085322 -288.266632) (xy 265.084824 -288.293281)
			(xy 279.461204 -288.293281) (xy 279.461204 -288.239983) (xy 279.469147 -288.187279) (xy 279.484857 -288.136349)
			(xy 279.507983 -288.088328) (xy 279.538007 -288.044291) (xy 279.574259 -288.00522) (xy 279.61593 -287.971989)
			(xy 279.662088 -287.94534) (xy 279.711702 -287.925868) (xy 279.763664 -287.914008) (xy 279.816814 -287.910025)
			(xy 279.869964 -287.914008) (xy 279.921926 -287.925868) (xy 279.97154 -287.94534) (xy 280.017698 -287.971989)
			(xy 280.059369 -288.00522) (xy 280.095621 -288.044291) (xy 280.125645 -288.088328) (xy 280.148771 -288.136349)
			(xy 280.164481 -288.187279) (xy 280.172424 -288.239983) (xy 280.172922 -288.266632) (xy 280.172424 -288.293281)
			(xy 294.548804 -288.293281) (xy 294.548804 -288.239983) (xy 294.556747 -288.187279) (xy 294.572457 -288.136349)
			(xy 294.595583 -288.088328) (xy 294.625607 -288.044291) (xy 294.661859 -288.00522) (xy 294.70353 -287.971989)
			(xy 294.749688 -287.94534) (xy 294.799302 -287.925868) (xy 294.851264 -287.914008) (xy 294.904414 -287.910025)
			(xy 294.957564 -287.914008) (xy 295.009526 -287.925868) (xy 295.05914 -287.94534) (xy 295.105298 -287.971989)
			(xy 295.146969 -288.00522) (xy 295.183221 -288.044291) (xy 295.213245 -288.088328) (xy 295.236371 -288.136349)
			(xy 295.252081 -288.187279) (xy 295.260024 -288.239983) (xy 295.260522 -288.266632) (xy 295.260024 -288.293281)
			(xy 295.252081 -288.345985) (xy 295.236371 -288.396915) (xy 295.213245 -288.444936) (xy 295.183221 -288.488973)
			(xy 295.146969 -288.528044) (xy 295.105298 -288.561275) (xy 295.05914 -288.587924) (xy 295.009526 -288.607396)
			(xy 294.957564 -288.619256) (xy 294.904414 -288.62324) (xy 294.851264 -288.619256) (xy 294.799302 -288.607396)
			(xy 294.749688 -288.587924) (xy 294.70353 -288.561275) (xy 294.661859 -288.528044) (xy 294.625607 -288.488973)
			(xy 294.595583 -288.444936) (xy 294.572457 -288.396915) (xy 294.556747 -288.345985) (xy 294.548804 -288.293281)
			(xy 280.172424 -288.293281) (xy 280.164481 -288.345985) (xy 280.148771 -288.396915) (xy 280.125645 -288.444936)
			(xy 280.095621 -288.488973) (xy 280.059369 -288.528044) (xy 280.017698 -288.561275) (xy 279.97154 -288.587924)
			(xy 279.921926 -288.607396) (xy 279.869964 -288.619256) (xy 279.816814 -288.62324) (xy 279.763664 -288.619256)
			(xy 279.711702 -288.607396) (xy 279.662088 -288.587924) (xy 279.61593 -288.561275) (xy 279.574259 -288.528044)
			(xy 279.538007 -288.488973) (xy 279.507983 -288.444936) (xy 279.484857 -288.396915) (xy 279.469147 -288.345985)
			(xy 279.461204 -288.293281) (xy 265.084824 -288.293281) (xy 265.076881 -288.345985) (xy 265.061171 -288.396915)
			(xy 265.038045 -288.444936) (xy 265.008021 -288.488973) (xy 264.971769 -288.528044) (xy 264.930098 -288.561275)
			(xy 264.88394 -288.587924) (xy 264.834326 -288.607396) (xy 264.782364 -288.619256) (xy 264.729214 -288.62324)
			(xy 264.676064 -288.619256) (xy 264.624102 -288.607396) (xy 264.574488 -288.587924) (xy 264.52833 -288.561275)
			(xy 264.486659 -288.528044) (xy 264.450407 -288.488973) (xy 264.420383 -288.444936) (xy 264.397257 -288.396915)
			(xy 264.381547 -288.345985) (xy 264.373604 -288.293281) (xy 254.20828 -288.293281) (xy 254.20828 -289.143419)
			(xy 268.473672 -289.143419) (xy 268.473672 -289.090121) (xy 268.481615 -289.037417) (xy 268.497325 -288.986487)
			(xy 268.520451 -288.938466) (xy 268.550475 -288.894429) (xy 268.586727 -288.855358) (xy 268.628398 -288.822127)
			(xy 268.674556 -288.795478) (xy 268.72417 -288.776006) (xy 268.776132 -288.764146) (xy 268.829282 -288.760163)
			(xy 268.882432 -288.764146) (xy 268.934394 -288.776006) (xy 268.984008 -288.795478) (xy 269.030166 -288.822127)
			(xy 269.071837 -288.855358) (xy 269.108089 -288.894429) (xy 269.138113 -288.938466) (xy 269.161239 -288.986487)
			(xy 269.176949 -289.037417) (xy 269.184892 -289.090121) (xy 269.18539 -289.11677) (xy 269.184892 -289.143419)
			(xy 283.561272 -289.143419) (xy 283.561272 -289.090121) (xy 283.569215 -289.037417) (xy 283.584925 -288.986487)
			(xy 283.608051 -288.938466) (xy 283.638075 -288.894429) (xy 283.674327 -288.855358) (xy 283.715998 -288.822127)
			(xy 283.762156 -288.795478) (xy 283.81177 -288.776006) (xy 283.863732 -288.764146) (xy 283.916882 -288.760163)
			(xy 283.970032 -288.764146) (xy 284.021994 -288.776006) (xy 284.071608 -288.795478) (xy 284.117766 -288.822127)
			(xy 284.159437 -288.855358) (xy 284.195689 -288.894429) (xy 284.225713 -288.938466) (xy 284.248839 -288.986487)
			(xy 284.264549 -289.037417) (xy 284.272492 -289.090121) (xy 284.27299 -289.11677) (xy 284.272492 -289.143419)
			(xy 298.674272 -289.143419) (xy 298.674272 -289.090121) (xy 298.682215 -289.037417) (xy 298.697925 -288.986487)
			(xy 298.721051 -288.938466) (xy 298.751075 -288.894429) (xy 298.787327 -288.855358) (xy 298.828998 -288.822127)
			(xy 298.875156 -288.795478) (xy 298.92477 -288.776006) (xy 298.976732 -288.764146) (xy 299.029882 -288.760163)
			(xy 299.083032 -288.764146) (xy 299.134994 -288.776006) (xy 299.184608 -288.795478) (xy 299.230766 -288.822127)
			(xy 299.272437 -288.855358) (xy 299.308689 -288.894429) (xy 299.338713 -288.938466) (xy 299.361839 -288.986487)
			(xy 299.377549 -289.037417) (xy 299.385492 -289.090121) (xy 299.38599 -289.11677) (xy 299.385492 -289.143419)
			(xy 299.377549 -289.196123) (xy 299.361839 -289.247053) (xy 299.338713 -289.295074) (xy 299.308689 -289.339111)
			(xy 299.272437 -289.378182) (xy 299.230766 -289.411413) (xy 299.184608 -289.438062) (xy 299.134994 -289.457534)
			(xy 299.083032 -289.469394) (xy 299.029882 -289.473378) (xy 298.976732 -289.469394) (xy 298.92477 -289.457534)
			(xy 298.875156 -289.438062) (xy 298.828998 -289.411413) (xy 298.787327 -289.378182) (xy 298.751075 -289.339111)
			(xy 298.721051 -289.295074) (xy 298.697925 -289.247053) (xy 298.682215 -289.196123) (xy 298.674272 -289.143419)
			(xy 284.272492 -289.143419) (xy 284.264549 -289.196123) (xy 284.248839 -289.247053) (xy 284.225713 -289.295074)
			(xy 284.195689 -289.339111) (xy 284.159437 -289.378182) (xy 284.117766 -289.411413) (xy 284.071608 -289.438062)
			(xy 284.021994 -289.457534) (xy 283.970032 -289.469394) (xy 283.916882 -289.473378) (xy 283.863732 -289.469394)
			(xy 283.81177 -289.457534) (xy 283.762156 -289.438062) (xy 283.715998 -289.411413) (xy 283.674327 -289.378182)
			(xy 283.638075 -289.339111) (xy 283.608051 -289.295074) (xy 283.584925 -289.247053) (xy 283.569215 -289.196123)
			(xy 283.561272 -289.143419) (xy 269.184892 -289.143419) (xy 269.176949 -289.196123) (xy 269.161239 -289.247053)
			(xy 269.138113 -289.295074) (xy 269.108089 -289.339111) (xy 269.071837 -289.378182) (xy 269.030166 -289.411413)
			(xy 268.984008 -289.438062) (xy 268.934394 -289.457534) (xy 268.882432 -289.469394) (xy 268.829282 -289.473378)
			(xy 268.776132 -289.469394) (xy 268.72417 -289.457534) (xy 268.674556 -289.438062) (xy 268.628398 -289.411413)
			(xy 268.586727 -289.378182) (xy 268.550475 -289.339111) (xy 268.520451 -289.295074) (xy 268.497325 -289.247053)
			(xy 268.481615 -289.196123) (xy 268.473672 -289.143419) (xy 254.20828 -289.143419) (xy 254.20828 -289.993303)
			(xy 264.373604 -289.993303) (xy 264.373604 -289.940005) (xy 264.381547 -289.887301) (xy 264.397257 -289.836371)
			(xy 264.420383 -289.78835) (xy 264.450407 -289.744313) (xy 264.486659 -289.705242) (xy 264.52833 -289.672011)
			(xy 264.574488 -289.645362) (xy 264.624102 -289.62589) (xy 264.676064 -289.61403) (xy 264.729214 -289.610047)
			(xy 264.782364 -289.61403) (xy 264.834326 -289.62589) (xy 264.88394 -289.645362) (xy 264.930098 -289.672011)
			(xy 264.971769 -289.705242) (xy 265.008021 -289.744313) (xy 265.038045 -289.78835) (xy 265.061171 -289.836371)
			(xy 265.076881 -289.887301) (xy 265.084824 -289.940005) (xy 265.085322 -289.966654) (xy 265.084824 -289.993303)
			(xy 279.461204 -289.993303) (xy 279.461204 -289.940005) (xy 279.469147 -289.887301) (xy 279.484857 -289.836371)
			(xy 279.507983 -289.78835) (xy 279.538007 -289.744313) (xy 279.574259 -289.705242) (xy 279.61593 -289.672011)
			(xy 279.662088 -289.645362) (xy 279.711702 -289.62589) (xy 279.763664 -289.61403) (xy 279.816814 -289.610047)
			(xy 279.869964 -289.61403) (xy 279.921926 -289.62589) (xy 279.97154 -289.645362) (xy 280.017698 -289.672011)
			(xy 280.059369 -289.705242) (xy 280.095621 -289.744313) (xy 280.125645 -289.78835) (xy 280.148771 -289.836371)
			(xy 280.164481 -289.887301) (xy 280.172424 -289.940005) (xy 280.172922 -289.966654) (xy 280.172424 -289.993303)
			(xy 294.548804 -289.993303) (xy 294.548804 -289.940005) (xy 294.556747 -289.887301) (xy 294.572457 -289.836371)
			(xy 294.595583 -289.78835) (xy 294.625607 -289.744313) (xy 294.661859 -289.705242) (xy 294.70353 -289.672011)
			(xy 294.749688 -289.645362) (xy 294.799302 -289.62589) (xy 294.851264 -289.61403) (xy 294.904414 -289.610047)
			(xy 294.957564 -289.61403) (xy 295.009526 -289.62589) (xy 295.05914 -289.645362) (xy 295.105298 -289.672011)
			(xy 295.146969 -289.705242) (xy 295.183221 -289.744313) (xy 295.213245 -289.78835) (xy 295.236371 -289.836371)
			(xy 295.252081 -289.887301) (xy 295.260024 -289.940005) (xy 295.260522 -289.966654) (xy 295.260024 -289.993303)
			(xy 295.252081 -290.046007) (xy 295.236371 -290.096937) (xy 295.213245 -290.144958) (xy 295.183221 -290.188995)
			(xy 295.146969 -290.228066) (xy 295.105298 -290.261297) (xy 295.05914 -290.287946) (xy 295.009526 -290.307418)
			(xy 294.957564 -290.319278) (xy 294.904414 -290.323262) (xy 294.851264 -290.319278) (xy 294.799302 -290.307418)
			(xy 294.749688 -290.287946) (xy 294.70353 -290.261297) (xy 294.661859 -290.228066) (xy 294.625607 -290.188995)
			(xy 294.595583 -290.144958) (xy 294.572457 -290.096937) (xy 294.556747 -290.046007) (xy 294.548804 -289.993303)
			(xy 280.172424 -289.993303) (xy 280.164481 -290.046007) (xy 280.148771 -290.096937) (xy 280.125645 -290.144958)
			(xy 280.095621 -290.188995) (xy 280.059369 -290.228066) (xy 280.017698 -290.261297) (xy 279.97154 -290.287946)
			(xy 279.921926 -290.307418) (xy 279.869964 -290.319278) (xy 279.816814 -290.323262) (xy 279.763664 -290.319278)
			(xy 279.711702 -290.307418) (xy 279.662088 -290.287946) (xy 279.61593 -290.261297) (xy 279.574259 -290.228066)
			(xy 279.538007 -290.188995) (xy 279.507983 -290.144958) (xy 279.484857 -290.096937) (xy 279.469147 -290.046007)
			(xy 279.461204 -289.993303) (xy 265.084824 -289.993303) (xy 265.076881 -290.046007) (xy 265.061171 -290.096937)
			(xy 265.038045 -290.144958) (xy 265.008021 -290.188995) (xy 264.971769 -290.228066) (xy 264.930098 -290.261297)
			(xy 264.88394 -290.287946) (xy 264.834326 -290.307418) (xy 264.782364 -290.319278) (xy 264.729214 -290.323262)
			(xy 264.676064 -290.319278) (xy 264.624102 -290.307418) (xy 264.574488 -290.287946) (xy 264.52833 -290.261297)
			(xy 264.486659 -290.228066) (xy 264.450407 -290.188995) (xy 264.420383 -290.144958) (xy 264.397257 -290.096937)
			(xy 264.381547 -290.046007) (xy 264.373604 -289.993303) (xy 254.20828 -289.993303) (xy 254.20828 -290.843441)
			(xy 268.473672 -290.843441) (xy 268.473672 -290.790143) (xy 268.481615 -290.737439) (xy 268.497325 -290.686509)
			(xy 268.520451 -290.638488) (xy 268.550475 -290.594451) (xy 268.586727 -290.55538) (xy 268.628398 -290.522149)
			(xy 268.674556 -290.4955) (xy 268.72417 -290.476028) (xy 268.776132 -290.464168) (xy 268.829282 -290.460185)
			(xy 268.882432 -290.464168) (xy 268.934394 -290.476028) (xy 268.984008 -290.4955) (xy 269.030166 -290.522149)
			(xy 269.071837 -290.55538) (xy 269.108089 -290.594451) (xy 269.138113 -290.638488) (xy 269.161239 -290.686509)
			(xy 269.176949 -290.737439) (xy 269.184892 -290.790143) (xy 269.18539 -290.816792) (xy 269.184892 -290.843441)
			(xy 283.561272 -290.843441) (xy 283.561272 -290.790143) (xy 283.569215 -290.737439) (xy 283.584925 -290.686509)
			(xy 283.608051 -290.638488) (xy 283.638075 -290.594451) (xy 283.674327 -290.55538) (xy 283.715998 -290.522149)
			(xy 283.762156 -290.4955) (xy 283.81177 -290.476028) (xy 283.863732 -290.464168) (xy 283.916882 -290.460185)
			(xy 283.970032 -290.464168) (xy 284.021994 -290.476028) (xy 284.071608 -290.4955) (xy 284.117766 -290.522149)
			(xy 284.159437 -290.55538) (xy 284.195689 -290.594451) (xy 284.225713 -290.638488) (xy 284.248839 -290.686509)
			(xy 284.264549 -290.737439) (xy 284.272492 -290.790143) (xy 284.27299 -290.816792) (xy 284.272492 -290.843441)
			(xy 298.674272 -290.843441) (xy 298.674272 -290.790143) (xy 298.682215 -290.737439) (xy 298.697925 -290.686509)
			(xy 298.721051 -290.638488) (xy 298.751075 -290.594451) (xy 298.787327 -290.55538) (xy 298.828998 -290.522149)
			(xy 298.875156 -290.4955) (xy 298.92477 -290.476028) (xy 298.976732 -290.464168) (xy 299.029882 -290.460185)
			(xy 299.083032 -290.464168) (xy 299.134994 -290.476028) (xy 299.184608 -290.4955) (xy 299.230766 -290.522149)
			(xy 299.272437 -290.55538) (xy 299.308689 -290.594451) (xy 299.338713 -290.638488) (xy 299.361839 -290.686509)
			(xy 299.377549 -290.737439) (xy 299.385492 -290.790143) (xy 299.38599 -290.816792) (xy 299.385492 -290.843441)
			(xy 299.377549 -290.896145) (xy 299.361839 -290.947075) (xy 299.338713 -290.995096) (xy 299.308689 -291.039133)
			(xy 299.272437 -291.078204) (xy 299.230766 -291.111435) (xy 299.184608 -291.138084) (xy 299.134994 -291.157556)
			(xy 299.083032 -291.169416) (xy 299.029882 -291.1734) (xy 298.976732 -291.169416) (xy 298.92477 -291.157556)
			(xy 298.875156 -291.138084) (xy 298.828998 -291.111435) (xy 298.787327 -291.078204) (xy 298.751075 -291.039133)
			(xy 298.721051 -290.995096) (xy 298.697925 -290.947075) (xy 298.682215 -290.896145) (xy 298.674272 -290.843441)
			(xy 284.272492 -290.843441) (xy 284.264549 -290.896145) (xy 284.248839 -290.947075) (xy 284.225713 -290.995096)
			(xy 284.195689 -291.039133) (xy 284.159437 -291.078204) (xy 284.117766 -291.111435) (xy 284.071608 -291.138084)
			(xy 284.021994 -291.157556) (xy 283.970032 -291.169416) (xy 283.916882 -291.1734) (xy 283.863732 -291.169416)
			(xy 283.81177 -291.157556) (xy 283.762156 -291.138084) (xy 283.715998 -291.111435) (xy 283.674327 -291.078204)
			(xy 283.638075 -291.039133) (xy 283.608051 -290.995096) (xy 283.584925 -290.947075) (xy 283.569215 -290.896145)
			(xy 283.561272 -290.843441) (xy 269.184892 -290.843441) (xy 269.176949 -290.896145) (xy 269.161239 -290.947075)
			(xy 269.138113 -290.995096) (xy 269.108089 -291.039133) (xy 269.071837 -291.078204) (xy 269.030166 -291.111435)
			(xy 268.984008 -291.138084) (xy 268.934394 -291.157556) (xy 268.882432 -291.169416) (xy 268.829282 -291.1734)
			(xy 268.776132 -291.169416) (xy 268.72417 -291.157556) (xy 268.674556 -291.138084) (xy 268.628398 -291.111435)
			(xy 268.586727 -291.078204) (xy 268.550475 -291.039133) (xy 268.520451 -290.995096) (xy 268.497325 -290.947075)
			(xy 268.481615 -290.896145) (xy 268.473672 -290.843441) (xy 254.20828 -290.843441) (xy 254.20828 -291.693325)
			(xy 264.373604 -291.693325) (xy 264.373604 -291.640027) (xy 264.381547 -291.587323) (xy 264.397257 -291.536393)
			(xy 264.420383 -291.488372) (xy 264.450407 -291.444335) (xy 264.486659 -291.405264) (xy 264.52833 -291.372033)
			(xy 264.574488 -291.345384) (xy 264.624102 -291.325912) (xy 264.676064 -291.314052) (xy 264.729214 -291.310069)
			(xy 264.782364 -291.314052) (xy 264.834326 -291.325912) (xy 264.88394 -291.345384) (xy 264.930098 -291.372033)
			(xy 264.971769 -291.405264) (xy 265.008021 -291.444335) (xy 265.038045 -291.488372) (xy 265.061171 -291.536393)
			(xy 265.076881 -291.587323) (xy 265.084824 -291.640027) (xy 265.085322 -291.666676) (xy 265.084824 -291.693325)
			(xy 279.461204 -291.693325) (xy 279.461204 -291.640027) (xy 279.469147 -291.587323) (xy 279.484857 -291.536393)
			(xy 279.507983 -291.488372) (xy 279.538007 -291.444335) (xy 279.574259 -291.405264) (xy 279.61593 -291.372033)
			(xy 279.662088 -291.345384) (xy 279.711702 -291.325912) (xy 279.763664 -291.314052) (xy 279.816814 -291.310069)
			(xy 279.869964 -291.314052) (xy 279.921926 -291.325912) (xy 279.97154 -291.345384) (xy 280.017698 -291.372033)
			(xy 280.059369 -291.405264) (xy 280.095621 -291.444335) (xy 280.125645 -291.488372) (xy 280.148771 -291.536393)
			(xy 280.164481 -291.587323) (xy 280.172424 -291.640027) (xy 280.172922 -291.666676) (xy 280.172424 -291.693325)
			(xy 294.548804 -291.693325) (xy 294.548804 -291.640027) (xy 294.556747 -291.587323) (xy 294.572457 -291.536393)
			(xy 294.595583 -291.488372) (xy 294.625607 -291.444335) (xy 294.661859 -291.405264) (xy 294.70353 -291.372033)
			(xy 294.749688 -291.345384) (xy 294.799302 -291.325912) (xy 294.851264 -291.314052) (xy 294.904414 -291.310069)
			(xy 294.957564 -291.314052) (xy 295.009526 -291.325912) (xy 295.05914 -291.345384) (xy 295.105298 -291.372033)
			(xy 295.146969 -291.405264) (xy 295.183221 -291.444335) (xy 295.213245 -291.488372) (xy 295.236371 -291.536393)
			(xy 295.252081 -291.587323) (xy 295.260024 -291.640027) (xy 295.260522 -291.666676) (xy 295.260024 -291.693325)
			(xy 295.252081 -291.746029) (xy 295.236371 -291.796959) (xy 295.213245 -291.84498) (xy 295.183221 -291.889017)
			(xy 295.146969 -291.928088) (xy 295.105298 -291.961319) (xy 295.05914 -291.987968) (xy 295.009526 -292.00744)
			(xy 294.957564 -292.0193) (xy 294.904414 -292.023284) (xy 294.851264 -292.0193) (xy 294.799302 -292.00744)
			(xy 294.749688 -291.987968) (xy 294.70353 -291.961319) (xy 294.661859 -291.928088) (xy 294.625607 -291.889017)
			(xy 294.595583 -291.84498) (xy 294.572457 -291.796959) (xy 294.556747 -291.746029) (xy 294.548804 -291.693325)
			(xy 280.172424 -291.693325) (xy 280.164481 -291.746029) (xy 280.148771 -291.796959) (xy 280.125645 -291.84498)
			(xy 280.095621 -291.889017) (xy 280.059369 -291.928088) (xy 280.017698 -291.961319) (xy 279.97154 -291.987968)
			(xy 279.921926 -292.00744) (xy 279.869964 -292.0193) (xy 279.816814 -292.023284) (xy 279.763664 -292.0193)
			(xy 279.711702 -292.00744) (xy 279.662088 -291.987968) (xy 279.61593 -291.961319) (xy 279.574259 -291.928088)
			(xy 279.538007 -291.889017) (xy 279.507983 -291.84498) (xy 279.484857 -291.796959) (xy 279.469147 -291.746029)
			(xy 279.461204 -291.693325) (xy 265.084824 -291.693325) (xy 265.076881 -291.746029) (xy 265.061171 -291.796959)
			(xy 265.038045 -291.84498) (xy 265.008021 -291.889017) (xy 264.971769 -291.928088) (xy 264.930098 -291.961319)
			(xy 264.88394 -291.987968) (xy 264.834326 -292.00744) (xy 264.782364 -292.0193) (xy 264.729214 -292.023284)
			(xy 264.676064 -292.0193) (xy 264.624102 -292.00744) (xy 264.574488 -291.987968) (xy 264.52833 -291.961319)
			(xy 264.486659 -291.928088) (xy 264.450407 -291.889017) (xy 264.420383 -291.84498) (xy 264.397257 -291.796959)
			(xy 264.381547 -291.746029) (xy 264.373604 -291.693325) (xy 254.20828 -291.693325) (xy 254.20828 -292.543463)
			(xy 268.473672 -292.543463) (xy 268.473672 -292.490165) (xy 268.481615 -292.437461) (xy 268.497325 -292.386531)
			(xy 268.520451 -292.33851) (xy 268.550475 -292.294473) (xy 268.586727 -292.255402) (xy 268.628398 -292.222171)
			(xy 268.674556 -292.195522) (xy 268.72417 -292.17605) (xy 268.776132 -292.16419) (xy 268.829282 -292.160207)
			(xy 268.882432 -292.16419) (xy 268.934394 -292.17605) (xy 268.984008 -292.195522) (xy 269.030166 -292.222171)
			(xy 269.071837 -292.255402) (xy 269.108089 -292.294473) (xy 269.138113 -292.33851) (xy 269.161239 -292.386531)
			(xy 269.176949 -292.437461) (xy 269.184892 -292.490165) (xy 269.18539 -292.516814) (xy 269.184892 -292.543463)
			(xy 283.561272 -292.543463) (xy 283.561272 -292.490165) (xy 283.569215 -292.437461) (xy 283.584925 -292.386531)
			(xy 283.608051 -292.33851) (xy 283.638075 -292.294473) (xy 283.674327 -292.255402) (xy 283.715998 -292.222171)
			(xy 283.762156 -292.195522) (xy 283.81177 -292.17605) (xy 283.863732 -292.16419) (xy 283.916882 -292.160207)
			(xy 283.970032 -292.16419) (xy 284.021994 -292.17605) (xy 284.071608 -292.195522) (xy 284.117766 -292.222171)
			(xy 284.159437 -292.255402) (xy 284.195689 -292.294473) (xy 284.225713 -292.33851) (xy 284.248839 -292.386531)
			(xy 284.264549 -292.437461) (xy 284.272492 -292.490165) (xy 284.27299 -292.516814) (xy 284.272492 -292.543463)
			(xy 298.674272 -292.543463) (xy 298.674272 -292.490165) (xy 298.682215 -292.437461) (xy 298.697925 -292.386531)
			(xy 298.721051 -292.33851) (xy 298.751075 -292.294473) (xy 298.787327 -292.255402) (xy 298.828998 -292.222171)
			(xy 298.875156 -292.195522) (xy 298.92477 -292.17605) (xy 298.976732 -292.16419) (xy 299.029882 -292.160207)
			(xy 299.083032 -292.16419) (xy 299.134994 -292.17605) (xy 299.184608 -292.195522) (xy 299.230766 -292.222171)
			(xy 299.272437 -292.255402) (xy 299.308689 -292.294473) (xy 299.338713 -292.33851) (xy 299.361839 -292.386531)
			(xy 299.377549 -292.437461) (xy 299.385492 -292.490165) (xy 299.38599 -292.516814) (xy 299.385492 -292.543463)
			(xy 299.377549 -292.596167) (xy 299.361839 -292.647097) (xy 299.338713 -292.695118) (xy 299.308689 -292.739155)
			(xy 299.272437 -292.778226) (xy 299.230766 -292.811457) (xy 299.184608 -292.838106) (xy 299.134994 -292.857578)
			(xy 299.083032 -292.869438) (xy 299.029882 -292.873422) (xy 298.976732 -292.869438) (xy 298.92477 -292.857578)
			(xy 298.875156 -292.838106) (xy 298.828998 -292.811457) (xy 298.787327 -292.778226) (xy 298.751075 -292.739155)
			(xy 298.721051 -292.695118) (xy 298.697925 -292.647097) (xy 298.682215 -292.596167) (xy 298.674272 -292.543463)
			(xy 284.272492 -292.543463) (xy 284.264549 -292.596167) (xy 284.248839 -292.647097) (xy 284.225713 -292.695118)
			(xy 284.195689 -292.739155) (xy 284.159437 -292.778226) (xy 284.117766 -292.811457) (xy 284.071608 -292.838106)
			(xy 284.021994 -292.857578) (xy 283.970032 -292.869438) (xy 283.916882 -292.873422) (xy 283.863732 -292.869438)
			(xy 283.81177 -292.857578) (xy 283.762156 -292.838106) (xy 283.715998 -292.811457) (xy 283.674327 -292.778226)
			(xy 283.638075 -292.739155) (xy 283.608051 -292.695118) (xy 283.584925 -292.647097) (xy 283.569215 -292.596167)
			(xy 283.561272 -292.543463) (xy 269.184892 -292.543463) (xy 269.176949 -292.596167) (xy 269.161239 -292.647097)
			(xy 269.138113 -292.695118) (xy 269.108089 -292.739155) (xy 269.071837 -292.778226) (xy 269.030166 -292.811457)
			(xy 268.984008 -292.838106) (xy 268.934394 -292.857578) (xy 268.882432 -292.869438) (xy 268.829282 -292.873422)
			(xy 268.776132 -292.869438) (xy 268.72417 -292.857578) (xy 268.674556 -292.838106) (xy 268.628398 -292.811457)
			(xy 268.586727 -292.778226) (xy 268.550475 -292.739155) (xy 268.520451 -292.695118) (xy 268.497325 -292.647097)
			(xy 268.481615 -292.596167) (xy 268.473672 -292.543463) (xy 254.20828 -292.543463) (xy 254.20828 -293.393347)
			(xy 264.373604 -293.393347) (xy 264.373604 -293.340049) (xy 264.381547 -293.287345) (xy 264.397257 -293.236415)
			(xy 264.420383 -293.188394) (xy 264.450407 -293.144357) (xy 264.486659 -293.105286) (xy 264.52833 -293.072055)
			(xy 264.574488 -293.045406) (xy 264.624102 -293.025934) (xy 264.676064 -293.014074) (xy 264.729214 -293.010091)
			(xy 264.782364 -293.014074) (xy 264.834326 -293.025934) (xy 264.88394 -293.045406) (xy 264.930098 -293.072055)
			(xy 264.971769 -293.105286) (xy 265.008021 -293.144357) (xy 265.038045 -293.188394) (xy 265.061171 -293.236415)
			(xy 265.076881 -293.287345) (xy 265.084824 -293.340049) (xy 265.085322 -293.366698) (xy 265.084824 -293.393347)
			(xy 268.473672 -293.393347) (xy 268.473672 -293.340049) (xy 268.481615 -293.287345) (xy 268.497325 -293.236415)
			(xy 268.520451 -293.188394) (xy 268.550475 -293.144357) (xy 268.586727 -293.105286) (xy 268.628398 -293.072055)
			(xy 268.674556 -293.045406) (xy 268.72417 -293.025934) (xy 268.776132 -293.014074) (xy 268.829282 -293.010091)
			(xy 268.882432 -293.014074) (xy 268.934394 -293.025934) (xy 268.984008 -293.045406) (xy 269.030166 -293.072055)
			(xy 269.071837 -293.105286) (xy 269.108089 -293.144357) (xy 269.138113 -293.188394) (xy 269.161239 -293.236415)
			(xy 269.176949 -293.287345) (xy 269.184892 -293.340049) (xy 269.18539 -293.366698) (xy 269.184892 -293.393347)
			(xy 279.461204 -293.393347) (xy 279.461204 -293.340049) (xy 279.469147 -293.287345) (xy 279.484857 -293.236415)
			(xy 279.507983 -293.188394) (xy 279.538007 -293.144357) (xy 279.574259 -293.105286) (xy 279.61593 -293.072055)
			(xy 279.662088 -293.045406) (xy 279.711702 -293.025934) (xy 279.763664 -293.014074) (xy 279.816814 -293.010091)
			(xy 279.869964 -293.014074) (xy 279.921926 -293.025934) (xy 279.97154 -293.045406) (xy 280.017698 -293.072055)
			(xy 280.059369 -293.105286) (xy 280.095621 -293.144357) (xy 280.125645 -293.188394) (xy 280.148771 -293.236415)
			(xy 280.164481 -293.287345) (xy 280.172424 -293.340049) (xy 280.172922 -293.366698) (xy 280.172424 -293.393347)
			(xy 283.561272 -293.393347) (xy 283.561272 -293.340049) (xy 283.569215 -293.287345) (xy 283.584925 -293.236415)
			(xy 283.608051 -293.188394) (xy 283.638075 -293.144357) (xy 283.674327 -293.105286) (xy 283.715998 -293.072055)
			(xy 283.762156 -293.045406) (xy 283.81177 -293.025934) (xy 283.863732 -293.014074) (xy 283.916882 -293.010091)
			(xy 283.970032 -293.014074) (xy 284.021994 -293.025934) (xy 284.071608 -293.045406) (xy 284.117766 -293.072055)
			(xy 284.159437 -293.105286) (xy 284.195689 -293.144357) (xy 284.225713 -293.188394) (xy 284.248839 -293.236415)
			(xy 284.264549 -293.287345) (xy 284.272492 -293.340049) (xy 284.27299 -293.366698) (xy 284.272492 -293.393347)
			(xy 294.548804 -293.393347) (xy 294.548804 -293.340049) (xy 294.556747 -293.287345) (xy 294.572457 -293.236415)
			(xy 294.595583 -293.188394) (xy 294.625607 -293.144357) (xy 294.661859 -293.105286) (xy 294.70353 -293.072055)
			(xy 294.749688 -293.045406) (xy 294.799302 -293.025934) (xy 294.851264 -293.014074) (xy 294.904414 -293.010091)
			(xy 294.957564 -293.014074) (xy 295.009526 -293.025934) (xy 295.05914 -293.045406) (xy 295.105298 -293.072055)
			(xy 295.146969 -293.105286) (xy 295.183221 -293.144357) (xy 295.213245 -293.188394) (xy 295.236371 -293.236415)
			(xy 295.252081 -293.287345) (xy 295.260024 -293.340049) (xy 295.260522 -293.366698) (xy 295.260024 -293.393347)
			(xy 295.259986 -293.393601) (xy 298.674272 -293.393601) (xy 298.674272 -293.340303) (xy 298.682215 -293.287599)
			(xy 298.697925 -293.236669) (xy 298.721051 -293.188648) (xy 298.751075 -293.144611) (xy 298.787327 -293.10554)
			(xy 298.828998 -293.072309) (xy 298.875156 -293.04566) (xy 298.92477 -293.026188) (xy 298.976732 -293.014328)
			(xy 299.029882 -293.010345) (xy 299.083032 -293.014328) (xy 299.134994 -293.026188) (xy 299.184608 -293.04566)
			(xy 299.230766 -293.072309) (xy 299.272437 -293.10554) (xy 299.308689 -293.144611) (xy 299.338713 -293.188648)
			(xy 299.361839 -293.236669) (xy 299.377549 -293.287599) (xy 299.385492 -293.340303) (xy 299.38599 -293.366952)
			(xy 299.385492 -293.393601) (xy 299.377549 -293.446305) (xy 299.361839 -293.497235) (xy 299.338713 -293.545256)
			(xy 299.308689 -293.589293) (xy 299.272437 -293.628364) (xy 299.230766 -293.661595) (xy 299.184608 -293.688244)
			(xy 299.134994 -293.707716) (xy 299.083032 -293.719576) (xy 299.029882 -293.72356) (xy 298.976732 -293.719576)
			(xy 298.92477 -293.707716) (xy 298.875156 -293.688244) (xy 298.828998 -293.661595) (xy 298.787327 -293.628364)
			(xy 298.751075 -293.589293) (xy 298.721051 -293.545256) (xy 298.697925 -293.497235) (xy 298.682215 -293.446305)
			(xy 298.674272 -293.393601) (xy 295.259986 -293.393601) (xy 295.252081 -293.446051) (xy 295.236371 -293.496981)
			(xy 295.213245 -293.545002) (xy 295.183221 -293.589039) (xy 295.146969 -293.62811) (xy 295.105298 -293.661341)
			(xy 295.05914 -293.68799) (xy 295.009526 -293.707462) (xy 294.957564 -293.719322) (xy 294.904414 -293.723306)
			(xy 294.851264 -293.719322) (xy 294.799302 -293.707462) (xy 294.749688 -293.68799) (xy 294.70353 -293.661341)
			(xy 294.661859 -293.62811) (xy 294.625607 -293.589039) (xy 294.595583 -293.545002) (xy 294.572457 -293.496981)
			(xy 294.556747 -293.446051) (xy 294.548804 -293.393347) (xy 284.272492 -293.393347) (xy 284.264549 -293.446051)
			(xy 284.248839 -293.496981) (xy 284.225713 -293.545002) (xy 284.195689 -293.589039) (xy 284.159437 -293.62811)
			(xy 284.117766 -293.661341) (xy 284.071608 -293.68799) (xy 284.021994 -293.707462) (xy 283.970032 -293.719322)
			(xy 283.916882 -293.723306) (xy 283.863732 -293.719322) (xy 283.81177 -293.707462) (xy 283.762156 -293.68799)
			(xy 283.715998 -293.661341) (xy 283.674327 -293.62811) (xy 283.638075 -293.589039) (xy 283.608051 -293.545002)
			(xy 283.584925 -293.496981) (xy 283.569215 -293.446051) (xy 283.561272 -293.393347) (xy 280.172424 -293.393347)
			(xy 280.164481 -293.446051) (xy 280.148771 -293.496981) (xy 280.125645 -293.545002) (xy 280.095621 -293.589039)
			(xy 280.059369 -293.62811) (xy 280.017698 -293.661341) (xy 279.97154 -293.68799) (xy 279.921926 -293.707462)
			(xy 279.869964 -293.719322) (xy 279.816814 -293.723306) (xy 279.763664 -293.719322) (xy 279.711702 -293.707462)
			(xy 279.662088 -293.68799) (xy 279.61593 -293.661341) (xy 279.574259 -293.62811) (xy 279.538007 -293.589039)
			(xy 279.507983 -293.545002) (xy 279.484857 -293.496981) (xy 279.469147 -293.446051) (xy 279.461204 -293.393347)
			(xy 269.184892 -293.393347) (xy 269.176949 -293.446051) (xy 269.161239 -293.496981) (xy 269.138113 -293.545002)
			(xy 269.108089 -293.589039) (xy 269.071837 -293.62811) (xy 269.030166 -293.661341) (xy 268.984008 -293.68799)
			(xy 268.934394 -293.707462) (xy 268.882432 -293.719322) (xy 268.829282 -293.723306) (xy 268.776132 -293.719322)
			(xy 268.72417 -293.707462) (xy 268.674556 -293.68799) (xy 268.628398 -293.661341) (xy 268.586727 -293.62811)
			(xy 268.550475 -293.589039) (xy 268.520451 -293.545002) (xy 268.497325 -293.496981) (xy 268.481615 -293.446051)
			(xy 268.473672 -293.393347) (xy 265.084824 -293.393347) (xy 265.076881 -293.446051) (xy 265.061171 -293.496981)
			(xy 265.038045 -293.545002) (xy 265.008021 -293.589039) (xy 264.971769 -293.62811) (xy 264.930098 -293.661341)
			(xy 264.88394 -293.68799) (xy 264.834326 -293.707462) (xy 264.782364 -293.719322) (xy 264.729214 -293.723306)
			(xy 264.676064 -293.719322) (xy 264.624102 -293.707462) (xy 264.574488 -293.68799) (xy 264.52833 -293.661341)
			(xy 264.486659 -293.62811) (xy 264.450407 -293.589039) (xy 264.420383 -293.545002) (xy 264.397257 -293.496981)
			(xy 264.381547 -293.446051) (xy 264.373604 -293.393347) (xy 254.20828 -293.393347) (xy 254.20828 -294.243231)
			(xy 264.373604 -294.243231) (xy 264.373604 -294.189933) (xy 264.381547 -294.137229) (xy 264.397257 -294.086299)
			(xy 264.420383 -294.038278) (xy 264.450407 -293.994241) (xy 264.486659 -293.95517) (xy 264.52833 -293.921939)
			(xy 264.574488 -293.89529) (xy 264.624102 -293.875818) (xy 264.676064 -293.863958) (xy 264.729214 -293.859975)
			(xy 264.782364 -293.863958) (xy 264.834326 -293.875818) (xy 264.88394 -293.89529) (xy 264.930098 -293.921939)
			(xy 264.971769 -293.95517) (xy 265.008021 -293.994241) (xy 265.038045 -294.038278) (xy 265.061171 -294.086299)
			(xy 265.076881 -294.137229) (xy 265.084824 -294.189933) (xy 265.085322 -294.216582) (xy 265.084824 -294.243231)
			(xy 279.461204 -294.243231) (xy 279.461204 -294.189933) (xy 279.469147 -294.137229) (xy 279.484857 -294.086299)
			(xy 279.507983 -294.038278) (xy 279.538007 -293.994241) (xy 279.574259 -293.95517) (xy 279.61593 -293.921939)
			(xy 279.662088 -293.89529) (xy 279.711702 -293.875818) (xy 279.763664 -293.863958) (xy 279.816814 -293.859975)
			(xy 279.869964 -293.863958) (xy 279.921926 -293.875818) (xy 279.97154 -293.89529) (xy 280.017698 -293.921939)
			(xy 280.059369 -293.95517) (xy 280.095621 -293.994241) (xy 280.125645 -294.038278) (xy 280.148771 -294.086299)
			(xy 280.164481 -294.137229) (xy 280.172424 -294.189933) (xy 280.172922 -294.216582) (xy 280.172424 -294.243231)
			(xy 294.548804 -294.243231) (xy 294.548804 -294.189933) (xy 294.556747 -294.137229) (xy 294.572457 -294.086299)
			(xy 294.595583 -294.038278) (xy 294.625607 -293.994241) (xy 294.661859 -293.95517) (xy 294.70353 -293.921939)
			(xy 294.749688 -293.89529) (xy 294.799302 -293.875818) (xy 294.851264 -293.863958) (xy 294.904414 -293.859975)
			(xy 294.957564 -293.863958) (xy 295.009526 -293.875818) (xy 295.05914 -293.89529) (xy 295.105298 -293.921939)
			(xy 295.146969 -293.95517) (xy 295.183221 -293.994241) (xy 295.213245 -294.038278) (xy 295.236371 -294.086299)
			(xy 295.252081 -294.137229) (xy 295.260024 -294.189933) (xy 295.260522 -294.216582) (xy 295.260024 -294.243231)
			(xy 295.252081 -294.295935) (xy 295.236371 -294.346865) (xy 295.213245 -294.394886) (xy 295.183221 -294.438923)
			(xy 295.146969 -294.477994) (xy 295.105298 -294.511225) (xy 295.05914 -294.537874) (xy 295.009526 -294.557346)
			(xy 294.957564 -294.569206) (xy 294.904414 -294.57319) (xy 294.851264 -294.569206) (xy 294.799302 -294.557346)
			(xy 294.749688 -294.537874) (xy 294.70353 -294.511225) (xy 294.661859 -294.477994) (xy 294.625607 -294.438923)
			(xy 294.595583 -294.394886) (xy 294.572457 -294.346865) (xy 294.556747 -294.295935) (xy 294.548804 -294.243231)
			(xy 280.172424 -294.243231) (xy 280.164481 -294.295935) (xy 280.148771 -294.346865) (xy 280.125645 -294.394886)
			(xy 280.095621 -294.438923) (xy 280.059369 -294.477994) (xy 280.017698 -294.511225) (xy 279.97154 -294.537874)
			(xy 279.921926 -294.557346) (xy 279.869964 -294.569206) (xy 279.816814 -294.57319) (xy 279.763664 -294.569206)
			(xy 279.711702 -294.557346) (xy 279.662088 -294.537874) (xy 279.61593 -294.511225) (xy 279.574259 -294.477994)
			(xy 279.538007 -294.438923) (xy 279.507983 -294.394886) (xy 279.484857 -294.346865) (xy 279.469147 -294.295935)
			(xy 279.461204 -294.243231) (xy 265.084824 -294.243231) (xy 265.076881 -294.295935) (xy 265.061171 -294.346865)
			(xy 265.038045 -294.394886) (xy 265.008021 -294.438923) (xy 264.971769 -294.477994) (xy 264.930098 -294.511225)
			(xy 264.88394 -294.537874) (xy 264.834326 -294.557346) (xy 264.782364 -294.569206) (xy 264.729214 -294.57319)
			(xy 264.676064 -294.569206) (xy 264.624102 -294.557346) (xy 264.574488 -294.537874) (xy 264.52833 -294.511225)
			(xy 264.486659 -294.477994) (xy 264.450407 -294.438923) (xy 264.420383 -294.394886) (xy 264.397257 -294.346865)
			(xy 264.381547 -294.295935) (xy 264.373604 -294.243231) (xy 254.20828 -294.243231) (xy 254.20828 -295.093369)
			(xy 268.473672 -295.093369) (xy 268.473672 -295.040071) (xy 268.481615 -294.987367) (xy 268.497325 -294.936437)
			(xy 268.520451 -294.888416) (xy 268.550475 -294.844379) (xy 268.586727 -294.805308) (xy 268.628398 -294.772077)
			(xy 268.674556 -294.745428) (xy 268.72417 -294.725956) (xy 268.776132 -294.714096) (xy 268.829282 -294.710113)
			(xy 268.882432 -294.714096) (xy 268.934394 -294.725956) (xy 268.984008 -294.745428) (xy 269.030166 -294.772077)
			(xy 269.071837 -294.805308) (xy 269.108089 -294.844379) (xy 269.138113 -294.888416) (xy 269.161239 -294.936437)
			(xy 269.176949 -294.987367) (xy 269.184892 -295.040071) (xy 269.18539 -295.06672) (xy 269.184892 -295.093369)
			(xy 283.561272 -295.093369) (xy 283.561272 -295.040071) (xy 283.569215 -294.987367) (xy 283.584925 -294.936437)
			(xy 283.608051 -294.888416) (xy 283.638075 -294.844379) (xy 283.674327 -294.805308) (xy 283.715998 -294.772077)
			(xy 283.762156 -294.745428) (xy 283.81177 -294.725956) (xy 283.863732 -294.714096) (xy 283.916882 -294.710113)
			(xy 283.970032 -294.714096) (xy 284.021994 -294.725956) (xy 284.071608 -294.745428) (xy 284.117766 -294.772077)
			(xy 284.159437 -294.805308) (xy 284.195689 -294.844379) (xy 284.225713 -294.888416) (xy 284.248839 -294.936437)
			(xy 284.264549 -294.987367) (xy 284.272492 -295.040071) (xy 284.27299 -295.06672) (xy 284.272492 -295.093369)
			(xy 298.674272 -295.093369) (xy 298.674272 -295.040071) (xy 298.682215 -294.987367) (xy 298.697925 -294.936437)
			(xy 298.721051 -294.888416) (xy 298.751075 -294.844379) (xy 298.787327 -294.805308) (xy 298.828998 -294.772077)
			(xy 298.875156 -294.745428) (xy 298.92477 -294.725956) (xy 298.976732 -294.714096) (xy 299.029882 -294.710113)
			(xy 299.083032 -294.714096) (xy 299.134994 -294.725956) (xy 299.184608 -294.745428) (xy 299.230766 -294.772077)
			(xy 299.272437 -294.805308) (xy 299.308689 -294.844379) (xy 299.338713 -294.888416) (xy 299.361839 -294.936437)
			(xy 299.377549 -294.987367) (xy 299.385492 -295.040071) (xy 299.38599 -295.06672) (xy 299.385492 -295.093369)
			(xy 299.377549 -295.146073) (xy 299.361839 -295.197003) (xy 299.338713 -295.245024) (xy 299.308689 -295.289061)
			(xy 299.272437 -295.328132) (xy 299.230766 -295.361363) (xy 299.184608 -295.388012) (xy 299.134994 -295.407484)
			(xy 299.083032 -295.419344) (xy 299.029882 -295.423328) (xy 298.976732 -295.419344) (xy 298.92477 -295.407484)
			(xy 298.875156 -295.388012) (xy 298.828998 -295.361363) (xy 298.787327 -295.328132) (xy 298.751075 -295.289061)
			(xy 298.721051 -295.245024) (xy 298.697925 -295.197003) (xy 298.682215 -295.146073) (xy 298.674272 -295.093369)
			(xy 284.272492 -295.093369) (xy 284.264549 -295.146073) (xy 284.248839 -295.197003) (xy 284.225713 -295.245024)
			(xy 284.195689 -295.289061) (xy 284.159437 -295.328132) (xy 284.117766 -295.361363) (xy 284.071608 -295.388012)
			(xy 284.021994 -295.407484) (xy 283.970032 -295.419344) (xy 283.916882 -295.423328) (xy 283.863732 -295.419344)
			(xy 283.81177 -295.407484) (xy 283.762156 -295.388012) (xy 283.715998 -295.361363) (xy 283.674327 -295.328132)
			(xy 283.638075 -295.289061) (xy 283.608051 -295.245024) (xy 283.584925 -295.197003) (xy 283.569215 -295.146073)
			(xy 283.561272 -295.093369) (xy 269.184892 -295.093369) (xy 269.176949 -295.146073) (xy 269.161239 -295.197003)
			(xy 269.138113 -295.245024) (xy 269.108089 -295.289061) (xy 269.071837 -295.328132) (xy 269.030166 -295.361363)
			(xy 268.984008 -295.388012) (xy 268.934394 -295.407484) (xy 268.882432 -295.419344) (xy 268.829282 -295.423328)
			(xy 268.776132 -295.419344) (xy 268.72417 -295.407484) (xy 268.674556 -295.388012) (xy 268.628398 -295.361363)
			(xy 268.586727 -295.328132) (xy 268.550475 -295.289061) (xy 268.520451 -295.245024) (xy 268.497325 -295.197003)
			(xy 268.481615 -295.146073) (xy 268.473672 -295.093369) (xy 254.20828 -295.093369) (xy 254.20828 -295.943253)
			(xy 264.373604 -295.943253) (xy 264.373604 -295.889955) (xy 264.381547 -295.837251) (xy 264.397257 -295.786321)
			(xy 264.420383 -295.7383) (xy 264.450407 -295.694263) (xy 264.486659 -295.655192) (xy 264.52833 -295.621961)
			(xy 264.574488 -295.595312) (xy 264.624102 -295.57584) (xy 264.676064 -295.56398) (xy 264.729214 -295.559997)
			(xy 264.782364 -295.56398) (xy 264.834326 -295.57584) (xy 264.88394 -295.595312) (xy 264.930098 -295.621961)
			(xy 264.971769 -295.655192) (xy 265.008021 -295.694263) (xy 265.038045 -295.7383) (xy 265.061171 -295.786321)
			(xy 265.076881 -295.837251) (xy 265.084824 -295.889955) (xy 265.085322 -295.916604) (xy 265.084824 -295.943253)
			(xy 279.461204 -295.943253) (xy 279.461204 -295.889955) (xy 279.469147 -295.837251) (xy 279.484857 -295.786321)
			(xy 279.507983 -295.7383) (xy 279.538007 -295.694263) (xy 279.574259 -295.655192) (xy 279.61593 -295.621961)
			(xy 279.662088 -295.595312) (xy 279.711702 -295.57584) (xy 279.763664 -295.56398) (xy 279.816814 -295.559997)
			(xy 279.869964 -295.56398) (xy 279.921926 -295.57584) (xy 279.97154 -295.595312) (xy 280.017698 -295.621961)
			(xy 280.059369 -295.655192) (xy 280.095621 -295.694263) (xy 280.125645 -295.7383) (xy 280.148771 -295.786321)
			(xy 280.164481 -295.837251) (xy 280.172424 -295.889955) (xy 280.172922 -295.916604) (xy 280.172424 -295.943253)
			(xy 294.548804 -295.943253) (xy 294.548804 -295.889955) (xy 294.556747 -295.837251) (xy 294.572457 -295.786321)
			(xy 294.595583 -295.7383) (xy 294.625607 -295.694263) (xy 294.661859 -295.655192) (xy 294.70353 -295.621961)
			(xy 294.749688 -295.595312) (xy 294.799302 -295.57584) (xy 294.851264 -295.56398) (xy 294.904414 -295.559997)
			(xy 294.957564 -295.56398) (xy 295.009526 -295.57584) (xy 295.05914 -295.595312) (xy 295.105298 -295.621961)
			(xy 295.146969 -295.655192) (xy 295.183221 -295.694263) (xy 295.213245 -295.7383) (xy 295.236371 -295.786321)
			(xy 295.252081 -295.837251) (xy 295.260024 -295.889955) (xy 295.260522 -295.916604) (xy 295.260024 -295.943253)
			(xy 295.252081 -295.995957) (xy 295.236371 -296.046887) (xy 295.213245 -296.094908) (xy 295.183221 -296.138945)
			(xy 295.146969 -296.178016) (xy 295.105298 -296.211247) (xy 295.05914 -296.237896) (xy 295.009526 -296.257368)
			(xy 294.957564 -296.269228) (xy 294.904414 -296.273212) (xy 294.851264 -296.269228) (xy 294.799302 -296.257368)
			(xy 294.749688 -296.237896) (xy 294.70353 -296.211247) (xy 294.661859 -296.178016) (xy 294.625607 -296.138945)
			(xy 294.595583 -296.094908) (xy 294.572457 -296.046887) (xy 294.556747 -295.995957) (xy 294.548804 -295.943253)
			(xy 280.172424 -295.943253) (xy 280.164481 -295.995957) (xy 280.148771 -296.046887) (xy 280.125645 -296.094908)
			(xy 280.095621 -296.138945) (xy 280.059369 -296.178016) (xy 280.017698 -296.211247) (xy 279.97154 -296.237896)
			(xy 279.921926 -296.257368) (xy 279.869964 -296.269228) (xy 279.816814 -296.273212) (xy 279.763664 -296.269228)
			(xy 279.711702 -296.257368) (xy 279.662088 -296.237896) (xy 279.61593 -296.211247) (xy 279.574259 -296.178016)
			(xy 279.538007 -296.138945) (xy 279.507983 -296.094908) (xy 279.484857 -296.046887) (xy 279.469147 -295.995957)
			(xy 279.461204 -295.943253) (xy 265.084824 -295.943253) (xy 265.076881 -295.995957) (xy 265.061171 -296.046887)
			(xy 265.038045 -296.094908) (xy 265.008021 -296.138945) (xy 264.971769 -296.178016) (xy 264.930098 -296.211247)
			(xy 264.88394 -296.237896) (xy 264.834326 -296.257368) (xy 264.782364 -296.269228) (xy 264.729214 -296.273212)
			(xy 264.676064 -296.269228) (xy 264.624102 -296.257368) (xy 264.574488 -296.237896) (xy 264.52833 -296.211247)
			(xy 264.486659 -296.178016) (xy 264.450407 -296.138945) (xy 264.420383 -296.094908) (xy 264.397257 -296.046887)
			(xy 264.381547 -295.995957) (xy 264.373604 -295.943253) (xy 254.20828 -295.943253) (xy 254.20828 -296.793391)
			(xy 268.473672 -296.793391) (xy 268.473672 -296.740093) (xy 268.481615 -296.687389) (xy 268.497325 -296.636459)
			(xy 268.520451 -296.588438) (xy 268.550475 -296.544401) (xy 268.586727 -296.50533) (xy 268.628398 -296.472099)
			(xy 268.674556 -296.44545) (xy 268.72417 -296.425978) (xy 268.776132 -296.414118) (xy 268.829282 -296.410135)
			(xy 268.882432 -296.414118) (xy 268.934394 -296.425978) (xy 268.984008 -296.44545) (xy 269.030166 -296.472099)
			(xy 269.071837 -296.50533) (xy 269.108089 -296.544401) (xy 269.138113 -296.588438) (xy 269.161239 -296.636459)
			(xy 269.176949 -296.687389) (xy 269.184892 -296.740093) (xy 269.18539 -296.766742) (xy 269.184892 -296.793391)
			(xy 283.561272 -296.793391) (xy 283.561272 -296.740093) (xy 283.569215 -296.687389) (xy 283.584925 -296.636459)
			(xy 283.608051 -296.588438) (xy 283.638075 -296.544401) (xy 283.674327 -296.50533) (xy 283.715998 -296.472099)
			(xy 283.762156 -296.44545) (xy 283.81177 -296.425978) (xy 283.863732 -296.414118) (xy 283.916882 -296.410135)
			(xy 283.970032 -296.414118) (xy 284.021994 -296.425978) (xy 284.071608 -296.44545) (xy 284.117766 -296.472099)
			(xy 284.159437 -296.50533) (xy 284.195689 -296.544401) (xy 284.225713 -296.588438) (xy 284.248839 -296.636459)
			(xy 284.264549 -296.687389) (xy 284.272492 -296.740093) (xy 284.27299 -296.766742) (xy 284.272492 -296.793391)
			(xy 298.674272 -296.793391) (xy 298.674272 -296.740093) (xy 298.682215 -296.687389) (xy 298.697925 -296.636459)
			(xy 298.721051 -296.588438) (xy 298.751075 -296.544401) (xy 298.787327 -296.50533) (xy 298.828998 -296.472099)
			(xy 298.875156 -296.44545) (xy 298.92477 -296.425978) (xy 298.976732 -296.414118) (xy 299.029882 -296.410135)
			(xy 299.083032 -296.414118) (xy 299.134994 -296.425978) (xy 299.184608 -296.44545) (xy 299.230766 -296.472099)
			(xy 299.272437 -296.50533) (xy 299.308689 -296.544401) (xy 299.338713 -296.588438) (xy 299.361839 -296.636459)
			(xy 299.377549 -296.687389) (xy 299.385492 -296.740093) (xy 299.38599 -296.766742) (xy 299.385492 -296.793391)
			(xy 299.377549 -296.846095) (xy 299.361839 -296.897025) (xy 299.338713 -296.945046) (xy 299.308689 -296.989083)
			(xy 299.272437 -297.028154) (xy 299.230766 -297.061385) (xy 299.184608 -297.088034) (xy 299.134994 -297.107506)
			(xy 299.083032 -297.119366) (xy 299.029882 -297.12335) (xy 298.976732 -297.119366) (xy 298.92477 -297.107506)
			(xy 298.875156 -297.088034) (xy 298.828998 -297.061385) (xy 298.787327 -297.028154) (xy 298.751075 -296.989083)
			(xy 298.721051 -296.945046) (xy 298.697925 -296.897025) (xy 298.682215 -296.846095) (xy 298.674272 -296.793391)
			(xy 284.272492 -296.793391) (xy 284.264549 -296.846095) (xy 284.248839 -296.897025) (xy 284.225713 -296.945046)
			(xy 284.195689 -296.989083) (xy 284.159437 -297.028154) (xy 284.117766 -297.061385) (xy 284.071608 -297.088034)
			(xy 284.021994 -297.107506) (xy 283.970032 -297.119366) (xy 283.916882 -297.12335) (xy 283.863732 -297.119366)
			(xy 283.81177 -297.107506) (xy 283.762156 -297.088034) (xy 283.715998 -297.061385) (xy 283.674327 -297.028154)
			(xy 283.638075 -296.989083) (xy 283.608051 -296.945046) (xy 283.584925 -296.897025) (xy 283.569215 -296.846095)
			(xy 283.561272 -296.793391) (xy 269.184892 -296.793391) (xy 269.176949 -296.846095) (xy 269.161239 -296.897025)
			(xy 269.138113 -296.945046) (xy 269.108089 -296.989083) (xy 269.071837 -297.028154) (xy 269.030166 -297.061385)
			(xy 268.984008 -297.088034) (xy 268.934394 -297.107506) (xy 268.882432 -297.119366) (xy 268.829282 -297.12335)
			(xy 268.776132 -297.119366) (xy 268.72417 -297.107506) (xy 268.674556 -297.088034) (xy 268.628398 -297.061385)
			(xy 268.586727 -297.028154) (xy 268.550475 -296.989083) (xy 268.520451 -296.945046) (xy 268.497325 -296.897025)
			(xy 268.481615 -296.846095) (xy 268.473672 -296.793391) (xy 254.20828 -296.793391) (xy 254.20828 -297.643275)
			(xy 264.373604 -297.643275) (xy 264.373604 -297.589977) (xy 264.381547 -297.537273) (xy 264.397257 -297.486343)
			(xy 264.420383 -297.438322) (xy 264.450407 -297.394285) (xy 264.486659 -297.355214) (xy 264.52833 -297.321983)
			(xy 264.574488 -297.295334) (xy 264.624102 -297.275862) (xy 264.676064 -297.264002) (xy 264.729214 -297.260019)
			(xy 264.782364 -297.264002) (xy 264.834326 -297.275862) (xy 264.88394 -297.295334) (xy 264.930098 -297.321983)
			(xy 264.971769 -297.355214) (xy 265.008021 -297.394285) (xy 265.038045 -297.438322) (xy 265.061171 -297.486343)
			(xy 265.076881 -297.537273) (xy 265.084824 -297.589977) (xy 265.085322 -297.616626) (xy 265.084824 -297.643275)
			(xy 279.461204 -297.643275) (xy 279.461204 -297.589977) (xy 279.469147 -297.537273) (xy 279.484857 -297.486343)
			(xy 279.507983 -297.438322) (xy 279.538007 -297.394285) (xy 279.574259 -297.355214) (xy 279.61593 -297.321983)
			(xy 279.662088 -297.295334) (xy 279.711702 -297.275862) (xy 279.763664 -297.264002) (xy 279.816814 -297.260019)
			(xy 279.869964 -297.264002) (xy 279.921926 -297.275862) (xy 279.97154 -297.295334) (xy 280.017698 -297.321983)
			(xy 280.059369 -297.355214) (xy 280.095621 -297.394285) (xy 280.125645 -297.438322) (xy 280.148771 -297.486343)
			(xy 280.164481 -297.537273) (xy 280.172424 -297.589977) (xy 280.172922 -297.616626) (xy 280.172424 -297.643275)
			(xy 294.548804 -297.643275) (xy 294.548804 -297.589977) (xy 294.556747 -297.537273) (xy 294.572457 -297.486343)
			(xy 294.595583 -297.438322) (xy 294.625607 -297.394285) (xy 294.661859 -297.355214) (xy 294.70353 -297.321983)
			(xy 294.749688 -297.295334) (xy 294.799302 -297.275862) (xy 294.851264 -297.264002) (xy 294.904414 -297.260019)
			(xy 294.957564 -297.264002) (xy 295.009526 -297.275862) (xy 295.05914 -297.295334) (xy 295.105298 -297.321983)
			(xy 295.146969 -297.355214) (xy 295.183221 -297.394285) (xy 295.213245 -297.438322) (xy 295.236371 -297.486343)
			(xy 295.252081 -297.537273) (xy 295.260024 -297.589977) (xy 295.260522 -297.616626) (xy 295.260024 -297.643275)
			(xy 295.252081 -297.695979) (xy 295.236371 -297.746909) (xy 295.213245 -297.79493) (xy 295.183221 -297.838967)
			(xy 295.146969 -297.878038) (xy 295.105298 -297.911269) (xy 295.05914 -297.937918) (xy 295.009526 -297.95739)
			(xy 294.957564 -297.96925) (xy 294.904414 -297.973234) (xy 294.851264 -297.96925) (xy 294.799302 -297.95739)
			(xy 294.749688 -297.937918) (xy 294.70353 -297.911269) (xy 294.661859 -297.878038) (xy 294.625607 -297.838967)
			(xy 294.595583 -297.79493) (xy 294.572457 -297.746909) (xy 294.556747 -297.695979) (xy 294.548804 -297.643275)
			(xy 280.172424 -297.643275) (xy 280.164481 -297.695979) (xy 280.148771 -297.746909) (xy 280.125645 -297.79493)
			(xy 280.095621 -297.838967) (xy 280.059369 -297.878038) (xy 280.017698 -297.911269) (xy 279.97154 -297.937918)
			(xy 279.921926 -297.95739) (xy 279.869964 -297.96925) (xy 279.816814 -297.973234) (xy 279.763664 -297.96925)
			(xy 279.711702 -297.95739) (xy 279.662088 -297.937918) (xy 279.61593 -297.911269) (xy 279.574259 -297.878038)
			(xy 279.538007 -297.838967) (xy 279.507983 -297.79493) (xy 279.484857 -297.746909) (xy 279.469147 -297.695979)
			(xy 279.461204 -297.643275) (xy 265.084824 -297.643275) (xy 265.076881 -297.695979) (xy 265.061171 -297.746909)
			(xy 265.038045 -297.79493) (xy 265.008021 -297.838967) (xy 264.971769 -297.878038) (xy 264.930098 -297.911269)
			(xy 264.88394 -297.937918) (xy 264.834326 -297.95739) (xy 264.782364 -297.96925) (xy 264.729214 -297.973234)
			(xy 264.676064 -297.96925) (xy 264.624102 -297.95739) (xy 264.574488 -297.937918) (xy 264.52833 -297.911269)
			(xy 264.486659 -297.878038) (xy 264.450407 -297.838967) (xy 264.420383 -297.79493) (xy 264.397257 -297.746909)
			(xy 264.381547 -297.695979) (xy 264.373604 -297.643275) (xy 254.20828 -297.643275) (xy 254.20828 -298.493413)
			(xy 268.473672 -298.493413) (xy 268.473672 -298.440115) (xy 268.481615 -298.387411) (xy 268.497325 -298.336481)
			(xy 268.520451 -298.28846) (xy 268.550475 -298.244423) (xy 268.586727 -298.205352) (xy 268.628398 -298.172121)
			(xy 268.674556 -298.145472) (xy 268.72417 -298.126) (xy 268.776132 -298.11414) (xy 268.829282 -298.110157)
			(xy 268.882432 -298.11414) (xy 268.934394 -298.126) (xy 268.984008 -298.145472) (xy 269.030166 -298.172121)
			(xy 269.071837 -298.205352) (xy 269.108089 -298.244423) (xy 269.138113 -298.28846) (xy 269.161239 -298.336481)
			(xy 269.176949 -298.387411) (xy 269.184892 -298.440115) (xy 269.18539 -298.466764) (xy 269.184892 -298.493413)
			(xy 283.561272 -298.493413) (xy 283.561272 -298.440115) (xy 283.569215 -298.387411) (xy 283.584925 -298.336481)
			(xy 283.608051 -298.28846) (xy 283.638075 -298.244423) (xy 283.674327 -298.205352) (xy 283.715998 -298.172121)
			(xy 283.762156 -298.145472) (xy 283.81177 -298.126) (xy 283.863732 -298.11414) (xy 283.916882 -298.110157)
			(xy 283.970032 -298.11414) (xy 284.021994 -298.126) (xy 284.071608 -298.145472) (xy 284.117766 -298.172121)
			(xy 284.159437 -298.205352) (xy 284.195689 -298.244423) (xy 284.225713 -298.28846) (xy 284.248839 -298.336481)
			(xy 284.264549 -298.387411) (xy 284.272492 -298.440115) (xy 284.27299 -298.466764) (xy 284.272492 -298.493413)
			(xy 298.674272 -298.493413) (xy 298.674272 -298.440115) (xy 298.682215 -298.387411) (xy 298.697925 -298.336481)
			(xy 298.721051 -298.28846) (xy 298.751075 -298.244423) (xy 298.787327 -298.205352) (xy 298.828998 -298.172121)
			(xy 298.875156 -298.145472) (xy 298.92477 -298.126) (xy 298.976732 -298.11414) (xy 299.029882 -298.110157)
			(xy 299.083032 -298.11414) (xy 299.134994 -298.126) (xy 299.184608 -298.145472) (xy 299.230766 -298.172121)
			(xy 299.272437 -298.205352) (xy 299.308689 -298.244423) (xy 299.338713 -298.28846) (xy 299.361839 -298.336481)
			(xy 299.377549 -298.387411) (xy 299.385492 -298.440115) (xy 299.38599 -298.466764) (xy 299.385492 -298.493413)
			(xy 299.377549 -298.546117) (xy 299.361839 -298.597047) (xy 299.338713 -298.645068) (xy 299.308689 -298.689105)
			(xy 299.272437 -298.728176) (xy 299.230766 -298.761407) (xy 299.184608 -298.788056) (xy 299.134994 -298.807528)
			(xy 299.083032 -298.819388) (xy 299.029882 -298.823372) (xy 298.976732 -298.819388) (xy 298.92477 -298.807528)
			(xy 298.875156 -298.788056) (xy 298.828998 -298.761407) (xy 298.787327 -298.728176) (xy 298.751075 -298.689105)
			(xy 298.721051 -298.645068) (xy 298.697925 -298.597047) (xy 298.682215 -298.546117) (xy 298.674272 -298.493413)
			(xy 284.272492 -298.493413) (xy 284.264549 -298.546117) (xy 284.248839 -298.597047) (xy 284.225713 -298.645068)
			(xy 284.195689 -298.689105) (xy 284.159437 -298.728176) (xy 284.117766 -298.761407) (xy 284.071608 -298.788056)
			(xy 284.021994 -298.807528) (xy 283.970032 -298.819388) (xy 283.916882 -298.823372) (xy 283.863732 -298.819388)
			(xy 283.81177 -298.807528) (xy 283.762156 -298.788056) (xy 283.715998 -298.761407) (xy 283.674327 -298.728176)
			(xy 283.638075 -298.689105) (xy 283.608051 -298.645068) (xy 283.584925 -298.597047) (xy 283.569215 -298.546117)
			(xy 283.561272 -298.493413) (xy 269.184892 -298.493413) (xy 269.176949 -298.546117) (xy 269.161239 -298.597047)
			(xy 269.138113 -298.645068) (xy 269.108089 -298.689105) (xy 269.071837 -298.728176) (xy 269.030166 -298.761407)
			(xy 268.984008 -298.788056) (xy 268.934394 -298.807528) (xy 268.882432 -298.819388) (xy 268.829282 -298.823372)
			(xy 268.776132 -298.819388) (xy 268.72417 -298.807528) (xy 268.674556 -298.788056) (xy 268.628398 -298.761407)
			(xy 268.586727 -298.728176) (xy 268.550475 -298.689105) (xy 268.520451 -298.645068) (xy 268.497325 -298.597047)
			(xy 268.481615 -298.546117) (xy 268.473672 -298.493413) (xy 254.20828 -298.493413) (xy 254.20828 -299.343297)
			(xy 264.373604 -299.343297) (xy 264.373604 -299.289999) (xy 264.381547 -299.237295) (xy 264.397257 -299.186365)
			(xy 264.420383 -299.138344) (xy 264.450407 -299.094307) (xy 264.486659 -299.055236) (xy 264.52833 -299.022005)
			(xy 264.574488 -298.995356) (xy 264.624102 -298.975884) (xy 264.676064 -298.964024) (xy 264.729214 -298.960041)
			(xy 264.782364 -298.964024) (xy 264.834326 -298.975884) (xy 264.88394 -298.995356) (xy 264.930098 -299.022005)
			(xy 264.971769 -299.055236) (xy 265.008021 -299.094307) (xy 265.038045 -299.138344) (xy 265.061171 -299.186365)
			(xy 265.076881 -299.237295) (xy 265.084824 -299.289999) (xy 265.085322 -299.316648) (xy 265.084824 -299.343297)
			(xy 279.461204 -299.343297) (xy 279.461204 -299.289999) (xy 279.469147 -299.237295) (xy 279.484857 -299.186365)
			(xy 279.507983 -299.138344) (xy 279.538007 -299.094307) (xy 279.574259 -299.055236) (xy 279.61593 -299.022005)
			(xy 279.662088 -298.995356) (xy 279.711702 -298.975884) (xy 279.763664 -298.964024) (xy 279.816814 -298.960041)
			(xy 279.869964 -298.964024) (xy 279.921926 -298.975884) (xy 279.97154 -298.995356) (xy 280.017698 -299.022005)
			(xy 280.059369 -299.055236) (xy 280.095621 -299.094307) (xy 280.125645 -299.138344) (xy 280.148771 -299.186365)
			(xy 280.164481 -299.237295) (xy 280.172424 -299.289999) (xy 280.172922 -299.316648) (xy 280.172424 -299.343297)
			(xy 294.548804 -299.343297) (xy 294.548804 -299.289999) (xy 294.556747 -299.237295) (xy 294.572457 -299.186365)
			(xy 294.595583 -299.138344) (xy 294.625607 -299.094307) (xy 294.661859 -299.055236) (xy 294.70353 -299.022005)
			(xy 294.749688 -298.995356) (xy 294.799302 -298.975884) (xy 294.851264 -298.964024) (xy 294.904414 -298.960041)
			(xy 294.957564 -298.964024) (xy 295.009526 -298.975884) (xy 295.05914 -298.995356) (xy 295.105298 -299.022005)
			(xy 295.146969 -299.055236) (xy 295.183221 -299.094307) (xy 295.213245 -299.138344) (xy 295.236371 -299.186365)
			(xy 295.252081 -299.237295) (xy 295.260024 -299.289999) (xy 295.260522 -299.316648) (xy 295.260024 -299.343297)
			(xy 309.636404 -299.343297) (xy 309.636404 -299.289999) (xy 309.644347 -299.237295) (xy 309.660057 -299.186365)
			(xy 309.683183 -299.138344) (xy 309.713207 -299.094307) (xy 309.749459 -299.055236) (xy 309.79113 -299.022005)
			(xy 309.837288 -298.995356) (xy 309.886902 -298.975884) (xy 309.938864 -298.964024) (xy 309.992014 -298.960041)
			(xy 310.045164 -298.964024) (xy 310.097126 -298.975884) (xy 310.14674 -298.995356) (xy 310.192898 -299.022005)
			(xy 310.234569 -299.055236) (xy 310.270821 -299.094307) (xy 310.300845 -299.138344) (xy 310.323971 -299.186365)
			(xy 310.339681 -299.237295) (xy 310.347624 -299.289999) (xy 310.348122 -299.316648) (xy 310.347624 -299.343297)
			(xy 310.339681 -299.396001) (xy 310.323971 -299.446931) (xy 310.300845 -299.494952) (xy 310.270821 -299.538989)
			(xy 310.234569 -299.57806) (xy 310.192898 -299.611291) (xy 310.14674 -299.63794) (xy 310.097126 -299.657412)
			(xy 310.045164 -299.669272) (xy 309.992014 -299.673256) (xy 309.938864 -299.669272) (xy 309.886902 -299.657412)
			(xy 309.837288 -299.63794) (xy 309.79113 -299.611291) (xy 309.749459 -299.57806) (xy 309.713207 -299.538989)
			(xy 309.683183 -299.494952) (xy 309.660057 -299.446931) (xy 309.644347 -299.396001) (xy 309.636404 -299.343297)
			(xy 295.260024 -299.343297) (xy 295.252081 -299.396001) (xy 295.236371 -299.446931) (xy 295.213245 -299.494952)
			(xy 295.183221 -299.538989) (xy 295.146969 -299.57806) (xy 295.105298 -299.611291) (xy 295.05914 -299.63794)
			(xy 295.009526 -299.657412) (xy 294.957564 -299.669272) (xy 294.904414 -299.673256) (xy 294.851264 -299.669272)
			(xy 294.799302 -299.657412) (xy 294.749688 -299.63794) (xy 294.70353 -299.611291) (xy 294.661859 -299.57806)
			(xy 294.625607 -299.538989) (xy 294.595583 -299.494952) (xy 294.572457 -299.446931) (xy 294.556747 -299.396001)
			(xy 294.548804 -299.343297) (xy 280.172424 -299.343297) (xy 280.164481 -299.396001) (xy 280.148771 -299.446931)
			(xy 280.125645 -299.494952) (xy 280.095621 -299.538989) (xy 280.059369 -299.57806) (xy 280.017698 -299.611291)
			(xy 279.97154 -299.63794) (xy 279.921926 -299.657412) (xy 279.869964 -299.669272) (xy 279.816814 -299.673256)
			(xy 279.763664 -299.669272) (xy 279.711702 -299.657412) (xy 279.662088 -299.63794) (xy 279.61593 -299.611291)
			(xy 279.574259 -299.57806) (xy 279.538007 -299.538989) (xy 279.507983 -299.494952) (xy 279.484857 -299.446931)
			(xy 279.469147 -299.396001) (xy 279.461204 -299.343297) (xy 265.084824 -299.343297) (xy 265.076881 -299.396001)
			(xy 265.061171 -299.446931) (xy 265.038045 -299.494952) (xy 265.008021 -299.538989) (xy 264.971769 -299.57806)
			(xy 264.930098 -299.611291) (xy 264.88394 -299.63794) (xy 264.834326 -299.657412) (xy 264.782364 -299.669272)
			(xy 264.729214 -299.673256) (xy 264.676064 -299.669272) (xy 264.624102 -299.657412) (xy 264.574488 -299.63794)
			(xy 264.52833 -299.611291) (xy 264.486659 -299.57806) (xy 264.450407 -299.538989) (xy 264.420383 -299.494952)
			(xy 264.397257 -299.446931) (xy 264.381547 -299.396001) (xy 264.373604 -299.343297) (xy 254.20828 -299.343297)
			(xy 254.20828 -300.193435) (xy 268.473672 -300.193435) (xy 268.473672 -300.140137) (xy 268.481615 -300.087433)
			(xy 268.497325 -300.036503) (xy 268.520451 -299.988482) (xy 268.550475 -299.944445) (xy 268.586727 -299.905374)
			(xy 268.628398 -299.872143) (xy 268.674556 -299.845494) (xy 268.72417 -299.826022) (xy 268.776132 -299.814162)
			(xy 268.829282 -299.810179) (xy 268.882432 -299.814162) (xy 268.934394 -299.826022) (xy 268.984008 -299.845494)
			(xy 269.030166 -299.872143) (xy 269.071837 -299.905374) (xy 269.108089 -299.944445) (xy 269.138113 -299.988482)
			(xy 269.161239 -300.036503) (xy 269.176949 -300.087433) (xy 269.184892 -300.140137) (xy 269.18539 -300.166786)
			(xy 269.184892 -300.193435) (xy 283.561272 -300.193435) (xy 283.561272 -300.140137) (xy 283.569215 -300.087433)
			(xy 283.584925 -300.036503) (xy 283.608051 -299.988482) (xy 283.638075 -299.944445) (xy 283.674327 -299.905374)
			(xy 283.715998 -299.872143) (xy 283.762156 -299.845494) (xy 283.81177 -299.826022) (xy 283.863732 -299.814162)
			(xy 283.916882 -299.810179) (xy 283.970032 -299.814162) (xy 284.021994 -299.826022) (xy 284.071608 -299.845494)
			(xy 284.117766 -299.872143) (xy 284.159437 -299.905374) (xy 284.195689 -299.944445) (xy 284.225713 -299.988482)
			(xy 284.248839 -300.036503) (xy 284.264549 -300.087433) (xy 284.272492 -300.140137) (xy 284.27299 -300.166786)
			(xy 284.272492 -300.193435) (xy 298.674272 -300.193435) (xy 298.674272 -300.140137) (xy 298.682215 -300.087433)
			(xy 298.697925 -300.036503) (xy 298.721051 -299.988482) (xy 298.751075 -299.944445) (xy 298.787327 -299.905374)
			(xy 298.828998 -299.872143) (xy 298.875156 -299.845494) (xy 298.92477 -299.826022) (xy 298.976732 -299.814162)
			(xy 299.029882 -299.810179) (xy 299.083032 -299.814162) (xy 299.134994 -299.826022) (xy 299.184608 -299.845494)
			(xy 299.230766 -299.872143) (xy 299.272437 -299.905374) (xy 299.308689 -299.944445) (xy 299.338713 -299.988482)
			(xy 299.361839 -300.036503) (xy 299.377549 -300.087433) (xy 299.385492 -300.140137) (xy 299.38599 -300.166786)
			(xy 299.385492 -300.193435) (xy 299.377549 -300.246139) (xy 299.361839 -300.297069) (xy 299.338713 -300.34509)
			(xy 299.308689 -300.389127) (xy 299.272437 -300.428198) (xy 299.230766 -300.461429) (xy 299.184608 -300.488078)
			(xy 299.134994 -300.50755) (xy 299.083032 -300.51941) (xy 299.029882 -300.523394) (xy 298.976732 -300.51941)
			(xy 298.92477 -300.50755) (xy 298.875156 -300.488078) (xy 298.828998 -300.461429) (xy 298.787327 -300.428198)
			(xy 298.751075 -300.389127) (xy 298.721051 -300.34509) (xy 298.697925 -300.297069) (xy 298.682215 -300.246139)
			(xy 298.674272 -300.193435) (xy 284.272492 -300.193435) (xy 284.264549 -300.246139) (xy 284.248839 -300.297069)
			(xy 284.225713 -300.34509) (xy 284.195689 -300.389127) (xy 284.159437 -300.428198) (xy 284.117766 -300.461429)
			(xy 284.071608 -300.488078) (xy 284.021994 -300.50755) (xy 283.970032 -300.51941) (xy 283.916882 -300.523394)
			(xy 283.863732 -300.51941) (xy 283.81177 -300.50755) (xy 283.762156 -300.488078) (xy 283.715998 -300.461429)
			(xy 283.674327 -300.428198) (xy 283.638075 -300.389127) (xy 283.608051 -300.34509) (xy 283.584925 -300.297069)
			(xy 283.569215 -300.246139) (xy 283.561272 -300.193435) (xy 269.184892 -300.193435) (xy 269.176949 -300.246139)
			(xy 269.161239 -300.297069) (xy 269.138113 -300.34509) (xy 269.108089 -300.389127) (xy 269.071837 -300.428198)
			(xy 269.030166 -300.461429) (xy 268.984008 -300.488078) (xy 268.934394 -300.50755) (xy 268.882432 -300.51941)
			(xy 268.829282 -300.523394) (xy 268.776132 -300.51941) (xy 268.72417 -300.50755) (xy 268.674556 -300.488078)
			(xy 268.628398 -300.461429) (xy 268.586727 -300.428198) (xy 268.550475 -300.389127) (xy 268.520451 -300.34509)
			(xy 268.497325 -300.297069) (xy 268.481615 -300.246139) (xy 268.473672 -300.193435) (xy 254.20828 -300.193435)
			(xy 254.20828 -301.043319) (xy 264.373604 -301.043319) (xy 264.373604 -300.990021) (xy 264.381547 -300.937317)
			(xy 264.397257 -300.886387) (xy 264.420383 -300.838366) (xy 264.450407 -300.794329) (xy 264.486659 -300.755258)
			(xy 264.52833 -300.722027) (xy 264.574488 -300.695378) (xy 264.624102 -300.675906) (xy 264.676064 -300.664046)
			(xy 264.729214 -300.660063) (xy 264.782364 -300.664046) (xy 264.834326 -300.675906) (xy 264.88394 -300.695378)
			(xy 264.930098 -300.722027) (xy 264.971769 -300.755258) (xy 265.008021 -300.794329) (xy 265.038045 -300.838366)
			(xy 265.061171 -300.886387) (xy 265.076881 -300.937317) (xy 265.084824 -300.990021) (xy 265.085322 -301.01667)
			(xy 265.084824 -301.043319) (xy 279.461204 -301.043319) (xy 279.461204 -300.990021) (xy 279.469147 -300.937317)
			(xy 279.484857 -300.886387) (xy 279.507983 -300.838366) (xy 279.538007 -300.794329) (xy 279.574259 -300.755258)
			(xy 279.61593 -300.722027) (xy 279.662088 -300.695378) (xy 279.711702 -300.675906) (xy 279.763664 -300.664046)
			(xy 279.816814 -300.660063) (xy 279.869964 -300.664046) (xy 279.921926 -300.675906) (xy 279.97154 -300.695378)
			(xy 280.017698 -300.722027) (xy 280.059369 -300.755258) (xy 280.095621 -300.794329) (xy 280.125645 -300.838366)
			(xy 280.148771 -300.886387) (xy 280.164481 -300.937317) (xy 280.172424 -300.990021) (xy 280.172922 -301.01667)
			(xy 280.172424 -301.043319) (xy 294.548804 -301.043319) (xy 294.548804 -300.990021) (xy 294.556747 -300.937317)
			(xy 294.572457 -300.886387) (xy 294.595583 -300.838366) (xy 294.625607 -300.794329) (xy 294.661859 -300.755258)
			(xy 294.70353 -300.722027) (xy 294.749688 -300.695378) (xy 294.799302 -300.675906) (xy 294.851264 -300.664046)
			(xy 294.904414 -300.660063) (xy 294.957564 -300.664046) (xy 295.009526 -300.675906) (xy 295.05914 -300.695378)
			(xy 295.105298 -300.722027) (xy 295.146969 -300.755258) (xy 295.183221 -300.794329) (xy 295.213245 -300.838366)
			(xy 295.236371 -300.886387) (xy 295.252081 -300.937317) (xy 295.260024 -300.990021) (xy 295.260522 -301.01667)
			(xy 295.260024 -301.043319) (xy 309.636404 -301.043319) (xy 309.636404 -300.990021) (xy 309.644347 -300.937317)
			(xy 309.660057 -300.886387) (xy 309.683183 -300.838366) (xy 309.713207 -300.794329) (xy 309.749459 -300.755258)
			(xy 309.79113 -300.722027) (xy 309.837288 -300.695378) (xy 309.886902 -300.675906) (xy 309.938864 -300.664046)
			(xy 309.992014 -300.660063) (xy 310.045164 -300.664046) (xy 310.097126 -300.675906) (xy 310.14674 -300.695378)
			(xy 310.192898 -300.722027) (xy 310.234569 -300.755258) (xy 310.270821 -300.794329) (xy 310.300845 -300.838366)
			(xy 310.323971 -300.886387) (xy 310.339681 -300.937317) (xy 310.347624 -300.990021) (xy 310.348122 -301.01667)
			(xy 310.347624 -301.043319) (xy 310.339681 -301.096023) (xy 310.323971 -301.146953) (xy 310.300845 -301.194974)
			(xy 310.270821 -301.239011) (xy 310.234569 -301.278082) (xy 310.192898 -301.311313) (xy 310.14674 -301.337962)
			(xy 310.097126 -301.357434) (xy 310.045164 -301.369294) (xy 309.992014 -301.373278) (xy 309.938864 -301.369294)
			(xy 309.886902 -301.357434) (xy 309.837288 -301.337962) (xy 309.79113 -301.311313) (xy 309.749459 -301.278082)
			(xy 309.713207 -301.239011) (xy 309.683183 -301.194974) (xy 309.660057 -301.146953) (xy 309.644347 -301.096023)
			(xy 309.636404 -301.043319) (xy 295.260024 -301.043319) (xy 295.252081 -301.096023) (xy 295.236371 -301.146953)
			(xy 295.213245 -301.194974) (xy 295.183221 -301.239011) (xy 295.146969 -301.278082) (xy 295.105298 -301.311313)
			(xy 295.05914 -301.337962) (xy 295.009526 -301.357434) (xy 294.957564 -301.369294) (xy 294.904414 -301.373278)
			(xy 294.851264 -301.369294) (xy 294.799302 -301.357434) (xy 294.749688 -301.337962) (xy 294.70353 -301.311313)
			(xy 294.661859 -301.278082) (xy 294.625607 -301.239011) (xy 294.595583 -301.194974) (xy 294.572457 -301.146953)
			(xy 294.556747 -301.096023) (xy 294.548804 -301.043319) (xy 280.172424 -301.043319) (xy 280.164481 -301.096023)
			(xy 280.148771 -301.146953) (xy 280.125645 -301.194974) (xy 280.095621 -301.239011) (xy 280.059369 -301.278082)
			(xy 280.017698 -301.311313) (xy 279.97154 -301.337962) (xy 279.921926 -301.357434) (xy 279.869964 -301.369294)
			(xy 279.816814 -301.373278) (xy 279.763664 -301.369294) (xy 279.711702 -301.357434) (xy 279.662088 -301.337962)
			(xy 279.61593 -301.311313) (xy 279.574259 -301.278082) (xy 279.538007 -301.239011) (xy 279.507983 -301.194974)
			(xy 279.484857 -301.146953) (xy 279.469147 -301.096023) (xy 279.461204 -301.043319) (xy 265.084824 -301.043319)
			(xy 265.076881 -301.096023) (xy 265.061171 -301.146953) (xy 265.038045 -301.194974) (xy 265.008021 -301.239011)
			(xy 264.971769 -301.278082) (xy 264.930098 -301.311313) (xy 264.88394 -301.337962) (xy 264.834326 -301.357434)
			(xy 264.782364 -301.369294) (xy 264.729214 -301.373278) (xy 264.676064 -301.369294) (xy 264.624102 -301.357434)
			(xy 264.574488 -301.337962) (xy 264.52833 -301.311313) (xy 264.486659 -301.278082) (xy 264.450407 -301.239011)
			(xy 264.420383 -301.194974) (xy 264.397257 -301.146953) (xy 264.381547 -301.096023) (xy 264.373604 -301.043319)
			(xy 254.20828 -301.043319) (xy 254.20828 -301.893457) (xy 268.473672 -301.893457) (xy 268.473672 -301.840159)
			(xy 268.481615 -301.787455) (xy 268.497325 -301.736525) (xy 268.520451 -301.688504) (xy 268.550475 -301.644467)
			(xy 268.586727 -301.605396) (xy 268.628398 -301.572165) (xy 268.674556 -301.545516) (xy 268.72417 -301.526044)
			(xy 268.776132 -301.514184) (xy 268.829282 -301.510201) (xy 268.882432 -301.514184) (xy 268.934394 -301.526044)
			(xy 268.984008 -301.545516) (xy 269.030166 -301.572165) (xy 269.071837 -301.605396) (xy 269.108089 -301.644467)
			(xy 269.138113 -301.688504) (xy 269.161239 -301.736525) (xy 269.176949 -301.787455) (xy 269.184892 -301.840159)
			(xy 269.18539 -301.866808) (xy 269.184892 -301.893457) (xy 283.561272 -301.893457) (xy 283.561272 -301.840159)
			(xy 283.569215 -301.787455) (xy 283.584925 -301.736525) (xy 283.608051 -301.688504) (xy 283.638075 -301.644467)
			(xy 283.674327 -301.605396) (xy 283.715998 -301.572165) (xy 283.762156 -301.545516) (xy 283.81177 -301.526044)
			(xy 283.863732 -301.514184) (xy 283.916882 -301.510201) (xy 283.970032 -301.514184) (xy 284.021994 -301.526044)
			(xy 284.071608 -301.545516) (xy 284.117766 -301.572165) (xy 284.159437 -301.605396) (xy 284.195689 -301.644467)
			(xy 284.225713 -301.688504) (xy 284.248839 -301.736525) (xy 284.264549 -301.787455) (xy 284.272492 -301.840159)
			(xy 284.27299 -301.866808) (xy 284.272492 -301.893457) (xy 298.674272 -301.893457) (xy 298.674272 -301.840159)
			(xy 298.682215 -301.787455) (xy 298.697925 -301.736525) (xy 298.721051 -301.688504) (xy 298.751075 -301.644467)
			(xy 298.787327 -301.605396) (xy 298.828998 -301.572165) (xy 298.875156 -301.545516) (xy 298.92477 -301.526044)
			(xy 298.976732 -301.514184) (xy 299.029882 -301.510201) (xy 299.083032 -301.514184) (xy 299.134994 -301.526044)
			(xy 299.184608 -301.545516) (xy 299.230766 -301.572165) (xy 299.272437 -301.605396) (xy 299.308689 -301.644467)
			(xy 299.338713 -301.688504) (xy 299.361839 -301.736525) (xy 299.377549 -301.787455) (xy 299.385492 -301.840159)
			(xy 299.38599 -301.866808) (xy 299.385492 -301.893457) (xy 299.377549 -301.946161) (xy 299.361839 -301.997091)
			(xy 299.338713 -302.045112) (xy 299.308689 -302.089149) (xy 299.272437 -302.12822) (xy 299.230766 -302.161451)
			(xy 299.184608 -302.1881) (xy 299.134994 -302.207572) (xy 299.083032 -302.219432) (xy 299.029882 -302.223416)
			(xy 298.976732 -302.219432) (xy 298.92477 -302.207572) (xy 298.875156 -302.1881) (xy 298.828998 -302.161451)
			(xy 298.787327 -302.12822) (xy 298.751075 -302.089149) (xy 298.721051 -302.045112) (xy 298.697925 -301.997091)
			(xy 298.682215 -301.946161) (xy 298.674272 -301.893457) (xy 284.272492 -301.893457) (xy 284.264549 -301.946161)
			(xy 284.248839 -301.997091) (xy 284.225713 -302.045112) (xy 284.195689 -302.089149) (xy 284.159437 -302.12822)
			(xy 284.117766 -302.161451) (xy 284.071608 -302.1881) (xy 284.021994 -302.207572) (xy 283.970032 -302.219432)
			(xy 283.916882 -302.223416) (xy 283.863732 -302.219432) (xy 283.81177 -302.207572) (xy 283.762156 -302.1881)
			(xy 283.715998 -302.161451) (xy 283.674327 -302.12822) (xy 283.638075 -302.089149) (xy 283.608051 -302.045112)
			(xy 283.584925 -301.997091) (xy 283.569215 -301.946161) (xy 283.561272 -301.893457) (xy 269.184892 -301.893457)
			(xy 269.176949 -301.946161) (xy 269.161239 -301.997091) (xy 269.138113 -302.045112) (xy 269.108089 -302.089149)
			(xy 269.071837 -302.12822) (xy 269.030166 -302.161451) (xy 268.984008 -302.1881) (xy 268.934394 -302.207572)
			(xy 268.882432 -302.219432) (xy 268.829282 -302.223416) (xy 268.776132 -302.219432) (xy 268.72417 -302.207572)
			(xy 268.674556 -302.1881) (xy 268.628398 -302.161451) (xy 268.586727 -302.12822) (xy 268.550475 -302.089149)
			(xy 268.520451 -302.045112) (xy 268.497325 -301.997091) (xy 268.481615 -301.946161) (xy 268.473672 -301.893457)
			(xy 254.20828 -301.893457) (xy 254.20828 -302.743341) (xy 264.373604 -302.743341) (xy 264.373604 -302.690043)
			(xy 264.381547 -302.637339) (xy 264.397257 -302.586409) (xy 264.420383 -302.538388) (xy 264.450407 -302.494351)
			(xy 264.486659 -302.45528) (xy 264.52833 -302.422049) (xy 264.574488 -302.3954) (xy 264.624102 -302.375928)
			(xy 264.676064 -302.364068) (xy 264.729214 -302.360085) (xy 264.782364 -302.364068) (xy 264.834326 -302.375928)
			(xy 264.88394 -302.3954) (xy 264.930098 -302.422049) (xy 264.971769 -302.45528) (xy 265.008021 -302.494351)
			(xy 265.038045 -302.538388) (xy 265.061171 -302.586409) (xy 265.076881 -302.637339) (xy 265.084824 -302.690043)
			(xy 265.085322 -302.716692) (xy 265.084824 -302.743341) (xy 268.473672 -302.743341) (xy 268.473672 -302.690043)
			(xy 268.481615 -302.637339) (xy 268.497325 -302.586409) (xy 268.520451 -302.538388) (xy 268.550475 -302.494351)
			(xy 268.586727 -302.45528) (xy 268.628398 -302.422049) (xy 268.674556 -302.3954) (xy 268.72417 -302.375928)
			(xy 268.776132 -302.364068) (xy 268.829282 -302.360085) (xy 268.882432 -302.364068) (xy 268.934394 -302.375928)
			(xy 268.984008 -302.3954) (xy 269.030166 -302.422049) (xy 269.071837 -302.45528) (xy 269.108089 -302.494351)
			(xy 269.138113 -302.538388) (xy 269.161239 -302.586409) (xy 269.176949 -302.637339) (xy 269.184892 -302.690043)
			(xy 269.18539 -302.716692) (xy 269.184892 -302.743341) (xy 279.461204 -302.743341) (xy 279.461204 -302.690043)
			(xy 279.469147 -302.637339) (xy 279.484857 -302.586409) (xy 279.507983 -302.538388) (xy 279.538007 -302.494351)
			(xy 279.574259 -302.45528) (xy 279.61593 -302.422049) (xy 279.662088 -302.3954) (xy 279.711702 -302.375928)
			(xy 279.763664 -302.364068) (xy 279.816814 -302.360085) (xy 279.869964 -302.364068) (xy 279.921926 -302.375928)
			(xy 279.97154 -302.3954) (xy 280.017698 -302.422049) (xy 280.059369 -302.45528) (xy 280.095621 -302.494351)
			(xy 280.125645 -302.538388) (xy 280.148771 -302.586409) (xy 280.164481 -302.637339) (xy 280.172424 -302.690043)
			(xy 280.172922 -302.716692) (xy 280.172424 -302.743341) (xy 283.561272 -302.743341) (xy 283.561272 -302.690043)
			(xy 283.569215 -302.637339) (xy 283.584925 -302.586409) (xy 283.608051 -302.538388) (xy 283.638075 -302.494351)
			(xy 283.674327 -302.45528) (xy 283.715998 -302.422049) (xy 283.762156 -302.3954) (xy 283.81177 -302.375928)
			(xy 283.863732 -302.364068) (xy 283.916882 -302.360085) (xy 283.970032 -302.364068) (xy 284.021994 -302.375928)
			(xy 284.071608 -302.3954) (xy 284.117766 -302.422049) (xy 284.159437 -302.45528) (xy 284.195689 -302.494351)
			(xy 284.225713 -302.538388) (xy 284.248839 -302.586409) (xy 284.264549 -302.637339) (xy 284.272492 -302.690043)
			(xy 284.27299 -302.716692) (xy 284.272492 -302.743341) (xy 294.548804 -302.743341) (xy 294.548804 -302.690043)
			(xy 294.556747 -302.637339) (xy 294.572457 -302.586409) (xy 294.595583 -302.538388) (xy 294.625607 -302.494351)
			(xy 294.661859 -302.45528) (xy 294.70353 -302.422049) (xy 294.749688 -302.3954) (xy 294.799302 -302.375928)
			(xy 294.851264 -302.364068) (xy 294.904414 -302.360085) (xy 294.957564 -302.364068) (xy 295.009526 -302.375928)
			(xy 295.05914 -302.3954) (xy 295.105298 -302.422049) (xy 295.146969 -302.45528) (xy 295.183221 -302.494351)
			(xy 295.213245 -302.538388) (xy 295.236371 -302.586409) (xy 295.252081 -302.637339) (xy 295.260024 -302.690043)
			(xy 295.260522 -302.716692) (xy 295.260024 -302.743341) (xy 295.259986 -302.743595) (xy 298.674272 -302.743595)
			(xy 298.674272 -302.690297) (xy 298.682215 -302.637593) (xy 298.697925 -302.586663) (xy 298.721051 -302.538642)
			(xy 298.751075 -302.494605) (xy 298.787327 -302.455534) (xy 298.828998 -302.422303) (xy 298.875156 -302.395654)
			(xy 298.92477 -302.376182) (xy 298.976732 -302.364322) (xy 299.029882 -302.360339) (xy 299.083032 -302.364322)
			(xy 299.134994 -302.376182) (xy 299.184608 -302.395654) (xy 299.230766 -302.422303) (xy 299.272437 -302.455534)
			(xy 299.308689 -302.494605) (xy 299.338713 -302.538642) (xy 299.361839 -302.586663) (xy 299.377549 -302.637593)
			(xy 299.385492 -302.690297) (xy 299.38599 -302.716946) (xy 299.385497 -302.743341) (xy 309.636404 -302.743341)
			(xy 309.636404 -302.690043) (xy 309.644347 -302.637339) (xy 309.660057 -302.586409) (xy 309.683183 -302.538388)
			(xy 309.713207 -302.494351) (xy 309.749459 -302.45528) (xy 309.79113 -302.422049) (xy 309.837288 -302.3954)
			(xy 309.886902 -302.375928) (xy 309.938864 -302.364068) (xy 309.992014 -302.360085) (xy 310.045164 -302.364068)
			(xy 310.097126 -302.375928) (xy 310.14674 -302.3954) (xy 310.192898 -302.422049) (xy 310.234569 -302.45528)
			(xy 310.270821 -302.494351) (xy 310.300845 -302.538388) (xy 310.323971 -302.586409) (xy 310.339681 -302.637339)
			(xy 310.347624 -302.690043) (xy 310.348122 -302.716692) (xy 310.347624 -302.743341) (xy 310.339681 -302.796045)
			(xy 310.323971 -302.846975) (xy 310.300845 -302.894996) (xy 310.270821 -302.939033) (xy 310.234569 -302.978104)
			(xy 310.192898 -303.011335) (xy 310.14674 -303.037984) (xy 310.097126 -303.057456) (xy 310.045164 -303.069316)
			(xy 309.992014 -303.0733) (xy 309.938864 -303.069316) (xy 309.886902 -303.057456) (xy 309.837288 -303.037984)
			(xy 309.79113 -303.011335) (xy 309.749459 -302.978104) (xy 309.713207 -302.939033) (xy 309.683183 -302.894996)
			(xy 309.660057 -302.846975) (xy 309.644347 -302.796045) (xy 309.636404 -302.743341) (xy 299.385497 -302.743341)
			(xy 299.385492 -302.743595) (xy 299.377549 -302.796299) (xy 299.361839 -302.847229) (xy 299.338713 -302.89525)
			(xy 299.308689 -302.939287) (xy 299.272437 -302.978358) (xy 299.230766 -303.011589) (xy 299.184608 -303.038238)
			(xy 299.134994 -303.05771) (xy 299.083032 -303.06957) (xy 299.029882 -303.073554) (xy 298.976732 -303.06957)
			(xy 298.92477 -303.05771) (xy 298.875156 -303.038238) (xy 298.828998 -303.011589) (xy 298.787327 -302.978358)
			(xy 298.751075 -302.939287) (xy 298.721051 -302.89525) (xy 298.697925 -302.847229) (xy 298.682215 -302.796299)
			(xy 298.674272 -302.743595) (xy 295.259986 -302.743595) (xy 295.252081 -302.796045) (xy 295.236371 -302.846975)
			(xy 295.213245 -302.894996) (xy 295.183221 -302.939033) (xy 295.146969 -302.978104) (xy 295.105298 -303.011335)
			(xy 295.05914 -303.037984) (xy 295.009526 -303.057456) (xy 294.957564 -303.069316) (xy 294.904414 -303.0733)
			(xy 294.851264 -303.069316) (xy 294.799302 -303.057456) (xy 294.749688 -303.037984) (xy 294.70353 -303.011335)
			(xy 294.661859 -302.978104) (xy 294.625607 -302.939033) (xy 294.595583 -302.894996) (xy 294.572457 -302.846975)
			(xy 294.556747 -302.796045) (xy 294.548804 -302.743341) (xy 284.272492 -302.743341) (xy 284.264549 -302.796045)
			(xy 284.248839 -302.846975) (xy 284.225713 -302.894996) (xy 284.195689 -302.939033) (xy 284.159437 -302.978104)
			(xy 284.117766 -303.011335) (xy 284.071608 -303.037984) (xy 284.021994 -303.057456) (xy 283.970032 -303.069316)
			(xy 283.916882 -303.0733) (xy 283.863732 -303.069316) (xy 283.81177 -303.057456) (xy 283.762156 -303.037984)
			(xy 283.715998 -303.011335) (xy 283.674327 -302.978104) (xy 283.638075 -302.939033) (xy 283.608051 -302.894996)
			(xy 283.584925 -302.846975) (xy 283.569215 -302.796045) (xy 283.561272 -302.743341) (xy 280.172424 -302.743341)
			(xy 280.164481 -302.796045) (xy 280.148771 -302.846975) (xy 280.125645 -302.894996) (xy 280.095621 -302.939033)
			(xy 280.059369 -302.978104) (xy 280.017698 -303.011335) (xy 279.97154 -303.037984) (xy 279.921926 -303.057456)
			(xy 279.869964 -303.069316) (xy 279.816814 -303.0733) (xy 279.763664 -303.069316) (xy 279.711702 -303.057456)
			(xy 279.662088 -303.037984) (xy 279.61593 -303.011335) (xy 279.574259 -302.978104) (xy 279.538007 -302.939033)
			(xy 279.507983 -302.894996) (xy 279.484857 -302.846975) (xy 279.469147 -302.796045) (xy 279.461204 -302.743341)
			(xy 269.184892 -302.743341) (xy 269.176949 -302.796045) (xy 269.161239 -302.846975) (xy 269.138113 -302.894996)
			(xy 269.108089 -302.939033) (xy 269.071837 -302.978104) (xy 269.030166 -303.011335) (xy 268.984008 -303.037984)
			(xy 268.934394 -303.057456) (xy 268.882432 -303.069316) (xy 268.829282 -303.0733) (xy 268.776132 -303.069316)
			(xy 268.72417 -303.057456) (xy 268.674556 -303.037984) (xy 268.628398 -303.011335) (xy 268.586727 -302.978104)
			(xy 268.550475 -302.939033) (xy 268.520451 -302.894996) (xy 268.497325 -302.846975) (xy 268.481615 -302.796045)
			(xy 268.473672 -302.743341) (xy 265.084824 -302.743341) (xy 265.076881 -302.796045) (xy 265.061171 -302.846975)
			(xy 265.038045 -302.894996) (xy 265.008021 -302.939033) (xy 264.971769 -302.978104) (xy 264.930098 -303.011335)
			(xy 264.88394 -303.037984) (xy 264.834326 -303.057456) (xy 264.782364 -303.069316) (xy 264.729214 -303.0733)
			(xy 264.676064 -303.069316) (xy 264.624102 -303.057456) (xy 264.574488 -303.037984) (xy 264.52833 -303.011335)
			(xy 264.486659 -302.978104) (xy 264.450407 -302.939033) (xy 264.420383 -302.894996) (xy 264.397257 -302.846975)
			(xy 264.381547 -302.796045) (xy 264.373604 -302.743341) (xy 254.20828 -302.743341) (xy 254.20828 -303.593225)
			(xy 264.373604 -303.593225) (xy 264.373604 -303.539927) (xy 264.381547 -303.487223) (xy 264.397257 -303.436293)
			(xy 264.420383 -303.388272) (xy 264.450407 -303.344235) (xy 264.486659 -303.305164) (xy 264.52833 -303.271933)
			(xy 264.574488 -303.245284) (xy 264.624102 -303.225812) (xy 264.676064 -303.213952) (xy 264.729214 -303.209969)
			(xy 264.782364 -303.213952) (xy 264.834326 -303.225812) (xy 264.88394 -303.245284) (xy 264.930098 -303.271933)
			(xy 264.971769 -303.305164) (xy 265.008021 -303.344235) (xy 265.038045 -303.388272) (xy 265.061171 -303.436293)
			(xy 265.076881 -303.487223) (xy 265.084824 -303.539927) (xy 265.085322 -303.566576) (xy 265.084824 -303.593225)
			(xy 279.461204 -303.593225) (xy 279.461204 -303.539927) (xy 279.469147 -303.487223) (xy 279.484857 -303.436293)
			(xy 279.507983 -303.388272) (xy 279.538007 -303.344235) (xy 279.574259 -303.305164) (xy 279.61593 -303.271933)
			(xy 279.662088 -303.245284) (xy 279.711702 -303.225812) (xy 279.763664 -303.213952) (xy 279.816814 -303.209969)
			(xy 279.869964 -303.213952) (xy 279.921926 -303.225812) (xy 279.97154 -303.245284) (xy 280.017698 -303.271933)
			(xy 280.059369 -303.305164) (xy 280.095621 -303.344235) (xy 280.125645 -303.388272) (xy 280.148771 -303.436293)
			(xy 280.164481 -303.487223) (xy 280.172424 -303.539927) (xy 280.172922 -303.566576) (xy 280.172424 -303.593225)
			(xy 294.548804 -303.593225) (xy 294.548804 -303.539927) (xy 294.556747 -303.487223) (xy 294.572457 -303.436293)
			(xy 294.595583 -303.388272) (xy 294.625607 -303.344235) (xy 294.661859 -303.305164) (xy 294.70353 -303.271933)
			(xy 294.749688 -303.245284) (xy 294.799302 -303.225812) (xy 294.851264 -303.213952) (xy 294.904414 -303.209969)
			(xy 294.957564 -303.213952) (xy 295.009526 -303.225812) (xy 295.05914 -303.245284) (xy 295.105298 -303.271933)
			(xy 295.146969 -303.305164) (xy 295.183221 -303.344235) (xy 295.213245 -303.388272) (xy 295.236371 -303.436293)
			(xy 295.252081 -303.487223) (xy 295.260024 -303.539927) (xy 295.260522 -303.566576) (xy 295.260024 -303.593225)
			(xy 309.636404 -303.593225) (xy 309.636404 -303.539927) (xy 309.644347 -303.487223) (xy 309.660057 -303.436293)
			(xy 309.683183 -303.388272) (xy 309.713207 -303.344235) (xy 309.749459 -303.305164) (xy 309.79113 -303.271933)
			(xy 309.837288 -303.245284) (xy 309.886902 -303.225812) (xy 309.938864 -303.213952) (xy 309.992014 -303.209969)
			(xy 310.045164 -303.213952) (xy 310.097126 -303.225812) (xy 310.14674 -303.245284) (xy 310.192898 -303.271933)
			(xy 310.234569 -303.305164) (xy 310.270821 -303.344235) (xy 310.300845 -303.388272) (xy 310.323971 -303.436293)
			(xy 310.339681 -303.487223) (xy 310.347624 -303.539927) (xy 310.348122 -303.566576) (xy 310.347624 -303.593225)
			(xy 310.339681 -303.645929) (xy 310.323971 -303.696859) (xy 310.300845 -303.74488) (xy 310.270821 -303.788917)
			(xy 310.234569 -303.827988) (xy 310.192898 -303.861219) (xy 310.14674 -303.887868) (xy 310.097126 -303.90734)
			(xy 310.045164 -303.9192) (xy 309.992014 -303.923184) (xy 309.938864 -303.9192) (xy 309.886902 -303.90734)
			(xy 309.837288 -303.887868) (xy 309.79113 -303.861219) (xy 309.749459 -303.827988) (xy 309.713207 -303.788917)
			(xy 309.683183 -303.74488) (xy 309.660057 -303.696859) (xy 309.644347 -303.645929) (xy 309.636404 -303.593225)
			(xy 295.260024 -303.593225) (xy 295.252081 -303.645929) (xy 295.236371 -303.696859) (xy 295.213245 -303.74488)
			(xy 295.183221 -303.788917) (xy 295.146969 -303.827988) (xy 295.105298 -303.861219) (xy 295.05914 -303.887868)
			(xy 295.009526 -303.90734) (xy 294.957564 -303.9192) (xy 294.904414 -303.923184) (xy 294.851264 -303.9192)
			(xy 294.799302 -303.90734) (xy 294.749688 -303.887868) (xy 294.70353 -303.861219) (xy 294.661859 -303.827988)
			(xy 294.625607 -303.788917) (xy 294.595583 -303.74488) (xy 294.572457 -303.696859) (xy 294.556747 -303.645929)
			(xy 294.548804 -303.593225) (xy 280.172424 -303.593225) (xy 280.164481 -303.645929) (xy 280.148771 -303.696859)
			(xy 280.125645 -303.74488) (xy 280.095621 -303.788917) (xy 280.059369 -303.827988) (xy 280.017698 -303.861219)
			(xy 279.97154 -303.887868) (xy 279.921926 -303.90734) (xy 279.869964 -303.9192) (xy 279.816814 -303.923184)
			(xy 279.763664 -303.9192) (xy 279.711702 -303.90734) (xy 279.662088 -303.887868) (xy 279.61593 -303.861219)
			(xy 279.574259 -303.827988) (xy 279.538007 -303.788917) (xy 279.507983 -303.74488) (xy 279.484857 -303.696859)
			(xy 279.469147 -303.645929) (xy 279.461204 -303.593225) (xy 265.084824 -303.593225) (xy 265.076881 -303.645929)
			(xy 265.061171 -303.696859) (xy 265.038045 -303.74488) (xy 265.008021 -303.788917) (xy 264.971769 -303.827988)
			(xy 264.930098 -303.861219) (xy 264.88394 -303.887868) (xy 264.834326 -303.90734) (xy 264.782364 -303.9192)
			(xy 264.729214 -303.923184) (xy 264.676064 -303.9192) (xy 264.624102 -303.90734) (xy 264.574488 -303.887868)
			(xy 264.52833 -303.861219) (xy 264.486659 -303.827988) (xy 264.450407 -303.788917) (xy 264.420383 -303.74488)
			(xy 264.397257 -303.696859) (xy 264.381547 -303.645929) (xy 264.373604 -303.593225) (xy 254.20828 -303.593225)
			(xy 254.20828 -304.443363) (xy 268.473672 -304.443363) (xy 268.473672 -304.390065) (xy 268.481615 -304.337361)
			(xy 268.497325 -304.286431) (xy 268.520451 -304.23841) (xy 268.550475 -304.194373) (xy 268.586727 -304.155302)
			(xy 268.628398 -304.122071) (xy 268.674556 -304.095422) (xy 268.72417 -304.07595) (xy 268.776132 -304.06409)
			(xy 268.829282 -304.060107) (xy 268.882432 -304.06409) (xy 268.934394 -304.07595) (xy 268.984008 -304.095422)
			(xy 269.030166 -304.122071) (xy 269.071837 -304.155302) (xy 269.108089 -304.194373) (xy 269.138113 -304.23841)
			(xy 269.161239 -304.286431) (xy 269.176949 -304.337361) (xy 269.184892 -304.390065) (xy 269.18539 -304.416714)
			(xy 269.184892 -304.443363) (xy 283.561272 -304.443363) (xy 283.561272 -304.390065) (xy 283.569215 -304.337361)
			(xy 283.584925 -304.286431) (xy 283.608051 -304.23841) (xy 283.638075 -304.194373) (xy 283.674327 -304.155302)
			(xy 283.715998 -304.122071) (xy 283.762156 -304.095422) (xy 283.81177 -304.07595) (xy 283.863732 -304.06409)
			(xy 283.916882 -304.060107) (xy 283.970032 -304.06409) (xy 284.021994 -304.07595) (xy 284.071608 -304.095422)
			(xy 284.117766 -304.122071) (xy 284.159437 -304.155302) (xy 284.195689 -304.194373) (xy 284.225713 -304.23841)
			(xy 284.248839 -304.286431) (xy 284.264549 -304.337361) (xy 284.272492 -304.390065) (xy 284.27299 -304.416714)
			(xy 284.272492 -304.443363) (xy 298.674272 -304.443363) (xy 298.674272 -304.390065) (xy 298.682215 -304.337361)
			(xy 298.697925 -304.286431) (xy 298.721051 -304.23841) (xy 298.751075 -304.194373) (xy 298.787327 -304.155302)
			(xy 298.828998 -304.122071) (xy 298.875156 -304.095422) (xy 298.92477 -304.07595) (xy 298.976732 -304.06409)
			(xy 299.029882 -304.060107) (xy 299.083032 -304.06409) (xy 299.134994 -304.07595) (xy 299.184608 -304.095422)
			(xy 299.230766 -304.122071) (xy 299.272437 -304.155302) (xy 299.308689 -304.194373) (xy 299.338713 -304.23841)
			(xy 299.361839 -304.286431) (xy 299.377549 -304.337361) (xy 299.385492 -304.390065) (xy 299.38599 -304.416714)
			(xy 299.385492 -304.443363) (xy 299.377549 -304.496067) (xy 299.361839 -304.546997) (xy 299.338713 -304.595018)
			(xy 299.308689 -304.639055) (xy 299.272437 -304.678126) (xy 299.230766 -304.711357) (xy 299.184608 -304.738006)
			(xy 299.134994 -304.757478) (xy 299.083032 -304.769338) (xy 299.029882 -304.773322) (xy 298.976732 -304.769338)
			(xy 298.92477 -304.757478) (xy 298.875156 -304.738006) (xy 298.828998 -304.711357) (xy 298.787327 -304.678126)
			(xy 298.751075 -304.639055) (xy 298.721051 -304.595018) (xy 298.697925 -304.546997) (xy 298.682215 -304.496067)
			(xy 298.674272 -304.443363) (xy 284.272492 -304.443363) (xy 284.264549 -304.496067) (xy 284.248839 -304.546997)
			(xy 284.225713 -304.595018) (xy 284.195689 -304.639055) (xy 284.159437 -304.678126) (xy 284.117766 -304.711357)
			(xy 284.071608 -304.738006) (xy 284.021994 -304.757478) (xy 283.970032 -304.769338) (xy 283.916882 -304.773322)
			(xy 283.863732 -304.769338) (xy 283.81177 -304.757478) (xy 283.762156 -304.738006) (xy 283.715998 -304.711357)
			(xy 283.674327 -304.678126) (xy 283.638075 -304.639055) (xy 283.608051 -304.595018) (xy 283.584925 -304.546997)
			(xy 283.569215 -304.496067) (xy 283.561272 -304.443363) (xy 269.184892 -304.443363) (xy 269.176949 -304.496067)
			(xy 269.161239 -304.546997) (xy 269.138113 -304.595018) (xy 269.108089 -304.639055) (xy 269.071837 -304.678126)
			(xy 269.030166 -304.711357) (xy 268.984008 -304.738006) (xy 268.934394 -304.757478) (xy 268.882432 -304.769338)
			(xy 268.829282 -304.773322) (xy 268.776132 -304.769338) (xy 268.72417 -304.757478) (xy 268.674556 -304.738006)
			(xy 268.628398 -304.711357) (xy 268.586727 -304.678126) (xy 268.550475 -304.639055) (xy 268.520451 -304.595018)
			(xy 268.497325 -304.546997) (xy 268.481615 -304.496067) (xy 268.473672 -304.443363) (xy 254.20828 -304.443363)
			(xy 254.20828 -305.293247) (xy 264.373604 -305.293247) (xy 264.373604 -305.239949) (xy 264.381547 -305.187245)
			(xy 264.397257 -305.136315) (xy 264.420383 -305.088294) (xy 264.450407 -305.044257) (xy 264.486659 -305.005186)
			(xy 264.52833 -304.971955) (xy 264.574488 -304.945306) (xy 264.624102 -304.925834) (xy 264.676064 -304.913974)
			(xy 264.729214 -304.909991) (xy 264.782364 -304.913974) (xy 264.834326 -304.925834) (xy 264.88394 -304.945306)
			(xy 264.930098 -304.971955) (xy 264.971769 -305.005186) (xy 265.008021 -305.044257) (xy 265.038045 -305.088294)
			(xy 265.061171 -305.136315) (xy 265.076881 -305.187245) (xy 265.084824 -305.239949) (xy 265.085322 -305.266598)
			(xy 265.084824 -305.293247) (xy 279.461204 -305.293247) (xy 279.461204 -305.239949) (xy 279.469147 -305.187245)
			(xy 279.484857 -305.136315) (xy 279.507983 -305.088294) (xy 279.538007 -305.044257) (xy 279.574259 -305.005186)
			(xy 279.61593 -304.971955) (xy 279.662088 -304.945306) (xy 279.711702 -304.925834) (xy 279.763664 -304.913974)
			(xy 279.816814 -304.909991) (xy 279.869964 -304.913974) (xy 279.921926 -304.925834) (xy 279.97154 -304.945306)
			(xy 280.017698 -304.971955) (xy 280.059369 -305.005186) (xy 280.095621 -305.044257) (xy 280.125645 -305.088294)
			(xy 280.148771 -305.136315) (xy 280.164481 -305.187245) (xy 280.172424 -305.239949) (xy 280.172922 -305.266598)
			(xy 280.172424 -305.293247) (xy 294.548804 -305.293247) (xy 294.548804 -305.239949) (xy 294.556747 -305.187245)
			(xy 294.572457 -305.136315) (xy 294.595583 -305.088294) (xy 294.625607 -305.044257) (xy 294.661859 -305.005186)
			(xy 294.70353 -304.971955) (xy 294.749688 -304.945306) (xy 294.799302 -304.925834) (xy 294.851264 -304.913974)
			(xy 294.904414 -304.909991) (xy 294.957564 -304.913974) (xy 295.009526 -304.925834) (xy 295.05914 -304.945306)
			(xy 295.105298 -304.971955) (xy 295.146969 -305.005186) (xy 295.183221 -305.044257) (xy 295.213245 -305.088294)
			(xy 295.236371 -305.136315) (xy 295.252081 -305.187245) (xy 295.260024 -305.239949) (xy 295.260522 -305.266598)
			(xy 295.260024 -305.293247) (xy 309.636404 -305.293247) (xy 309.636404 -305.239949) (xy 309.644347 -305.187245)
			(xy 309.660057 -305.136315) (xy 309.683183 -305.088294) (xy 309.713207 -305.044257) (xy 309.749459 -305.005186)
			(xy 309.79113 -304.971955) (xy 309.837288 -304.945306) (xy 309.886902 -304.925834) (xy 309.938864 -304.913974)
			(xy 309.992014 -304.909991) (xy 310.045164 -304.913974) (xy 310.097126 -304.925834) (xy 310.14674 -304.945306)
			(xy 310.192898 -304.971955) (xy 310.234569 -305.005186) (xy 310.270821 -305.044257) (xy 310.300845 -305.088294)
			(xy 310.323971 -305.136315) (xy 310.339681 -305.187245) (xy 310.347624 -305.239949) (xy 310.348122 -305.266598)
			(xy 310.347624 -305.293247) (xy 310.339681 -305.345951) (xy 310.323971 -305.396881) (xy 310.300845 -305.444902)
			(xy 310.270821 -305.488939) (xy 310.234569 -305.52801) (xy 310.192898 -305.561241) (xy 310.14674 -305.58789)
			(xy 310.097126 -305.607362) (xy 310.045164 -305.619222) (xy 309.992014 -305.623206) (xy 309.938864 -305.619222)
			(xy 309.886902 -305.607362) (xy 309.837288 -305.58789) (xy 309.79113 -305.561241) (xy 309.749459 -305.52801)
			(xy 309.713207 -305.488939) (xy 309.683183 -305.444902) (xy 309.660057 -305.396881) (xy 309.644347 -305.345951)
			(xy 309.636404 -305.293247) (xy 295.260024 -305.293247) (xy 295.252081 -305.345951) (xy 295.236371 -305.396881)
			(xy 295.213245 -305.444902) (xy 295.183221 -305.488939) (xy 295.146969 -305.52801) (xy 295.105298 -305.561241)
			(xy 295.05914 -305.58789) (xy 295.009526 -305.607362) (xy 294.957564 -305.619222) (xy 294.904414 -305.623206)
			(xy 294.851264 -305.619222) (xy 294.799302 -305.607362) (xy 294.749688 -305.58789) (xy 294.70353 -305.561241)
			(xy 294.661859 -305.52801) (xy 294.625607 -305.488939) (xy 294.595583 -305.444902) (xy 294.572457 -305.396881)
			(xy 294.556747 -305.345951) (xy 294.548804 -305.293247) (xy 280.172424 -305.293247) (xy 280.164481 -305.345951)
			(xy 280.148771 -305.396881) (xy 280.125645 -305.444902) (xy 280.095621 -305.488939) (xy 280.059369 -305.52801)
			(xy 280.017698 -305.561241) (xy 279.97154 -305.58789) (xy 279.921926 -305.607362) (xy 279.869964 -305.619222)
			(xy 279.816814 -305.623206) (xy 279.763664 -305.619222) (xy 279.711702 -305.607362) (xy 279.662088 -305.58789)
			(xy 279.61593 -305.561241) (xy 279.574259 -305.52801) (xy 279.538007 -305.488939) (xy 279.507983 -305.444902)
			(xy 279.484857 -305.396881) (xy 279.469147 -305.345951) (xy 279.461204 -305.293247) (xy 265.084824 -305.293247)
			(xy 265.076881 -305.345951) (xy 265.061171 -305.396881) (xy 265.038045 -305.444902) (xy 265.008021 -305.488939)
			(xy 264.971769 -305.52801) (xy 264.930098 -305.561241) (xy 264.88394 -305.58789) (xy 264.834326 -305.607362)
			(xy 264.782364 -305.619222) (xy 264.729214 -305.623206) (xy 264.676064 -305.619222) (xy 264.624102 -305.607362)
			(xy 264.574488 -305.58789) (xy 264.52833 -305.561241) (xy 264.486659 -305.52801) (xy 264.450407 -305.488939)
			(xy 264.420383 -305.444902) (xy 264.397257 -305.396881) (xy 264.381547 -305.345951) (xy 264.373604 -305.293247)
			(xy 254.20828 -305.293247) (xy 254.20828 -306.143385) (xy 268.473672 -306.143385) (xy 268.473672 -306.090087)
			(xy 268.481615 -306.037383) (xy 268.497325 -305.986453) (xy 268.520451 -305.938432) (xy 268.550475 -305.894395)
			(xy 268.586727 -305.855324) (xy 268.628398 -305.822093) (xy 268.674556 -305.795444) (xy 268.72417 -305.775972)
			(xy 268.776132 -305.764112) (xy 268.829282 -305.760129) (xy 268.882432 -305.764112) (xy 268.934394 -305.775972)
			(xy 268.984008 -305.795444) (xy 269.030166 -305.822093) (xy 269.071837 -305.855324) (xy 269.108089 -305.894395)
			(xy 269.138113 -305.938432) (xy 269.161239 -305.986453) (xy 269.176949 -306.037383) (xy 269.184892 -306.090087)
			(xy 269.18539 -306.116736) (xy 269.184892 -306.143385) (xy 283.561272 -306.143385) (xy 283.561272 -306.090087)
			(xy 283.569215 -306.037383) (xy 283.584925 -305.986453) (xy 283.608051 -305.938432) (xy 283.638075 -305.894395)
			(xy 283.674327 -305.855324) (xy 283.715998 -305.822093) (xy 283.762156 -305.795444) (xy 283.81177 -305.775972)
			(xy 283.863732 -305.764112) (xy 283.916882 -305.760129) (xy 283.970032 -305.764112) (xy 284.021994 -305.775972)
			(xy 284.071608 -305.795444) (xy 284.117766 -305.822093) (xy 284.159437 -305.855324) (xy 284.195689 -305.894395)
			(xy 284.225713 -305.938432) (xy 284.248839 -305.986453) (xy 284.264549 -306.037383) (xy 284.272492 -306.090087)
			(xy 284.27299 -306.116736) (xy 284.272492 -306.143385) (xy 298.674272 -306.143385) (xy 298.674272 -306.090087)
			(xy 298.682215 -306.037383) (xy 298.697925 -305.986453) (xy 298.721051 -305.938432) (xy 298.751075 -305.894395)
			(xy 298.787327 -305.855324) (xy 298.828998 -305.822093) (xy 298.875156 -305.795444) (xy 298.92477 -305.775972)
			(xy 298.976732 -305.764112) (xy 299.029882 -305.760129) (xy 299.083032 -305.764112) (xy 299.134994 -305.775972)
			(xy 299.184608 -305.795444) (xy 299.230766 -305.822093) (xy 299.272437 -305.855324) (xy 299.308689 -305.894395)
			(xy 299.338713 -305.938432) (xy 299.361839 -305.986453) (xy 299.377549 -306.037383) (xy 299.385492 -306.090087)
			(xy 299.38599 -306.116736) (xy 299.385492 -306.143385) (xy 299.377549 -306.196089) (xy 299.361839 -306.247019)
			(xy 299.338713 -306.29504) (xy 299.308689 -306.339077) (xy 299.272437 -306.378148) (xy 299.230766 -306.411379)
			(xy 299.184608 -306.438028) (xy 299.134994 -306.4575) (xy 299.083032 -306.46936) (xy 299.029882 -306.473344)
			(xy 298.976732 -306.46936) (xy 298.92477 -306.4575) (xy 298.875156 -306.438028) (xy 298.828998 -306.411379)
			(xy 298.787327 -306.378148) (xy 298.751075 -306.339077) (xy 298.721051 -306.29504) (xy 298.697925 -306.247019)
			(xy 298.682215 -306.196089) (xy 298.674272 -306.143385) (xy 284.272492 -306.143385) (xy 284.264549 -306.196089)
			(xy 284.248839 -306.247019) (xy 284.225713 -306.29504) (xy 284.195689 -306.339077) (xy 284.159437 -306.378148)
			(xy 284.117766 -306.411379) (xy 284.071608 -306.438028) (xy 284.021994 -306.4575) (xy 283.970032 -306.46936)
			(xy 283.916882 -306.473344) (xy 283.863732 -306.46936) (xy 283.81177 -306.4575) (xy 283.762156 -306.438028)
			(xy 283.715998 -306.411379) (xy 283.674327 -306.378148) (xy 283.638075 -306.339077) (xy 283.608051 -306.29504)
			(xy 283.584925 -306.247019) (xy 283.569215 -306.196089) (xy 283.561272 -306.143385) (xy 269.184892 -306.143385)
			(xy 269.176949 -306.196089) (xy 269.161239 -306.247019) (xy 269.138113 -306.29504) (xy 269.108089 -306.339077)
			(xy 269.071837 -306.378148) (xy 269.030166 -306.411379) (xy 268.984008 -306.438028) (xy 268.934394 -306.4575)
			(xy 268.882432 -306.46936) (xy 268.829282 -306.473344) (xy 268.776132 -306.46936) (xy 268.72417 -306.4575)
			(xy 268.674556 -306.438028) (xy 268.628398 -306.411379) (xy 268.586727 -306.378148) (xy 268.550475 -306.339077)
			(xy 268.520451 -306.29504) (xy 268.497325 -306.247019) (xy 268.481615 -306.196089) (xy 268.473672 -306.143385)
			(xy 254.20828 -306.143385) (xy 254.20828 -306.993269) (xy 264.373604 -306.993269) (xy 264.373604 -306.939971)
			(xy 264.381547 -306.887267) (xy 264.397257 -306.836337) (xy 264.420383 -306.788316) (xy 264.450407 -306.744279)
			(xy 264.486659 -306.705208) (xy 264.52833 -306.671977) (xy 264.574488 -306.645328) (xy 264.624102 -306.625856)
			(xy 264.676064 -306.613996) (xy 264.729214 -306.610013) (xy 264.782364 -306.613996) (xy 264.834326 -306.625856)
			(xy 264.88394 -306.645328) (xy 264.930098 -306.671977) (xy 264.971769 -306.705208) (xy 265.008021 -306.744279)
			(xy 265.038045 -306.788316) (xy 265.061171 -306.836337) (xy 265.076881 -306.887267) (xy 265.084824 -306.939971)
			(xy 265.085322 -306.96662) (xy 265.084824 -306.993269) (xy 279.461204 -306.993269) (xy 279.461204 -306.939971)
			(xy 279.469147 -306.887267) (xy 279.484857 -306.836337) (xy 279.507983 -306.788316) (xy 279.538007 -306.744279)
			(xy 279.574259 -306.705208) (xy 279.61593 -306.671977) (xy 279.662088 -306.645328) (xy 279.711702 -306.625856)
			(xy 279.763664 -306.613996) (xy 279.816814 -306.610013) (xy 279.869964 -306.613996) (xy 279.921926 -306.625856)
			(xy 279.97154 -306.645328) (xy 280.017698 -306.671977) (xy 280.059369 -306.705208) (xy 280.095621 -306.744279)
			(xy 280.125645 -306.788316) (xy 280.148771 -306.836337) (xy 280.164481 -306.887267) (xy 280.172424 -306.939971)
			(xy 280.172922 -306.96662) (xy 280.172424 -306.993269) (xy 294.548804 -306.993269) (xy 294.548804 -306.939971)
			(xy 294.556747 -306.887267) (xy 294.572457 -306.836337) (xy 294.595583 -306.788316) (xy 294.625607 -306.744279)
			(xy 294.661859 -306.705208) (xy 294.70353 -306.671977) (xy 294.749688 -306.645328) (xy 294.799302 -306.625856)
			(xy 294.851264 -306.613996) (xy 294.904414 -306.610013) (xy 294.957564 -306.613996) (xy 295.009526 -306.625856)
			(xy 295.05914 -306.645328) (xy 295.105298 -306.671977) (xy 295.146969 -306.705208) (xy 295.183221 -306.744279)
			(xy 295.213245 -306.788316) (xy 295.236371 -306.836337) (xy 295.252081 -306.887267) (xy 295.260024 -306.939971)
			(xy 295.260522 -306.96662) (xy 295.260024 -306.993269) (xy 309.636404 -306.993269) (xy 309.636404 -306.939971)
			(xy 309.644347 -306.887267) (xy 309.660057 -306.836337) (xy 309.683183 -306.788316) (xy 309.713207 -306.744279)
			(xy 309.749459 -306.705208) (xy 309.79113 -306.671977) (xy 309.837288 -306.645328) (xy 309.886902 -306.625856)
			(xy 309.938864 -306.613996) (xy 309.992014 -306.610013) (xy 310.045164 -306.613996) (xy 310.097126 -306.625856)
			(xy 310.14674 -306.645328) (xy 310.192898 -306.671977) (xy 310.234569 -306.705208) (xy 310.270821 -306.744279)
			(xy 310.300845 -306.788316) (xy 310.323971 -306.836337) (xy 310.339681 -306.887267) (xy 310.347624 -306.939971)
			(xy 310.348122 -306.96662) (xy 310.347624 -306.993269) (xy 310.339681 -307.045973) (xy 310.323971 -307.096903)
			(xy 310.300845 -307.144924) (xy 310.270821 -307.188961) (xy 310.234569 -307.228032) (xy 310.192898 -307.261263)
			(xy 310.14674 -307.287912) (xy 310.097126 -307.307384) (xy 310.045164 -307.319244) (xy 309.992014 -307.323228)
			(xy 309.938864 -307.319244) (xy 309.886902 -307.307384) (xy 309.837288 -307.287912) (xy 309.79113 -307.261263)
			(xy 309.749459 -307.228032) (xy 309.713207 -307.188961) (xy 309.683183 -307.144924) (xy 309.660057 -307.096903)
			(xy 309.644347 -307.045973) (xy 309.636404 -306.993269) (xy 295.260024 -306.993269) (xy 295.252081 -307.045973)
			(xy 295.236371 -307.096903) (xy 295.213245 -307.144924) (xy 295.183221 -307.188961) (xy 295.146969 -307.228032)
			(xy 295.105298 -307.261263) (xy 295.05914 -307.287912) (xy 295.009526 -307.307384) (xy 294.957564 -307.319244)
			(xy 294.904414 -307.323228) (xy 294.851264 -307.319244) (xy 294.799302 -307.307384) (xy 294.749688 -307.287912)
			(xy 294.70353 -307.261263) (xy 294.661859 -307.228032) (xy 294.625607 -307.188961) (xy 294.595583 -307.144924)
			(xy 294.572457 -307.096903) (xy 294.556747 -307.045973) (xy 294.548804 -306.993269) (xy 280.172424 -306.993269)
			(xy 280.164481 -307.045973) (xy 280.148771 -307.096903) (xy 280.125645 -307.144924) (xy 280.095621 -307.188961)
			(xy 280.059369 -307.228032) (xy 280.017698 -307.261263) (xy 279.97154 -307.287912) (xy 279.921926 -307.307384)
			(xy 279.869964 -307.319244) (xy 279.816814 -307.323228) (xy 279.763664 -307.319244) (xy 279.711702 -307.307384)
			(xy 279.662088 -307.287912) (xy 279.61593 -307.261263) (xy 279.574259 -307.228032) (xy 279.538007 -307.188961)
			(xy 279.507983 -307.144924) (xy 279.484857 -307.096903) (xy 279.469147 -307.045973) (xy 279.461204 -306.993269)
			(xy 265.084824 -306.993269) (xy 265.076881 -307.045973) (xy 265.061171 -307.096903) (xy 265.038045 -307.144924)
			(xy 265.008021 -307.188961) (xy 264.971769 -307.228032) (xy 264.930098 -307.261263) (xy 264.88394 -307.287912)
			(xy 264.834326 -307.307384) (xy 264.782364 -307.319244) (xy 264.729214 -307.323228) (xy 264.676064 -307.319244)
			(xy 264.624102 -307.307384) (xy 264.574488 -307.287912) (xy 264.52833 -307.261263) (xy 264.486659 -307.228032)
			(xy 264.450407 -307.188961) (xy 264.420383 -307.144924) (xy 264.397257 -307.096903) (xy 264.381547 -307.045973)
			(xy 264.373604 -306.993269) (xy 254.20828 -306.993269) (xy 254.20828 -307.843407) (xy 268.473672 -307.843407)
			(xy 268.473672 -307.790109) (xy 268.481615 -307.737405) (xy 268.497325 -307.686475) (xy 268.520451 -307.638454)
			(xy 268.550475 -307.594417) (xy 268.586727 -307.555346) (xy 268.628398 -307.522115) (xy 268.674556 -307.495466)
			(xy 268.72417 -307.475994) (xy 268.776132 -307.464134) (xy 268.829282 -307.460151) (xy 268.882432 -307.464134)
			(xy 268.934394 -307.475994) (xy 268.984008 -307.495466) (xy 269.030166 -307.522115) (xy 269.071837 -307.555346)
			(xy 269.108089 -307.594417) (xy 269.138113 -307.638454) (xy 269.161239 -307.686475) (xy 269.176949 -307.737405)
			(xy 269.184892 -307.790109) (xy 269.18539 -307.816758) (xy 269.184892 -307.843407) (xy 283.561272 -307.843407)
			(xy 283.561272 -307.790109) (xy 283.569215 -307.737405) (xy 283.584925 -307.686475) (xy 283.608051 -307.638454)
			(xy 283.638075 -307.594417) (xy 283.674327 -307.555346) (xy 283.715998 -307.522115) (xy 283.762156 -307.495466)
			(xy 283.81177 -307.475994) (xy 283.863732 -307.464134) (xy 283.916882 -307.460151) (xy 283.970032 -307.464134)
			(xy 284.021994 -307.475994) (xy 284.071608 -307.495466) (xy 284.117766 -307.522115) (xy 284.159437 -307.555346)
			(xy 284.195689 -307.594417) (xy 284.225713 -307.638454) (xy 284.248839 -307.686475) (xy 284.264549 -307.737405)
			(xy 284.272492 -307.790109) (xy 284.27299 -307.816758) (xy 284.272492 -307.843407) (xy 298.674272 -307.843407)
			(xy 298.674272 -307.790109) (xy 298.682215 -307.737405) (xy 298.697925 -307.686475) (xy 298.721051 -307.638454)
			(xy 298.751075 -307.594417) (xy 298.787327 -307.555346) (xy 298.828998 -307.522115) (xy 298.875156 -307.495466)
			(xy 298.92477 -307.475994) (xy 298.976732 -307.464134) (xy 299.029882 -307.460151) (xy 299.083032 -307.464134)
			(xy 299.134994 -307.475994) (xy 299.184608 -307.495466) (xy 299.230766 -307.522115) (xy 299.272437 -307.555346)
			(xy 299.308689 -307.594417) (xy 299.338713 -307.638454) (xy 299.361839 -307.686475) (xy 299.377549 -307.737405)
			(xy 299.385492 -307.790109) (xy 299.38599 -307.816758) (xy 299.385492 -307.843407) (xy 299.377549 -307.896111)
			(xy 299.361839 -307.947041) (xy 299.338713 -307.995062) (xy 299.308689 -308.039099) (xy 299.272437 -308.07817)
			(xy 299.230766 -308.111401) (xy 299.184608 -308.13805) (xy 299.134994 -308.157522) (xy 299.083032 -308.169382)
			(xy 299.029882 -308.173366) (xy 298.976732 -308.169382) (xy 298.92477 -308.157522) (xy 298.875156 -308.13805)
			(xy 298.828998 -308.111401) (xy 298.787327 -308.07817) (xy 298.751075 -308.039099) (xy 298.721051 -307.995062)
			(xy 298.697925 -307.947041) (xy 298.682215 -307.896111) (xy 298.674272 -307.843407) (xy 284.272492 -307.843407)
			(xy 284.264549 -307.896111) (xy 284.248839 -307.947041) (xy 284.225713 -307.995062) (xy 284.195689 -308.039099)
			(xy 284.159437 -308.07817) (xy 284.117766 -308.111401) (xy 284.071608 -308.13805) (xy 284.021994 -308.157522)
			(xy 283.970032 -308.169382) (xy 283.916882 -308.173366) (xy 283.863732 -308.169382) (xy 283.81177 -308.157522)
			(xy 283.762156 -308.13805) (xy 283.715998 -308.111401) (xy 283.674327 -308.07817) (xy 283.638075 -308.039099)
			(xy 283.608051 -307.995062) (xy 283.584925 -307.947041) (xy 283.569215 -307.896111) (xy 283.561272 -307.843407)
			(xy 269.184892 -307.843407) (xy 269.176949 -307.896111) (xy 269.161239 -307.947041) (xy 269.138113 -307.995062)
			(xy 269.108089 -308.039099) (xy 269.071837 -308.07817) (xy 269.030166 -308.111401) (xy 268.984008 -308.13805)
			(xy 268.934394 -308.157522) (xy 268.882432 -308.169382) (xy 268.829282 -308.173366) (xy 268.776132 -308.169382)
			(xy 268.72417 -308.157522) (xy 268.674556 -308.13805) (xy 268.628398 -308.111401) (xy 268.586727 -308.07817)
			(xy 268.550475 -308.039099) (xy 268.520451 -307.995062) (xy 268.497325 -307.947041) (xy 268.481615 -307.896111)
			(xy 268.473672 -307.843407) (xy 254.20828 -307.843407) (xy 254.20828 -308.693291) (xy 264.373604 -308.693291)
			(xy 264.373604 -308.639993) (xy 264.381547 -308.587289) (xy 264.397257 -308.536359) (xy 264.420383 -308.488338)
			(xy 264.450407 -308.444301) (xy 264.486659 -308.40523) (xy 264.52833 -308.371999) (xy 264.574488 -308.34535)
			(xy 264.624102 -308.325878) (xy 264.676064 -308.314018) (xy 264.729214 -308.310035) (xy 264.782364 -308.314018)
			(xy 264.834326 -308.325878) (xy 264.88394 -308.34535) (xy 264.930098 -308.371999) (xy 264.971769 -308.40523)
			(xy 265.008021 -308.444301) (xy 265.038045 -308.488338) (xy 265.061171 -308.536359) (xy 265.076881 -308.587289)
			(xy 265.084824 -308.639993) (xy 265.085322 -308.666642) (xy 265.084824 -308.693291) (xy 279.461204 -308.693291)
			(xy 279.461204 -308.639993) (xy 279.469147 -308.587289) (xy 279.484857 -308.536359) (xy 279.507983 -308.488338)
			(xy 279.538007 -308.444301) (xy 279.574259 -308.40523) (xy 279.61593 -308.371999) (xy 279.662088 -308.34535)
			(xy 279.711702 -308.325878) (xy 279.763664 -308.314018) (xy 279.816814 -308.310035) (xy 279.869964 -308.314018)
			(xy 279.921926 -308.325878) (xy 279.97154 -308.34535) (xy 280.017698 -308.371999) (xy 280.059369 -308.40523)
			(xy 280.095621 -308.444301) (xy 280.125645 -308.488338) (xy 280.148771 -308.536359) (xy 280.164481 -308.587289)
			(xy 280.172424 -308.639993) (xy 280.172922 -308.666642) (xy 280.172424 -308.693291) (xy 294.548804 -308.693291)
			(xy 294.548804 -308.639993) (xy 294.556747 -308.587289) (xy 294.572457 -308.536359) (xy 294.595583 -308.488338)
			(xy 294.625607 -308.444301) (xy 294.661859 -308.40523) (xy 294.70353 -308.371999) (xy 294.749688 -308.34535)
			(xy 294.799302 -308.325878) (xy 294.851264 -308.314018) (xy 294.904414 -308.310035) (xy 294.957564 -308.314018)
			(xy 295.009526 -308.325878) (xy 295.05914 -308.34535) (xy 295.105298 -308.371999) (xy 295.146969 -308.40523)
			(xy 295.183221 -308.444301) (xy 295.213245 -308.488338) (xy 295.236371 -308.536359) (xy 295.252081 -308.587289)
			(xy 295.260024 -308.639993) (xy 295.260522 -308.666642) (xy 295.260024 -308.693291) (xy 295.252081 -308.745995)
			(xy 295.236371 -308.796925) (xy 295.213245 -308.844946) (xy 295.183221 -308.888983) (xy 295.146969 -308.928054)
			(xy 295.105298 -308.961285) (xy 295.05914 -308.987934) (xy 295.009526 -309.007406) (xy 294.957564 -309.019266)
			(xy 294.904414 -309.02325) (xy 294.851264 -309.019266) (xy 294.799302 -309.007406) (xy 294.749688 -308.987934)
			(xy 294.70353 -308.961285) (xy 294.661859 -308.928054) (xy 294.625607 -308.888983) (xy 294.595583 -308.844946)
			(xy 294.572457 -308.796925) (xy 294.556747 -308.745995) (xy 294.548804 -308.693291) (xy 280.172424 -308.693291)
			(xy 280.164481 -308.745995) (xy 280.148771 -308.796925) (xy 280.125645 -308.844946) (xy 280.095621 -308.888983)
			(xy 280.059369 -308.928054) (xy 280.017698 -308.961285) (xy 279.97154 -308.987934) (xy 279.921926 -309.007406)
			(xy 279.869964 -309.019266) (xy 279.816814 -309.02325) (xy 279.763664 -309.019266) (xy 279.711702 -309.007406)
			(xy 279.662088 -308.987934) (xy 279.61593 -308.961285) (xy 279.574259 -308.928054) (xy 279.538007 -308.888983)
			(xy 279.507983 -308.844946) (xy 279.484857 -308.796925) (xy 279.469147 -308.745995) (xy 279.461204 -308.693291)
			(xy 265.084824 -308.693291) (xy 265.076881 -308.745995) (xy 265.061171 -308.796925) (xy 265.038045 -308.844946)
			(xy 265.008021 -308.888983) (xy 264.971769 -308.928054) (xy 264.930098 -308.961285) (xy 264.88394 -308.987934)
			(xy 264.834326 -309.007406) (xy 264.782364 -309.019266) (xy 264.729214 -309.02325) (xy 264.676064 -309.019266)
			(xy 264.624102 -309.007406) (xy 264.574488 -308.987934) (xy 264.52833 -308.961285) (xy 264.486659 -308.928054)
			(xy 264.450407 -308.888983) (xy 264.420383 -308.844946) (xy 264.397257 -308.796925) (xy 264.381547 -308.745995)
			(xy 264.373604 -308.693291) (xy 254.20828 -308.693291) (xy 254.20828 -309.543429) (xy 268.473672 -309.543429)
			(xy 268.473672 -309.490131) (xy 268.481615 -309.437427) (xy 268.497325 -309.386497) (xy 268.520451 -309.338476)
			(xy 268.550475 -309.294439) (xy 268.586727 -309.255368) (xy 268.628398 -309.222137) (xy 268.674556 -309.195488)
			(xy 268.72417 -309.176016) (xy 268.776132 -309.164156) (xy 268.829282 -309.160173) (xy 268.882432 -309.164156)
			(xy 268.934394 -309.176016) (xy 268.984008 -309.195488) (xy 269.030166 -309.222137) (xy 269.071837 -309.255368)
			(xy 269.108089 -309.294439) (xy 269.138113 -309.338476) (xy 269.161239 -309.386497) (xy 269.176949 -309.437427)
			(xy 269.184892 -309.490131) (xy 269.18539 -309.51678) (xy 269.184892 -309.543429) (xy 283.561272 -309.543429)
			(xy 283.561272 -309.490131) (xy 283.569215 -309.437427) (xy 283.584925 -309.386497) (xy 283.608051 -309.338476)
			(xy 283.638075 -309.294439) (xy 283.674327 -309.255368) (xy 283.715998 -309.222137) (xy 283.762156 -309.195488)
			(xy 283.81177 -309.176016) (xy 283.863732 -309.164156) (xy 283.916882 -309.160173) (xy 283.970032 -309.164156)
			(xy 284.021994 -309.176016) (xy 284.071608 -309.195488) (xy 284.117766 -309.222137) (xy 284.159437 -309.255368)
			(xy 284.195689 -309.294439) (xy 284.225713 -309.338476) (xy 284.248839 -309.386497) (xy 284.264549 -309.437427)
			(xy 284.272492 -309.490131) (xy 284.27299 -309.51678) (xy 284.272492 -309.543429) (xy 298.674272 -309.543429)
			(xy 298.674272 -309.490131) (xy 298.682215 -309.437427) (xy 298.697925 -309.386497) (xy 298.721051 -309.338476)
			(xy 298.751075 -309.294439) (xy 298.787327 -309.255368) (xy 298.828998 -309.222137) (xy 298.875156 -309.195488)
			(xy 298.92477 -309.176016) (xy 298.976732 -309.164156) (xy 299.029882 -309.160173) (xy 299.083032 -309.164156)
			(xy 299.134994 -309.176016) (xy 299.184608 -309.195488) (xy 299.230766 -309.222137) (xy 299.272437 -309.255368)
			(xy 299.308689 -309.294439) (xy 299.338713 -309.338476) (xy 299.361839 -309.386497) (xy 299.377549 -309.437427)
			(xy 299.385492 -309.490131) (xy 299.38599 -309.51678) (xy 299.385492 -309.543429) (xy 299.377549 -309.596133)
			(xy 299.361839 -309.647063) (xy 299.338713 -309.695084) (xy 299.308689 -309.739121) (xy 299.272437 -309.778192)
			(xy 299.230766 -309.811423) (xy 299.184608 -309.838072) (xy 299.134994 -309.857544) (xy 299.083032 -309.869404)
			(xy 299.029882 -309.873388) (xy 298.976732 -309.869404) (xy 298.92477 -309.857544) (xy 298.875156 -309.838072)
			(xy 298.828998 -309.811423) (xy 298.787327 -309.778192) (xy 298.751075 -309.739121) (xy 298.721051 -309.695084)
			(xy 298.697925 -309.647063) (xy 298.682215 -309.596133) (xy 298.674272 -309.543429) (xy 284.272492 -309.543429)
			(xy 284.264549 -309.596133) (xy 284.248839 -309.647063) (xy 284.225713 -309.695084) (xy 284.195689 -309.739121)
			(xy 284.159437 -309.778192) (xy 284.117766 -309.811423) (xy 284.071608 -309.838072) (xy 284.021994 -309.857544)
			(xy 283.970032 -309.869404) (xy 283.916882 -309.873388) (xy 283.863732 -309.869404) (xy 283.81177 -309.857544)
			(xy 283.762156 -309.838072) (xy 283.715998 -309.811423) (xy 283.674327 -309.778192) (xy 283.638075 -309.739121)
			(xy 283.608051 -309.695084) (xy 283.584925 -309.647063) (xy 283.569215 -309.596133) (xy 283.561272 -309.543429)
			(xy 269.184892 -309.543429) (xy 269.176949 -309.596133) (xy 269.161239 -309.647063) (xy 269.138113 -309.695084)
			(xy 269.108089 -309.739121) (xy 269.071837 -309.778192) (xy 269.030166 -309.811423) (xy 268.984008 -309.838072)
			(xy 268.934394 -309.857544) (xy 268.882432 -309.869404) (xy 268.829282 -309.873388) (xy 268.776132 -309.869404)
			(xy 268.72417 -309.857544) (xy 268.674556 -309.838072) (xy 268.628398 -309.811423) (xy 268.586727 -309.778192)
			(xy 268.550475 -309.739121) (xy 268.520451 -309.695084) (xy 268.497325 -309.647063) (xy 268.481615 -309.596133)
			(xy 268.473672 -309.543429) (xy 254.20828 -309.543429) (xy 254.20828 -310.393313) (xy 264.373604 -310.393313)
			(xy 264.373604 -310.340015) (xy 264.381547 -310.287311) (xy 264.397257 -310.236381) (xy 264.420383 -310.18836)
			(xy 264.450407 -310.144323) (xy 264.486659 -310.105252) (xy 264.52833 -310.072021) (xy 264.574488 -310.045372)
			(xy 264.624102 -310.0259) (xy 264.676064 -310.01404) (xy 264.729214 -310.010057) (xy 264.782364 -310.01404)
			(xy 264.834326 -310.0259) (xy 264.88394 -310.045372) (xy 264.930098 -310.072021) (xy 264.971769 -310.105252)
			(xy 265.008021 -310.144323) (xy 265.038045 -310.18836) (xy 265.061171 -310.236381) (xy 265.076881 -310.287311)
			(xy 265.084824 -310.340015) (xy 265.085322 -310.366664) (xy 265.084824 -310.393313) (xy 279.461204 -310.393313)
			(xy 279.461204 -310.340015) (xy 279.469147 -310.287311) (xy 279.484857 -310.236381) (xy 279.507983 -310.18836)
			(xy 279.538007 -310.144323) (xy 279.574259 -310.105252) (xy 279.61593 -310.072021) (xy 279.662088 -310.045372)
			(xy 279.711702 -310.0259) (xy 279.763664 -310.01404) (xy 279.816814 -310.010057) (xy 279.869964 -310.01404)
			(xy 279.921926 -310.0259) (xy 279.97154 -310.045372) (xy 280.017698 -310.072021) (xy 280.059369 -310.105252)
			(xy 280.095621 -310.144323) (xy 280.125645 -310.18836) (xy 280.148771 -310.236381) (xy 280.164481 -310.287311)
			(xy 280.172424 -310.340015) (xy 280.172922 -310.366664) (xy 280.172424 -310.393313) (xy 294.548804 -310.393313)
			(xy 294.548804 -310.340015) (xy 294.556747 -310.287311) (xy 294.572457 -310.236381) (xy 294.595583 -310.18836)
			(xy 294.625607 -310.144323) (xy 294.661859 -310.105252) (xy 294.70353 -310.072021) (xy 294.749688 -310.045372)
			(xy 294.799302 -310.0259) (xy 294.851264 -310.01404) (xy 294.904414 -310.010057) (xy 294.957564 -310.01404)
			(xy 295.009526 -310.0259) (xy 295.05914 -310.045372) (xy 295.105298 -310.072021) (xy 295.146969 -310.105252)
			(xy 295.183221 -310.144323) (xy 295.213245 -310.18836) (xy 295.236371 -310.236381) (xy 295.252081 -310.287311)
			(xy 295.260024 -310.340015) (xy 295.260522 -310.366664) (xy 295.260024 -310.393313) (xy 295.252081 -310.446017)
			(xy 295.236371 -310.496947) (xy 295.213245 -310.544968) (xy 295.183221 -310.589005) (xy 295.146969 -310.628076)
			(xy 295.105298 -310.661307) (xy 295.05914 -310.687956) (xy 295.009526 -310.707428) (xy 294.957564 -310.719288)
			(xy 294.904414 -310.723272) (xy 294.851264 -310.719288) (xy 294.799302 -310.707428) (xy 294.749688 -310.687956)
			(xy 294.70353 -310.661307) (xy 294.661859 -310.628076) (xy 294.625607 -310.589005) (xy 294.595583 -310.544968)
			(xy 294.572457 -310.496947) (xy 294.556747 -310.446017) (xy 294.548804 -310.393313) (xy 280.172424 -310.393313)
			(xy 280.164481 -310.446017) (xy 280.148771 -310.496947) (xy 280.125645 -310.544968) (xy 280.095621 -310.589005)
			(xy 280.059369 -310.628076) (xy 280.017698 -310.661307) (xy 279.97154 -310.687956) (xy 279.921926 -310.707428)
			(xy 279.869964 -310.719288) (xy 279.816814 -310.723272) (xy 279.763664 -310.719288) (xy 279.711702 -310.707428)
			(xy 279.662088 -310.687956) (xy 279.61593 -310.661307) (xy 279.574259 -310.628076) (xy 279.538007 -310.589005)
			(xy 279.507983 -310.544968) (xy 279.484857 -310.496947) (xy 279.469147 -310.446017) (xy 279.461204 -310.393313)
			(xy 265.084824 -310.393313) (xy 265.076881 -310.446017) (xy 265.061171 -310.496947) (xy 265.038045 -310.544968)
			(xy 265.008021 -310.589005) (xy 264.971769 -310.628076) (xy 264.930098 -310.661307) (xy 264.88394 -310.687956)
			(xy 264.834326 -310.707428) (xy 264.782364 -310.719288) (xy 264.729214 -310.723272) (xy 264.676064 -310.719288)
			(xy 264.624102 -310.707428) (xy 264.574488 -310.687956) (xy 264.52833 -310.661307) (xy 264.486659 -310.628076)
			(xy 264.450407 -310.589005) (xy 264.420383 -310.544968) (xy 264.397257 -310.496947) (xy 264.381547 -310.446017)
			(xy 264.373604 -310.393313) (xy 254.20828 -310.393313) (xy 254.20828 -311.243451) (xy 268.473672 -311.243451)
			(xy 268.473672 -311.190153) (xy 268.481615 -311.137449) (xy 268.497325 -311.086519) (xy 268.520451 -311.038498)
			(xy 268.550475 -310.994461) (xy 268.586727 -310.95539) (xy 268.628398 -310.922159) (xy 268.674556 -310.89551)
			(xy 268.72417 -310.876038) (xy 268.776132 -310.864178) (xy 268.829282 -310.860195) (xy 268.882432 -310.864178)
			(xy 268.934394 -310.876038) (xy 268.984008 -310.89551) (xy 269.030166 -310.922159) (xy 269.071837 -310.95539)
			(xy 269.108089 -310.994461) (xy 269.138113 -311.038498) (xy 269.161239 -311.086519) (xy 269.176949 -311.137449)
			(xy 269.184892 -311.190153) (xy 269.18539 -311.216802) (xy 269.184892 -311.243451) (xy 283.561272 -311.243451)
			(xy 283.561272 -311.190153) (xy 283.569215 -311.137449) (xy 283.584925 -311.086519) (xy 283.608051 -311.038498)
			(xy 283.638075 -310.994461) (xy 283.674327 -310.95539) (xy 283.715998 -310.922159) (xy 283.762156 -310.89551)
			(xy 283.81177 -310.876038) (xy 283.863732 -310.864178) (xy 283.916882 -310.860195) (xy 283.970032 -310.864178)
			(xy 284.021994 -310.876038) (xy 284.071608 -310.89551) (xy 284.117766 -310.922159) (xy 284.159437 -310.95539)
			(xy 284.195689 -310.994461) (xy 284.225713 -311.038498) (xy 284.248839 -311.086519) (xy 284.264549 -311.137449)
			(xy 284.272492 -311.190153) (xy 284.27299 -311.216802) (xy 284.272492 -311.243451) (xy 298.674272 -311.243451)
			(xy 298.674272 -311.190153) (xy 298.682215 -311.137449) (xy 298.697925 -311.086519) (xy 298.721051 -311.038498)
			(xy 298.751075 -310.994461) (xy 298.787327 -310.95539) (xy 298.828998 -310.922159) (xy 298.875156 -310.89551)
			(xy 298.92477 -310.876038) (xy 298.976732 -310.864178) (xy 299.029882 -310.860195) (xy 299.083032 -310.864178)
			(xy 299.134994 -310.876038) (xy 299.184608 -310.89551) (xy 299.230766 -310.922159) (xy 299.272437 -310.95539)
			(xy 299.308689 -310.994461) (xy 299.338713 -311.038498) (xy 299.361839 -311.086519) (xy 299.377549 -311.137449)
			(xy 299.385492 -311.190153) (xy 299.38599 -311.216802) (xy 299.385492 -311.243451) (xy 299.377549 -311.296155)
			(xy 299.361839 -311.347085) (xy 299.338713 -311.395106) (xy 299.308689 -311.439143) (xy 299.272437 -311.478214)
			(xy 299.230766 -311.511445) (xy 299.184608 -311.538094) (xy 299.134994 -311.557566) (xy 299.083032 -311.569426)
			(xy 299.029882 -311.57341) (xy 298.976732 -311.569426) (xy 298.92477 -311.557566) (xy 298.875156 -311.538094)
			(xy 298.828998 -311.511445) (xy 298.787327 -311.478214) (xy 298.751075 -311.439143) (xy 298.721051 -311.395106)
			(xy 298.697925 -311.347085) (xy 298.682215 -311.296155) (xy 298.674272 -311.243451) (xy 284.272492 -311.243451)
			(xy 284.264549 -311.296155) (xy 284.248839 -311.347085) (xy 284.225713 -311.395106) (xy 284.195689 -311.439143)
			(xy 284.159437 -311.478214) (xy 284.117766 -311.511445) (xy 284.071608 -311.538094) (xy 284.021994 -311.557566)
			(xy 283.970032 -311.569426) (xy 283.916882 -311.57341) (xy 283.863732 -311.569426) (xy 283.81177 -311.557566)
			(xy 283.762156 -311.538094) (xy 283.715998 -311.511445) (xy 283.674327 -311.478214) (xy 283.638075 -311.439143)
			(xy 283.608051 -311.395106) (xy 283.584925 -311.347085) (xy 283.569215 -311.296155) (xy 283.561272 -311.243451)
			(xy 269.184892 -311.243451) (xy 269.176949 -311.296155) (xy 269.161239 -311.347085) (xy 269.138113 -311.395106)
			(xy 269.108089 -311.439143) (xy 269.071837 -311.478214) (xy 269.030166 -311.511445) (xy 268.984008 -311.538094)
			(xy 268.934394 -311.557566) (xy 268.882432 -311.569426) (xy 268.829282 -311.57341) (xy 268.776132 -311.569426)
			(xy 268.72417 -311.557566) (xy 268.674556 -311.538094) (xy 268.628398 -311.511445) (xy 268.586727 -311.478214)
			(xy 268.550475 -311.439143) (xy 268.520451 -311.395106) (xy 268.497325 -311.347085) (xy 268.481615 -311.296155)
			(xy 268.473672 -311.243451) (xy 254.20828 -311.243451) (xy 254.20828 -312.093335) (xy 264.373604 -312.093335)
			(xy 264.373604 -312.040037) (xy 264.381547 -311.987333) (xy 264.397257 -311.936403) (xy 264.420383 -311.888382)
			(xy 264.450407 -311.844345) (xy 264.486659 -311.805274) (xy 264.52833 -311.772043) (xy 264.574488 -311.745394)
			(xy 264.624102 -311.725922) (xy 264.676064 -311.714062) (xy 264.729214 -311.710079) (xy 264.782364 -311.714062)
			(xy 264.834326 -311.725922) (xy 264.88394 -311.745394) (xy 264.930098 -311.772043) (xy 264.971769 -311.805274)
			(xy 265.008021 -311.844345) (xy 265.038045 -311.888382) (xy 265.061171 -311.936403) (xy 265.076881 -311.987333)
			(xy 265.084824 -312.040037) (xy 265.085322 -312.066686) (xy 265.084824 -312.093335) (xy 268.473672 -312.093335)
			(xy 268.473672 -312.040037) (xy 268.481615 -311.987333) (xy 268.497325 -311.936403) (xy 268.520451 -311.888382)
			(xy 268.550475 -311.844345) (xy 268.586727 -311.805274) (xy 268.628398 -311.772043) (xy 268.674556 -311.745394)
			(xy 268.72417 -311.725922) (xy 268.776132 -311.714062) (xy 268.829282 -311.710079) (xy 268.882432 -311.714062)
			(xy 268.934394 -311.725922) (xy 268.984008 -311.745394) (xy 269.030166 -311.772043) (xy 269.071837 -311.805274)
			(xy 269.108089 -311.844345) (xy 269.138113 -311.888382) (xy 269.161239 -311.936403) (xy 269.176949 -311.987333)
			(xy 269.184892 -312.040037) (xy 269.18539 -312.066686) (xy 269.184892 -312.093335) (xy 279.461204 -312.093335)
			(xy 279.461204 -312.040037) (xy 279.469147 -311.987333) (xy 279.484857 -311.936403) (xy 279.507983 -311.888382)
			(xy 279.538007 -311.844345) (xy 279.574259 -311.805274) (xy 279.61593 -311.772043) (xy 279.662088 -311.745394)
			(xy 279.711702 -311.725922) (xy 279.763664 -311.714062) (xy 279.816814 -311.710079) (xy 279.869964 -311.714062)
			(xy 279.921926 -311.725922) (xy 279.97154 -311.745394) (xy 280.017698 -311.772043) (xy 280.059369 -311.805274)
			(xy 280.095621 -311.844345) (xy 280.125645 -311.888382) (xy 280.148771 -311.936403) (xy 280.164481 -311.987333)
			(xy 280.172424 -312.040037) (xy 280.172922 -312.066686) (xy 280.172424 -312.093335) (xy 283.561272 -312.093335)
			(xy 283.561272 -312.040037) (xy 283.569215 -311.987333) (xy 283.584925 -311.936403) (xy 283.608051 -311.888382)
			(xy 283.638075 -311.844345) (xy 283.674327 -311.805274) (xy 283.715998 -311.772043) (xy 283.762156 -311.745394)
			(xy 283.81177 -311.725922) (xy 283.863732 -311.714062) (xy 283.916882 -311.710079) (xy 283.970032 -311.714062)
			(xy 284.021994 -311.725922) (xy 284.071608 -311.745394) (xy 284.117766 -311.772043) (xy 284.159437 -311.805274)
			(xy 284.195689 -311.844345) (xy 284.225713 -311.888382) (xy 284.248839 -311.936403) (xy 284.264549 -311.987333)
			(xy 284.272492 -312.040037) (xy 284.27299 -312.066686) (xy 284.272492 -312.093335) (xy 294.548804 -312.093335)
			(xy 294.548804 -312.040037) (xy 294.556747 -311.987333) (xy 294.572457 -311.936403) (xy 294.595583 -311.888382)
			(xy 294.625607 -311.844345) (xy 294.661859 -311.805274) (xy 294.70353 -311.772043) (xy 294.749688 -311.745394)
			(xy 294.799302 -311.725922) (xy 294.851264 -311.714062) (xy 294.904414 -311.710079) (xy 294.957564 -311.714062)
			(xy 295.009526 -311.725922) (xy 295.05914 -311.745394) (xy 295.105298 -311.772043) (xy 295.146969 -311.805274)
			(xy 295.183221 -311.844345) (xy 295.213245 -311.888382) (xy 295.236371 -311.936403) (xy 295.252081 -311.987333)
			(xy 295.260024 -312.040037) (xy 295.260522 -312.066686) (xy 295.260024 -312.093335) (xy 298.674272 -312.093335)
			(xy 298.674272 -312.040037) (xy 298.682215 -311.987333) (xy 298.697925 -311.936403) (xy 298.721051 -311.888382)
			(xy 298.751075 -311.844345) (xy 298.787327 -311.805274) (xy 298.828998 -311.772043) (xy 298.875156 -311.745394)
			(xy 298.92477 -311.725922) (xy 298.976732 -311.714062) (xy 299.029882 -311.710079) (xy 299.083032 -311.714062)
			(xy 299.134994 -311.725922) (xy 299.184608 -311.745394) (xy 299.230766 -311.772043) (xy 299.272437 -311.805274)
			(xy 299.308689 -311.844345) (xy 299.338713 -311.888382) (xy 299.361839 -311.936403) (xy 299.377549 -311.987333)
			(xy 299.385492 -312.040037) (xy 299.38599 -312.066686) (xy 299.385492 -312.093335) (xy 299.377549 -312.146039)
			(xy 299.361839 -312.196969) (xy 299.338713 -312.24499) (xy 299.308689 -312.289027) (xy 299.272437 -312.328098)
			(xy 299.230766 -312.361329) (xy 299.184608 -312.387978) (xy 299.134994 -312.40745) (xy 299.083032 -312.41931)
			(xy 299.029882 -312.423294) (xy 298.976732 -312.41931) (xy 298.92477 -312.40745) (xy 298.875156 -312.387978)
			(xy 298.828998 -312.361329) (xy 298.787327 -312.328098) (xy 298.751075 -312.289027) (xy 298.721051 -312.24499)
			(xy 298.697925 -312.196969) (xy 298.682215 -312.146039) (xy 298.674272 -312.093335) (xy 295.260024 -312.093335)
			(xy 295.252081 -312.146039) (xy 295.236371 -312.196969) (xy 295.213245 -312.24499) (xy 295.183221 -312.289027)
			(xy 295.146969 -312.328098) (xy 295.105298 -312.361329) (xy 295.05914 -312.387978) (xy 295.009526 -312.40745)
			(xy 294.957564 -312.41931) (xy 294.904414 -312.423294) (xy 294.851264 -312.41931) (xy 294.799302 -312.40745)
			(xy 294.749688 -312.387978) (xy 294.70353 -312.361329) (xy 294.661859 -312.328098) (xy 294.625607 -312.289027)
			(xy 294.595583 -312.24499) (xy 294.572457 -312.196969) (xy 294.556747 -312.146039) (xy 294.548804 -312.093335)
			(xy 284.272492 -312.093335) (xy 284.264549 -312.146039) (xy 284.248839 -312.196969) (xy 284.225713 -312.24499)
			(xy 284.195689 -312.289027) (xy 284.159437 -312.328098) (xy 284.117766 -312.361329) (xy 284.071608 -312.387978)
			(xy 284.021994 -312.40745) (xy 283.970032 -312.41931) (xy 283.916882 -312.423294) (xy 283.863732 -312.41931)
			(xy 283.81177 -312.40745) (xy 283.762156 -312.387978) (xy 283.715998 -312.361329) (xy 283.674327 -312.328098)
			(xy 283.638075 -312.289027) (xy 283.608051 -312.24499) (xy 283.584925 -312.196969) (xy 283.569215 -312.146039)
			(xy 283.561272 -312.093335) (xy 280.172424 -312.093335) (xy 280.164481 -312.146039) (xy 280.148771 -312.196969)
			(xy 280.125645 -312.24499) (xy 280.095621 -312.289027) (xy 280.059369 -312.328098) (xy 280.017698 -312.361329)
			(xy 279.97154 -312.387978) (xy 279.921926 -312.40745) (xy 279.869964 -312.41931) (xy 279.816814 -312.423294)
			(xy 279.763664 -312.41931) (xy 279.711702 -312.40745) (xy 279.662088 -312.387978) (xy 279.61593 -312.361329)
			(xy 279.574259 -312.328098) (xy 279.538007 -312.289027) (xy 279.507983 -312.24499) (xy 279.484857 -312.196969)
			(xy 279.469147 -312.146039) (xy 279.461204 -312.093335) (xy 269.184892 -312.093335) (xy 269.176949 -312.146039)
			(xy 269.161239 -312.196969) (xy 269.138113 -312.24499) (xy 269.108089 -312.289027) (xy 269.071837 -312.328098)
			(xy 269.030166 -312.361329) (xy 268.984008 -312.387978) (xy 268.934394 -312.40745) (xy 268.882432 -312.41931)
			(xy 268.829282 -312.423294) (xy 268.776132 -312.41931) (xy 268.72417 -312.40745) (xy 268.674556 -312.387978)
			(xy 268.628398 -312.361329) (xy 268.586727 -312.328098) (xy 268.550475 -312.289027) (xy 268.520451 -312.24499)
			(xy 268.497325 -312.196969) (xy 268.481615 -312.146039) (xy 268.473672 -312.093335) (xy 265.084824 -312.093335)
			(xy 265.076881 -312.146039) (xy 265.061171 -312.196969) (xy 265.038045 -312.24499) (xy 265.008021 -312.289027)
			(xy 264.971769 -312.328098) (xy 264.930098 -312.361329) (xy 264.88394 -312.387978) (xy 264.834326 -312.40745)
			(xy 264.782364 -312.41931) (xy 264.729214 -312.423294) (xy 264.676064 -312.41931) (xy 264.624102 -312.40745)
			(xy 264.574488 -312.387978) (xy 264.52833 -312.361329) (xy 264.486659 -312.328098) (xy 264.450407 -312.289027)
			(xy 264.420383 -312.24499) (xy 264.397257 -312.196969) (xy 264.381547 -312.146039) (xy 264.373604 -312.093335)
			(xy 254.20828 -312.093335) (xy 254.20828 -312.943219) (xy 264.373604 -312.943219) (xy 264.373604 -312.889921)
			(xy 264.381547 -312.837217) (xy 264.397257 -312.786287) (xy 264.420383 -312.738266) (xy 264.450407 -312.694229)
			(xy 264.486659 -312.655158) (xy 264.52833 -312.621927) (xy 264.574488 -312.595278) (xy 264.624102 -312.575806)
			(xy 264.676064 -312.563946) (xy 264.729214 -312.559963) (xy 264.782364 -312.563946) (xy 264.834326 -312.575806)
			(xy 264.88394 -312.595278) (xy 264.930098 -312.621927) (xy 264.971769 -312.655158) (xy 265.008021 -312.694229)
			(xy 265.038045 -312.738266) (xy 265.061171 -312.786287) (xy 265.076881 -312.837217) (xy 265.084824 -312.889921)
			(xy 265.085322 -312.91657) (xy 265.084824 -312.943219) (xy 279.461204 -312.943219) (xy 279.461204 -312.889921)
			(xy 279.469147 -312.837217) (xy 279.484857 -312.786287) (xy 279.507983 -312.738266) (xy 279.538007 -312.694229)
			(xy 279.574259 -312.655158) (xy 279.61593 -312.621927) (xy 279.662088 -312.595278) (xy 279.711702 -312.575806)
			(xy 279.763664 -312.563946) (xy 279.816814 -312.559963) (xy 279.869964 -312.563946) (xy 279.921926 -312.575806)
			(xy 279.97154 -312.595278) (xy 280.017698 -312.621927) (xy 280.059369 -312.655158) (xy 280.095621 -312.694229)
			(xy 280.125645 -312.738266) (xy 280.148771 -312.786287) (xy 280.164481 -312.837217) (xy 280.172424 -312.889921)
			(xy 280.172922 -312.91657) (xy 280.172424 -312.943219) (xy 294.548804 -312.943219) (xy 294.548804 -312.889921)
			(xy 294.556747 -312.837217) (xy 294.572457 -312.786287) (xy 294.595583 -312.738266) (xy 294.625607 -312.694229)
			(xy 294.661859 -312.655158) (xy 294.70353 -312.621927) (xy 294.749688 -312.595278) (xy 294.799302 -312.575806)
			(xy 294.851264 -312.563946) (xy 294.904414 -312.559963) (xy 294.957564 -312.563946) (xy 295.009526 -312.575806)
			(xy 295.05914 -312.595278) (xy 295.105298 -312.621927) (xy 295.146969 -312.655158) (xy 295.183221 -312.694229)
			(xy 295.213245 -312.738266) (xy 295.236371 -312.786287) (xy 295.252081 -312.837217) (xy 295.260024 -312.889921)
			(xy 295.260522 -312.91657) (xy 295.260024 -312.943219) (xy 295.252081 -312.995923) (xy 295.236371 -313.046853)
			(xy 295.213245 -313.094874) (xy 295.183221 -313.138911) (xy 295.146969 -313.177982) (xy 295.105298 -313.211213)
			(xy 295.05914 -313.237862) (xy 295.009526 -313.257334) (xy 294.957564 -313.269194) (xy 294.904414 -313.273178)
			(xy 294.851264 -313.269194) (xy 294.799302 -313.257334) (xy 294.749688 -313.237862) (xy 294.70353 -313.211213)
			(xy 294.661859 -313.177982) (xy 294.625607 -313.138911) (xy 294.595583 -313.094874) (xy 294.572457 -313.046853)
			(xy 294.556747 -312.995923) (xy 294.548804 -312.943219) (xy 280.172424 -312.943219) (xy 280.164481 -312.995923)
			(xy 280.148771 -313.046853) (xy 280.125645 -313.094874) (xy 280.095621 -313.138911) (xy 280.059369 -313.177982)
			(xy 280.017698 -313.211213) (xy 279.97154 -313.237862) (xy 279.921926 -313.257334) (xy 279.869964 -313.269194)
			(xy 279.816814 -313.273178) (xy 279.763664 -313.269194) (xy 279.711702 -313.257334) (xy 279.662088 -313.237862)
			(xy 279.61593 -313.211213) (xy 279.574259 -313.177982) (xy 279.538007 -313.138911) (xy 279.507983 -313.094874)
			(xy 279.484857 -313.046853) (xy 279.469147 -312.995923) (xy 279.461204 -312.943219) (xy 265.084824 -312.943219)
			(xy 265.076881 -312.995923) (xy 265.061171 -313.046853) (xy 265.038045 -313.094874) (xy 265.008021 -313.138911)
			(xy 264.971769 -313.177982) (xy 264.930098 -313.211213) (xy 264.88394 -313.237862) (xy 264.834326 -313.257334)
			(xy 264.782364 -313.269194) (xy 264.729214 -313.273178) (xy 264.676064 -313.269194) (xy 264.624102 -313.257334)
			(xy 264.574488 -313.237862) (xy 264.52833 -313.211213) (xy 264.486659 -313.177982) (xy 264.450407 -313.138911)
			(xy 264.420383 -313.094874) (xy 264.397257 -313.046853) (xy 264.381547 -312.995923) (xy 264.373604 -312.943219)
			(xy 254.20828 -312.943219) (xy 254.20828 -313.793357) (xy 268.473672 -313.793357) (xy 268.473672 -313.740059)
			(xy 268.481615 -313.687355) (xy 268.497325 -313.636425) (xy 268.520451 -313.588404) (xy 268.550475 -313.544367)
			(xy 268.586727 -313.505296) (xy 268.628398 -313.472065) (xy 268.674556 -313.445416) (xy 268.72417 -313.425944)
			(xy 268.776132 -313.414084) (xy 268.829282 -313.410101) (xy 268.882432 -313.414084) (xy 268.934394 -313.425944)
			(xy 268.984008 -313.445416) (xy 269.030166 -313.472065) (xy 269.071837 -313.505296) (xy 269.108089 -313.544367)
			(xy 269.138113 -313.588404) (xy 269.161239 -313.636425) (xy 269.176949 -313.687355) (xy 269.184892 -313.740059)
			(xy 269.18539 -313.766708) (xy 269.184892 -313.793357) (xy 283.561272 -313.793357) (xy 283.561272 -313.740059)
			(xy 283.569215 -313.687355) (xy 283.584925 -313.636425) (xy 283.608051 -313.588404) (xy 283.638075 -313.544367)
			(xy 283.674327 -313.505296) (xy 283.715998 -313.472065) (xy 283.762156 -313.445416) (xy 283.81177 -313.425944)
			(xy 283.863732 -313.414084) (xy 283.916882 -313.410101) (xy 283.970032 -313.414084) (xy 284.021994 -313.425944)
			(xy 284.071608 -313.445416) (xy 284.117766 -313.472065) (xy 284.159437 -313.505296) (xy 284.195689 -313.544367)
			(xy 284.225713 -313.588404) (xy 284.248839 -313.636425) (xy 284.264549 -313.687355) (xy 284.272492 -313.740059)
			(xy 284.27299 -313.766708) (xy 284.272492 -313.793357) (xy 298.674272 -313.793357) (xy 298.674272 -313.740059)
			(xy 298.682215 -313.687355) (xy 298.697925 -313.636425) (xy 298.721051 -313.588404) (xy 298.751075 -313.544367)
			(xy 298.787327 -313.505296) (xy 298.828998 -313.472065) (xy 298.875156 -313.445416) (xy 298.92477 -313.425944)
			(xy 298.976732 -313.414084) (xy 299.029882 -313.410101) (xy 299.083032 -313.414084) (xy 299.134994 -313.425944)
			(xy 299.184608 -313.445416) (xy 299.230766 -313.472065) (xy 299.272437 -313.505296) (xy 299.308689 -313.544367)
			(xy 299.338713 -313.588404) (xy 299.361839 -313.636425) (xy 299.377549 -313.687355) (xy 299.385492 -313.740059)
			(xy 299.38599 -313.766708) (xy 299.385492 -313.793357) (xy 299.377549 -313.846061) (xy 299.361839 -313.896991)
			(xy 299.338713 -313.945012) (xy 299.308689 -313.989049) (xy 299.272437 -314.02812) (xy 299.230766 -314.061351)
			(xy 299.184608 -314.088) (xy 299.134994 -314.107472) (xy 299.083032 -314.119332) (xy 299.029882 -314.123316)
			(xy 298.976732 -314.119332) (xy 298.92477 -314.107472) (xy 298.875156 -314.088) (xy 298.828998 -314.061351)
			(xy 298.787327 -314.02812) (xy 298.751075 -313.989049) (xy 298.721051 -313.945012) (xy 298.697925 -313.896991)
			(xy 298.682215 -313.846061) (xy 298.674272 -313.793357) (xy 284.272492 -313.793357) (xy 284.264549 -313.846061)
			(xy 284.248839 -313.896991) (xy 284.225713 -313.945012) (xy 284.195689 -313.989049) (xy 284.159437 -314.02812)
			(xy 284.117766 -314.061351) (xy 284.071608 -314.088) (xy 284.021994 -314.107472) (xy 283.970032 -314.119332)
			(xy 283.916882 -314.123316) (xy 283.863732 -314.119332) (xy 283.81177 -314.107472) (xy 283.762156 -314.088)
			(xy 283.715998 -314.061351) (xy 283.674327 -314.02812) (xy 283.638075 -313.989049) (xy 283.608051 -313.945012)
			(xy 283.584925 -313.896991) (xy 283.569215 -313.846061) (xy 283.561272 -313.793357) (xy 269.184892 -313.793357)
			(xy 269.176949 -313.846061) (xy 269.161239 -313.896991) (xy 269.138113 -313.945012) (xy 269.108089 -313.989049)
			(xy 269.071837 -314.02812) (xy 269.030166 -314.061351) (xy 268.984008 -314.088) (xy 268.934394 -314.107472)
			(xy 268.882432 -314.119332) (xy 268.829282 -314.123316) (xy 268.776132 -314.119332) (xy 268.72417 -314.107472)
			(xy 268.674556 -314.088) (xy 268.628398 -314.061351) (xy 268.586727 -314.02812) (xy 268.550475 -313.989049)
			(xy 268.520451 -313.945012) (xy 268.497325 -313.896991) (xy 268.481615 -313.846061) (xy 268.473672 -313.793357)
			(xy 254.20828 -313.793357) (xy 254.20828 -314.643241) (xy 264.373604 -314.643241) (xy 264.373604 -314.589943)
			(xy 264.381547 -314.537239) (xy 264.397257 -314.486309) (xy 264.420383 -314.438288) (xy 264.450407 -314.394251)
			(xy 264.486659 -314.35518) (xy 264.52833 -314.321949) (xy 264.574488 -314.2953) (xy 264.624102 -314.275828)
			(xy 264.676064 -314.263968) (xy 264.729214 -314.259985) (xy 264.782364 -314.263968) (xy 264.834326 -314.275828)
			(xy 264.88394 -314.2953) (xy 264.930098 -314.321949) (xy 264.971769 -314.35518) (xy 265.008021 -314.394251)
			(xy 265.038045 -314.438288) (xy 265.061171 -314.486309) (xy 265.076881 -314.537239) (xy 265.084824 -314.589943)
			(xy 265.085322 -314.616592) (xy 265.084824 -314.643241) (xy 279.461204 -314.643241) (xy 279.461204 -314.589943)
			(xy 279.469147 -314.537239) (xy 279.484857 -314.486309) (xy 279.507983 -314.438288) (xy 279.538007 -314.394251)
			(xy 279.574259 -314.35518) (xy 279.61593 -314.321949) (xy 279.662088 -314.2953) (xy 279.711702 -314.275828)
			(xy 279.763664 -314.263968) (xy 279.816814 -314.259985) (xy 279.869964 -314.263968) (xy 279.921926 -314.275828)
			(xy 279.97154 -314.2953) (xy 280.017698 -314.321949) (xy 280.059369 -314.35518) (xy 280.095621 -314.394251)
			(xy 280.125645 -314.438288) (xy 280.148771 -314.486309) (xy 280.164481 -314.537239) (xy 280.172424 -314.589943)
			(xy 280.172922 -314.616592) (xy 280.172424 -314.643241) (xy 294.548804 -314.643241) (xy 294.548804 -314.589943)
			(xy 294.556747 -314.537239) (xy 294.572457 -314.486309) (xy 294.595583 -314.438288) (xy 294.625607 -314.394251)
			(xy 294.661859 -314.35518) (xy 294.70353 -314.321949) (xy 294.749688 -314.2953) (xy 294.799302 -314.275828)
			(xy 294.851264 -314.263968) (xy 294.904414 -314.259985) (xy 294.957564 -314.263968) (xy 295.009526 -314.275828)
			(xy 295.05914 -314.2953) (xy 295.105298 -314.321949) (xy 295.146969 -314.35518) (xy 295.183221 -314.394251)
			(xy 295.213245 -314.438288) (xy 295.236371 -314.486309) (xy 295.252081 -314.537239) (xy 295.260024 -314.589943)
			(xy 295.260522 -314.616592) (xy 295.260024 -314.643241) (xy 295.252081 -314.695945) (xy 295.236371 -314.746875)
			(xy 295.213245 -314.794896) (xy 295.183221 -314.838933) (xy 295.146969 -314.878004) (xy 295.105298 -314.911235)
			(xy 295.05914 -314.937884) (xy 295.009526 -314.957356) (xy 294.957564 -314.969216) (xy 294.904414 -314.9732)
			(xy 294.851264 -314.969216) (xy 294.799302 -314.957356) (xy 294.749688 -314.937884) (xy 294.70353 -314.911235)
			(xy 294.661859 -314.878004) (xy 294.625607 -314.838933) (xy 294.595583 -314.794896) (xy 294.572457 -314.746875)
			(xy 294.556747 -314.695945) (xy 294.548804 -314.643241) (xy 280.172424 -314.643241) (xy 280.164481 -314.695945)
			(xy 280.148771 -314.746875) (xy 280.125645 -314.794896) (xy 280.095621 -314.838933) (xy 280.059369 -314.878004)
			(xy 280.017698 -314.911235) (xy 279.97154 -314.937884) (xy 279.921926 -314.957356) (xy 279.869964 -314.969216)
			(xy 279.816814 -314.9732) (xy 279.763664 -314.969216) (xy 279.711702 -314.957356) (xy 279.662088 -314.937884)
			(xy 279.61593 -314.911235) (xy 279.574259 -314.878004) (xy 279.538007 -314.838933) (xy 279.507983 -314.794896)
			(xy 279.484857 -314.746875) (xy 279.469147 -314.695945) (xy 279.461204 -314.643241) (xy 265.084824 -314.643241)
			(xy 265.076881 -314.695945) (xy 265.061171 -314.746875) (xy 265.038045 -314.794896) (xy 265.008021 -314.838933)
			(xy 264.971769 -314.878004) (xy 264.930098 -314.911235) (xy 264.88394 -314.937884) (xy 264.834326 -314.957356)
			(xy 264.782364 -314.969216) (xy 264.729214 -314.9732) (xy 264.676064 -314.969216) (xy 264.624102 -314.957356)
			(xy 264.574488 -314.937884) (xy 264.52833 -314.911235) (xy 264.486659 -314.878004) (xy 264.450407 -314.838933)
			(xy 264.420383 -314.794896) (xy 264.397257 -314.746875) (xy 264.381547 -314.695945) (xy 264.373604 -314.643241)
			(xy 254.20828 -314.643241) (xy 254.20828 -314.724288) (xy 254.977371 -315.493379) (xy 268.473672 -315.493379)
			(xy 268.473672 -315.440081) (xy 268.481615 -315.387377) (xy 268.497325 -315.336447) (xy 268.520451 -315.288426)
			(xy 268.550475 -315.244389) (xy 268.586727 -315.205318) (xy 268.628398 -315.172087) (xy 268.674556 -315.145438)
			(xy 268.72417 -315.125966) (xy 268.776132 -315.114106) (xy 268.829282 -315.110123) (xy 268.882432 -315.114106)
			(xy 268.934394 -315.125966) (xy 268.984008 -315.145438) (xy 269.030166 -315.172087) (xy 269.071837 -315.205318)
			(xy 269.108089 -315.244389) (xy 269.138113 -315.288426) (xy 269.161239 -315.336447) (xy 269.176949 -315.387377)
			(xy 269.184892 -315.440081) (xy 269.18539 -315.46673) (xy 269.184892 -315.493379) (xy 283.561272 -315.493379)
			(xy 283.561272 -315.440081) (xy 283.569215 -315.387377) (xy 283.584925 -315.336447) (xy 283.608051 -315.288426)
			(xy 283.638075 -315.244389) (xy 283.674327 -315.205318) (xy 283.715998 -315.172087) (xy 283.762156 -315.145438)
			(xy 283.81177 -315.125966) (xy 283.863732 -315.114106) (xy 283.916882 -315.110123) (xy 283.970032 -315.114106)
			(xy 284.021994 -315.125966) (xy 284.071608 -315.145438) (xy 284.117766 -315.172087) (xy 284.159437 -315.205318)
			(xy 284.195689 -315.244389) (xy 284.225713 -315.288426) (xy 284.248839 -315.336447) (xy 284.264549 -315.387377)
			(xy 284.272492 -315.440081) (xy 284.27299 -315.46673) (xy 284.272492 -315.493379) (xy 298.66589 -315.493379)
			(xy 298.66589 -315.440081) (xy 298.673833 -315.387377) (xy 298.689543 -315.336447) (xy 298.712669 -315.288426)
			(xy 298.742693 -315.244389) (xy 298.778945 -315.205318) (xy 298.820616 -315.172087) (xy 298.866774 -315.145438)
			(xy 298.916388 -315.125966) (xy 298.96835 -315.114106) (xy 299.0215 -315.110123) (xy 299.07465 -315.114106)
			(xy 299.126612 -315.125966) (xy 299.176226 -315.145438) (xy 299.222384 -315.172087) (xy 299.264055 -315.205318)
			(xy 299.300307 -315.244389) (xy 299.330331 -315.288426) (xy 299.353457 -315.336447) (xy 299.369167 -315.387377)
			(xy 299.37711 -315.440081) (xy 299.377608 -315.46673) (xy 299.37711 -315.493379) (xy 299.369167 -315.546083)
			(xy 299.353457 -315.597013) (xy 299.330331 -315.645034) (xy 299.300307 -315.689071) (xy 299.264055 -315.728142)
			(xy 299.222384 -315.761373) (xy 299.176226 -315.788022) (xy 299.126612 -315.807494) (xy 299.07465 -315.819354)
			(xy 299.0215 -315.823338) (xy 298.96835 -315.819354) (xy 298.916388 -315.807494) (xy 298.866774 -315.788022)
			(xy 298.820616 -315.761373) (xy 298.778945 -315.728142) (xy 298.742693 -315.689071) (xy 298.712669 -315.645034)
			(xy 298.689543 -315.597013) (xy 298.673833 -315.546083) (xy 298.66589 -315.493379) (xy 284.272492 -315.493379)
			(xy 284.264549 -315.546083) (xy 284.248839 -315.597013) (xy 284.225713 -315.645034) (xy 284.195689 -315.689071)
			(xy 284.159437 -315.728142) (xy 284.117766 -315.761373) (xy 284.071608 -315.788022) (xy 284.021994 -315.807494)
			(xy 283.970032 -315.819354) (xy 283.916882 -315.823338) (xy 283.863732 -315.819354) (xy 283.81177 -315.807494)
			(xy 283.762156 -315.788022) (xy 283.715998 -315.761373) (xy 283.674327 -315.728142) (xy 283.638075 -315.689071)
			(xy 283.608051 -315.645034) (xy 283.584925 -315.597013) (xy 283.569215 -315.546083) (xy 283.561272 -315.493379)
			(xy 269.184892 -315.493379) (xy 269.176949 -315.546083) (xy 269.161239 -315.597013) (xy 269.138113 -315.645034)
			(xy 269.108089 -315.689071) (xy 269.071837 -315.728142) (xy 269.030166 -315.761373) (xy 268.984008 -315.788022)
			(xy 268.934394 -315.807494) (xy 268.882432 -315.819354) (xy 268.829282 -315.823338) (xy 268.776132 -315.819354)
			(xy 268.72417 -315.807494) (xy 268.674556 -315.788022) (xy 268.628398 -315.761373) (xy 268.586727 -315.728142)
			(xy 268.550475 -315.689071) (xy 268.520451 -315.645034) (xy 268.497325 -315.597013) (xy 268.481615 -315.546083)
			(xy 268.473672 -315.493379) (xy 254.977371 -315.493379) (xy 255.94564 -316.461648)
		)
		(stroke
			(width 0)
			(type solid)
		)
		(fill yes)
		(layer "In15.Cu")
		(net "GND")
	)
	(gr_poly
		(pts
			(xy 56.09971 -321.614038) (xy 56.082438 -321.581018) (xy 56.069789 -321.555491) (xy 56.05189 -321.501409)
			(xy 56.042851 -321.445164) (xy 56.042306 -321.41668) (xy 56.042856 -321.388698) (xy 56.051614 -321.333424)
			(xy 56.068911 -321.280201) (xy 56.09432 -321.230338) (xy 56.127217 -321.185065) (xy 56.166791 -321.145495)
			(xy 56.212068 -321.112602) (xy 56.261932 -321.087198) (xy 56.315158 -321.069906) (xy 56.370432 -321.061154)
			(xy 56.398414 -321.060572) (xy 56.426895 -321.061137) (xy 56.483131 -321.070202) (xy 56.537214 -321.088083)
			(xy 56.562752 -321.100704) (xy 56.595772 -321.117976) (xy 58.584846 -319.128902) (xy 58.595156 -319.11775)
			(xy 58.609307 -319.090894) (xy 58.614946 -319.061067) (xy 58.611578 -319.030899) (xy 58.599499 -319.003051)
			(xy 58.579774 -318.979977) (xy 58.554143 -318.963714) (xy 58.539634 -318.95923) (xy 58.513024 -318.951512)
			(xy 58.462203 -318.929447) (xy 58.41511 -318.900262) (xy 58.372735 -318.864569) (xy 58.33597 -318.82312)
			(xy 58.30559 -318.776788) (xy 58.282234 -318.726548) (xy 58.266393 -318.673457) (xy 58.258401 -318.618632)
			(xy 58.257948 -318.59093) (xy 58.258432 -318.563676) (xy 58.266185 -318.509723) (xy 58.281537 -318.457422)
			(xy 58.304175 -318.407838) (xy 58.33364 -318.361981) (xy 58.369331 -318.320783) (xy 58.410522 -318.285085)
			(xy 58.456373 -318.255611) (xy 58.505953 -318.232962) (xy 58.55825 -318.2176) (xy 58.612202 -318.209837)
			(xy 58.639456 -318.209422) (xy 58.667153 -318.20992) (xy 58.721963 -318.217936) (xy 58.775039 -318.233791)
			(xy 58.825266 -318.257151) (xy 58.871588 -318.287527) (xy 58.913033 -318.32428) (xy 58.948729 -318.366638)
			(xy 58.977928 -318.413711) (xy 59.000015 -318.46451) (xy 59.007756 -318.491108) (xy 59.012279 -318.505612)
			(xy 59.028508 -318.531277) (xy 59.05157 -318.551031) (xy 59.079422 -318.563126) (xy 59.109601 -318.566492)
			(xy 59.139434 -318.560831) (xy 59.166281 -318.546644) (xy 59.177428 -318.53632) (xy 64.6684 -313.045348)
			(xy 64.6684 -254.261874) (xy 64.63284 -254.250698) (xy 64.60612 -254.241718) (xy 64.555695 -254.216525)
			(xy 64.509867 -254.183705) (xy 64.469779 -254.144079) (xy 64.436431 -254.098634) (xy 64.410655 -254.048505)
			(xy 64.393094 -253.994943) (xy 64.384186 -253.939284) (xy 64.383666 -253.9111) (xy 64.384246 -253.881565)
			(xy 64.39399 -253.823305) (xy 64.41321 -253.76745) (xy 64.44138 -253.71553) (xy 64.459104 -253.691898)
			(xy 64.48679 -253.656338) (xy 62.738 -251.907548) (xy 62.738 -221.224348) (xy 67.0814 -216.880948)
			(xy 67.0814 -189.601348) (xy 64.9224 -187.442348) (xy 53.095906 -187.442348) (xy 53.082137 -187.442791)
			(xy 53.055597 -187.450134) (xy 53.031991 -187.464314) (xy 53.013043 -187.484296) (xy 53.000134 -187.50862)
			(xy 52.994208 -187.535512) (xy 52.99456 -187.549282) (xy 52.995068 -187.569348) (xy 52.994578 -187.596596)
			(xy 52.986816 -187.650536) (xy 52.971456 -187.702823) (xy 52.948812 -187.752391) (xy 52.919344 -187.798233)
			(xy 52.883652 -187.839414) (xy 52.842462 -187.875097) (xy 52.796614 -187.904554) (xy 52.74704 -187.927187)
			(xy 52.69475 -187.942535) (xy 52.640808 -187.950285) (xy 52.61356 -187.950856) (xy 52.586321 -187.950368)
			(xy 52.532397 -187.942614) (xy 52.480125 -187.927269) (xy 52.430567 -187.904645) (xy 52.38473 -187.875202)
			(xy 52.343547 -187.839538) (xy 52.307856 -187.79838) (xy 52.278381 -187.752564) (xy 52.255723 -187.703021)
			(xy 52.240342 -187.650759) (xy 52.23255 -187.596841) (xy 52.232052 -187.569602) (xy 52.23161 -187.556217)
			(xy 52.224577 -187.530386) (xy 52.211072 -187.507269) (xy 52.192024 -187.488456) (xy 52.168742 -187.47524)
			(xy 52.142825 -187.468528) (xy 52.129436 -187.468256) (xy 52.12588 -187.468256) (xy 52.092681 -187.467538)
			(xy 52.027286 -187.456043) (xy 51.995832 -187.445396) (xy 51.98745 -187.442348) (xy 51.300888 -187.442348)
			(xy 51.275884 -187.456232) (xy 51.222663 -187.477171) (xy 51.166911 -187.489926) (xy 51.10988 -187.494209)
			(xy 51.052849 -187.489926) (xy 50.997097 -187.477171) (xy 50.943876 -187.456232) (xy 50.918872 -187.442348)
			(xy 47.809912 -187.442348) (xy 47.802292 -187.484258) (xy 47.797166 -187.510353) (xy 47.780635 -187.560898)
			(xy 47.757238 -187.608653) (xy 47.727429 -187.652693) (xy 47.691787 -187.69216) (xy 47.651004 -187.726289)
			(xy 47.605873 -187.754417) (xy 47.557269 -187.775997) (xy 47.506137 -187.79061) (xy 47.45347 -187.797973)
			(xy 47.42688 -187.798456) (xy 47.397964 -187.79792) (xy 47.340796 -187.78919) (xy 47.2856 -187.771932)
			(xy 47.23364 -187.746543) (xy 47.186107 -187.713603) (xy 47.144089 -187.673867) (xy 47.12589 -187.65139)
			(xy 47.115993 -187.639585) (xy 47.090669 -187.622066) (xy 47.061276 -187.61289) (xy 47.030484 -187.61289)
			(xy 47.001091 -187.622066) (xy 46.975767 -187.639585) (xy 46.96587 -187.65139) (xy 46.949117 -187.672173)
			(xy 46.910763 -187.709303) (xy 46.867609 -187.740725) (xy 46.820495 -187.765824) (xy 46.770343 -187.78411)
			(xy 46.718132 -187.795227) (xy 46.66488 -187.798957) (xy 46.611628 -187.795227) (xy 46.559417 -187.78411)
			(xy 46.509265 -187.765824) (xy 46.462151 -187.740725) (xy 46.418997 -187.709303) (xy 46.380643 -187.672173)
			(xy 46.36389 -187.65139) (xy 46.353993 -187.639585) (xy 46.328669 -187.622066) (xy 46.299276 -187.61289)
			(xy 46.268484 -187.61289) (xy 46.239091 -187.622066) (xy 46.213767 -187.639585) (xy 46.20387 -187.65139)
			(xy 46.185681 -187.673876) (xy 46.143665 -187.713619) (xy 46.096131 -187.746564) (xy 46.044169 -187.771956)
			(xy 45.988969 -187.789213) (xy 45.931797 -187.79794) (xy 45.90288 -187.798456) (xy 45.876296 -187.797987)
			(xy 45.823645 -187.790586) (xy 45.772532 -187.775946) (xy 45.723947 -187.754349) (xy 45.678833 -187.726214)
			(xy 45.638063 -187.692086) (xy 45.602427 -187.652627) (xy 45.572617 -187.608601) (xy 45.54921 -187.560863)
			(xy 45.532659 -187.510336) (xy 45.527468 -187.484258) (xy 45.519848 -187.442348) (xy 32.157416 -187.442348)
			(xy 32.142447 -187.442887) (xy 32.113796 -187.451576) (xy 32.088887 -187.468185) (xy 32.069852 -187.491294)
			(xy 32.058319 -187.518923) (xy 32.055277 -187.548707) (xy 32.057594 -187.563506) (xy 32.060911 -187.581548)
			(xy 32.064476 -187.618061) (xy 32.064706 -187.636404) (xy 32.06422 -187.663655) (xy 32.056463 -187.717602)
			(xy 32.041107 -187.769896) (xy 32.018466 -187.819473) (xy 31.989 -187.865323) (xy 31.953308 -187.906512)
			(xy 31.912118 -187.942203) (xy 31.866268 -187.971669) (xy 31.816691 -187.99431) (xy 31.764396 -188.009664)
			(xy 31.710449 -188.01742) (xy 31.683198 -188.017912) (xy 31.654281 -188.017378) (xy 31.59711 -188.008651)
			(xy 31.54191 -187.991397) (xy 31.489946 -187.966011) (xy 31.442407 -187.933075) (xy 31.400383 -187.893343)
			(xy 31.382208 -187.870846) (xy 31.372311 -187.859041) (xy 31.346987 -187.841522) (xy 31.317594 -187.832346)
			(xy 31.286802 -187.832346) (xy 31.257409 -187.841522) (xy 31.232085 -187.859041) (xy 31.222188 -187.870846)
			(xy 31.205435 -187.891629) (xy 31.167081 -187.928759) (xy 31.123927 -187.960181) (xy 31.076813 -187.98528)
			(xy 31.026661 -188.003566) (xy 30.97445 -188.014683) (xy 30.921198 -188.018413) (xy 30.867946 -188.014683)
			(xy 30.815735 -188.003566) (xy 30.765583 -187.98528) (xy 30.718469 -187.960181) (xy 30.675315 -187.928759)
			(xy 30.636961 -187.891629) (xy 30.620208 -187.870846) (xy 30.610311 -187.859041) (xy 30.584987 -187.841522)
			(xy 30.555594 -187.832346) (xy 30.524802 -187.832346) (xy 30.495409 -187.841522) (xy 30.470085 -187.859041)
			(xy 30.460188 -187.870846) (xy 30.442 -187.893335) (xy 30.399987 -187.933084) (xy 30.352454 -187.966035)
			(xy 30.300492 -187.991433) (xy 30.245291 -188.008695) (xy 30.188117 -188.017426) (xy 30.159198 -188.017912)
			(xy 30.131947 -188.017426) (xy 30.077999 -188.009669) (xy 30.025704 -187.994314) (xy 29.976127 -187.971673)
			(xy 29.930277 -187.942207) (xy 29.889086 -187.906515) (xy 29.853395 -187.865325) (xy 29.823928 -187.819475)
			(xy 29.801287 -187.769898) (xy 29.785931 -187.717603) (xy 29.778174 -187.663655) (xy 29.77769 -187.636404)
			(xy 29.777934 -187.618062) (xy 29.781497 -187.58155) (xy 29.784802 -187.563506) (xy 29.787174 -187.548705)
			(xy 29.784177 -187.518893) (xy 29.772654 -187.491236) (xy 29.753599 -187.468115) (xy 29.728652 -187.451522)
			(xy 29.699962 -187.442886) (xy 29.68498 -187.442348) (xy 21.300186 -187.442348) (xy 21.29155 -187.48248)
			(xy 21.285337 -187.509048) (xy 21.266339 -187.560194) (xy 21.240249 -187.608113) (xy 21.207597 -187.651825)
			(xy 21.169051 -187.690439) (xy 21.125396 -187.723168) (xy 21.077524 -187.749343) (xy 21.026411 -187.76843)
			(xy 20.9731 -187.780041) (xy 20.918678 -187.783938) (xy 20.864256 -187.780041) (xy 20.810945 -187.76843)
			(xy 20.759832 -187.749343) (xy 20.71196 -187.723168) (xy 20.668305 -187.690439) (xy 20.629759 -187.651825)
			(xy 20.597107 -187.608113) (xy 20.571017 -187.560194) (xy 20.552019 -187.509048) (xy 20.545806 -187.48248)
			(xy 20.53717 -187.442348) (xy 16.65859 -187.442348) (xy 16.643428 -187.442908) (xy 16.614442 -187.451815)
			(xy 16.58935 -187.46884) (xy 16.570362 -187.492483) (xy 16.559154 -187.520659) (xy 16.556714 -187.550884)
			(xy 16.563256 -187.580493) (xy 16.570198 -187.593986) (xy 16.581985 -187.615591) (xy 16.60052 -187.661184)
			(xy 16.613042 -187.70878) (xy 16.619342 -187.757592) (xy 16.619728 -187.7822) (xy 16.619242 -187.809451)
			(xy 16.611486 -187.863399) (xy 16.596131 -187.915694) (xy 16.573489 -187.965271) (xy 16.544023 -188.011121)
			(xy 16.508332 -188.052312) (xy 16.467141 -188.088003) (xy 16.421291 -188.117469) (xy 16.371714 -188.140111)
			(xy 16.319419 -188.155466) (xy 16.265471 -188.163222) (xy 16.210969 -188.163222) (xy 16.157021 -188.155466)
			(xy 16.104726 -188.140111) (xy 16.055149 -188.117469) (xy 16.009299 -188.088003) (xy 15.968108 -188.052312)
			(xy 15.932417 -188.011121) (xy 15.902951 -187.965271) (xy 15.880309 -187.915694) (xy 15.864954 -187.863399)
			(xy 15.857198 -187.809451) (xy 15.856712 -187.7822) (xy 15.857078 -187.75759) (xy 15.863373 -187.708776)
			(xy 15.875897 -187.661177) (xy 15.894442 -187.615585) (xy 15.906242 -187.593986) (xy 15.913232 -187.58051)
			(xy 15.919775 -187.550883) (xy 15.917332 -187.52064) (xy 15.906119 -187.492447) (xy 15.887124 -187.468788)
			(xy 15.86202 -187.451747) (xy 15.83302 -187.442826) (xy 15.81785 -187.442348) (xy 15.588488 -187.442348)
			(xy 15.57364 -187.442858) (xy 15.545194 -187.451389) (xy 15.520396 -187.467728) (xy 15.501335 -187.4905)
			(xy 15.489615 -187.517787) (xy 15.486223 -187.547289) (xy 15.488412 -187.561982) (xy 15.491254 -187.578793)
			(xy 15.494304 -187.612752) (xy 15.494508 -187.6298) (xy 15.494022 -187.657051) (xy 15.486266 -187.710999)
			(xy 15.470911 -187.763294) (xy 15.448269 -187.812871) (xy 15.418803 -187.858721) (xy 15.383112 -187.899912)
			(xy 15.341921 -187.935603) (xy 15.296071 -187.965069) (xy 15.246494 -187.987711) (xy 15.194199 -188.003066)
			(xy 15.140251 -188.010822) (xy 15.085749 -188.010822) (xy 15.031801 -188.003066) (xy 14.979506 -187.987711)
			(xy 14.929929 -187.965069) (xy 14.884079 -187.935603) (xy 14.842888 -187.899912) (xy 14.807197 -187.858721)
			(xy 14.777731 -187.812871) (xy 14.755089 -187.763294) (xy 14.739734 -187.710999) (xy 14.731978 -187.657051)
			(xy 14.731492 -187.6298) (xy 14.731674 -187.612751) (xy 14.734728 -187.57879) (xy 14.737588 -187.561982)
			(xy 14.739728 -187.547274) (xy 14.736383 -187.517755) (xy 14.724688 -187.490447) (xy 14.705632 -187.467656)
			(xy 14.680826 -187.451309) (xy 14.652366 -187.442789) (xy 14.637512 -187.442348) (xy 9.04494 -187.442348)
			(xy 8.46328 -188.024008) (xy 8.46328 -188.277246) (xy 21.112224 -188.277246) (xy 21.116295 -188.221624)
			(xy 21.128421 -188.167187) (xy 21.148344 -188.115096) (xy 21.17564 -188.066461) (xy 21.209726 -188.022318)
			(xy 21.249875 -187.983609) (xy 21.295233 -187.951158) (xy 21.344833 -187.925657) (xy 21.397617 -187.90765)
			(xy 21.45246 -187.89752) (xy 21.508194 -187.895483) (xy 21.563631 -187.901583) (xy 21.617588 -187.915689)
			(xy 21.668917 -187.937501) (xy 21.716523 -187.966555) (xy 21.759391 -188.00223) (xy 21.796608 -188.043767)
			(xy 21.827381 -188.09028) (xy 21.851053 -188.140777) (xy 21.867121 -188.194184) (xy 21.875241 -188.24936)
			(xy 21.87575 -188.277246) (xy 21.875241 -188.305132) (xy 21.867121 -188.360308) (xy 21.851053 -188.413715)
			(xy 21.827381 -188.464212) (xy 21.796608 -188.510725) (xy 21.759391 -188.552262) (xy 21.716523 -188.587937)
			(xy 21.668917 -188.616991) (xy 21.617588 -188.638803) (xy 21.563631 -188.652909) (xy 21.508194 -188.659009)
			(xy 21.45246 -188.656972) (xy 21.397617 -188.646842) (xy 21.344833 -188.628835) (xy 21.295233 -188.603334)
			(xy 21.249875 -188.570883) (xy 21.209726 -188.532174) (xy 21.17564 -188.488031) (xy 21.148344 -188.439396)
			(xy 21.128421 -188.387305) (xy 21.116295 -188.332868) (xy 21.112224 -188.277246) (xy 8.46328 -188.277246)
			(xy 8.46328 -191.663828) (xy 8.499856 -191.700404) (xy 18.352768 -191.700404) (xy 18.356839 -191.644782)
			(xy 18.368965 -191.590345) (xy 18.388888 -191.538254) (xy 18.416184 -191.489619) (xy 18.45027 -191.445476)
			(xy 18.490419 -191.406767) (xy 18.535777 -191.374316) (xy 18.585377 -191.348815) (xy 18.638161 -191.330808)
			(xy 18.693004 -191.320678) (xy 18.748738 -191.318641) (xy 18.804175 -191.324741) (xy 18.858132 -191.338847)
			(xy 18.909461 -191.360659) (xy 18.957067 -191.389713) (xy 18.999935 -191.425388) (xy 19.037152 -191.466925)
			(xy 19.067925 -191.513438) (xy 19.091597 -191.563935) (xy 19.107665 -191.617342) (xy 19.115785 -191.672518)
			(xy 19.116294 -191.700404) (xy 19.115785 -191.72829) (xy 19.107665 -191.783466) (xy 19.091597 -191.836873)
			(xy 19.067925 -191.88737) (xy 19.037152 -191.933883) (xy 18.999935 -191.97542) (xy 18.957067 -192.011095)
			(xy 18.909461 -192.040149) (xy 18.858132 -192.061961) (xy 18.804175 -192.076067) (xy 18.748738 -192.082167)
			(xy 18.693004 -192.08013) (xy 18.638161 -192.07) (xy 18.585377 -192.051993) (xy 18.535777 -192.026492)
			(xy 18.490419 -191.994041) (xy 18.45027 -191.955332) (xy 18.416184 -191.911189) (xy 18.388888 -191.862554)
			(xy 18.368965 -191.810463) (xy 18.356839 -191.756026) (xy 18.352768 -191.700404) (xy 8.499856 -191.700404)
			(xy 8.686546 -191.887094) (xy 8.711429 -191.912644) (xy 8.755911 -191.968395) (xy 8.793869 -192.028779)
			(xy 8.824825 -192.093033) (xy 8.848388 -192.160351) (xy 8.864263 -192.229885) (xy 8.87225 -192.300759)
			(xy 8.872728 -192.33642) (xy 8.872728 -192.848484) (xy 18.352768 -192.848484) (xy 18.356839 -192.792862)
			(xy 18.368965 -192.738425) (xy 18.388888 -192.686334) (xy 18.416184 -192.637699) (xy 18.45027 -192.593556)
			(xy 18.490419 -192.554847) (xy 18.535777 -192.522396) (xy 18.585377 -192.496895) (xy 18.638161 -192.478888)
			(xy 18.693004 -192.468758) (xy 18.748738 -192.466721) (xy 18.804175 -192.472821) (xy 18.858132 -192.486927)
			(xy 18.909461 -192.508739) (xy 18.957067 -192.537793) (xy 18.999935 -192.573468) (xy 19.037152 -192.615005)
			(xy 19.067925 -192.661518) (xy 19.091597 -192.712015) (xy 19.107665 -192.765422) (xy 19.115785 -192.820598)
			(xy 19.116294 -192.848484) (xy 20.437346 -192.848484) (xy 20.441417 -192.792862) (xy 20.453543 -192.738425)
			(xy 20.473466 -192.686334) (xy 20.500762 -192.637699) (xy 20.534848 -192.593556) (xy 20.574997 -192.554847)
			(xy 20.620355 -192.522396) (xy 20.669955 -192.496895) (xy 20.722739 -192.478888) (xy 20.777582 -192.468758)
			(xy 20.833316 -192.466721) (xy 20.888753 -192.472821) (xy 20.94271 -192.486927) (xy 20.994039 -192.508739)
			(xy 21.041645 -192.537793) (xy 21.084513 -192.573468) (xy 21.12173 -192.615005) (xy 21.152503 -192.661518)
			(xy 21.176175 -192.712015) (xy 21.192243 -192.765422) (xy 21.200363 -192.820598) (xy 21.200872 -192.848484)
			(xy 21.200738 -192.85585) (xy 21.43074 -192.85585) (xy 21.434811 -192.800228) (xy 21.446937 -192.745791)
			(xy 21.46686 -192.6937) (xy 21.494156 -192.645065) (xy 21.528242 -192.600922) (xy 21.568391 -192.562213)
			(xy 21.613749 -192.529762) (xy 21.663349 -192.504261) (xy 21.716133 -192.486254) (xy 21.770976 -192.476124)
			(xy 21.82671 -192.474087) (xy 21.882147 -192.480187) (xy 21.936104 -192.494293) (xy 21.987433 -192.516105)
			(xy 22.035039 -192.545159) (xy 22.077907 -192.580834) (xy 22.115124 -192.622371) (xy 22.145897 -192.668884)
			(xy 22.169569 -192.719381) (xy 22.179601 -192.752726) (xy 27.69184 -192.752726) (xy 27.695911 -192.697104)
			(xy 27.708037 -192.642667) (xy 27.72796 -192.590576) (xy 27.755256 -192.541941) (xy 27.789342 -192.497798)
			(xy 27.829491 -192.459089) (xy 27.874849 -192.426638) (xy 27.924449 -192.401137) (xy 27.977233 -192.38313)
			(xy 28.032076 -192.373) (xy 28.08781 -192.370963) (xy 28.143247 -192.377063) (xy 28.197204 -192.391169)
			(xy 28.248533 -192.412981) (xy 28.296139 -192.442035) (xy 28.339007 -192.47771) (xy 28.376224 -192.519247)
			(xy 28.379452 -192.524126) (xy 37.94074 -192.524126) (xy 37.944811 -192.468504) (xy 37.956937 -192.414067)
			(xy 37.97686 -192.361976) (xy 38.004156 -192.313341) (xy 38.038242 -192.269198) (xy 38.078391 -192.230489)
			(xy 38.123749 -192.198038) (xy 38.173349 -192.172537) (xy 38.226133 -192.15453) (xy 38.280976 -192.1444)
			(xy 38.33671 -192.142363) (xy 38.392147 -192.148463) (xy 38.446104 -192.162569) (xy 38.497433 -192.184381)
			(xy 38.545039 -192.213435) (xy 38.587907 -192.24911) (xy 38.625124 -192.290647) (xy 38.64438 -192.319752)
			(xy 46.821056 -192.319752) (xy 46.821056 -192.265248) (xy 46.828813 -192.211298) (xy 46.844168 -192.159001)
			(xy 46.86681 -192.109421) (xy 46.896277 -192.063569) (xy 46.931969 -192.022376) (xy 46.973161 -191.986683)
			(xy 47.019013 -191.957215) (xy 47.068591 -191.934572) (xy 47.120888 -191.919215) (xy 47.174838 -191.911457)
			(xy 47.20209 -191.91097) (xy 47.231082 -191.911497) (xy 47.288399 -191.920264) (xy 47.343727 -191.937611)
			(xy 47.39579 -191.963139) (xy 47.443384 -191.996258) (xy 47.485413 -192.036204) (xy 47.503588 -192.058798)
			(xy 47.5126 -192.069773) (xy 47.535503 -192.086551) (xy 47.56214 -192.096373) (xy 47.590452 -192.09848)
			(xy 47.61825 -192.092709) (xy 47.643384 -192.079506) (xy 47.663911 -192.059893) (xy 47.671482 -192.047876)
			(xy 47.686278 -192.023698) (xy 47.721914 -191.979617) (xy 47.76368 -191.941294) (xy 47.810656 -191.909572)
			(xy 47.861808 -191.885149) (xy 47.91601 -191.868563) (xy 47.97207 -191.860179) (xy 48.000412 -191.859662)
			(xy 48.029222 -191.860183) (xy 48.086184 -191.868861) (xy 48.141194 -191.886003) (xy 48.193003 -191.91122)
			(xy 48.240432 -191.943939) (xy 48.261778 -191.963294) (xy 48.273444 -191.973537) (xy 48.30135 -191.987104)
			(xy 48.332043 -191.991657) (xy 48.362685 -191.986777) (xy 48.390445 -191.972915) (xy 48.401986 -191.962532)
			(xy 48.423474 -191.94261) (xy 48.471368 -191.908856) (xy 48.523857 -191.882818) (xy 48.579709 -191.865107)
			(xy 48.637612 -191.856139) (xy 48.666908 -191.855598) (xy 48.694159 -191.856072) (xy 48.748107 -191.86383)
			(xy 48.800402 -191.879186) (xy 48.849979 -191.901828) (xy 48.895829 -191.931295) (xy 48.937019 -191.966987)
			(xy 48.97271 -192.008178) (xy 49.002176 -192.054028) (xy 49.024817 -192.103606) (xy 49.040172 -192.155901)
			(xy 49.047928 -192.209849) (xy 49.047928 -192.237106) (xy 49.30089 -192.237106) (xy 49.304961 -192.181484)
			(xy 49.317087 -192.127047) (xy 49.33701 -192.074956) (xy 49.364306 -192.026321) (xy 49.398392 -191.982178)
			(xy 49.438541 -191.943469) (xy 49.483899 -191.911018) (xy 49.533499 -191.885517) (xy 49.586283 -191.86751)
			(xy 49.641126 -191.85738) (xy 49.69686 -191.855343) (xy 49.752297 -191.861443) (xy 49.806254 -191.875549)
			(xy 49.857583 -191.897361) (xy 49.905189 -191.926415) (xy 49.948057 -191.96209) (xy 49.985274 -192.003627)
			(xy 50.016047 -192.05014) (xy 50.039719 -192.100637) (xy 50.055787 -192.154044) (xy 50.063907 -192.20922)
			(xy 50.064416 -192.237106) (xy 50.064342 -192.24117) (xy 51.33289 -192.24117) (xy 51.336961 -192.185548)
			(xy 51.349087 -192.131111) (xy 51.36901 -192.07902) (xy 51.396306 -192.030385) (xy 51.430392 -191.986242)
			(xy 51.470541 -191.947533) (xy 51.515899 -191.915082) (xy 51.565499 -191.889581) (xy 51.618283 -191.871574)
			(xy 51.673126 -191.861444) (xy 51.72886 -191.859407) (xy 51.784297 -191.865507) (xy 51.838254 -191.879613)
			(xy 51.889583 -191.901425) (xy 51.937189 -191.930479) (xy 51.980057 -191.966154) (xy 52.017274 -192.007691)
			(xy 52.048047 -192.054204) (xy 52.071719 -192.104701) (xy 52.087787 -192.158108) (xy 52.095907 -192.213284)
			(xy 52.096416 -192.24117) (xy 53.36489 -192.24117) (xy 53.368961 -192.185548) (xy 53.381087 -192.131111)
			(xy 53.40101 -192.07902) (xy 53.428306 -192.030385) (xy 53.462392 -191.986242) (xy 53.502541 -191.947533)
			(xy 53.547899 -191.915082) (xy 53.597499 -191.889581) (xy 53.650283 -191.871574) (xy 53.705126 -191.861444)
			(xy 53.76086 -191.859407) (xy 53.816297 -191.865507) (xy 53.870254 -191.879613) (xy 53.921583 -191.901425)
			(xy 53.969189 -191.930479) (xy 54.012057 -191.966154) (xy 54.049274 -192.007691) (xy 54.080047 -192.054204)
			(xy 54.103719 -192.104701) (xy 54.119787 -192.158108) (xy 54.127907 -192.213284) (xy 54.128416 -192.24117)
			(xy 54.127907 -192.269056) (xy 54.127628 -192.270949) (xy 54.696888 -192.270949) (xy 54.696888 -192.216451)
			(xy 54.704644 -192.162508) (xy 54.719997 -192.110217) (xy 54.742635 -192.060643) (xy 54.772097 -192.014795)
			(xy 54.807784 -191.973607) (xy 54.84897 -191.937917) (xy 54.894815 -191.90845) (xy 54.944387 -191.885808)
			(xy 54.996676 -191.87045) (xy 55.050619 -191.86269) (xy 55.077868 -191.862202) (xy 55.104824 -191.862711)
			(xy 55.158199 -191.870292) (xy 55.209977 -191.885306) (xy 55.259128 -191.907455) (xy 55.304674 -191.9363)
			(xy 55.345708 -191.971265) (xy 55.381416 -192.011655) (xy 55.396638 -192.033906) (xy 55.404978 -192.045741)
			(xy 55.427026 -192.064492) (xy 55.453448 -192.076304) (xy 55.482123 -192.08023) (xy 55.510748 -192.075955)
			(xy 55.537024 -192.063821) (xy 55.558841 -192.044803) (xy 55.567072 -192.03289) (xy 55.58216 -192.010121)
			(xy 55.617836 -191.96876) (xy 55.659048 -191.932912) (xy 55.704953 -191.903311) (xy 55.754612 -191.880563)
			(xy 55.807009 -191.865133) (xy 55.861071 -191.857337) (xy 55.888382 -191.856868) (xy 55.915634 -191.857378)
			(xy 55.969583 -191.865132) (xy 56.02188 -191.880486) (xy 56.021889 -191.88049) (xy 61.97168 -191.88049)
			(xy 61.975751 -191.824868) (xy 61.987877 -191.770431) (xy 62.0078 -191.71834) (xy 62.035096 -191.669705)
			(xy 62.069182 -191.625562) (xy 62.109331 -191.586853) (xy 62.154689 -191.554402) (xy 62.204289 -191.528901)
			(xy 62.257073 -191.510894) (xy 62.311916 -191.500764) (xy 62.36765 -191.498727) (xy 62.423087 -191.504827)
			(xy 62.477044 -191.518933) (xy 62.528373 -191.540745) (xy 62.575979 -191.569799) (xy 62.618847 -191.605474)
			(xy 62.656064 -191.647011) (xy 62.686837 -191.693524) (xy 62.710509 -191.744021) (xy 62.726577 -191.797428)
			(xy 62.734697 -191.852604) (xy 62.734789 -191.85763) (xy 63.89446 -191.85763) (xy 63.898531 -191.802008)
			(xy 63.910657 -191.747571) (xy 63.93058 -191.69548) (xy 63.957876 -191.646845) (xy 63.991962 -191.602702)
			(xy 64.032111 -191.563993) (xy 64.077469 -191.531542) (xy 64.127069 -191.506041) (xy 64.179853 -191.488034)
			(xy 64.234696 -191.477904) (xy 64.29043 -191.475867) (xy 64.345867 -191.481967) (xy 64.399824 -191.496073)
			(xy 64.451153 -191.517885) (xy 64.498759 -191.546939) (xy 64.541627 -191.582614) (xy 64.578844 -191.624151)
			(xy 64.609617 -191.670664) (xy 64.633289 -191.721161) (xy 64.649357 -191.774568) (xy 64.657477 -191.829744)
			(xy 64.657986 -191.85763) (xy 64.657477 -191.885516) (xy 64.649357 -191.940692) (xy 64.633289 -191.994099)
			(xy 64.609617 -192.044596) (xy 64.578844 -192.091109) (xy 64.541627 -192.132646) (xy 64.498759 -192.168321)
			(xy 64.451153 -192.197375) (xy 64.399824 -192.219187) (xy 64.345867 -192.233293) (xy 64.29043 -192.239393)
			(xy 64.234696 -192.237356) (xy 64.179853 -192.227226) (xy 64.127069 -192.209219) (xy 64.077469 -192.183718)
			(xy 64.032111 -192.151267) (xy 63.991962 -192.112558) (xy 63.957876 -192.068415) (xy 63.93058 -192.01978)
			(xy 63.910657 -191.967689) (xy 63.898531 -191.913252) (xy 63.89446 -191.85763) (xy 62.734789 -191.85763)
			(xy 62.735206 -191.88049) (xy 62.734697 -191.908376) (xy 62.726577 -191.963552) (xy 62.710509 -192.016959)
			(xy 62.686837 -192.067456) (xy 62.656064 -192.113969) (xy 62.618847 -192.155506) (xy 62.575979 -192.191181)
			(xy 62.528373 -192.220235) (xy 62.477044 -192.242047) (xy 62.423087 -192.256153) (xy 62.36765 -192.262253)
			(xy 62.311916 -192.260216) (xy 62.257073 -192.250086) (xy 62.204289 -192.232079) (xy 62.154689 -192.206578)
			(xy 62.109331 -192.174127) (xy 62.069182 -192.135418) (xy 62.035096 -192.091275) (xy 62.0078 -192.04264)
			(xy 61.987877 -191.990549) (xy 61.975751 -191.936112) (xy 61.97168 -191.88049) (xy 56.021889 -191.88049)
			(xy 56.071459 -191.903126) (xy 56.117312 -191.932592) (xy 56.158504 -191.968283) (xy 56.194198 -192.009474)
			(xy 56.223665 -192.055325) (xy 56.246308 -192.104903) (xy 56.261664 -192.157199) (xy 56.269421 -192.211148)
			(xy 56.269421 -192.265652) (xy 56.261664 -192.319601) (xy 56.246308 -192.371897) (xy 56.223665 -192.421475)
			(xy 56.194198 -192.467326) (xy 56.177333 -192.486788) (xy 65.533522 -192.486788) (xy 65.537593 -192.431166)
			(xy 65.549719 -192.376729) (xy 65.569642 -192.324638) (xy 65.596938 -192.276003) (xy 65.631024 -192.23186)
			(xy 65.671173 -192.193151) (xy 65.716531 -192.1607) (xy 65.766131 -192.135199) (xy 65.818915 -192.117192)
			(xy 65.873758 -192.107062) (xy 65.929492 -192.105025) (xy 65.984929 -192.111125) (xy 66.038886 -192.125231)
			(xy 66.090215 -192.147043) (xy 66.137821 -192.176097) (xy 66.180689 -192.211772) (xy 66.217906 -192.253309)
			(xy 66.248679 -192.299822) (xy 66.272351 -192.350319) (xy 66.288419 -192.403726) (xy 66.296539 -192.458902)
			(xy 66.297048 -192.486788) (xy 66.296539 -192.514674) (xy 66.288419 -192.56985) (xy 66.272351 -192.623257)
			(xy 66.248679 -192.673754) (xy 66.217906 -192.720267) (xy 66.180689 -192.761804) (xy 66.137821 -192.797479)
			(xy 66.090215 -192.826533) (xy 66.038886 -192.848345) (xy 65.984929 -192.862451) (xy 65.929492 -192.868551)
			(xy 65.873758 -192.866514) (xy 65.818915 -192.856384) (xy 65.766131 -192.838377) (xy 65.716531 -192.812876)
			(xy 65.671173 -192.780425) (xy 65.631024 -192.741716) (xy 65.596938 -192.697573) (xy 65.569642 -192.648938)
			(xy 65.549719 -192.596847) (xy 65.537593 -192.54241) (xy 65.533522 -192.486788) (xy 56.177333 -192.486788)
			(xy 56.158504 -192.508517) (xy 56.117312 -192.544208) (xy 56.071459 -192.573674) (xy 56.02188 -192.596314)
			(xy 55.969583 -192.611668) (xy 55.915634 -192.619422) (xy 55.888382 -192.619884) (xy 55.861425 -192.619419)
			(xy 55.808047 -192.611832) (xy 55.756268 -192.59681) (xy 55.707117 -192.574653) (xy 55.661571 -192.545802)
			(xy 55.620538 -192.51083) (xy 55.584833 -192.470434) (xy 55.569612 -192.44818) (xy 55.561208 -192.436395)
			(xy 55.539174 -192.417649) (xy 55.512766 -192.405836) (xy 55.484105 -192.401904) (xy 55.455492 -192.40617)
			(xy 55.429224 -192.41829) (xy 55.407409 -192.437291) (xy 55.399178 -192.449196) (xy 55.384119 -192.471985)
			(xy 55.348439 -192.513347) (xy 55.307222 -192.549194) (xy 55.261312 -192.578792) (xy 55.211648 -192.601537)
			(xy 55.159246 -192.616962) (xy 55.10518 -192.624752) (xy 55.077868 -192.625218) (xy 55.050619 -192.62471)
			(xy 54.996676 -192.61695) (xy 54.944387 -192.601592) (xy 54.894815 -192.57895) (xy 54.84897 -192.549483)
			(xy 54.807784 -192.513793) (xy 54.772097 -192.472605) (xy 54.742635 -192.426757) (xy 54.719997 -192.377183)
			(xy 54.704644 -192.324892) (xy 54.696888 -192.270949) (xy 54.127628 -192.270949) (xy 54.119787 -192.324232)
			(xy 54.103719 -192.377639) (xy 54.080047 -192.428136) (xy 54.049274 -192.474649) (xy 54.012057 -192.516186)
			(xy 53.969189 -192.551861) (xy 53.921583 -192.580915) (xy 53.870254 -192.602727) (xy 53.816297 -192.616833)
			(xy 53.76086 -192.622933) (xy 53.705126 -192.620896) (xy 53.650283 -192.610766) (xy 53.597499 -192.592759)
			(xy 53.547899 -192.567258) (xy 53.502541 -192.534807) (xy 53.462392 -192.496098) (xy 53.428306 -192.451955)
			(xy 53.40101 -192.40332) (xy 53.381087 -192.351229) (xy 53.368961 -192.296792) (xy 53.36489 -192.24117)
			(xy 52.096416 -192.24117) (xy 52.095907 -192.269056) (xy 52.087787 -192.324232) (xy 52.071719 -192.377639)
			(xy 52.048047 -192.428136) (xy 52.017274 -192.474649) (xy 51.980057 -192.516186) (xy 51.937189 -192.551861)
			(xy 51.889583 -192.580915) (xy 51.838254 -192.602727) (xy 51.784297 -192.616833) (xy 51.72886 -192.622933)
			(xy 51.673126 -192.620896) (xy 51.618283 -192.610766) (xy 51.565499 -192.592759) (xy 51.515899 -192.567258)
			(xy 51.470541 -192.534807) (xy 51.430392 -192.496098) (xy 51.396306 -192.451955) (xy 51.36901 -192.40332)
			(xy 51.349087 -192.351229) (xy 51.336961 -192.296792) (xy 51.33289 -192.24117) (xy 50.064342 -192.24117)
			(xy 50.063907 -192.264992) (xy 50.055787 -192.320168) (xy 50.039719 -192.373575) (xy 50.016047 -192.424072)
			(xy 49.985274 -192.470585) (xy 49.948057 -192.512122) (xy 49.905189 -192.547797) (xy 49.857583 -192.576851)
			(xy 49.806254 -192.598663) (xy 49.752297 -192.612769) (xy 49.69686 -192.618869) (xy 49.641126 -192.616832)
			(xy 49.586283 -192.606702) (xy 49.533499 -192.588695) (xy 49.483899 -192.563194) (xy 49.438541 -192.530743)
			(xy 49.398392 -192.492034) (xy 49.364306 -192.447891) (xy 49.33701 -192.399256) (xy 49.317087 -192.347165)
			(xy 49.304961 -192.292728) (xy 49.30089 -192.237106) (xy 49.047928 -192.237106) (xy 49.047928 -192.264351)
			(xy 49.040172 -192.318299) (xy 49.024817 -192.370594) (xy 49.002176 -192.420172) (xy 48.97271 -192.466022)
			(xy 48.937019 -192.507213) (xy 48.895829 -192.542905) (xy 48.849979 -192.572372) (xy 48.800402 -192.595014)
			(xy 48.748107 -192.61037) (xy 48.694159 -192.618128) (xy 48.666908 -192.618614) (xy 48.6381 -192.618061)
			(xy 48.58114 -192.609387) (xy 48.526131 -192.592251) (xy 48.474322 -192.567042) (xy 48.42689 -192.534333)
			(xy 48.405542 -192.514982) (xy 48.393863 -192.504752) (xy 48.365963 -192.491173) (xy 48.335272 -192.486612)
			(xy 48.304629 -192.491491) (xy 48.276872 -192.505357) (xy 48.265334 -192.515744) (xy 48.243892 -192.535717)
			(xy 48.195984 -192.569461) (xy 48.143483 -192.595488) (xy 48.087621 -192.613188) (xy 48.029711 -192.622143)
			(xy 48.000412 -192.622678) (xy 47.971419 -192.622169) (xy 47.9141 -192.613402) (xy 47.858771 -192.596052)
			(xy 47.806708 -192.570521) (xy 47.759114 -192.537398) (xy 47.717087 -192.497447) (xy 47.698914 -192.47485)
			(xy 47.689893 -192.463886) (xy 47.66699 -192.447117) (xy 47.640356 -192.437301) (xy 47.612049 -192.435195)
			(xy 47.584256 -192.440963) (xy 47.559124 -192.454158) (xy 47.538595 -192.47376) (xy 47.53102 -192.485772)
			(xy 47.51624 -192.50996) (xy 47.480599 -192.554038) (xy 47.43883 -192.592359) (xy 47.391851 -192.624079)
			(xy 47.340697 -192.6485) (xy 47.286493 -192.665085) (xy 47.230432 -192.673469) (xy 47.20209 -192.673986)
			(xy 47.174838 -192.673543) (xy 47.120888 -192.665785) (xy 47.068591 -192.650428) (xy 47.019013 -192.627785)
			(xy 46.973161 -192.598317) (xy 46.931969 -192.562624) (xy 46.896277 -192.521431) (xy 46.86681 -192.475579)
			(xy 46.844168 -192.425999) (xy 46.828813 -192.373702) (xy 46.821056 -192.319752) (xy 38.64438 -192.319752)
			(xy 38.655897 -192.33716) (xy 38.679569 -192.387657) (xy 38.695637 -192.441064) (xy 38.703757 -192.49624)
			(xy 38.704266 -192.524126) (xy 38.703757 -192.552012) (xy 38.695637 -192.607188) (xy 38.679569 -192.660595)
			(xy 38.655897 -192.711092) (xy 38.625124 -192.757605) (xy 38.587907 -192.799142) (xy 38.545039 -192.834817)
			(xy 38.497433 -192.863871) (xy 38.446104 -192.885683) (xy 38.392147 -192.899789) (xy 38.33671 -192.905889)
			(xy 38.280976 -192.903852) (xy 38.226133 -192.893722) (xy 38.173349 -192.875715) (xy 38.123749 -192.850214)
			(xy 38.078391 -192.817763) (xy 38.038242 -192.779054) (xy 38.004156 -192.734911) (xy 37.97686 -192.686276)
			(xy 37.956937 -192.634185) (xy 37.944811 -192.579748) (xy 37.94074 -192.524126) (xy 28.379452 -192.524126)
			(xy 28.406997 -192.56576) (xy 28.430669 -192.616257) (xy 28.446737 -192.669664) (xy 28.454857 -192.72484)
			(xy 28.455366 -192.752726) (xy 28.454857 -192.780612) (xy 28.446737 -192.835788) (xy 28.430669 -192.889195)
			(xy 28.406997 -192.939692) (xy 28.376224 -192.986205) (xy 28.339007 -193.027742) (xy 28.296139 -193.063417)
			(xy 28.248533 -193.092471) (xy 28.197204 -193.114283) (xy 28.143247 -193.128389) (xy 28.08781 -193.134489)
			(xy 28.032076 -193.132452) (xy 27.977233 -193.122322) (xy 27.924449 -193.104315) (xy 27.874849 -193.078814)
			(xy 27.829491 -193.046363) (xy 27.789342 -193.007654) (xy 27.755256 -192.963511) (xy 27.72796 -192.914876)
			(xy 27.708037 -192.862785) (xy 27.695911 -192.808348) (xy 27.69184 -192.752726) (xy 22.179601 -192.752726)
			(xy 22.185637 -192.772788) (xy 22.193757 -192.827964) (xy 22.194266 -192.85585) (xy 22.193757 -192.883736)
			(xy 22.185637 -192.938912) (xy 22.169569 -192.992319) (xy 22.145897 -193.042816) (xy 22.115124 -193.089329)
			(xy 22.077907 -193.130866) (xy 22.035039 -193.166541) (xy 21.987433 -193.195595) (xy 21.936104 -193.217407)
			(xy 21.882147 -193.231513) (xy 21.82671 -193.237613) (xy 21.770976 -193.235576) (xy 21.716133 -193.225446)
			(xy 21.663349 -193.207439) (xy 21.613749 -193.181938) (xy 21.568391 -193.149487) (xy 21.528242 -193.110778)
			(xy 21.494156 -193.066635) (xy 21.46686 -193.018) (xy 21.446937 -192.965909) (xy 21.434811 -192.911472)
			(xy 21.43074 -192.85585) (xy 21.200738 -192.85585) (xy 21.200363 -192.87637) (xy 21.192243 -192.931546)
			(xy 21.176175 -192.984953) (xy 21.152503 -193.03545) (xy 21.12173 -193.081963) (xy 21.084513 -193.1235)
			(xy 21.041645 -193.159175) (xy 20.994039 -193.188229) (xy 20.94271 -193.210041) (xy 20.888753 -193.224147)
			(xy 20.833316 -193.230247) (xy 20.777582 -193.22821) (xy 20.722739 -193.21808) (xy 20.669955 -193.200073)
			(xy 20.620355 -193.174572) (xy 20.574997 -193.142121) (xy 20.534848 -193.103412) (xy 20.500762 -193.059269)
			(xy 20.473466 -193.010634) (xy 20.453543 -192.958543) (xy 20.441417 -192.904106) (xy 20.437346 -192.848484)
			(xy 19.116294 -192.848484) (xy 19.115785 -192.87637) (xy 19.107665 -192.931546) (xy 19.091597 -192.984953)
			(xy 19.067925 -193.03545) (xy 19.037152 -193.081963) (xy 18.999935 -193.1235) (xy 18.957067 -193.159175)
			(xy 18.909461 -193.188229) (xy 18.858132 -193.210041) (xy 18.804175 -193.224147) (xy 18.748738 -193.230247)
			(xy 18.693004 -193.22821) (xy 18.638161 -193.21808) (xy 18.585377 -193.200073) (xy 18.535777 -193.174572)
			(xy 18.490419 -193.142121) (xy 18.45027 -193.103412) (xy 18.416184 -193.059269) (xy 18.388888 -193.010634)
			(xy 18.368965 -192.958543) (xy 18.356839 -192.904106) (xy 18.352768 -192.848484) (xy 8.872728 -192.848484)
			(xy 8.872728 -194.793341) (xy 14.198336 -194.793341) (xy 14.198336 -194.740043) (xy 14.206279 -194.687339)
			(xy 14.221989 -194.636409) (xy 14.245115 -194.588388) (xy 14.275139 -194.544351) (xy 14.311391 -194.50528)
			(xy 14.353062 -194.472049) (xy 14.39922 -194.4454) (xy 14.448834 -194.425928) (xy 14.500796 -194.414068)
			(xy 14.553946 -194.410085) (xy 14.607096 -194.414068) (xy 14.659058 -194.425928) (xy 14.708672 -194.4454)
			(xy 14.75483 -194.472049) (xy 14.763115 -194.478656) (xy 16.969992 -194.478656) (xy 16.974063 -194.423034)
			(xy 16.986189 -194.368597) (xy 17.006112 -194.316506) (xy 17.033408 -194.267871) (xy 17.067494 -194.223728)
			(xy 17.107643 -194.185019) (xy 17.153001 -194.152568) (xy 17.202601 -194.127067) (xy 17.255385 -194.10906)
			(xy 17.310228 -194.09893) (xy 17.365962 -194.096893) (xy 17.421399 -194.102993) (xy 17.475356 -194.117099)
			(xy 17.526685 -194.138911) (xy 17.574291 -194.167965) (xy 17.617159 -194.20364) (xy 17.654376 -194.245177)
			(xy 17.685149 -194.29169) (xy 17.708821 -194.342187) (xy 17.724889 -194.395594) (xy 17.733009 -194.45077)
			(xy 17.733518 -194.478656) (xy 17.733009 -194.506542) (xy 17.724889 -194.561718) (xy 17.708821 -194.615125)
			(xy 17.685149 -194.665622) (xy 17.654376 -194.712135) (xy 17.617159 -194.753672) (xy 17.574291 -194.789347)
			(xy 17.567747 -194.793341) (xy 21.742136 -194.793341) (xy 21.742136 -194.740043) (xy 21.750079 -194.687339)
			(xy 21.765789 -194.636409) (xy 21.788915 -194.588388) (xy 21.818939 -194.544351) (xy 21.855191 -194.50528)
			(xy 21.896862 -194.472049) (xy 21.94302 -194.4454) (xy 21.992634 -194.425928) (xy 22.044596 -194.414068)
			(xy 22.097746 -194.410085) (xy 22.150896 -194.414068) (xy 22.202858 -194.425928) (xy 22.252472 -194.4454)
			(xy 22.29863 -194.472049) (xy 22.340301 -194.50528) (xy 22.376553 -194.544351) (xy 22.406577 -194.588388)
			(xy 22.429703 -194.636409) (xy 22.445413 -194.687339) (xy 22.453356 -194.740043) (xy 22.453854 -194.766692)
			(xy 22.453465 -194.787499) (xy 29.252408 -194.787499) (xy 29.252408 -194.734201) (xy 29.260351 -194.681497)
			(xy 29.276061 -194.630567) (xy 29.299187 -194.582546) (xy 29.329211 -194.538509) (xy 29.365463 -194.499438)
			(xy 29.407134 -194.466207) (xy 29.453292 -194.439558) (xy 29.502906 -194.420086) (xy 29.554868 -194.408226)
			(xy 29.608018 -194.404243) (xy 29.661168 -194.408226) (xy 29.71313 -194.420086) (xy 29.762744 -194.439558)
			(xy 29.808902 -194.466207) (xy 29.850573 -194.499438) (xy 29.886825 -194.538509) (xy 29.916849 -194.582546)
			(xy 29.939975 -194.630567) (xy 29.955685 -194.681497) (xy 29.963628 -194.734201) (xy 29.964126 -194.76085)
			(xy 29.963628 -194.787499) (xy 36.821608 -194.787499) (xy 36.821608 -194.734201) (xy 36.829551 -194.681497)
			(xy 36.845261 -194.630567) (xy 36.868387 -194.582546) (xy 36.898411 -194.538509) (xy 36.934663 -194.499438)
			(xy 36.976334 -194.466207) (xy 37.022492 -194.439558) (xy 37.072106 -194.420086) (xy 37.124068 -194.408226)
			(xy 37.177218 -194.404243) (xy 37.230368 -194.408226) (xy 37.28233 -194.420086) (xy 37.331944 -194.439558)
			(xy 37.378102 -194.466207) (xy 37.419773 -194.499438) (xy 37.456025 -194.538509) (xy 37.486049 -194.582546)
			(xy 37.509175 -194.630567) (xy 37.524885 -194.681497) (xy 37.532828 -194.734201) (xy 37.533326 -194.76085)
			(xy 37.532828 -194.787499) (xy 37.531948 -194.793341) (xy 44.373536 -194.793341) (xy 44.373536 -194.740043)
			(xy 44.381479 -194.687339) (xy 44.397189 -194.636409) (xy 44.420315 -194.588388) (xy 44.450339 -194.544351)
			(xy 44.486591 -194.50528) (xy 44.528262 -194.472049) (xy 44.57442 -194.4454) (xy 44.624034 -194.425928)
			(xy 44.675996 -194.414068) (xy 44.729146 -194.410085) (xy 44.782296 -194.414068) (xy 44.834258 -194.425928)
			(xy 44.883872 -194.4454) (xy 44.93003 -194.472049) (xy 44.971701 -194.50528) (xy 45.007953 -194.544351)
			(xy 45.037977 -194.588388) (xy 45.061103 -194.636409) (xy 45.076813 -194.687339) (xy 45.084756 -194.740043)
			(xy 45.085254 -194.766692) (xy 45.084756 -194.793341) (xy 51.917336 -194.793341) (xy 51.917336 -194.740043)
			(xy 51.925279 -194.687339) (xy 51.940989 -194.636409) (xy 51.964115 -194.588388) (xy 51.994139 -194.544351)
			(xy 52.030391 -194.50528) (xy 52.072062 -194.472049) (xy 52.11822 -194.4454) (xy 52.167834 -194.425928)
			(xy 52.219796 -194.414068) (xy 52.272946 -194.410085) (xy 52.326096 -194.414068) (xy 52.378058 -194.425928)
			(xy 52.427672 -194.4454) (xy 52.47383 -194.472049) (xy 52.515501 -194.50528) (xy 52.551753 -194.544351)
			(xy 52.581777 -194.588388) (xy 52.604903 -194.636409) (xy 52.620613 -194.687339) (xy 52.628556 -194.740043)
			(xy 52.629054 -194.766692) (xy 52.628556 -194.793341) (xy 59.461136 -194.793341) (xy 59.461136 -194.740043)
			(xy 59.469079 -194.687339) (xy 59.484789 -194.636409) (xy 59.507915 -194.588388) (xy 59.537939 -194.544351)
			(xy 59.574191 -194.50528) (xy 59.615862 -194.472049) (xy 59.66202 -194.4454) (xy 59.711634 -194.425928)
			(xy 59.763596 -194.414068) (xy 59.816746 -194.410085) (xy 59.869896 -194.414068) (xy 59.921858 -194.425928)
			(xy 59.971472 -194.4454) (xy 60.01763 -194.472049) (xy 60.059301 -194.50528) (xy 60.095553 -194.544351)
			(xy 60.125577 -194.588388) (xy 60.148703 -194.636409) (xy 60.164413 -194.687339) (xy 60.172356 -194.740043)
			(xy 60.172854 -194.766692) (xy 60.172356 -194.793341) (xy 60.164413 -194.846045) (xy 60.148703 -194.896975)
			(xy 60.125577 -194.944996) (xy 60.095553 -194.989033) (xy 60.059301 -195.028104) (xy 60.01763 -195.061335)
			(xy 59.971472 -195.087984) (xy 59.921858 -195.107456) (xy 59.869896 -195.119316) (xy 59.816746 -195.1233)
			(xy 59.763596 -195.119316) (xy 59.711634 -195.107456) (xy 59.66202 -195.087984) (xy 59.615862 -195.061335)
			(xy 59.574191 -195.028104) (xy 59.537939 -194.989033) (xy 59.507915 -194.944996) (xy 59.484789 -194.896975)
			(xy 59.469079 -194.846045) (xy 59.461136 -194.793341) (xy 52.628556 -194.793341) (xy 52.620613 -194.846045)
			(xy 52.604903 -194.896975) (xy 52.581777 -194.944996) (xy 52.551753 -194.989033) (xy 52.515501 -195.028104)
			(xy 52.47383 -195.061335) (xy 52.427672 -195.087984) (xy 52.378058 -195.107456) (xy 52.326096 -195.119316)
			(xy 52.272946 -195.1233) (xy 52.219796 -195.119316) (xy 52.167834 -195.107456) (xy 52.11822 -195.087984)
			(xy 52.072062 -195.061335) (xy 52.030391 -195.028104) (xy 51.994139 -194.989033) (xy 51.964115 -194.944996)
			(xy 51.940989 -194.896975) (xy 51.925279 -194.846045) (xy 51.917336 -194.793341) (xy 45.084756 -194.793341)
			(xy 45.076813 -194.846045) (xy 45.061103 -194.896975) (xy 45.037977 -194.944996) (xy 45.007953 -194.989033)
			(xy 44.971701 -195.028104) (xy 44.93003 -195.061335) (xy 44.883872 -195.087984) (xy 44.834258 -195.107456)
			(xy 44.782296 -195.119316) (xy 44.729146 -195.1233) (xy 44.675996 -195.119316) (xy 44.624034 -195.107456)
			(xy 44.57442 -195.087984) (xy 44.528262 -195.061335) (xy 44.486591 -195.028104) (xy 44.450339 -194.989033)
			(xy 44.420315 -194.944996) (xy 44.397189 -194.896975) (xy 44.381479 -194.846045) (xy 44.373536 -194.793341)
			(xy 37.531948 -194.793341) (xy 37.524885 -194.840203) (xy 37.509175 -194.891133) (xy 37.486049 -194.939154)
			(xy 37.456025 -194.983191) (xy 37.419773 -195.022262) (xy 37.378102 -195.055493) (xy 37.331944 -195.082142)
			(xy 37.28233 -195.101614) (xy 37.230368 -195.113474) (xy 37.177218 -195.117458) (xy 37.124068 -195.113474)
			(xy 37.072106 -195.101614) (xy 37.022492 -195.082142) (xy 36.976334 -195.055493) (xy 36.934663 -195.022262)
			(xy 36.898411 -194.983191) (xy 36.868387 -194.939154) (xy 36.845261 -194.891133) (xy 36.829551 -194.840203)
			(xy 36.821608 -194.787499) (xy 29.963628 -194.787499) (xy 29.955685 -194.840203) (xy 29.939975 -194.891133)
			(xy 29.916849 -194.939154) (xy 29.886825 -194.983191) (xy 29.850573 -195.022262) (xy 29.808902 -195.055493)
			(xy 29.762744 -195.082142) (xy 29.71313 -195.101614) (xy 29.661168 -195.113474) (xy 29.608018 -195.117458)
			(xy 29.554868 -195.113474) (xy 29.502906 -195.101614) (xy 29.453292 -195.082142) (xy 29.407134 -195.055493)
			(xy 29.365463 -195.022262) (xy 29.329211 -194.983191) (xy 29.299187 -194.939154) (xy 29.276061 -194.891133)
			(xy 29.260351 -194.840203) (xy 29.252408 -194.787499) (xy 22.453465 -194.787499) (xy 22.453356 -194.793341)
			(xy 22.445413 -194.846045) (xy 22.429703 -194.896975) (xy 22.406577 -194.944996) (xy 22.376553 -194.989033)
			(xy 22.340301 -195.028104) (xy 22.29863 -195.061335) (xy 22.252472 -195.087984) (xy 22.202858 -195.107456)
			(xy 22.150896 -195.119316) (xy 22.097746 -195.1233) (xy 22.044596 -195.119316) (xy 21.992634 -195.107456)
			(xy 21.94302 -195.087984) (xy 21.896862 -195.061335) (xy 21.855191 -195.028104) (xy 21.818939 -194.989033)
			(xy 21.788915 -194.944996) (xy 21.765789 -194.896975) (xy 21.750079 -194.846045) (xy 21.742136 -194.793341)
			(xy 17.567747 -194.793341) (xy 17.526685 -194.818401) (xy 17.475356 -194.840213) (xy 17.421399 -194.854319)
			(xy 17.365962 -194.860419) (xy 17.310228 -194.858382) (xy 17.255385 -194.848252) (xy 17.202601 -194.830245)
			(xy 17.153001 -194.804744) (xy 17.107643 -194.772293) (xy 17.067494 -194.733584) (xy 17.033408 -194.689441)
			(xy 17.006112 -194.640806) (xy 16.986189 -194.588715) (xy 16.974063 -194.534278) (xy 16.969992 -194.478656)
			(xy 14.763115 -194.478656) (xy 14.796501 -194.50528) (xy 14.832753 -194.544351) (xy 14.862777 -194.588388)
			(xy 14.885903 -194.636409) (xy 14.901613 -194.687339) (xy 14.909556 -194.740043) (xy 14.910054 -194.766692)
			(xy 14.909556 -194.793341) (xy 14.901613 -194.846045) (xy 14.885903 -194.896975) (xy 14.862777 -194.944996)
			(xy 14.832753 -194.989033) (xy 14.796501 -195.028104) (xy 14.75483 -195.061335) (xy 14.708672 -195.087984)
			(xy 14.659058 -195.107456) (xy 14.607096 -195.119316) (xy 14.553946 -195.1233) (xy 14.500796 -195.119316)
			(xy 14.448834 -195.107456) (xy 14.39922 -195.087984) (xy 14.353062 -195.061335) (xy 14.311391 -195.028104)
			(xy 14.275139 -194.989033) (xy 14.245115 -194.944996) (xy 14.221989 -194.896975) (xy 14.206279 -194.846045)
			(xy 14.198336 -194.793341) (xy 8.872728 -194.793341) (xy 8.872728 -195.643225) (xy 20.533604 -195.643225)
			(xy 20.533604 -195.589927) (xy 20.541547 -195.537223) (xy 20.557257 -195.486293) (xy 20.580383 -195.438272)
			(xy 20.610407 -195.394235) (xy 20.646659 -195.355164) (xy 20.68833 -195.321933) (xy 20.734488 -195.295284)
			(xy 20.784102 -195.275812) (xy 20.836064 -195.263952) (xy 20.889214 -195.259969) (xy 20.942364 -195.263952)
			(xy 20.994326 -195.275812) (xy 21.04394 -195.295284) (xy 21.090098 -195.321933) (xy 21.131769 -195.355164)
			(xy 21.168021 -195.394235) (xy 21.198045 -195.438272) (xy 21.221171 -195.486293) (xy 21.236881 -195.537223)
			(xy 21.244824 -195.589927) (xy 21.245322 -195.616576) (xy 21.244824 -195.643225) (xy 35.621204 -195.643225)
			(xy 35.621204 -195.589927) (xy 35.629147 -195.537223) (xy 35.644857 -195.486293) (xy 35.667983 -195.438272)
			(xy 35.698007 -195.394235) (xy 35.734259 -195.355164) (xy 35.77593 -195.321933) (xy 35.822088 -195.295284)
			(xy 35.871702 -195.275812) (xy 35.923664 -195.263952) (xy 35.976814 -195.259969) (xy 36.029964 -195.263952)
			(xy 36.081926 -195.275812) (xy 36.13154 -195.295284) (xy 36.177698 -195.321933) (xy 36.219369 -195.355164)
			(xy 36.255621 -195.394235) (xy 36.285645 -195.438272) (xy 36.308771 -195.486293) (xy 36.324481 -195.537223)
			(xy 36.332424 -195.589927) (xy 36.332922 -195.616576) (xy 36.332424 -195.643225) (xy 50.708804 -195.643225)
			(xy 50.708804 -195.589927) (xy 50.716747 -195.537223) (xy 50.732457 -195.486293) (xy 50.755583 -195.438272)
			(xy 50.785607 -195.394235) (xy 50.821859 -195.355164) (xy 50.86353 -195.321933) (xy 50.909688 -195.295284)
			(xy 50.959302 -195.275812) (xy 51.011264 -195.263952) (xy 51.064414 -195.259969) (xy 51.117564 -195.263952)
			(xy 51.169526 -195.275812) (xy 51.21914 -195.295284) (xy 51.265298 -195.321933) (xy 51.306969 -195.355164)
			(xy 51.343221 -195.394235) (xy 51.373245 -195.438272) (xy 51.396371 -195.486293) (xy 51.412081 -195.537223)
			(xy 51.420024 -195.589927) (xy 51.420522 -195.616576) (xy 51.420024 -195.643225) (xy 51.412081 -195.695929)
			(xy 51.396371 -195.746859) (xy 51.373245 -195.79488) (xy 51.343221 -195.838917) (xy 51.306969 -195.877988)
			(xy 51.265298 -195.911219) (xy 51.21914 -195.937868) (xy 51.169526 -195.95734) (xy 51.117564 -195.9692)
			(xy 51.064414 -195.973184) (xy 51.011264 -195.9692) (xy 50.959302 -195.95734) (xy 50.909688 -195.937868)
			(xy 50.86353 -195.911219) (xy 50.821859 -195.877988) (xy 50.785607 -195.838917) (xy 50.755583 -195.79488)
			(xy 50.732457 -195.746859) (xy 50.716747 -195.695929) (xy 50.708804 -195.643225) (xy 36.332424 -195.643225)
			(xy 36.324481 -195.695929) (xy 36.308771 -195.746859) (xy 36.285645 -195.79488) (xy 36.255621 -195.838917)
			(xy 36.219369 -195.877988) (xy 36.177698 -195.911219) (xy 36.13154 -195.937868) (xy 36.081926 -195.95734)
			(xy 36.029964 -195.9692) (xy 35.976814 -195.973184) (xy 35.923664 -195.9692) (xy 35.871702 -195.95734)
			(xy 35.822088 -195.937868) (xy 35.77593 -195.911219) (xy 35.734259 -195.877988) (xy 35.698007 -195.838917)
			(xy 35.667983 -195.79488) (xy 35.644857 -195.746859) (xy 35.629147 -195.695929) (xy 35.621204 -195.643225)
			(xy 21.244824 -195.643225) (xy 21.236881 -195.695929) (xy 21.221171 -195.746859) (xy 21.198045 -195.79488)
			(xy 21.168021 -195.838917) (xy 21.131769 -195.877988) (xy 21.090098 -195.911219) (xy 21.04394 -195.937868)
			(xy 20.994326 -195.95734) (xy 20.942364 -195.9692) (xy 20.889214 -195.973184) (xy 20.836064 -195.9692)
			(xy 20.784102 -195.95734) (xy 20.734488 -195.937868) (xy 20.68833 -195.911219) (xy 20.646659 -195.877988)
			(xy 20.610407 -195.838917) (xy 20.580383 -195.79488) (xy 20.557257 -195.746859) (xy 20.541547 -195.695929)
			(xy 20.533604 -195.643225) (xy 8.872728 -195.643225) (xy 8.872728 -196.493363) (xy 16.433536 -196.493363)
			(xy 16.433536 -196.440065) (xy 16.441479 -196.387361) (xy 16.457189 -196.336431) (xy 16.480315 -196.28841)
			(xy 16.510339 -196.244373) (xy 16.546591 -196.205302) (xy 16.588262 -196.172071) (xy 16.63442 -196.145422)
			(xy 16.684034 -196.12595) (xy 16.735996 -196.11409) (xy 16.789146 -196.110107) (xy 16.842296 -196.11409)
			(xy 16.894258 -196.12595) (xy 16.943872 -196.145422) (xy 16.99003 -196.172071) (xy 17.031701 -196.205302)
			(xy 17.067953 -196.244373) (xy 17.097977 -196.28841) (xy 17.121103 -196.336431) (xy 17.136813 -196.387361)
			(xy 17.144756 -196.440065) (xy 17.145254 -196.466714) (xy 17.144756 -196.493363) (xy 31.521136 -196.493363)
			(xy 31.521136 -196.440065) (xy 31.529079 -196.387361) (xy 31.544789 -196.336431) (xy 31.567915 -196.28841)
			(xy 31.597939 -196.244373) (xy 31.634191 -196.205302) (xy 31.675862 -196.172071) (xy 31.72202 -196.145422)
			(xy 31.771634 -196.12595) (xy 31.823596 -196.11409) (xy 31.876746 -196.110107) (xy 31.929896 -196.11409)
			(xy 31.981858 -196.12595) (xy 32.031472 -196.145422) (xy 32.07763 -196.172071) (xy 32.119301 -196.205302)
			(xy 32.155553 -196.244373) (xy 32.185577 -196.28841) (xy 32.208703 -196.336431) (xy 32.224413 -196.387361)
			(xy 32.232356 -196.440065) (xy 32.232854 -196.466714) (xy 32.232356 -196.493363) (xy 46.608736 -196.493363)
			(xy 46.608736 -196.440065) (xy 46.616679 -196.387361) (xy 46.632389 -196.336431) (xy 46.655515 -196.28841)
			(xy 46.685539 -196.244373) (xy 46.721791 -196.205302) (xy 46.763462 -196.172071) (xy 46.80962 -196.145422)
			(xy 46.859234 -196.12595) (xy 46.911196 -196.11409) (xy 46.964346 -196.110107) (xy 47.017496 -196.11409)
			(xy 47.069458 -196.12595) (xy 47.119072 -196.145422) (xy 47.16523 -196.172071) (xy 47.206901 -196.205302)
			(xy 47.243153 -196.244373) (xy 47.273177 -196.28841) (xy 47.296303 -196.336431) (xy 47.312013 -196.387361)
			(xy 47.319956 -196.440065) (xy 47.320454 -196.466714) (xy 47.319956 -196.493363) (xy 47.312013 -196.546067)
			(xy 47.296303 -196.596997) (xy 47.273177 -196.645018) (xy 47.243153 -196.689055) (xy 47.206901 -196.728126)
			(xy 47.16523 -196.761357) (xy 47.119072 -196.788006) (xy 47.069458 -196.807478) (xy 47.017496 -196.819338)
			(xy 46.964346 -196.823322) (xy 46.911196 -196.819338) (xy 46.859234 -196.807478) (xy 46.80962 -196.788006)
			(xy 46.763462 -196.761357) (xy 46.721791 -196.728126) (xy 46.685539 -196.689055) (xy 46.655515 -196.645018)
			(xy 46.632389 -196.596997) (xy 46.616679 -196.546067) (xy 46.608736 -196.493363) (xy 32.232356 -196.493363)
			(xy 32.224413 -196.546067) (xy 32.208703 -196.596997) (xy 32.185577 -196.645018) (xy 32.155553 -196.689055)
			(xy 32.119301 -196.728126) (xy 32.07763 -196.761357) (xy 32.031472 -196.788006) (xy 31.981858 -196.807478)
			(xy 31.929896 -196.819338) (xy 31.876746 -196.823322) (xy 31.823596 -196.819338) (xy 31.771634 -196.807478)
			(xy 31.72202 -196.788006) (xy 31.675862 -196.761357) (xy 31.634191 -196.728126) (xy 31.597939 -196.689055)
			(xy 31.567915 -196.645018) (xy 31.544789 -196.596997) (xy 31.529079 -196.546067) (xy 31.521136 -196.493363)
			(xy 17.144756 -196.493363) (xy 17.136813 -196.546067) (xy 17.121103 -196.596997) (xy 17.097977 -196.645018)
			(xy 17.067953 -196.689055) (xy 17.031701 -196.728126) (xy 16.99003 -196.761357) (xy 16.943872 -196.788006)
			(xy 16.894258 -196.807478) (xy 16.842296 -196.819338) (xy 16.789146 -196.823322) (xy 16.735996 -196.819338)
			(xy 16.684034 -196.807478) (xy 16.63442 -196.788006) (xy 16.588262 -196.761357) (xy 16.546591 -196.728126)
			(xy 16.510339 -196.689055) (xy 16.480315 -196.645018) (xy 16.457189 -196.596997) (xy 16.441479 -196.546067)
			(xy 16.433536 -196.493363) (xy 8.872728 -196.493363) (xy 8.872728 -197.343247) (xy 20.533604 -197.343247)
			(xy 20.533604 -197.289949) (xy 20.541547 -197.237245) (xy 20.557257 -197.186315) (xy 20.580383 -197.138294)
			(xy 20.610407 -197.094257) (xy 20.646659 -197.055186) (xy 20.68833 -197.021955) (xy 20.734488 -196.995306)
			(xy 20.784102 -196.975834) (xy 20.836064 -196.963974) (xy 20.889214 -196.959991) (xy 20.942364 -196.963974)
			(xy 20.994326 -196.975834) (xy 21.04394 -196.995306) (xy 21.090098 -197.021955) (xy 21.131769 -197.055186)
			(xy 21.168021 -197.094257) (xy 21.198045 -197.138294) (xy 21.221171 -197.186315) (xy 21.236881 -197.237245)
			(xy 21.244824 -197.289949) (xy 21.245322 -197.316598) (xy 21.244824 -197.343247) (xy 35.621204 -197.343247)
			(xy 35.621204 -197.289949) (xy 35.629147 -197.237245) (xy 35.644857 -197.186315) (xy 35.667983 -197.138294)
			(xy 35.698007 -197.094257) (xy 35.734259 -197.055186) (xy 35.77593 -197.021955) (xy 35.822088 -196.995306)
			(xy 35.871702 -196.975834) (xy 35.923664 -196.963974) (xy 35.976814 -196.959991) (xy 36.029964 -196.963974)
			(xy 36.081926 -196.975834) (xy 36.13154 -196.995306) (xy 36.177698 -197.021955) (xy 36.219369 -197.055186)
			(xy 36.255621 -197.094257) (xy 36.285645 -197.138294) (xy 36.308771 -197.186315) (xy 36.324481 -197.237245)
			(xy 36.332424 -197.289949) (xy 36.332922 -197.316598) (xy 36.332424 -197.343247) (xy 50.708804 -197.343247)
			(xy 50.708804 -197.289949) (xy 50.716747 -197.237245) (xy 50.732457 -197.186315) (xy 50.755583 -197.138294)
			(xy 50.785607 -197.094257) (xy 50.821859 -197.055186) (xy 50.86353 -197.021955) (xy 50.909688 -196.995306)
			(xy 50.959302 -196.975834) (xy 51.011264 -196.963974) (xy 51.064414 -196.959991) (xy 51.117564 -196.963974)
			(xy 51.169526 -196.975834) (xy 51.21914 -196.995306) (xy 51.265298 -197.021955) (xy 51.306969 -197.055186)
			(xy 51.343221 -197.094257) (xy 51.373245 -197.138294) (xy 51.396371 -197.186315) (xy 51.412081 -197.237245)
			(xy 51.420024 -197.289949) (xy 51.420522 -197.316598) (xy 51.420024 -197.343247) (xy 51.412081 -197.395951)
			(xy 51.396371 -197.446881) (xy 51.373245 -197.494902) (xy 51.343221 -197.538939) (xy 51.306969 -197.57801)
			(xy 51.265298 -197.611241) (xy 51.21914 -197.63789) (xy 51.169526 -197.657362) (xy 51.117564 -197.669222)
			(xy 51.064414 -197.673206) (xy 51.011264 -197.669222) (xy 50.959302 -197.657362) (xy 50.909688 -197.63789)
			(xy 50.86353 -197.611241) (xy 50.821859 -197.57801) (xy 50.785607 -197.538939) (xy 50.755583 -197.494902)
			(xy 50.732457 -197.446881) (xy 50.716747 -197.395951) (xy 50.708804 -197.343247) (xy 36.332424 -197.343247)
			(xy 36.324481 -197.395951) (xy 36.308771 -197.446881) (xy 36.285645 -197.494902) (xy 36.255621 -197.538939)
			(xy 36.219369 -197.57801) (xy 36.177698 -197.611241) (xy 36.13154 -197.63789) (xy 36.081926 -197.657362)
			(xy 36.029964 -197.669222) (xy 35.976814 -197.673206) (xy 35.923664 -197.669222) (xy 35.871702 -197.657362)
			(xy 35.822088 -197.63789) (xy 35.77593 -197.611241) (xy 35.734259 -197.57801) (xy 35.698007 -197.538939)
			(xy 35.667983 -197.494902) (xy 35.644857 -197.446881) (xy 35.629147 -197.395951) (xy 35.621204 -197.343247)
			(xy 21.244824 -197.343247) (xy 21.236881 -197.395951) (xy 21.221171 -197.446881) (xy 21.198045 -197.494902)
			(xy 21.168021 -197.538939) (xy 21.131769 -197.57801) (xy 21.090098 -197.611241) (xy 21.04394 -197.63789)
			(xy 20.994326 -197.657362) (xy 20.942364 -197.669222) (xy 20.889214 -197.673206) (xy 20.836064 -197.669222)
			(xy 20.784102 -197.657362) (xy 20.734488 -197.63789) (xy 20.68833 -197.611241) (xy 20.646659 -197.57801)
			(xy 20.610407 -197.538939) (xy 20.580383 -197.494902) (xy 20.557257 -197.446881) (xy 20.541547 -197.395951)
			(xy 20.533604 -197.343247) (xy 8.872728 -197.343247) (xy 8.872728 -198.193385) (xy 16.433536 -198.193385)
			(xy 16.433536 -198.140087) (xy 16.441479 -198.087383) (xy 16.457189 -198.036453) (xy 16.480315 -197.988432)
			(xy 16.510339 -197.944395) (xy 16.546591 -197.905324) (xy 16.588262 -197.872093) (xy 16.63442 -197.845444)
			(xy 16.684034 -197.825972) (xy 16.735996 -197.814112) (xy 16.789146 -197.810129) (xy 16.842296 -197.814112)
			(xy 16.894258 -197.825972) (xy 16.943872 -197.845444) (xy 16.99003 -197.872093) (xy 17.031701 -197.905324)
			(xy 17.067953 -197.944395) (xy 17.097977 -197.988432) (xy 17.121103 -198.036453) (xy 17.136813 -198.087383)
			(xy 17.144756 -198.140087) (xy 17.145254 -198.166736) (xy 17.144756 -198.193385) (xy 31.521136 -198.193385)
			(xy 31.521136 -198.140087) (xy 31.529079 -198.087383) (xy 31.544789 -198.036453) (xy 31.567915 -197.988432)
			(xy 31.597939 -197.944395) (xy 31.634191 -197.905324) (xy 31.675862 -197.872093) (xy 31.72202 -197.845444)
			(xy 31.771634 -197.825972) (xy 31.823596 -197.814112) (xy 31.876746 -197.810129) (xy 31.929896 -197.814112)
			(xy 31.981858 -197.825972) (xy 32.031472 -197.845444) (xy 32.07763 -197.872093) (xy 32.119301 -197.905324)
			(xy 32.155553 -197.944395) (xy 32.185577 -197.988432) (xy 32.208703 -198.036453) (xy 32.224413 -198.087383)
			(xy 32.232356 -198.140087) (xy 32.232854 -198.166736) (xy 32.232356 -198.193385) (xy 46.608736 -198.193385)
			(xy 46.608736 -198.140087) (xy 46.616679 -198.087383) (xy 46.632389 -198.036453) (xy 46.655515 -197.988432)
			(xy 46.685539 -197.944395) (xy 46.721791 -197.905324) (xy 46.763462 -197.872093) (xy 46.80962 -197.845444)
			(xy 46.859234 -197.825972) (xy 46.911196 -197.814112) (xy 46.964346 -197.810129) (xy 47.017496 -197.814112)
			(xy 47.069458 -197.825972) (xy 47.119072 -197.845444) (xy 47.16523 -197.872093) (xy 47.206901 -197.905324)
			(xy 47.243153 -197.944395) (xy 47.273177 -197.988432) (xy 47.296303 -198.036453) (xy 47.312013 -198.087383)
			(xy 47.319956 -198.140087) (xy 47.320454 -198.166736) (xy 47.319956 -198.193385) (xy 47.312013 -198.246089)
			(xy 47.296303 -198.297019) (xy 47.273177 -198.34504) (xy 47.243153 -198.389077) (xy 47.206901 -198.428148)
			(xy 47.16523 -198.461379) (xy 47.119072 -198.488028) (xy 47.069458 -198.5075) (xy 47.017496 -198.51936)
			(xy 46.964346 -198.523344) (xy 46.911196 -198.51936) (xy 46.859234 -198.5075) (xy 46.80962 -198.488028)
			(xy 46.763462 -198.461379) (xy 46.721791 -198.428148) (xy 46.685539 -198.389077) (xy 46.655515 -198.34504)
			(xy 46.632389 -198.297019) (xy 46.616679 -198.246089) (xy 46.608736 -198.193385) (xy 32.232356 -198.193385)
			(xy 32.224413 -198.246089) (xy 32.208703 -198.297019) (xy 32.185577 -198.34504) (xy 32.155553 -198.389077)
			(xy 32.119301 -198.428148) (xy 32.07763 -198.461379) (xy 32.031472 -198.488028) (xy 31.981858 -198.5075)
			(xy 31.929896 -198.51936) (xy 31.876746 -198.523344) (xy 31.823596 -198.51936) (xy 31.771634 -198.5075)
			(xy 31.72202 -198.488028) (xy 31.675862 -198.461379) (xy 31.634191 -198.428148) (xy 31.597939 -198.389077)
			(xy 31.567915 -198.34504) (xy 31.544789 -198.297019) (xy 31.529079 -198.246089) (xy 31.521136 -198.193385)
			(xy 17.144756 -198.193385) (xy 17.136813 -198.246089) (xy 17.121103 -198.297019) (xy 17.097977 -198.34504)
			(xy 17.067953 -198.389077) (xy 17.031701 -198.428148) (xy 16.99003 -198.461379) (xy 16.943872 -198.488028)
			(xy 16.894258 -198.5075) (xy 16.842296 -198.51936) (xy 16.789146 -198.523344) (xy 16.735996 -198.51936)
			(xy 16.684034 -198.5075) (xy 16.63442 -198.488028) (xy 16.588262 -198.461379) (xy 16.546591 -198.428148)
			(xy 16.510339 -198.389077) (xy 16.480315 -198.34504) (xy 16.457189 -198.297019) (xy 16.441479 -198.246089)
			(xy 16.433536 -198.193385) (xy 8.872728 -198.193385) (xy 8.872728 -199.043269) (xy 20.533604 -199.043269)
			(xy 20.533604 -198.989971) (xy 20.541547 -198.937267) (xy 20.557257 -198.886337) (xy 20.580383 -198.838316)
			(xy 20.610407 -198.794279) (xy 20.646659 -198.755208) (xy 20.68833 -198.721977) (xy 20.734488 -198.695328)
			(xy 20.784102 -198.675856) (xy 20.836064 -198.663996) (xy 20.889214 -198.660013) (xy 20.942364 -198.663996)
			(xy 20.994326 -198.675856) (xy 21.04394 -198.695328) (xy 21.090098 -198.721977) (xy 21.131769 -198.755208)
			(xy 21.168021 -198.794279) (xy 21.198045 -198.838316) (xy 21.221171 -198.886337) (xy 21.236881 -198.937267)
			(xy 21.244824 -198.989971) (xy 21.245322 -199.01662) (xy 21.244824 -199.043269) (xy 35.621204 -199.043269)
			(xy 35.621204 -198.989971) (xy 35.629147 -198.937267) (xy 35.644857 -198.886337) (xy 35.667983 -198.838316)
			(xy 35.698007 -198.794279) (xy 35.734259 -198.755208) (xy 35.77593 -198.721977) (xy 35.822088 -198.695328)
			(xy 35.871702 -198.675856) (xy 35.923664 -198.663996) (xy 35.976814 -198.660013) (xy 36.029964 -198.663996)
			(xy 36.081926 -198.675856) (xy 36.13154 -198.695328) (xy 36.177698 -198.721977) (xy 36.219369 -198.755208)
			(xy 36.255621 -198.794279) (xy 36.285645 -198.838316) (xy 36.308771 -198.886337) (xy 36.324481 -198.937267)
			(xy 36.332424 -198.989971) (xy 36.332922 -199.01662) (xy 36.332424 -199.043269) (xy 50.708804 -199.043269)
			(xy 50.708804 -198.989971) (xy 50.716747 -198.937267) (xy 50.732457 -198.886337) (xy 50.755583 -198.838316)
			(xy 50.785607 -198.794279) (xy 50.821859 -198.755208) (xy 50.86353 -198.721977) (xy 50.909688 -198.695328)
			(xy 50.959302 -198.675856) (xy 51.011264 -198.663996) (xy 51.064414 -198.660013) (xy 51.117564 -198.663996)
			(xy 51.169526 -198.675856) (xy 51.21914 -198.695328) (xy 51.265298 -198.721977) (xy 51.306969 -198.755208)
			(xy 51.343221 -198.794279) (xy 51.373245 -198.838316) (xy 51.396371 -198.886337) (xy 51.412081 -198.937267)
			(xy 51.420024 -198.989971) (xy 51.420522 -199.01662) (xy 51.420024 -199.043269) (xy 51.412081 -199.095973)
			(xy 51.396371 -199.146903) (xy 51.373245 -199.194924) (xy 51.343221 -199.238961) (xy 51.306969 -199.278032)
			(xy 51.265298 -199.311263) (xy 51.21914 -199.337912) (xy 51.169526 -199.357384) (xy 51.117564 -199.369244)
			(xy 51.064414 -199.373228) (xy 51.011264 -199.369244) (xy 50.959302 -199.357384) (xy 50.909688 -199.337912)
			(xy 50.86353 -199.311263) (xy 50.821859 -199.278032) (xy 50.785607 -199.238961) (xy 50.755583 -199.194924)
			(xy 50.732457 -199.146903) (xy 50.716747 -199.095973) (xy 50.708804 -199.043269) (xy 36.332424 -199.043269)
			(xy 36.324481 -199.095973) (xy 36.308771 -199.146903) (xy 36.285645 -199.194924) (xy 36.255621 -199.238961)
			(xy 36.219369 -199.278032) (xy 36.177698 -199.311263) (xy 36.13154 -199.337912) (xy 36.081926 -199.357384)
			(xy 36.029964 -199.369244) (xy 35.976814 -199.373228) (xy 35.923664 -199.369244) (xy 35.871702 -199.357384)
			(xy 35.822088 -199.337912) (xy 35.77593 -199.311263) (xy 35.734259 -199.278032) (xy 35.698007 -199.238961)
			(xy 35.667983 -199.194924) (xy 35.644857 -199.146903) (xy 35.629147 -199.095973) (xy 35.621204 -199.043269)
			(xy 21.244824 -199.043269) (xy 21.236881 -199.095973) (xy 21.221171 -199.146903) (xy 21.198045 -199.194924)
			(xy 21.168021 -199.238961) (xy 21.131769 -199.278032) (xy 21.090098 -199.311263) (xy 21.04394 -199.337912)
			(xy 20.994326 -199.357384) (xy 20.942364 -199.369244) (xy 20.889214 -199.373228) (xy 20.836064 -199.369244)
			(xy 20.784102 -199.357384) (xy 20.734488 -199.337912) (xy 20.68833 -199.311263) (xy 20.646659 -199.278032)
			(xy 20.610407 -199.238961) (xy 20.580383 -199.194924) (xy 20.557257 -199.146903) (xy 20.541547 -199.095973)
			(xy 20.533604 -199.043269) (xy 8.872728 -199.043269) (xy 8.872728 -199.13854) (xy 8.872244 -199.1742)
			(xy 8.864252 -199.245072) (xy 8.848374 -199.314603) (xy 8.824809 -199.381919) (xy 8.793853 -199.446171)
			(xy 8.755896 -199.506553) (xy 8.711416 -199.562304) (xy 8.686546 -199.587866) (xy 8.381005 -199.893407)
			(xy 16.433536 -199.893407) (xy 16.433536 -199.840109) (xy 16.441479 -199.787405) (xy 16.457189 -199.736475)
			(xy 16.480315 -199.688454) (xy 16.510339 -199.644417) (xy 16.546591 -199.605346) (xy 16.588262 -199.572115)
			(xy 16.63442 -199.545466) (xy 16.684034 -199.525994) (xy 16.735996 -199.514134) (xy 16.789146 -199.510151)
			(xy 16.842296 -199.514134) (xy 16.894258 -199.525994) (xy 16.943872 -199.545466) (xy 16.99003 -199.572115)
			(xy 17.031701 -199.605346) (xy 17.067953 -199.644417) (xy 17.097977 -199.688454) (xy 17.121103 -199.736475)
			(xy 17.136813 -199.787405) (xy 17.144756 -199.840109) (xy 17.145254 -199.866758) (xy 17.144756 -199.893407)
			(xy 20.533604 -199.893407) (xy 20.533604 -199.840109) (xy 20.541547 -199.787405) (xy 20.557257 -199.736475)
			(xy 20.580383 -199.688454) (xy 20.610407 -199.644417) (xy 20.646659 -199.605346) (xy 20.68833 -199.572115)
			(xy 20.734488 -199.545466) (xy 20.784102 -199.525994) (xy 20.836064 -199.514134) (xy 20.889214 -199.510151)
			(xy 20.942364 -199.514134) (xy 20.994326 -199.525994) (xy 21.04394 -199.545466) (xy 21.090098 -199.572115)
			(xy 21.131769 -199.605346) (xy 21.168021 -199.644417) (xy 21.198045 -199.688454) (xy 21.221171 -199.736475)
			(xy 21.236881 -199.787405) (xy 21.244824 -199.840109) (xy 21.245322 -199.866758) (xy 21.244824 -199.893407)
			(xy 31.521136 -199.893407) (xy 31.521136 -199.840109) (xy 31.529079 -199.787405) (xy 31.544789 -199.736475)
			(xy 31.567915 -199.688454) (xy 31.597939 -199.644417) (xy 31.634191 -199.605346) (xy 31.675862 -199.572115)
			(xy 31.72202 -199.545466) (xy 31.771634 -199.525994) (xy 31.823596 -199.514134) (xy 31.876746 -199.510151)
			(xy 31.929896 -199.514134) (xy 31.981858 -199.525994) (xy 32.031472 -199.545466) (xy 32.07763 -199.572115)
			(xy 32.119301 -199.605346) (xy 32.155553 -199.644417) (xy 32.185577 -199.688454) (xy 32.208703 -199.736475)
			(xy 32.224413 -199.787405) (xy 32.232356 -199.840109) (xy 32.232854 -199.866758) (xy 32.232356 -199.893407)
			(xy 35.621204 -199.893407) (xy 35.621204 -199.840109) (xy 35.629147 -199.787405) (xy 35.644857 -199.736475)
			(xy 35.667983 -199.688454) (xy 35.698007 -199.644417) (xy 35.734259 -199.605346) (xy 35.77593 -199.572115)
			(xy 35.822088 -199.545466) (xy 35.871702 -199.525994) (xy 35.923664 -199.514134) (xy 35.976814 -199.510151)
			(xy 36.029964 -199.514134) (xy 36.081926 -199.525994) (xy 36.13154 -199.545466) (xy 36.177698 -199.572115)
			(xy 36.219369 -199.605346) (xy 36.255621 -199.644417) (xy 36.285645 -199.688454) (xy 36.308771 -199.736475)
			(xy 36.324481 -199.787405) (xy 36.332424 -199.840109) (xy 36.332922 -199.866758) (xy 36.332424 -199.893407)
			(xy 46.608736 -199.893407) (xy 46.608736 -199.840109) (xy 46.616679 -199.787405) (xy 46.632389 -199.736475)
			(xy 46.655515 -199.688454) (xy 46.685539 -199.644417) (xy 46.721791 -199.605346) (xy 46.763462 -199.572115)
			(xy 46.80962 -199.545466) (xy 46.859234 -199.525994) (xy 46.911196 -199.514134) (xy 46.964346 -199.510151)
			(xy 47.017496 -199.514134) (xy 47.069458 -199.525994) (xy 47.119072 -199.545466) (xy 47.16523 -199.572115)
			(xy 47.206901 -199.605346) (xy 47.243153 -199.644417) (xy 47.273177 -199.688454) (xy 47.296303 -199.736475)
			(xy 47.312013 -199.787405) (xy 47.319956 -199.840109) (xy 47.320454 -199.866758) (xy 47.319956 -199.893407)
			(xy 50.708804 -199.893407) (xy 50.708804 -199.840109) (xy 50.716747 -199.787405) (xy 50.732457 -199.736475)
			(xy 50.755583 -199.688454) (xy 50.785607 -199.644417) (xy 50.821859 -199.605346) (xy 50.86353 -199.572115)
			(xy 50.909688 -199.545466) (xy 50.959302 -199.525994) (xy 51.011264 -199.514134) (xy 51.064414 -199.510151)
			(xy 51.117564 -199.514134) (xy 51.169526 -199.525994) (xy 51.21914 -199.545466) (xy 51.265298 -199.572115)
			(xy 51.306969 -199.605346) (xy 51.343221 -199.644417) (xy 51.373245 -199.688454) (xy 51.396371 -199.736475)
			(xy 51.412081 -199.787405) (xy 51.420024 -199.840109) (xy 51.420522 -199.866758) (xy 51.420024 -199.893407)
			(xy 51.412081 -199.946111) (xy 51.396371 -199.997041) (xy 51.373245 -200.045062) (xy 51.343221 -200.089099)
			(xy 51.306969 -200.12817) (xy 51.265298 -200.161401) (xy 51.21914 -200.18805) (xy 51.169526 -200.207522)
			(xy 51.117564 -200.219382) (xy 51.064414 -200.223366) (xy 51.011264 -200.219382) (xy 50.959302 -200.207522)
			(xy 50.909688 -200.18805) (xy 50.86353 -200.161401) (xy 50.821859 -200.12817) (xy 50.785607 -200.089099)
			(xy 50.755583 -200.045062) (xy 50.732457 -199.997041) (xy 50.716747 -199.946111) (xy 50.708804 -199.893407)
			(xy 47.319956 -199.893407) (xy 47.312013 -199.946111) (xy 47.296303 -199.997041) (xy 47.273177 -200.045062)
			(xy 47.243153 -200.089099) (xy 47.206901 -200.12817) (xy 47.16523 -200.161401) (xy 47.119072 -200.18805)
			(xy 47.069458 -200.207522) (xy 47.017496 -200.219382) (xy 46.964346 -200.223366) (xy 46.911196 -200.219382)
			(xy 46.859234 -200.207522) (xy 46.80962 -200.18805) (xy 46.763462 -200.161401) (xy 46.721791 -200.12817)
			(xy 46.685539 -200.089099) (xy 46.655515 -200.045062) (xy 46.632389 -199.997041) (xy 46.616679 -199.946111)
			(xy 46.608736 -199.893407) (xy 36.332424 -199.893407) (xy 36.324481 -199.946111) (xy 36.308771 -199.997041)
			(xy 36.285645 -200.045062) (xy 36.255621 -200.089099) (xy 36.219369 -200.12817) (xy 36.177698 -200.161401)
			(xy 36.13154 -200.18805) (xy 36.081926 -200.207522) (xy 36.029964 -200.219382) (xy 35.976814 -200.223366)
			(xy 35.923664 -200.219382) (xy 35.871702 -200.207522) (xy 35.822088 -200.18805) (xy 35.77593 -200.161401)
			(xy 35.734259 -200.12817) (xy 35.698007 -200.089099) (xy 35.667983 -200.045062) (xy 35.644857 -199.997041)
			(xy 35.629147 -199.946111) (xy 35.621204 -199.893407) (xy 32.232356 -199.893407) (xy 32.224413 -199.946111)
			(xy 32.208703 -199.997041) (xy 32.185577 -200.045062) (xy 32.155553 -200.089099) (xy 32.119301 -200.12817)
			(xy 32.07763 -200.161401) (xy 32.031472 -200.18805) (xy 31.981858 -200.207522) (xy 31.929896 -200.219382)
			(xy 31.876746 -200.223366) (xy 31.823596 -200.219382) (xy 31.771634 -200.207522) (xy 31.72202 -200.18805)
			(xy 31.675862 -200.161401) (xy 31.634191 -200.12817) (xy 31.597939 -200.089099) (xy 31.567915 -200.045062)
			(xy 31.544789 -199.997041) (xy 31.529079 -199.946111) (xy 31.521136 -199.893407) (xy 21.244824 -199.893407)
			(xy 21.236881 -199.946111) (xy 21.221171 -199.997041) (xy 21.198045 -200.045062) (xy 21.168021 -200.089099)
			(xy 21.131769 -200.12817) (xy 21.090098 -200.161401) (xy 21.04394 -200.18805) (xy 20.994326 -200.207522)
			(xy 20.942364 -200.219382) (xy 20.889214 -200.223366) (xy 20.836064 -200.219382) (xy 20.784102 -200.207522)
			(xy 20.734488 -200.18805) (xy 20.68833 -200.161401) (xy 20.646659 -200.12817) (xy 20.610407 -200.089099)
			(xy 20.580383 -200.045062) (xy 20.557257 -199.997041) (xy 20.541547 -199.946111) (xy 20.533604 -199.893407)
			(xy 17.144756 -199.893407) (xy 17.136813 -199.946111) (xy 17.121103 -199.997041) (xy 17.097977 -200.045062)
			(xy 17.067953 -200.089099) (xy 17.031701 -200.12817) (xy 16.99003 -200.161401) (xy 16.943872 -200.18805)
			(xy 16.894258 -200.207522) (xy 16.842296 -200.219382) (xy 16.789146 -200.223366) (xy 16.735996 -200.219382)
			(xy 16.684034 -200.207522) (xy 16.63442 -200.18805) (xy 16.588262 -200.161401) (xy 16.546591 -200.12817)
			(xy 16.510339 -200.089099) (xy 16.480315 -200.045062) (xy 16.457189 -199.997041) (xy 16.441479 -199.946111)
			(xy 16.433536 -199.893407) (xy 8.381005 -199.893407) (xy 7.531121 -200.743291) (xy 16.433536 -200.743291)
			(xy 16.433536 -200.689993) (xy 16.441479 -200.637289) (xy 16.457189 -200.586359) (xy 16.480315 -200.538338)
			(xy 16.510339 -200.494301) (xy 16.546591 -200.45523) (xy 16.588262 -200.421999) (xy 16.63442 -200.39535)
			(xy 16.684034 -200.375878) (xy 16.735996 -200.364018) (xy 16.789146 -200.360035) (xy 16.842296 -200.364018)
			(xy 16.894258 -200.375878) (xy 16.943872 -200.39535) (xy 16.99003 -200.421999) (xy 17.031701 -200.45523)
			(xy 17.067953 -200.494301) (xy 17.097977 -200.538338) (xy 17.121103 -200.586359) (xy 17.136813 -200.637289)
			(xy 17.144756 -200.689993) (xy 17.145254 -200.716642) (xy 17.144756 -200.743291) (xy 31.521136 -200.743291)
			(xy 31.521136 -200.689993) (xy 31.529079 -200.637289) (xy 31.544789 -200.586359) (xy 31.567915 -200.538338)
			(xy 31.597939 -200.494301) (xy 31.634191 -200.45523) (xy 31.675862 -200.421999) (xy 31.72202 -200.39535)
			(xy 31.771634 -200.375878) (xy 31.823596 -200.364018) (xy 31.876746 -200.360035) (xy 31.929896 -200.364018)
			(xy 31.981858 -200.375878) (xy 32.031472 -200.39535) (xy 32.07763 -200.421999) (xy 32.119301 -200.45523)
			(xy 32.155553 -200.494301) (xy 32.185577 -200.538338) (xy 32.208703 -200.586359) (xy 32.224413 -200.637289)
			(xy 32.232356 -200.689993) (xy 32.232854 -200.716642) (xy 32.232356 -200.743291) (xy 46.608736 -200.743291)
			(xy 46.608736 -200.689993) (xy 46.616679 -200.637289) (xy 46.632389 -200.586359) (xy 46.655515 -200.538338)
			(xy 46.685539 -200.494301) (xy 46.721791 -200.45523) (xy 46.763462 -200.421999) (xy 46.80962 -200.39535)
			(xy 46.859234 -200.375878) (xy 46.911196 -200.364018) (xy 46.964346 -200.360035) (xy 47.017496 -200.364018)
			(xy 47.069458 -200.375878) (xy 47.119072 -200.39535) (xy 47.16523 -200.421999) (xy 47.206901 -200.45523)
			(xy 47.243153 -200.494301) (xy 47.273177 -200.538338) (xy 47.296303 -200.586359) (xy 47.312013 -200.637289)
			(xy 47.319956 -200.689993) (xy 47.320454 -200.716642) (xy 47.319956 -200.743291) (xy 47.312013 -200.795995)
			(xy 47.296303 -200.846925) (xy 47.273177 -200.894946) (xy 47.243153 -200.938983) (xy 47.206901 -200.978054)
			(xy 47.16523 -201.011285) (xy 47.119072 -201.037934) (xy 47.069458 -201.057406) (xy 47.017496 -201.069266)
			(xy 46.964346 -201.07325) (xy 46.911196 -201.069266) (xy 46.859234 -201.057406) (xy 46.80962 -201.037934)
			(xy 46.763462 -201.011285) (xy 46.721791 -200.978054) (xy 46.685539 -200.938983) (xy 46.655515 -200.894946)
			(xy 46.632389 -200.846925) (xy 46.616679 -200.795995) (xy 46.608736 -200.743291) (xy 32.232356 -200.743291)
			(xy 32.224413 -200.795995) (xy 32.208703 -200.846925) (xy 32.185577 -200.894946) (xy 32.155553 -200.938983)
			(xy 32.119301 -200.978054) (xy 32.07763 -201.011285) (xy 32.031472 -201.037934) (xy 31.981858 -201.057406)
			(xy 31.929896 -201.069266) (xy 31.876746 -201.07325) (xy 31.823596 -201.069266) (xy 31.771634 -201.057406)
			(xy 31.72202 -201.037934) (xy 31.675862 -201.011285) (xy 31.634191 -200.978054) (xy 31.597939 -200.938983)
			(xy 31.567915 -200.894946) (xy 31.544789 -200.846925) (xy 31.529079 -200.795995) (xy 31.521136 -200.743291)
			(xy 17.144756 -200.743291) (xy 17.136813 -200.795995) (xy 17.121103 -200.846925) (xy 17.097977 -200.894946)
			(xy 17.067953 -200.938983) (xy 17.031701 -200.978054) (xy 16.99003 -201.011285) (xy 16.943872 -201.037934)
			(xy 16.894258 -201.057406) (xy 16.842296 -201.069266) (xy 16.789146 -201.07325) (xy 16.735996 -201.069266)
			(xy 16.684034 -201.057406) (xy 16.63442 -201.037934) (xy 16.588262 -201.011285) (xy 16.546591 -200.978054)
			(xy 16.510339 -200.938983) (xy 16.480315 -200.894946) (xy 16.457189 -200.846925) (xy 16.441479 -200.795995)
			(xy 16.433536 -200.743291) (xy 7.531121 -200.743291) (xy 6.80339 -201.471022) (xy 6.80339 -201.593429)
			(xy 20.533604 -201.593429) (xy 20.533604 -201.540131) (xy 20.541547 -201.487427) (xy 20.557257 -201.436497)
			(xy 20.580383 -201.388476) (xy 20.610407 -201.344439) (xy 20.646659 -201.305368) (xy 20.68833 -201.272137)
			(xy 20.734488 -201.245488) (xy 20.784102 -201.226016) (xy 20.836064 -201.214156) (xy 20.889214 -201.210173)
			(xy 20.942364 -201.214156) (xy 20.994326 -201.226016) (xy 21.04394 -201.245488) (xy 21.090098 -201.272137)
			(xy 21.131769 -201.305368) (xy 21.168021 -201.344439) (xy 21.198045 -201.388476) (xy 21.221171 -201.436497)
			(xy 21.236881 -201.487427) (xy 21.244824 -201.540131) (xy 21.245322 -201.56678) (xy 21.244824 -201.593429)
			(xy 35.621204 -201.593429) (xy 35.621204 -201.540131) (xy 35.629147 -201.487427) (xy 35.644857 -201.436497)
			(xy 35.667983 -201.388476) (xy 35.698007 -201.344439) (xy 35.734259 -201.305368) (xy 35.77593 -201.272137)
			(xy 35.822088 -201.245488) (xy 35.871702 -201.226016) (xy 35.923664 -201.214156) (xy 35.976814 -201.210173)
			(xy 36.029964 -201.214156) (xy 36.081926 -201.226016) (xy 36.13154 -201.245488) (xy 36.177698 -201.272137)
			(xy 36.219369 -201.305368) (xy 36.255621 -201.344439) (xy 36.285645 -201.388476) (xy 36.308771 -201.436497)
			(xy 36.324481 -201.487427) (xy 36.332424 -201.540131) (xy 36.332922 -201.56678) (xy 36.332424 -201.593429)
			(xy 50.708804 -201.593429) (xy 50.708804 -201.540131) (xy 50.716747 -201.487427) (xy 50.732457 -201.436497)
			(xy 50.755583 -201.388476) (xy 50.785607 -201.344439) (xy 50.821859 -201.305368) (xy 50.86353 -201.272137)
			(xy 50.909688 -201.245488) (xy 50.959302 -201.226016) (xy 51.011264 -201.214156) (xy 51.064414 -201.210173)
			(xy 51.117564 -201.214156) (xy 51.169526 -201.226016) (xy 51.21914 -201.245488) (xy 51.265298 -201.272137)
			(xy 51.306969 -201.305368) (xy 51.343221 -201.344439) (xy 51.373245 -201.388476) (xy 51.396371 -201.436497)
			(xy 51.412081 -201.487427) (xy 51.420024 -201.540131) (xy 51.420522 -201.56678) (xy 51.420024 -201.593429)
			(xy 51.412081 -201.646133) (xy 51.396371 -201.697063) (xy 51.373245 -201.745084) (xy 51.343221 -201.789121)
			(xy 51.306969 -201.828192) (xy 51.265298 -201.861423) (xy 51.21914 -201.888072) (xy 51.169526 -201.907544)
			(xy 51.117564 -201.919404) (xy 51.064414 -201.923388) (xy 51.011264 -201.919404) (xy 50.959302 -201.907544)
			(xy 50.909688 -201.888072) (xy 50.86353 -201.861423) (xy 50.821859 -201.828192) (xy 50.785607 -201.789121)
			(xy 50.755583 -201.745084) (xy 50.732457 -201.697063) (xy 50.716747 -201.646133) (xy 50.708804 -201.593429)
			(xy 36.332424 -201.593429) (xy 36.324481 -201.646133) (xy 36.308771 -201.697063) (xy 36.285645 -201.745084)
			(xy 36.255621 -201.789121) (xy 36.219369 -201.828192) (xy 36.177698 -201.861423) (xy 36.13154 -201.888072)
			(xy 36.081926 -201.907544) (xy 36.029964 -201.919404) (xy 35.976814 -201.923388) (xy 35.923664 -201.919404)
			(xy 35.871702 -201.907544) (xy 35.822088 -201.888072) (xy 35.77593 -201.861423) (xy 35.734259 -201.828192)
			(xy 35.698007 -201.789121) (xy 35.667983 -201.745084) (xy 35.644857 -201.697063) (xy 35.629147 -201.646133)
			(xy 35.621204 -201.593429) (xy 21.244824 -201.593429) (xy 21.236881 -201.646133) (xy 21.221171 -201.697063)
			(xy 21.198045 -201.745084) (xy 21.168021 -201.789121) (xy 21.131769 -201.828192) (xy 21.090098 -201.861423)
			(xy 21.04394 -201.888072) (xy 20.994326 -201.907544) (xy 20.942364 -201.919404) (xy 20.889214 -201.923388)
			(xy 20.836064 -201.919404) (xy 20.784102 -201.907544) (xy 20.734488 -201.888072) (xy 20.68833 -201.861423)
			(xy 20.646659 -201.828192) (xy 20.610407 -201.789121) (xy 20.580383 -201.745084) (xy 20.557257 -201.697063)
			(xy 20.541547 -201.646133) (xy 20.533604 -201.593429) (xy 6.80339 -201.593429) (xy 6.80339 -202.443313)
			(xy 16.433536 -202.443313) (xy 16.433536 -202.390015) (xy 16.441479 -202.337311) (xy 16.457189 -202.286381)
			(xy 16.480315 -202.23836) (xy 16.510339 -202.194323) (xy 16.546591 -202.155252) (xy 16.588262 -202.122021)
			(xy 16.63442 -202.095372) (xy 16.684034 -202.0759) (xy 16.735996 -202.06404) (xy 16.789146 -202.060057)
			(xy 16.842296 -202.06404) (xy 16.894258 -202.0759) (xy 16.943872 -202.095372) (xy 16.99003 -202.122021)
			(xy 17.031701 -202.155252) (xy 17.067953 -202.194323) (xy 17.097977 -202.23836) (xy 17.121103 -202.286381)
			(xy 17.136813 -202.337311) (xy 17.144756 -202.390015) (xy 17.145254 -202.416664) (xy 17.144756 -202.443313)
			(xy 31.521136 -202.443313) (xy 31.521136 -202.390015) (xy 31.529079 -202.337311) (xy 31.544789 -202.286381)
			(xy 31.567915 -202.23836) (xy 31.597939 -202.194323) (xy 31.634191 -202.155252) (xy 31.675862 -202.122021)
			(xy 31.72202 -202.095372) (xy 31.771634 -202.0759) (xy 31.823596 -202.06404) (xy 31.876746 -202.060057)
			(xy 31.929896 -202.06404) (xy 31.981858 -202.0759) (xy 32.031472 -202.095372) (xy 32.07763 -202.122021)
			(xy 32.119301 -202.155252) (xy 32.155553 -202.194323) (xy 32.185577 -202.23836) (xy 32.208703 -202.286381)
			(xy 32.224413 -202.337311) (xy 32.232356 -202.390015) (xy 32.232854 -202.416664) (xy 32.232356 -202.443313)
			(xy 46.608736 -202.443313) (xy 46.608736 -202.390015) (xy 46.616679 -202.337311) (xy 46.632389 -202.286381)
			(xy 46.655515 -202.23836) (xy 46.685539 -202.194323) (xy 46.721791 -202.155252) (xy 46.763462 -202.122021)
			(xy 46.80962 -202.095372) (xy 46.859234 -202.0759) (xy 46.911196 -202.06404) (xy 46.964346 -202.060057)
			(xy 47.017496 -202.06404) (xy 47.069458 -202.0759) (xy 47.119072 -202.095372) (xy 47.16523 -202.122021)
			(xy 47.206901 -202.155252) (xy 47.243153 -202.194323) (xy 47.273177 -202.23836) (xy 47.296303 -202.286381)
			(xy 47.312013 -202.337311) (xy 47.319956 -202.390015) (xy 47.320454 -202.416664) (xy 47.319956 -202.443313)
			(xy 47.312013 -202.496017) (xy 47.296303 -202.546947) (xy 47.273177 -202.594968) (xy 47.243153 -202.639005)
			(xy 47.206901 -202.678076) (xy 47.16523 -202.711307) (xy 47.119072 -202.737956) (xy 47.069458 -202.757428)
			(xy 47.017496 -202.769288) (xy 46.964346 -202.773272) (xy 46.911196 -202.769288) (xy 46.859234 -202.757428)
			(xy 46.80962 -202.737956) (xy 46.763462 -202.711307) (xy 46.721791 -202.678076) (xy 46.685539 -202.639005)
			(xy 46.655515 -202.594968) (xy 46.632389 -202.546947) (xy 46.616679 -202.496017) (xy 46.608736 -202.443313)
			(xy 32.232356 -202.443313) (xy 32.224413 -202.496017) (xy 32.208703 -202.546947) (xy 32.185577 -202.594968)
			(xy 32.155553 -202.639005) (xy 32.119301 -202.678076) (xy 32.07763 -202.711307) (xy 32.031472 -202.737956)
			(xy 31.981858 -202.757428) (xy 31.929896 -202.769288) (xy 31.876746 -202.773272) (xy 31.823596 -202.769288)
			(xy 31.771634 -202.757428) (xy 31.72202 -202.737956) (xy 31.675862 -202.711307) (xy 31.634191 -202.678076)
			(xy 31.597939 -202.639005) (xy 31.567915 -202.594968) (xy 31.544789 -202.546947) (xy 31.529079 -202.496017)
			(xy 31.521136 -202.443313) (xy 17.144756 -202.443313) (xy 17.136813 -202.496017) (xy 17.121103 -202.546947)
			(xy 17.097977 -202.594968) (xy 17.067953 -202.639005) (xy 17.031701 -202.678076) (xy 16.99003 -202.711307)
			(xy 16.943872 -202.737956) (xy 16.894258 -202.757428) (xy 16.842296 -202.769288) (xy 16.789146 -202.773272)
			(xy 16.735996 -202.769288) (xy 16.684034 -202.757428) (xy 16.63442 -202.737956) (xy 16.588262 -202.711307)
			(xy 16.546591 -202.678076) (xy 16.510339 -202.639005) (xy 16.480315 -202.594968) (xy 16.457189 -202.546947)
			(xy 16.441479 -202.496017) (xy 16.433536 -202.443313) (xy 6.80339 -202.443313) (xy 6.80339 -203.293451)
			(xy 20.533604 -203.293451) (xy 20.533604 -203.240153) (xy 20.541547 -203.187449) (xy 20.557257 -203.136519)
			(xy 20.580383 -203.088498) (xy 20.610407 -203.044461) (xy 20.646659 -203.00539) (xy 20.68833 -202.972159)
			(xy 20.734488 -202.94551) (xy 20.784102 -202.926038) (xy 20.836064 -202.914178) (xy 20.889214 -202.910195)
			(xy 20.942364 -202.914178) (xy 20.994326 -202.926038) (xy 21.04394 -202.94551) (xy 21.090098 -202.972159)
			(xy 21.131769 -203.00539) (xy 21.168021 -203.044461) (xy 21.198045 -203.088498) (xy 21.221171 -203.136519)
			(xy 21.236881 -203.187449) (xy 21.244824 -203.240153) (xy 21.245322 -203.266802) (xy 21.244824 -203.293451)
			(xy 35.621204 -203.293451) (xy 35.621204 -203.240153) (xy 35.629147 -203.187449) (xy 35.644857 -203.136519)
			(xy 35.667983 -203.088498) (xy 35.698007 -203.044461) (xy 35.734259 -203.00539) (xy 35.77593 -202.972159)
			(xy 35.822088 -202.94551) (xy 35.871702 -202.926038) (xy 35.923664 -202.914178) (xy 35.976814 -202.910195)
			(xy 36.029964 -202.914178) (xy 36.081926 -202.926038) (xy 36.13154 -202.94551) (xy 36.177698 -202.972159)
			(xy 36.219369 -203.00539) (xy 36.255621 -203.044461) (xy 36.285645 -203.088498) (xy 36.308771 -203.136519)
			(xy 36.324481 -203.187449) (xy 36.332424 -203.240153) (xy 36.332922 -203.266802) (xy 36.332424 -203.293451)
			(xy 50.708804 -203.293451) (xy 50.708804 -203.240153) (xy 50.716747 -203.187449) (xy 50.732457 -203.136519)
			(xy 50.755583 -203.088498) (xy 50.785607 -203.044461) (xy 50.821859 -203.00539) (xy 50.86353 -202.972159)
			(xy 50.909688 -202.94551) (xy 50.959302 -202.926038) (xy 51.011264 -202.914178) (xy 51.064414 -202.910195)
			(xy 51.117564 -202.914178) (xy 51.169526 -202.926038) (xy 51.21914 -202.94551) (xy 51.265298 -202.972159)
			(xy 51.306969 -203.00539) (xy 51.343221 -203.044461) (xy 51.373245 -203.088498) (xy 51.396371 -203.136519)
			(xy 51.412081 -203.187449) (xy 51.420024 -203.240153) (xy 51.420522 -203.266802) (xy 51.420024 -203.293451)
			(xy 51.412081 -203.346155) (xy 51.396371 -203.397085) (xy 51.373245 -203.445106) (xy 51.343221 -203.489143)
			(xy 51.306969 -203.528214) (xy 51.265298 -203.561445) (xy 51.21914 -203.588094) (xy 51.169526 -203.607566)
			(xy 51.117564 -203.619426) (xy 51.064414 -203.62341) (xy 51.011264 -203.619426) (xy 50.959302 -203.607566)
			(xy 50.909688 -203.588094) (xy 50.86353 -203.561445) (xy 50.821859 -203.528214) (xy 50.785607 -203.489143)
			(xy 50.755583 -203.445106) (xy 50.732457 -203.397085) (xy 50.716747 -203.346155) (xy 50.708804 -203.293451)
			(xy 36.332424 -203.293451) (xy 36.324481 -203.346155) (xy 36.308771 -203.397085) (xy 36.285645 -203.445106)
			(xy 36.255621 -203.489143) (xy 36.219369 -203.528214) (xy 36.177698 -203.561445) (xy 36.13154 -203.588094)
			(xy 36.081926 -203.607566) (xy 36.029964 -203.619426) (xy 35.976814 -203.62341) (xy 35.923664 -203.619426)
			(xy 35.871702 -203.607566) (xy 35.822088 -203.588094) (xy 35.77593 -203.561445) (xy 35.734259 -203.528214)
			(xy 35.698007 -203.489143) (xy 35.667983 -203.445106) (xy 35.644857 -203.397085) (xy 35.629147 -203.346155)
			(xy 35.621204 -203.293451) (xy 21.244824 -203.293451) (xy 21.236881 -203.346155) (xy 21.221171 -203.397085)
			(xy 21.198045 -203.445106) (xy 21.168021 -203.489143) (xy 21.131769 -203.528214) (xy 21.090098 -203.561445)
			(xy 21.04394 -203.588094) (xy 20.994326 -203.607566) (xy 20.942364 -203.619426) (xy 20.889214 -203.62341)
			(xy 20.836064 -203.619426) (xy 20.784102 -203.607566) (xy 20.734488 -203.588094) (xy 20.68833 -203.561445)
			(xy 20.646659 -203.528214) (xy 20.610407 -203.489143) (xy 20.580383 -203.445106) (xy 20.557257 -203.397085)
			(xy 20.541547 -203.346155) (xy 20.533604 -203.293451) (xy 6.80339 -203.293451) (xy 6.80339 -204.143335)
			(xy 16.433536 -204.143335) (xy 16.433536 -204.090037) (xy 16.441479 -204.037333) (xy 16.457189 -203.986403)
			(xy 16.480315 -203.938382) (xy 16.510339 -203.894345) (xy 16.546591 -203.855274) (xy 16.588262 -203.822043)
			(xy 16.63442 -203.795394) (xy 16.684034 -203.775922) (xy 16.735996 -203.764062) (xy 16.789146 -203.760079)
			(xy 16.842296 -203.764062) (xy 16.894258 -203.775922) (xy 16.943872 -203.795394) (xy 16.99003 -203.822043)
			(xy 17.031701 -203.855274) (xy 17.067953 -203.894345) (xy 17.097977 -203.938382) (xy 17.121103 -203.986403)
			(xy 17.136813 -204.037333) (xy 17.144756 -204.090037) (xy 17.145254 -204.116686) (xy 17.144756 -204.143335)
			(xy 31.521136 -204.143335) (xy 31.521136 -204.090037) (xy 31.529079 -204.037333) (xy 31.544789 -203.986403)
			(xy 31.567915 -203.938382) (xy 31.597939 -203.894345) (xy 31.634191 -203.855274) (xy 31.675862 -203.822043)
			(xy 31.72202 -203.795394) (xy 31.771634 -203.775922) (xy 31.823596 -203.764062) (xy 31.876746 -203.760079)
			(xy 31.929896 -203.764062) (xy 31.981858 -203.775922) (xy 32.031472 -203.795394) (xy 32.07763 -203.822043)
			(xy 32.119301 -203.855274) (xy 32.155553 -203.894345) (xy 32.185577 -203.938382) (xy 32.208703 -203.986403)
			(xy 32.224413 -204.037333) (xy 32.232356 -204.090037) (xy 32.232854 -204.116686) (xy 32.232356 -204.143335)
			(xy 46.608736 -204.143335) (xy 46.608736 -204.090037) (xy 46.616679 -204.037333) (xy 46.632389 -203.986403)
			(xy 46.655515 -203.938382) (xy 46.685539 -203.894345) (xy 46.721791 -203.855274) (xy 46.763462 -203.822043)
			(xy 46.80962 -203.795394) (xy 46.859234 -203.775922) (xy 46.911196 -203.764062) (xy 46.964346 -203.760079)
			(xy 47.017496 -203.764062) (xy 47.069458 -203.775922) (xy 47.119072 -203.795394) (xy 47.16523 -203.822043)
			(xy 47.206901 -203.855274) (xy 47.243153 -203.894345) (xy 47.273177 -203.938382) (xy 47.296303 -203.986403)
			(xy 47.312013 -204.037333) (xy 47.319956 -204.090037) (xy 47.320454 -204.116686) (xy 47.319956 -204.143335)
			(xy 47.312013 -204.196039) (xy 47.296303 -204.246969) (xy 47.273177 -204.29499) (xy 47.243153 -204.339027)
			(xy 47.206901 -204.378098) (xy 47.16523 -204.411329) (xy 47.119072 -204.437978) (xy 47.069458 -204.45745)
			(xy 47.017496 -204.46931) (xy 46.964346 -204.473294) (xy 46.911196 -204.46931) (xy 46.859234 -204.45745)
			(xy 46.80962 -204.437978) (xy 46.763462 -204.411329) (xy 46.721791 -204.378098) (xy 46.685539 -204.339027)
			(xy 46.655515 -204.29499) (xy 46.632389 -204.246969) (xy 46.616679 -204.196039) (xy 46.608736 -204.143335)
			(xy 32.232356 -204.143335) (xy 32.224413 -204.196039) (xy 32.208703 -204.246969) (xy 32.185577 -204.29499)
			(xy 32.155553 -204.339027) (xy 32.119301 -204.378098) (xy 32.07763 -204.411329) (xy 32.031472 -204.437978)
			(xy 31.981858 -204.45745) (xy 31.929896 -204.46931) (xy 31.876746 -204.473294) (xy 31.823596 -204.46931)
			(xy 31.771634 -204.45745) (xy 31.72202 -204.437978) (xy 31.675862 -204.411329) (xy 31.634191 -204.378098)
			(xy 31.597939 -204.339027) (xy 31.567915 -204.29499) (xy 31.544789 -204.246969) (xy 31.529079 -204.196039)
			(xy 31.521136 -204.143335) (xy 17.144756 -204.143335) (xy 17.136813 -204.196039) (xy 17.121103 -204.246969)
			(xy 17.097977 -204.29499) (xy 17.067953 -204.339027) (xy 17.031701 -204.378098) (xy 16.99003 -204.411329)
			(xy 16.943872 -204.437978) (xy 16.894258 -204.45745) (xy 16.842296 -204.46931) (xy 16.789146 -204.473294)
			(xy 16.735996 -204.46931) (xy 16.684034 -204.45745) (xy 16.63442 -204.437978) (xy 16.588262 -204.411329)
			(xy 16.546591 -204.378098) (xy 16.510339 -204.339027) (xy 16.480315 -204.29499) (xy 16.457189 -204.246969)
			(xy 16.441479 -204.196039) (xy 16.433536 -204.143335) (xy 6.80339 -204.143335) (xy 6.80339 -204.993219)
			(xy 20.533604 -204.993219) (xy 20.533604 -204.939921) (xy 20.541547 -204.887217) (xy 20.557257 -204.836287)
			(xy 20.580383 -204.788266) (xy 20.610407 -204.744229) (xy 20.646659 -204.705158) (xy 20.68833 -204.671927)
			(xy 20.734488 -204.645278) (xy 20.784102 -204.625806) (xy 20.836064 -204.613946) (xy 20.889214 -204.609963)
			(xy 20.942364 -204.613946) (xy 20.994326 -204.625806) (xy 21.04394 -204.645278) (xy 21.090098 -204.671927)
			(xy 21.131769 -204.705158) (xy 21.168021 -204.744229) (xy 21.198045 -204.788266) (xy 21.221171 -204.836287)
			(xy 21.236881 -204.887217) (xy 21.244824 -204.939921) (xy 21.245322 -204.96657) (xy 21.244824 -204.993219)
			(xy 35.621204 -204.993219) (xy 35.621204 -204.939921) (xy 35.629147 -204.887217) (xy 35.644857 -204.836287)
			(xy 35.667983 -204.788266) (xy 35.698007 -204.744229) (xy 35.734259 -204.705158) (xy 35.77593 -204.671927)
			(xy 35.822088 -204.645278) (xy 35.871702 -204.625806) (xy 35.923664 -204.613946) (xy 35.976814 -204.609963)
			(xy 36.029964 -204.613946) (xy 36.081926 -204.625806) (xy 36.13154 -204.645278) (xy 36.177698 -204.671927)
			(xy 36.219369 -204.705158) (xy 36.255621 -204.744229) (xy 36.285645 -204.788266) (xy 36.308771 -204.836287)
			(xy 36.324481 -204.887217) (xy 36.332424 -204.939921) (xy 36.332922 -204.96657) (xy 36.332424 -204.993219)
			(xy 50.708804 -204.993219) (xy 50.708804 -204.939921) (xy 50.716747 -204.887217) (xy 50.732457 -204.836287)
			(xy 50.755583 -204.788266) (xy 50.785607 -204.744229) (xy 50.821859 -204.705158) (xy 50.86353 -204.671927)
			(xy 50.909688 -204.645278) (xy 50.959302 -204.625806) (xy 51.011264 -204.613946) (xy 51.064414 -204.609963)
			(xy 51.117564 -204.613946) (xy 51.169526 -204.625806) (xy 51.21914 -204.645278) (xy 51.265298 -204.671927)
			(xy 51.306969 -204.705158) (xy 51.343221 -204.744229) (xy 51.373245 -204.788266) (xy 51.396371 -204.836287)
			(xy 51.412081 -204.887217) (xy 51.420024 -204.939921) (xy 51.420522 -204.96657) (xy 51.420024 -204.993219)
			(xy 51.412081 -205.045923) (xy 51.396371 -205.096853) (xy 51.373245 -205.144874) (xy 51.343221 -205.188911)
			(xy 51.306969 -205.227982) (xy 51.265298 -205.261213) (xy 51.21914 -205.287862) (xy 51.169526 -205.307334)
			(xy 51.117564 -205.319194) (xy 51.064414 -205.323178) (xy 51.011264 -205.319194) (xy 50.959302 -205.307334)
			(xy 50.909688 -205.287862) (xy 50.86353 -205.261213) (xy 50.821859 -205.227982) (xy 50.785607 -205.188911)
			(xy 50.755583 -205.144874) (xy 50.732457 -205.096853) (xy 50.716747 -205.045923) (xy 50.708804 -204.993219)
			(xy 36.332424 -204.993219) (xy 36.324481 -205.045923) (xy 36.308771 -205.096853) (xy 36.285645 -205.144874)
			(xy 36.255621 -205.188911) (xy 36.219369 -205.227982) (xy 36.177698 -205.261213) (xy 36.13154 -205.287862)
			(xy 36.081926 -205.307334) (xy 36.029964 -205.319194) (xy 35.976814 -205.323178) (xy 35.923664 -205.319194)
			(xy 35.871702 -205.307334) (xy 35.822088 -205.287862) (xy 35.77593 -205.261213) (xy 35.734259 -205.227982)
			(xy 35.698007 -205.188911) (xy 35.667983 -205.144874) (xy 35.644857 -205.096853) (xy 35.629147 -205.045923)
			(xy 35.621204 -204.993219) (xy 21.244824 -204.993219) (xy 21.236881 -205.045923) (xy 21.221171 -205.096853)
			(xy 21.198045 -205.144874) (xy 21.168021 -205.188911) (xy 21.131769 -205.227982) (xy 21.090098 -205.261213)
			(xy 21.04394 -205.287862) (xy 20.994326 -205.307334) (xy 20.942364 -205.319194) (xy 20.889214 -205.323178)
			(xy 20.836064 -205.319194) (xy 20.784102 -205.307334) (xy 20.734488 -205.287862) (xy 20.68833 -205.261213)
			(xy 20.646659 -205.227982) (xy 20.610407 -205.188911) (xy 20.580383 -205.144874) (xy 20.557257 -205.096853)
			(xy 20.541547 -205.045923) (xy 20.533604 -204.993219) (xy 6.80339 -204.993219) (xy 6.80339 -205.843357)
			(xy 16.433536 -205.843357) (xy 16.433536 -205.790059) (xy 16.441479 -205.737355) (xy 16.457189 -205.686425)
			(xy 16.480315 -205.638404) (xy 16.510339 -205.594367) (xy 16.546591 -205.555296) (xy 16.588262 -205.522065)
			(xy 16.63442 -205.495416) (xy 16.684034 -205.475944) (xy 16.735996 -205.464084) (xy 16.789146 -205.460101)
			(xy 16.842296 -205.464084) (xy 16.894258 -205.475944) (xy 16.943872 -205.495416) (xy 16.99003 -205.522065)
			(xy 17.031701 -205.555296) (xy 17.067953 -205.594367) (xy 17.097977 -205.638404) (xy 17.121103 -205.686425)
			(xy 17.136813 -205.737355) (xy 17.144756 -205.790059) (xy 17.145254 -205.816708) (xy 17.144756 -205.843357)
			(xy 31.521136 -205.843357) (xy 31.521136 -205.790059) (xy 31.529079 -205.737355) (xy 31.544789 -205.686425)
			(xy 31.567915 -205.638404) (xy 31.597939 -205.594367) (xy 31.634191 -205.555296) (xy 31.675862 -205.522065)
			(xy 31.72202 -205.495416) (xy 31.771634 -205.475944) (xy 31.823596 -205.464084) (xy 31.876746 -205.460101)
			(xy 31.929896 -205.464084) (xy 31.981858 -205.475944) (xy 32.031472 -205.495416) (xy 32.07763 -205.522065)
			(xy 32.119301 -205.555296) (xy 32.155553 -205.594367) (xy 32.185577 -205.638404) (xy 32.208703 -205.686425)
			(xy 32.224413 -205.737355) (xy 32.232356 -205.790059) (xy 32.232854 -205.816708) (xy 32.232356 -205.843357)
			(xy 46.608736 -205.843357) (xy 46.608736 -205.790059) (xy 46.616679 -205.737355) (xy 46.632389 -205.686425)
			(xy 46.655515 -205.638404) (xy 46.685539 -205.594367) (xy 46.721791 -205.555296) (xy 46.763462 -205.522065)
			(xy 46.80962 -205.495416) (xy 46.859234 -205.475944) (xy 46.911196 -205.464084) (xy 46.964346 -205.460101)
			(xy 47.017496 -205.464084) (xy 47.069458 -205.475944) (xy 47.119072 -205.495416) (xy 47.16523 -205.522065)
			(xy 47.206901 -205.555296) (xy 47.243153 -205.594367) (xy 47.273177 -205.638404) (xy 47.296303 -205.686425)
			(xy 47.312013 -205.737355) (xy 47.319956 -205.790059) (xy 47.320454 -205.816708) (xy 47.319956 -205.843357)
			(xy 47.312013 -205.896061) (xy 47.296303 -205.946991) (xy 47.273177 -205.995012) (xy 47.243153 -206.039049)
			(xy 47.206901 -206.07812) (xy 47.16523 -206.111351) (xy 47.119072 -206.138) (xy 47.069458 -206.157472)
			(xy 47.017496 -206.169332) (xy 46.964346 -206.173316) (xy 46.911196 -206.169332) (xy 46.859234 -206.157472)
			(xy 46.80962 -206.138) (xy 46.763462 -206.111351) (xy 46.721791 -206.07812) (xy 46.685539 -206.039049)
			(xy 46.655515 -205.995012) (xy 46.632389 -205.946991) (xy 46.616679 -205.896061) (xy 46.608736 -205.843357)
			(xy 32.232356 -205.843357) (xy 32.224413 -205.896061) (xy 32.208703 -205.946991) (xy 32.185577 -205.995012)
			(xy 32.155553 -206.039049) (xy 32.119301 -206.07812) (xy 32.07763 -206.111351) (xy 32.031472 -206.138)
			(xy 31.981858 -206.157472) (xy 31.929896 -206.169332) (xy 31.876746 -206.173316) (xy 31.823596 -206.169332)
			(xy 31.771634 -206.157472) (xy 31.72202 -206.138) (xy 31.675862 -206.111351) (xy 31.634191 -206.07812)
			(xy 31.597939 -206.039049) (xy 31.567915 -205.995012) (xy 31.544789 -205.946991) (xy 31.529079 -205.896061)
			(xy 31.521136 -205.843357) (xy 17.144756 -205.843357) (xy 17.136813 -205.896061) (xy 17.121103 -205.946991)
			(xy 17.097977 -205.995012) (xy 17.067953 -206.039049) (xy 17.031701 -206.07812) (xy 16.99003 -206.111351)
			(xy 16.943872 -206.138) (xy 16.894258 -206.157472) (xy 16.842296 -206.169332) (xy 16.789146 -206.173316)
			(xy 16.735996 -206.169332) (xy 16.684034 -206.157472) (xy 16.63442 -206.138) (xy 16.588262 -206.111351)
			(xy 16.546591 -206.07812) (xy 16.510339 -206.039049) (xy 16.480315 -205.995012) (xy 16.457189 -205.946991)
			(xy 16.441479 -205.896061) (xy 16.433536 -205.843357) (xy 6.80339 -205.843357) (xy 6.80339 -206.693241)
			(xy 20.533604 -206.693241) (xy 20.533604 -206.639943) (xy 20.541547 -206.587239) (xy 20.557257 -206.536309)
			(xy 20.580383 -206.488288) (xy 20.610407 -206.444251) (xy 20.646659 -206.40518) (xy 20.68833 -206.371949)
			(xy 20.734488 -206.3453) (xy 20.784102 -206.325828) (xy 20.836064 -206.313968) (xy 20.889214 -206.309985)
			(xy 20.942364 -206.313968) (xy 20.994326 -206.325828) (xy 21.04394 -206.3453) (xy 21.090098 -206.371949)
			(xy 21.131769 -206.40518) (xy 21.168021 -206.444251) (xy 21.198045 -206.488288) (xy 21.221171 -206.536309)
			(xy 21.236881 -206.587239) (xy 21.244824 -206.639943) (xy 21.245322 -206.666592) (xy 21.244824 -206.693241)
			(xy 35.621204 -206.693241) (xy 35.621204 -206.639943) (xy 35.629147 -206.587239) (xy 35.644857 -206.536309)
			(xy 35.667983 -206.488288) (xy 35.698007 -206.444251) (xy 35.734259 -206.40518) (xy 35.77593 -206.371949)
			(xy 35.822088 -206.3453) (xy 35.871702 -206.325828) (xy 35.923664 -206.313968) (xy 35.976814 -206.309985)
			(xy 36.029964 -206.313968) (xy 36.081926 -206.325828) (xy 36.13154 -206.3453) (xy 36.177698 -206.371949)
			(xy 36.219369 -206.40518) (xy 36.255621 -206.444251) (xy 36.285645 -206.488288) (xy 36.308771 -206.536309)
			(xy 36.324481 -206.587239) (xy 36.332424 -206.639943) (xy 36.332922 -206.666592) (xy 36.332424 -206.693241)
			(xy 50.708804 -206.693241) (xy 50.708804 -206.639943) (xy 50.716747 -206.587239) (xy 50.732457 -206.536309)
			(xy 50.755583 -206.488288) (xy 50.785607 -206.444251) (xy 50.821859 -206.40518) (xy 50.86353 -206.371949)
			(xy 50.909688 -206.3453) (xy 50.959302 -206.325828) (xy 51.011264 -206.313968) (xy 51.064414 -206.309985)
			(xy 51.117564 -206.313968) (xy 51.169526 -206.325828) (xy 51.21914 -206.3453) (xy 51.265298 -206.371949)
			(xy 51.306969 -206.40518) (xy 51.343221 -206.444251) (xy 51.373245 -206.488288) (xy 51.396371 -206.536309)
			(xy 51.412081 -206.587239) (xy 51.420024 -206.639943) (xy 51.420522 -206.666592) (xy 51.420024 -206.693241)
			(xy 51.412081 -206.745945) (xy 51.396371 -206.796875) (xy 51.373245 -206.844896) (xy 51.343221 -206.888933)
			(xy 51.306969 -206.928004) (xy 51.265298 -206.961235) (xy 51.21914 -206.987884) (xy 51.169526 -207.007356)
			(xy 51.117564 -207.019216) (xy 51.064414 -207.0232) (xy 51.011264 -207.019216) (xy 50.959302 -207.007356)
			(xy 50.909688 -206.987884) (xy 50.86353 -206.961235) (xy 50.821859 -206.928004) (xy 50.785607 -206.888933)
			(xy 50.755583 -206.844896) (xy 50.732457 -206.796875) (xy 50.716747 -206.745945) (xy 50.708804 -206.693241)
			(xy 36.332424 -206.693241) (xy 36.324481 -206.745945) (xy 36.308771 -206.796875) (xy 36.285645 -206.844896)
			(xy 36.255621 -206.888933) (xy 36.219369 -206.928004) (xy 36.177698 -206.961235) (xy 36.13154 -206.987884)
			(xy 36.081926 -207.007356) (xy 36.029964 -207.019216) (xy 35.976814 -207.0232) (xy 35.923664 -207.019216)
			(xy 35.871702 -207.007356) (xy 35.822088 -206.987884) (xy 35.77593 -206.961235) (xy 35.734259 -206.928004)
			(xy 35.698007 -206.888933) (xy 35.667983 -206.844896) (xy 35.644857 -206.796875) (xy 35.629147 -206.745945)
			(xy 35.621204 -206.693241) (xy 21.244824 -206.693241) (xy 21.236881 -206.745945) (xy 21.221171 -206.796875)
			(xy 21.198045 -206.844896) (xy 21.168021 -206.888933) (xy 21.131769 -206.928004) (xy 21.090098 -206.961235)
			(xy 21.04394 -206.987884) (xy 20.994326 -207.007356) (xy 20.942364 -207.019216) (xy 20.889214 -207.0232)
			(xy 20.836064 -207.019216) (xy 20.784102 -207.007356) (xy 20.734488 -206.987884) (xy 20.68833 -206.961235)
			(xy 20.646659 -206.928004) (xy 20.610407 -206.888933) (xy 20.580383 -206.844896) (xy 20.557257 -206.796875)
			(xy 20.541547 -206.745945) (xy 20.533604 -206.693241) (xy 6.80339 -206.693241) (xy 6.80339 -207.543379)
			(xy 16.433536 -207.543379) (xy 16.433536 -207.490081) (xy 16.441479 -207.437377) (xy 16.457189 -207.386447)
			(xy 16.480315 -207.338426) (xy 16.510339 -207.294389) (xy 16.546591 -207.255318) (xy 16.588262 -207.222087)
			(xy 16.63442 -207.195438) (xy 16.684034 -207.175966) (xy 16.735996 -207.164106) (xy 16.789146 -207.160123)
			(xy 16.842296 -207.164106) (xy 16.894258 -207.175966) (xy 16.943872 -207.195438) (xy 16.99003 -207.222087)
			(xy 17.031701 -207.255318) (xy 17.067953 -207.294389) (xy 17.097977 -207.338426) (xy 17.121103 -207.386447)
			(xy 17.136813 -207.437377) (xy 17.144756 -207.490081) (xy 17.145254 -207.51673) (xy 17.144756 -207.543379)
			(xy 31.521136 -207.543379) (xy 31.521136 -207.490081) (xy 31.529079 -207.437377) (xy 31.544789 -207.386447)
			(xy 31.567915 -207.338426) (xy 31.597939 -207.294389) (xy 31.634191 -207.255318) (xy 31.675862 -207.222087)
			(xy 31.72202 -207.195438) (xy 31.771634 -207.175966) (xy 31.823596 -207.164106) (xy 31.876746 -207.160123)
			(xy 31.929896 -207.164106) (xy 31.981858 -207.175966) (xy 32.031472 -207.195438) (xy 32.07763 -207.222087)
			(xy 32.119301 -207.255318) (xy 32.155553 -207.294389) (xy 32.185577 -207.338426) (xy 32.208703 -207.386447)
			(xy 32.224413 -207.437377) (xy 32.232356 -207.490081) (xy 32.232854 -207.51673) (xy 32.232356 -207.543379)
			(xy 46.608736 -207.543379) (xy 46.608736 -207.490081) (xy 46.616679 -207.437377) (xy 46.632389 -207.386447)
			(xy 46.655515 -207.338426) (xy 46.685539 -207.294389) (xy 46.721791 -207.255318) (xy 46.763462 -207.222087)
			(xy 46.80962 -207.195438) (xy 46.859234 -207.175966) (xy 46.911196 -207.164106) (xy 46.964346 -207.160123)
			(xy 47.017496 -207.164106) (xy 47.069458 -207.175966) (xy 47.119072 -207.195438) (xy 47.16523 -207.222087)
			(xy 47.206901 -207.255318) (xy 47.243153 -207.294389) (xy 47.273177 -207.338426) (xy 47.296303 -207.386447)
			(xy 47.312013 -207.437377) (xy 47.319956 -207.490081) (xy 47.320454 -207.51673) (xy 47.319956 -207.543379)
			(xy 47.312013 -207.596083) (xy 47.296303 -207.647013) (xy 47.273177 -207.695034) (xy 47.243153 -207.739071)
			(xy 47.206901 -207.778142) (xy 47.16523 -207.811373) (xy 47.119072 -207.838022) (xy 47.069458 -207.857494)
			(xy 47.017496 -207.869354) (xy 46.964346 -207.873338) (xy 46.911196 -207.869354) (xy 46.859234 -207.857494)
			(xy 46.80962 -207.838022) (xy 46.763462 -207.811373) (xy 46.721791 -207.778142) (xy 46.685539 -207.739071)
			(xy 46.655515 -207.695034) (xy 46.632389 -207.647013) (xy 46.616679 -207.596083) (xy 46.608736 -207.543379)
			(xy 32.232356 -207.543379) (xy 32.224413 -207.596083) (xy 32.208703 -207.647013) (xy 32.185577 -207.695034)
			(xy 32.155553 -207.739071) (xy 32.119301 -207.778142) (xy 32.07763 -207.811373) (xy 32.031472 -207.838022)
			(xy 31.981858 -207.857494) (xy 31.929896 -207.869354) (xy 31.876746 -207.873338) (xy 31.823596 -207.869354)
			(xy 31.771634 -207.857494) (xy 31.72202 -207.838022) (xy 31.675862 -207.811373) (xy 31.634191 -207.778142)
			(xy 31.597939 -207.739071) (xy 31.567915 -207.695034) (xy 31.544789 -207.647013) (xy 31.529079 -207.596083)
			(xy 31.521136 -207.543379) (xy 17.144756 -207.543379) (xy 17.136813 -207.596083) (xy 17.121103 -207.647013)
			(xy 17.097977 -207.695034) (xy 17.067953 -207.739071) (xy 17.031701 -207.778142) (xy 16.99003 -207.811373)
			(xy 16.943872 -207.838022) (xy 16.894258 -207.857494) (xy 16.842296 -207.869354) (xy 16.789146 -207.873338)
			(xy 16.735996 -207.869354) (xy 16.684034 -207.857494) (xy 16.63442 -207.838022) (xy 16.588262 -207.811373)
			(xy 16.546591 -207.778142) (xy 16.510339 -207.739071) (xy 16.480315 -207.695034) (xy 16.457189 -207.647013)
			(xy 16.441479 -207.596083) (xy 16.433536 -207.543379) (xy 6.80339 -207.543379) (xy 6.80339 -208.393263)
			(xy 20.533604 -208.393263) (xy 20.533604 -208.339965) (xy 20.541547 -208.287261) (xy 20.557257 -208.236331)
			(xy 20.580383 -208.18831) (xy 20.610407 -208.144273) (xy 20.646659 -208.105202) (xy 20.68833 -208.071971)
			(xy 20.734488 -208.045322) (xy 20.784102 -208.02585) (xy 20.836064 -208.01399) (xy 20.889214 -208.010007)
			(xy 20.942364 -208.01399) (xy 20.994326 -208.02585) (xy 21.04394 -208.045322) (xy 21.090098 -208.071971)
			(xy 21.131769 -208.105202) (xy 21.168021 -208.144273) (xy 21.198045 -208.18831) (xy 21.221171 -208.236331)
			(xy 21.236881 -208.287261) (xy 21.244824 -208.339965) (xy 21.245322 -208.366614) (xy 21.244824 -208.393263)
			(xy 35.621204 -208.393263) (xy 35.621204 -208.339965) (xy 35.629147 -208.287261) (xy 35.644857 -208.236331)
			(xy 35.667983 -208.18831) (xy 35.698007 -208.144273) (xy 35.734259 -208.105202) (xy 35.77593 -208.071971)
			(xy 35.822088 -208.045322) (xy 35.871702 -208.02585) (xy 35.923664 -208.01399) (xy 35.976814 -208.010007)
			(xy 36.029964 -208.01399) (xy 36.081926 -208.02585) (xy 36.13154 -208.045322) (xy 36.177698 -208.071971)
			(xy 36.219369 -208.105202) (xy 36.255621 -208.144273) (xy 36.285645 -208.18831) (xy 36.308771 -208.236331)
			(xy 36.324481 -208.287261) (xy 36.332424 -208.339965) (xy 36.332922 -208.366614) (xy 36.332424 -208.393263)
			(xy 50.708804 -208.393263) (xy 50.708804 -208.339965) (xy 50.716747 -208.287261) (xy 50.732457 -208.236331)
			(xy 50.755583 -208.18831) (xy 50.785607 -208.144273) (xy 50.821859 -208.105202) (xy 50.86353 -208.071971)
			(xy 50.909688 -208.045322) (xy 50.959302 -208.02585) (xy 51.011264 -208.01399) (xy 51.064414 -208.010007)
			(xy 51.117564 -208.01399) (xy 51.169526 -208.02585) (xy 51.21914 -208.045322) (xy 51.265298 -208.071971)
			(xy 51.306969 -208.105202) (xy 51.343221 -208.144273) (xy 51.373245 -208.18831) (xy 51.396371 -208.236331)
			(xy 51.412081 -208.287261) (xy 51.420024 -208.339965) (xy 51.420522 -208.366614) (xy 51.420024 -208.393263)
			(xy 51.412081 -208.445967) (xy 51.396371 -208.496897) (xy 51.373245 -208.544918) (xy 51.343221 -208.588955)
			(xy 51.306969 -208.628026) (xy 51.265298 -208.661257) (xy 51.21914 -208.687906) (xy 51.169526 -208.707378)
			(xy 51.117564 -208.719238) (xy 51.064414 -208.723222) (xy 51.011264 -208.719238) (xy 50.959302 -208.707378)
			(xy 50.909688 -208.687906) (xy 50.86353 -208.661257) (xy 50.821859 -208.628026) (xy 50.785607 -208.588955)
			(xy 50.755583 -208.544918) (xy 50.732457 -208.496897) (xy 50.716747 -208.445967) (xy 50.708804 -208.393263)
			(xy 36.332424 -208.393263) (xy 36.324481 -208.445967) (xy 36.308771 -208.496897) (xy 36.285645 -208.544918)
			(xy 36.255621 -208.588955) (xy 36.219369 -208.628026) (xy 36.177698 -208.661257) (xy 36.13154 -208.687906)
			(xy 36.081926 -208.707378) (xy 36.029964 -208.719238) (xy 35.976814 -208.723222) (xy 35.923664 -208.719238)
			(xy 35.871702 -208.707378) (xy 35.822088 -208.687906) (xy 35.77593 -208.661257) (xy 35.734259 -208.628026)
			(xy 35.698007 -208.588955) (xy 35.667983 -208.544918) (xy 35.644857 -208.496897) (xy 35.629147 -208.445967)
			(xy 35.621204 -208.393263) (xy 21.244824 -208.393263) (xy 21.236881 -208.445967) (xy 21.221171 -208.496897)
			(xy 21.198045 -208.544918) (xy 21.168021 -208.588955) (xy 21.131769 -208.628026) (xy 21.090098 -208.661257)
			(xy 21.04394 -208.687906) (xy 20.994326 -208.707378) (xy 20.942364 -208.719238) (xy 20.889214 -208.723222)
			(xy 20.836064 -208.719238) (xy 20.784102 -208.707378) (xy 20.734488 -208.687906) (xy 20.68833 -208.661257)
			(xy 20.646659 -208.628026) (xy 20.610407 -208.588955) (xy 20.580383 -208.544918) (xy 20.557257 -208.496897)
			(xy 20.541547 -208.445967) (xy 20.533604 -208.393263) (xy 6.80339 -208.393263) (xy 6.80339 -209.243401)
			(xy 16.433536 -209.243401) (xy 16.433536 -209.190103) (xy 16.441479 -209.137399) (xy 16.457189 -209.086469)
			(xy 16.480315 -209.038448) (xy 16.510339 -208.994411) (xy 16.546591 -208.95534) (xy 16.588262 -208.922109)
			(xy 16.63442 -208.89546) (xy 16.684034 -208.875988) (xy 16.735996 -208.864128) (xy 16.789146 -208.860145)
			(xy 16.842296 -208.864128) (xy 16.894258 -208.875988) (xy 16.943872 -208.89546) (xy 16.99003 -208.922109)
			(xy 17.031701 -208.95534) (xy 17.067953 -208.994411) (xy 17.097977 -209.038448) (xy 17.121103 -209.086469)
			(xy 17.136813 -209.137399) (xy 17.144756 -209.190103) (xy 17.145254 -209.216752) (xy 17.144756 -209.243401)
			(xy 20.533604 -209.243401) (xy 20.533604 -209.190103) (xy 20.541547 -209.137399) (xy 20.557257 -209.086469)
			(xy 20.580383 -209.038448) (xy 20.610407 -208.994411) (xy 20.646659 -208.95534) (xy 20.68833 -208.922109)
			(xy 20.734488 -208.89546) (xy 20.784102 -208.875988) (xy 20.836064 -208.864128) (xy 20.889214 -208.860145)
			(xy 20.942364 -208.864128) (xy 20.994326 -208.875988) (xy 21.04394 -208.89546) (xy 21.090098 -208.922109)
			(xy 21.131769 -208.95534) (xy 21.168021 -208.994411) (xy 21.198045 -209.038448) (xy 21.221171 -209.086469)
			(xy 21.236881 -209.137399) (xy 21.244824 -209.190103) (xy 21.245322 -209.216752) (xy 21.244824 -209.243401)
			(xy 31.521136 -209.243401) (xy 31.521136 -209.190103) (xy 31.529079 -209.137399) (xy 31.544789 -209.086469)
			(xy 31.567915 -209.038448) (xy 31.597939 -208.994411) (xy 31.634191 -208.95534) (xy 31.675862 -208.922109)
			(xy 31.72202 -208.89546) (xy 31.771634 -208.875988) (xy 31.823596 -208.864128) (xy 31.876746 -208.860145)
			(xy 31.929896 -208.864128) (xy 31.981858 -208.875988) (xy 32.031472 -208.89546) (xy 32.07763 -208.922109)
			(xy 32.119301 -208.95534) (xy 32.155553 -208.994411) (xy 32.185577 -209.038448) (xy 32.208703 -209.086469)
			(xy 32.224413 -209.137399) (xy 32.232356 -209.190103) (xy 32.232854 -209.216752) (xy 32.232356 -209.243401)
			(xy 35.621204 -209.243401) (xy 35.621204 -209.190103) (xy 35.629147 -209.137399) (xy 35.644857 -209.086469)
			(xy 35.667983 -209.038448) (xy 35.698007 -208.994411) (xy 35.734259 -208.95534) (xy 35.77593 -208.922109)
			(xy 35.822088 -208.89546) (xy 35.871702 -208.875988) (xy 35.923664 -208.864128) (xy 35.976814 -208.860145)
			(xy 36.029964 -208.864128) (xy 36.081926 -208.875988) (xy 36.13154 -208.89546) (xy 36.177698 -208.922109)
			(xy 36.219369 -208.95534) (xy 36.255621 -208.994411) (xy 36.285645 -209.038448) (xy 36.308771 -209.086469)
			(xy 36.324481 -209.137399) (xy 36.332424 -209.190103) (xy 36.332922 -209.216752) (xy 36.332424 -209.243401)
			(xy 46.608736 -209.243401) (xy 46.608736 -209.190103) (xy 46.616679 -209.137399) (xy 46.632389 -209.086469)
			(xy 46.655515 -209.038448) (xy 46.685539 -208.994411) (xy 46.721791 -208.95534) (xy 46.763462 -208.922109)
			(xy 46.80962 -208.89546) (xy 46.859234 -208.875988) (xy 46.911196 -208.864128) (xy 46.964346 -208.860145)
			(xy 47.017496 -208.864128) (xy 47.069458 -208.875988) (xy 47.119072 -208.89546) (xy 47.16523 -208.922109)
			(xy 47.206901 -208.95534) (xy 47.243153 -208.994411) (xy 47.273177 -209.038448) (xy 47.296303 -209.086469)
			(xy 47.312013 -209.137399) (xy 47.319956 -209.190103) (xy 47.320454 -209.216752) (xy 47.319956 -209.243401)
			(xy 50.708804 -209.243401) (xy 50.708804 -209.190103) (xy 50.716747 -209.137399) (xy 50.732457 -209.086469)
			(xy 50.755583 -209.038448) (xy 50.785607 -208.994411) (xy 50.821859 -208.95534) (xy 50.86353 -208.922109)
			(xy 50.909688 -208.89546) (xy 50.959302 -208.875988) (xy 51.011264 -208.864128) (xy 51.064414 -208.860145)
			(xy 51.117564 -208.864128) (xy 51.169526 -208.875988) (xy 51.21914 -208.89546) (xy 51.265298 -208.922109)
			(xy 51.306969 -208.95534) (xy 51.343221 -208.994411) (xy 51.373245 -209.038448) (xy 51.396371 -209.086469)
			(xy 51.412081 -209.137399) (xy 51.420024 -209.190103) (xy 51.420522 -209.216752) (xy 51.420024 -209.243401)
			(xy 51.412081 -209.296105) (xy 51.396371 -209.347035) (xy 51.373245 -209.395056) (xy 51.343221 -209.439093)
			(xy 51.306969 -209.478164) (xy 51.265298 -209.511395) (xy 51.21914 -209.538044) (xy 51.169526 -209.557516)
			(xy 51.117564 -209.569376) (xy 51.064414 -209.57336) (xy 51.011264 -209.569376) (xy 50.959302 -209.557516)
			(xy 50.909688 -209.538044) (xy 50.86353 -209.511395) (xy 50.821859 -209.478164) (xy 50.785607 -209.439093)
			(xy 50.755583 -209.395056) (xy 50.732457 -209.347035) (xy 50.716747 -209.296105) (xy 50.708804 -209.243401)
			(xy 47.319956 -209.243401) (xy 47.312013 -209.296105) (xy 47.296303 -209.347035) (xy 47.273177 -209.395056)
			(xy 47.243153 -209.439093) (xy 47.206901 -209.478164) (xy 47.16523 -209.511395) (xy 47.119072 -209.538044)
			(xy 47.069458 -209.557516) (xy 47.017496 -209.569376) (xy 46.964346 -209.57336) (xy 46.911196 -209.569376)
			(xy 46.859234 -209.557516) (xy 46.80962 -209.538044) (xy 46.763462 -209.511395) (xy 46.721791 -209.478164)
			(xy 46.685539 -209.439093) (xy 46.655515 -209.395056) (xy 46.632389 -209.347035) (xy 46.616679 -209.296105)
			(xy 46.608736 -209.243401) (xy 36.332424 -209.243401) (xy 36.324481 -209.296105) (xy 36.308771 -209.347035)
			(xy 36.285645 -209.395056) (xy 36.255621 -209.439093) (xy 36.219369 -209.478164) (xy 36.177698 -209.511395)
			(xy 36.13154 -209.538044) (xy 36.081926 -209.557516) (xy 36.029964 -209.569376) (xy 35.976814 -209.57336)
			(xy 35.923664 -209.569376) (xy 35.871702 -209.557516) (xy 35.822088 -209.538044) (xy 35.77593 -209.511395)
			(xy 35.734259 -209.478164) (xy 35.698007 -209.439093) (xy 35.667983 -209.395056) (xy 35.644857 -209.347035)
			(xy 35.629147 -209.296105) (xy 35.621204 -209.243401) (xy 32.232356 -209.243401) (xy 32.224413 -209.296105)
			(xy 32.208703 -209.347035) (xy 32.185577 -209.395056) (xy 32.155553 -209.439093) (xy 32.119301 -209.478164)
			(xy 32.07763 -209.511395) (xy 32.031472 -209.538044) (xy 31.981858 -209.557516) (xy 31.929896 -209.569376)
			(xy 31.876746 -209.57336) (xy 31.823596 -209.569376) (xy 31.771634 -209.557516) (xy 31.72202 -209.538044)
			(xy 31.675862 -209.511395) (xy 31.634191 -209.478164) (xy 31.597939 -209.439093) (xy 31.567915 -209.395056)
			(xy 31.544789 -209.347035) (xy 31.529079 -209.296105) (xy 31.521136 -209.243401) (xy 21.244824 -209.243401)
			(xy 21.236881 -209.296105) (xy 21.221171 -209.347035) (xy 21.198045 -209.395056) (xy 21.168021 -209.439093)
			(xy 21.131769 -209.478164) (xy 21.090098 -209.511395) (xy 21.04394 -209.538044) (xy 20.994326 -209.557516)
			(xy 20.942364 -209.569376) (xy 20.889214 -209.57336) (xy 20.836064 -209.569376) (xy 20.784102 -209.557516)
			(xy 20.734488 -209.538044) (xy 20.68833 -209.511395) (xy 20.646659 -209.478164) (xy 20.610407 -209.439093)
			(xy 20.580383 -209.395056) (xy 20.557257 -209.347035) (xy 20.541547 -209.296105) (xy 20.533604 -209.243401)
			(xy 17.144756 -209.243401) (xy 17.136813 -209.296105) (xy 17.121103 -209.347035) (xy 17.097977 -209.395056)
			(xy 17.067953 -209.439093) (xy 17.031701 -209.478164) (xy 16.99003 -209.511395) (xy 16.943872 -209.538044)
			(xy 16.894258 -209.557516) (xy 16.842296 -209.569376) (xy 16.789146 -209.57336) (xy 16.735996 -209.569376)
			(xy 16.684034 -209.557516) (xy 16.63442 -209.538044) (xy 16.588262 -209.511395) (xy 16.546591 -209.478164)
			(xy 16.510339 -209.439093) (xy 16.480315 -209.395056) (xy 16.457189 -209.347035) (xy 16.441479 -209.296105)
			(xy 16.433536 -209.243401) (xy 6.80339 -209.243401) (xy 6.80339 -210.093285) (xy 16.433536 -210.093285)
			(xy 16.433536 -210.039987) (xy 16.441479 -209.987283) (xy 16.457189 -209.936353) (xy 16.480315 -209.888332)
			(xy 16.510339 -209.844295) (xy 16.546591 -209.805224) (xy 16.588262 -209.771993) (xy 16.63442 -209.745344)
			(xy 16.684034 -209.725872) (xy 16.735996 -209.714012) (xy 16.789146 -209.710029) (xy 16.842296 -209.714012)
			(xy 16.894258 -209.725872) (xy 16.943872 -209.745344) (xy 16.99003 -209.771993) (xy 17.031701 -209.805224)
			(xy 17.067953 -209.844295) (xy 17.097977 -209.888332) (xy 17.121103 -209.936353) (xy 17.136813 -209.987283)
			(xy 17.144756 -210.039987) (xy 17.145254 -210.066636) (xy 17.144756 -210.093285) (xy 31.521136 -210.093285)
			(xy 31.521136 -210.039987) (xy 31.529079 -209.987283) (xy 31.544789 -209.936353) (xy 31.567915 -209.888332)
			(xy 31.597939 -209.844295) (xy 31.634191 -209.805224) (xy 31.675862 -209.771993) (xy 31.72202 -209.745344)
			(xy 31.771634 -209.725872) (xy 31.823596 -209.714012) (xy 31.876746 -209.710029) (xy 31.929896 -209.714012)
			(xy 31.981858 -209.725872) (xy 32.031472 -209.745344) (xy 32.07763 -209.771993) (xy 32.119301 -209.805224)
			(xy 32.155553 -209.844295) (xy 32.185577 -209.888332) (xy 32.208703 -209.936353) (xy 32.224413 -209.987283)
			(xy 32.232356 -210.039987) (xy 32.232854 -210.066636) (xy 32.232356 -210.093285) (xy 46.608736 -210.093285)
			(xy 46.608736 -210.039987) (xy 46.616679 -209.987283) (xy 46.632389 -209.936353) (xy 46.655515 -209.888332)
			(xy 46.685539 -209.844295) (xy 46.721791 -209.805224) (xy 46.763462 -209.771993) (xy 46.80962 -209.745344)
			(xy 46.859234 -209.725872) (xy 46.911196 -209.714012) (xy 46.964346 -209.710029) (xy 47.017496 -209.714012)
			(xy 47.069458 -209.725872) (xy 47.119072 -209.745344) (xy 47.16523 -209.771993) (xy 47.206901 -209.805224)
			(xy 47.243153 -209.844295) (xy 47.273177 -209.888332) (xy 47.296303 -209.936353) (xy 47.312013 -209.987283)
			(xy 47.319956 -210.039987) (xy 47.320454 -210.066636) (xy 47.319956 -210.093285) (xy 47.312013 -210.145989)
			(xy 47.296303 -210.196919) (xy 47.273177 -210.24494) (xy 47.243153 -210.288977) (xy 47.206901 -210.328048)
			(xy 47.16523 -210.361279) (xy 47.119072 -210.387928) (xy 47.069458 -210.4074) (xy 47.017496 -210.41926)
			(xy 46.964346 -210.423244) (xy 46.911196 -210.41926) (xy 46.859234 -210.4074) (xy 46.80962 -210.387928)
			(xy 46.763462 -210.361279) (xy 46.721791 -210.328048) (xy 46.685539 -210.288977) (xy 46.655515 -210.24494)
			(xy 46.632389 -210.196919) (xy 46.616679 -210.145989) (xy 46.608736 -210.093285) (xy 32.232356 -210.093285)
			(xy 32.224413 -210.145989) (xy 32.208703 -210.196919) (xy 32.185577 -210.24494) (xy 32.155553 -210.288977)
			(xy 32.119301 -210.328048) (xy 32.07763 -210.361279) (xy 32.031472 -210.387928) (xy 31.981858 -210.4074)
			(xy 31.929896 -210.41926) (xy 31.876746 -210.423244) (xy 31.823596 -210.41926) (xy 31.771634 -210.4074)
			(xy 31.72202 -210.387928) (xy 31.675862 -210.361279) (xy 31.634191 -210.328048) (xy 31.597939 -210.288977)
			(xy 31.567915 -210.24494) (xy 31.544789 -210.196919) (xy 31.529079 -210.145989) (xy 31.521136 -210.093285)
			(xy 17.144756 -210.093285) (xy 17.136813 -210.145989) (xy 17.121103 -210.196919) (xy 17.097977 -210.24494)
			(xy 17.067953 -210.288977) (xy 17.031701 -210.328048) (xy 16.99003 -210.361279) (xy 16.943872 -210.387928)
			(xy 16.894258 -210.4074) (xy 16.842296 -210.41926) (xy 16.789146 -210.423244) (xy 16.735996 -210.41926)
			(xy 16.684034 -210.4074) (xy 16.63442 -210.387928) (xy 16.588262 -210.361279) (xy 16.546591 -210.328048)
			(xy 16.510339 -210.288977) (xy 16.480315 -210.24494) (xy 16.457189 -210.196919) (xy 16.441479 -210.145989)
			(xy 16.433536 -210.093285) (xy 6.80339 -210.093285) (xy 6.80339 -210.943423) (xy 20.533604 -210.943423)
			(xy 20.533604 -210.890125) (xy 20.541547 -210.837421) (xy 20.557257 -210.786491) (xy 20.580383 -210.73847)
			(xy 20.610407 -210.694433) (xy 20.646659 -210.655362) (xy 20.68833 -210.622131) (xy 20.734488 -210.595482)
			(xy 20.784102 -210.57601) (xy 20.836064 -210.56415) (xy 20.889214 -210.560167) (xy 20.942364 -210.56415)
			(xy 20.994326 -210.57601) (xy 21.04394 -210.595482) (xy 21.090098 -210.622131) (xy 21.131769 -210.655362)
			(xy 21.168021 -210.694433) (xy 21.198045 -210.73847) (xy 21.221171 -210.786491) (xy 21.236881 -210.837421)
			(xy 21.244824 -210.890125) (xy 21.245322 -210.916774) (xy 21.244824 -210.943423) (xy 35.621204 -210.943423)
			(xy 35.621204 -210.890125) (xy 35.629147 -210.837421) (xy 35.644857 -210.786491) (xy 35.667983 -210.73847)
			(xy 35.698007 -210.694433) (xy 35.734259 -210.655362) (xy 35.77593 -210.622131) (xy 35.822088 -210.595482)
			(xy 35.871702 -210.57601) (xy 35.923664 -210.56415) (xy 35.976814 -210.560167) (xy 36.029964 -210.56415)
			(xy 36.081926 -210.57601) (xy 36.13154 -210.595482) (xy 36.177698 -210.622131) (xy 36.219369 -210.655362)
			(xy 36.255621 -210.694433) (xy 36.285645 -210.73847) (xy 36.308771 -210.786491) (xy 36.324481 -210.837421)
			(xy 36.332424 -210.890125) (xy 36.332922 -210.916774) (xy 36.332424 -210.943423) (xy 50.708804 -210.943423)
			(xy 50.708804 -210.890125) (xy 50.716747 -210.837421) (xy 50.732457 -210.786491) (xy 50.755583 -210.73847)
			(xy 50.785607 -210.694433) (xy 50.821859 -210.655362) (xy 50.86353 -210.622131) (xy 50.909688 -210.595482)
			(xy 50.959302 -210.57601) (xy 51.011264 -210.56415) (xy 51.064414 -210.560167) (xy 51.117564 -210.56415)
			(xy 51.169526 -210.57601) (xy 51.21914 -210.595482) (xy 51.265298 -210.622131) (xy 51.306969 -210.655362)
			(xy 51.343221 -210.694433) (xy 51.373245 -210.73847) (xy 51.396371 -210.786491) (xy 51.412081 -210.837421)
			(xy 51.420024 -210.890125) (xy 51.420522 -210.916774) (xy 51.420024 -210.943423) (xy 51.412081 -210.996127)
			(xy 51.396371 -211.047057) (xy 51.373245 -211.095078) (xy 51.343221 -211.139115) (xy 51.306969 -211.178186)
			(xy 51.265298 -211.211417) (xy 51.21914 -211.238066) (xy 51.169526 -211.257538) (xy 51.117564 -211.269398)
			(xy 51.064414 -211.273382) (xy 51.011264 -211.269398) (xy 50.959302 -211.257538) (xy 50.909688 -211.238066)
			(xy 50.86353 -211.211417) (xy 50.821859 -211.178186) (xy 50.785607 -211.139115) (xy 50.755583 -211.095078)
			(xy 50.732457 -211.047057) (xy 50.716747 -210.996127) (xy 50.708804 -210.943423) (xy 36.332424 -210.943423)
			(xy 36.324481 -210.996127) (xy 36.308771 -211.047057) (xy 36.285645 -211.095078) (xy 36.255621 -211.139115)
			(xy 36.219369 -211.178186) (xy 36.177698 -211.211417) (xy 36.13154 -211.238066) (xy 36.081926 -211.257538)
			(xy 36.029964 -211.269398) (xy 35.976814 -211.273382) (xy 35.923664 -211.269398) (xy 35.871702 -211.257538)
			(xy 35.822088 -211.238066) (xy 35.77593 -211.211417) (xy 35.734259 -211.178186) (xy 35.698007 -211.139115)
			(xy 35.667983 -211.095078) (xy 35.644857 -211.047057) (xy 35.629147 -210.996127) (xy 35.621204 -210.943423)
			(xy 21.244824 -210.943423) (xy 21.236881 -210.996127) (xy 21.221171 -211.047057) (xy 21.198045 -211.095078)
			(xy 21.168021 -211.139115) (xy 21.131769 -211.178186) (xy 21.090098 -211.211417) (xy 21.04394 -211.238066)
			(xy 20.994326 -211.257538) (xy 20.942364 -211.269398) (xy 20.889214 -211.273382) (xy 20.836064 -211.269398)
			(xy 20.784102 -211.257538) (xy 20.734488 -211.238066) (xy 20.68833 -211.211417) (xy 20.646659 -211.178186)
			(xy 20.610407 -211.139115) (xy 20.580383 -211.095078) (xy 20.557257 -211.047057) (xy 20.541547 -210.996127)
			(xy 20.533604 -210.943423) (xy 6.80339 -210.943423) (xy 6.80339 -211.793307) (xy 16.433536 -211.793307)
			(xy 16.433536 -211.740009) (xy 16.441479 -211.687305) (xy 16.457189 -211.636375) (xy 16.480315 -211.588354)
			(xy 16.510339 -211.544317) (xy 16.546591 -211.505246) (xy 16.588262 -211.472015) (xy 16.63442 -211.445366)
			(xy 16.684034 -211.425894) (xy 16.735996 -211.414034) (xy 16.789146 -211.410051) (xy 16.842296 -211.414034)
			(xy 16.894258 -211.425894) (xy 16.943872 -211.445366) (xy 16.99003 -211.472015) (xy 17.031701 -211.505246)
			(xy 17.067953 -211.544317) (xy 17.097977 -211.588354) (xy 17.121103 -211.636375) (xy 17.136813 -211.687305)
			(xy 17.144756 -211.740009) (xy 17.145254 -211.766658) (xy 17.144756 -211.793307) (xy 31.521136 -211.793307)
			(xy 31.521136 -211.740009) (xy 31.529079 -211.687305) (xy 31.544789 -211.636375) (xy 31.567915 -211.588354)
			(xy 31.597939 -211.544317) (xy 31.634191 -211.505246) (xy 31.675862 -211.472015) (xy 31.72202 -211.445366)
			(xy 31.771634 -211.425894) (xy 31.823596 -211.414034) (xy 31.876746 -211.410051) (xy 31.929896 -211.414034)
			(xy 31.981858 -211.425894) (xy 32.031472 -211.445366) (xy 32.07763 -211.472015) (xy 32.119301 -211.505246)
			(xy 32.155553 -211.544317) (xy 32.185577 -211.588354) (xy 32.208703 -211.636375) (xy 32.224413 -211.687305)
			(xy 32.232356 -211.740009) (xy 32.232854 -211.766658) (xy 32.232356 -211.793307) (xy 46.608736 -211.793307)
			(xy 46.608736 -211.740009) (xy 46.616679 -211.687305) (xy 46.632389 -211.636375) (xy 46.655515 -211.588354)
			(xy 46.685539 -211.544317) (xy 46.721791 -211.505246) (xy 46.763462 -211.472015) (xy 46.80962 -211.445366)
			(xy 46.859234 -211.425894) (xy 46.911196 -211.414034) (xy 46.964346 -211.410051) (xy 47.017496 -211.414034)
			(xy 47.069458 -211.425894) (xy 47.119072 -211.445366) (xy 47.16523 -211.472015) (xy 47.206901 -211.505246)
			(xy 47.243153 -211.544317) (xy 47.273177 -211.588354) (xy 47.296303 -211.636375) (xy 47.312013 -211.687305)
			(xy 47.319956 -211.740009) (xy 47.320454 -211.766658) (xy 47.319956 -211.793307) (xy 47.312013 -211.846011)
			(xy 47.296303 -211.896941) (xy 47.273177 -211.944962) (xy 47.243153 -211.988999) (xy 47.206901 -212.02807)
			(xy 47.16523 -212.061301) (xy 47.119072 -212.08795) (xy 47.069458 -212.107422) (xy 47.017496 -212.119282)
			(xy 46.964346 -212.123266) (xy 46.911196 -212.119282) (xy 46.859234 -212.107422) (xy 46.80962 -212.08795)
			(xy 46.763462 -212.061301) (xy 46.721791 -212.02807) (xy 46.685539 -211.988999) (xy 46.655515 -211.944962)
			(xy 46.632389 -211.896941) (xy 46.616679 -211.846011) (xy 46.608736 -211.793307) (xy 32.232356 -211.793307)
			(xy 32.224413 -211.846011) (xy 32.208703 -211.896941) (xy 32.185577 -211.944962) (xy 32.155553 -211.988999)
			(xy 32.119301 -212.02807) (xy 32.07763 -212.061301) (xy 32.031472 -212.08795) (xy 31.981858 -212.107422)
			(xy 31.929896 -212.119282) (xy 31.876746 -212.123266) (xy 31.823596 -212.119282) (xy 31.771634 -212.107422)
			(xy 31.72202 -212.08795) (xy 31.675862 -212.061301) (xy 31.634191 -212.02807) (xy 31.597939 -211.988999)
			(xy 31.567915 -211.944962) (xy 31.544789 -211.896941) (xy 31.529079 -211.846011) (xy 31.521136 -211.793307)
			(xy 17.144756 -211.793307) (xy 17.136813 -211.846011) (xy 17.121103 -211.896941) (xy 17.097977 -211.944962)
			(xy 17.067953 -211.988999) (xy 17.031701 -212.02807) (xy 16.99003 -212.061301) (xy 16.943872 -212.08795)
			(xy 16.894258 -212.107422) (xy 16.842296 -212.119282) (xy 16.789146 -212.123266) (xy 16.735996 -212.119282)
			(xy 16.684034 -212.107422) (xy 16.63442 -212.08795) (xy 16.588262 -212.061301) (xy 16.546591 -212.02807)
			(xy 16.510339 -211.988999) (xy 16.480315 -211.944962) (xy 16.457189 -211.896941) (xy 16.441479 -211.846011)
			(xy 16.433536 -211.793307) (xy 6.80339 -211.793307) (xy 6.80339 -212.643445) (xy 20.533604 -212.643445)
			(xy 20.533604 -212.590147) (xy 20.541547 -212.537443) (xy 20.557257 -212.486513) (xy 20.580383 -212.438492)
			(xy 20.610407 -212.394455) (xy 20.646659 -212.355384) (xy 20.68833 -212.322153) (xy 20.734488 -212.295504)
			(xy 20.784102 -212.276032) (xy 20.836064 -212.264172) (xy 20.889214 -212.260189) (xy 20.942364 -212.264172)
			(xy 20.994326 -212.276032) (xy 21.04394 -212.295504) (xy 21.090098 -212.322153) (xy 21.131769 -212.355384)
			(xy 21.168021 -212.394455) (xy 21.198045 -212.438492) (xy 21.221171 -212.486513) (xy 21.236881 -212.537443)
			(xy 21.244824 -212.590147) (xy 21.245322 -212.616796) (xy 21.244824 -212.643445) (xy 35.621204 -212.643445)
			(xy 35.621204 -212.590147) (xy 35.629147 -212.537443) (xy 35.644857 -212.486513) (xy 35.667983 -212.438492)
			(xy 35.698007 -212.394455) (xy 35.734259 -212.355384) (xy 35.77593 -212.322153) (xy 35.822088 -212.295504)
			(xy 35.871702 -212.276032) (xy 35.923664 -212.264172) (xy 35.976814 -212.260189) (xy 36.029964 -212.264172)
			(xy 36.081926 -212.276032) (xy 36.13154 -212.295504) (xy 36.177698 -212.322153) (xy 36.219369 -212.355384)
			(xy 36.255621 -212.394455) (xy 36.285645 -212.438492) (xy 36.308771 -212.486513) (xy 36.324481 -212.537443)
			(xy 36.332424 -212.590147) (xy 36.332922 -212.616796) (xy 36.332424 -212.643445) (xy 50.708804 -212.643445)
			(xy 50.708804 -212.590147) (xy 50.716747 -212.537443) (xy 50.732457 -212.486513) (xy 50.755583 -212.438492)
			(xy 50.785607 -212.394455) (xy 50.821859 -212.355384) (xy 50.86353 -212.322153) (xy 50.909688 -212.295504)
			(xy 50.959302 -212.276032) (xy 51.011264 -212.264172) (xy 51.064414 -212.260189) (xy 51.117564 -212.264172)
			(xy 51.169526 -212.276032) (xy 51.21914 -212.295504) (xy 51.265298 -212.322153) (xy 51.306969 -212.355384)
			(xy 51.343221 -212.394455) (xy 51.373245 -212.438492) (xy 51.396371 -212.486513) (xy 51.412081 -212.537443)
			(xy 51.420024 -212.590147) (xy 51.420522 -212.616796) (xy 51.420024 -212.643445) (xy 51.412081 -212.696149)
			(xy 51.396371 -212.747079) (xy 51.373245 -212.7951) (xy 51.343221 -212.839137) (xy 51.306969 -212.878208)
			(xy 51.265298 -212.911439) (xy 51.21914 -212.938088) (xy 51.169526 -212.95756) (xy 51.117564 -212.96942)
			(xy 51.064414 -212.973404) (xy 51.011264 -212.96942) (xy 50.959302 -212.95756) (xy 50.909688 -212.938088)
			(xy 50.86353 -212.911439) (xy 50.821859 -212.878208) (xy 50.785607 -212.839137) (xy 50.755583 -212.7951)
			(xy 50.732457 -212.747079) (xy 50.716747 -212.696149) (xy 50.708804 -212.643445) (xy 36.332424 -212.643445)
			(xy 36.324481 -212.696149) (xy 36.308771 -212.747079) (xy 36.285645 -212.7951) (xy 36.255621 -212.839137)
			(xy 36.219369 -212.878208) (xy 36.177698 -212.911439) (xy 36.13154 -212.938088) (xy 36.081926 -212.95756)
			(xy 36.029964 -212.96942) (xy 35.976814 -212.973404) (xy 35.923664 -212.96942) (xy 35.871702 -212.95756)
			(xy 35.822088 -212.938088) (xy 35.77593 -212.911439) (xy 35.734259 -212.878208) (xy 35.698007 -212.839137)
			(xy 35.667983 -212.7951) (xy 35.644857 -212.747079) (xy 35.629147 -212.696149) (xy 35.621204 -212.643445)
			(xy 21.244824 -212.643445) (xy 21.236881 -212.696149) (xy 21.221171 -212.747079) (xy 21.198045 -212.7951)
			(xy 21.168021 -212.839137) (xy 21.131769 -212.878208) (xy 21.090098 -212.911439) (xy 21.04394 -212.938088)
			(xy 20.994326 -212.95756) (xy 20.942364 -212.96942) (xy 20.889214 -212.973404) (xy 20.836064 -212.96942)
			(xy 20.784102 -212.95756) (xy 20.734488 -212.938088) (xy 20.68833 -212.911439) (xy 20.646659 -212.878208)
			(xy 20.610407 -212.839137) (xy 20.580383 -212.7951) (xy 20.557257 -212.747079) (xy 20.541547 -212.696149)
			(xy 20.533604 -212.643445) (xy 6.80339 -212.643445) (xy 6.80339 -213.493329) (xy 16.433536 -213.493329)
			(xy 16.433536 -213.440031) (xy 16.441479 -213.387327) (xy 16.457189 -213.336397) (xy 16.480315 -213.288376)
			(xy 16.510339 -213.244339) (xy 16.546591 -213.205268) (xy 16.588262 -213.172037) (xy 16.63442 -213.145388)
			(xy 16.684034 -213.125916) (xy 16.735996 -213.114056) (xy 16.789146 -213.110073) (xy 16.842296 -213.114056)
			(xy 16.894258 -213.125916) (xy 16.943872 -213.145388) (xy 16.99003 -213.172037) (xy 17.031701 -213.205268)
			(xy 17.067953 -213.244339) (xy 17.097977 -213.288376) (xy 17.121103 -213.336397) (xy 17.136813 -213.387327)
			(xy 17.144756 -213.440031) (xy 17.145254 -213.46668) (xy 17.144756 -213.493329) (xy 31.521136 -213.493329)
			(xy 31.521136 -213.440031) (xy 31.529079 -213.387327) (xy 31.544789 -213.336397) (xy 31.567915 -213.288376)
			(xy 31.597939 -213.244339) (xy 31.634191 -213.205268) (xy 31.675862 -213.172037) (xy 31.72202 -213.145388)
			(xy 31.771634 -213.125916) (xy 31.823596 -213.114056) (xy 31.876746 -213.110073) (xy 31.929896 -213.114056)
			(xy 31.981858 -213.125916) (xy 32.031472 -213.145388) (xy 32.07763 -213.172037) (xy 32.119301 -213.205268)
			(xy 32.155553 -213.244339) (xy 32.185577 -213.288376) (xy 32.208703 -213.336397) (xy 32.224413 -213.387327)
			(xy 32.232356 -213.440031) (xy 32.232854 -213.46668) (xy 32.232356 -213.493329) (xy 46.608736 -213.493329)
			(xy 46.608736 -213.440031) (xy 46.616679 -213.387327) (xy 46.632389 -213.336397) (xy 46.655515 -213.288376)
			(xy 46.685539 -213.244339) (xy 46.721791 -213.205268) (xy 46.763462 -213.172037) (xy 46.80962 -213.145388)
			(xy 46.859234 -213.125916) (xy 46.911196 -213.114056) (xy 46.964346 -213.110073) (xy 47.017496 -213.114056)
			(xy 47.069458 -213.125916) (xy 47.119072 -213.145388) (xy 47.16523 -213.172037) (xy 47.206901 -213.205268)
			(xy 47.243153 -213.244339) (xy 47.273177 -213.288376) (xy 47.296303 -213.336397) (xy 47.312013 -213.387327)
			(xy 47.319956 -213.440031) (xy 47.320454 -213.46668) (xy 47.319956 -213.493329) (xy 47.312013 -213.546033)
			(xy 47.296303 -213.596963) (xy 47.273177 -213.644984) (xy 47.243153 -213.689021) (xy 47.206901 -213.728092)
			(xy 47.16523 -213.761323) (xy 47.119072 -213.787972) (xy 47.069458 -213.807444) (xy 47.017496 -213.819304)
			(xy 46.964346 -213.823288) (xy 46.911196 -213.819304) (xy 46.859234 -213.807444) (xy 46.80962 -213.787972)
			(xy 46.763462 -213.761323) (xy 46.721791 -213.728092) (xy 46.685539 -213.689021) (xy 46.655515 -213.644984)
			(xy 46.632389 -213.596963) (xy 46.616679 -213.546033) (xy 46.608736 -213.493329) (xy 32.232356 -213.493329)
			(xy 32.224413 -213.546033) (xy 32.208703 -213.596963) (xy 32.185577 -213.644984) (xy 32.155553 -213.689021)
			(xy 32.119301 -213.728092) (xy 32.07763 -213.761323) (xy 32.031472 -213.787972) (xy 31.981858 -213.807444)
			(xy 31.929896 -213.819304) (xy 31.876746 -213.823288) (xy 31.823596 -213.819304) (xy 31.771634 -213.807444)
			(xy 31.72202 -213.787972) (xy 31.675862 -213.761323) (xy 31.634191 -213.728092) (xy 31.597939 -213.689021)
			(xy 31.567915 -213.644984) (xy 31.544789 -213.596963) (xy 31.529079 -213.546033) (xy 31.521136 -213.493329)
			(xy 17.144756 -213.493329) (xy 17.136813 -213.546033) (xy 17.121103 -213.596963) (xy 17.097977 -213.644984)
			(xy 17.067953 -213.689021) (xy 17.031701 -213.728092) (xy 16.99003 -213.761323) (xy 16.943872 -213.787972)
			(xy 16.894258 -213.807444) (xy 16.842296 -213.819304) (xy 16.789146 -213.823288) (xy 16.735996 -213.819304)
			(xy 16.684034 -213.807444) (xy 16.63442 -213.787972) (xy 16.588262 -213.761323) (xy 16.546591 -213.728092)
			(xy 16.510339 -213.689021) (xy 16.480315 -213.644984) (xy 16.457189 -213.596963) (xy 16.441479 -213.546033)
			(xy 16.433536 -213.493329) (xy 6.80339 -213.493329) (xy 6.80339 -214.343213) (xy 20.533604 -214.343213)
			(xy 20.533604 -214.289915) (xy 20.541547 -214.237211) (xy 20.557257 -214.186281) (xy 20.580383 -214.13826)
			(xy 20.610407 -214.094223) (xy 20.646659 -214.055152) (xy 20.68833 -214.021921) (xy 20.734488 -213.995272)
			(xy 20.784102 -213.9758) (xy 20.836064 -213.96394) (xy 20.889214 -213.959957) (xy 20.942364 -213.96394)
			(xy 20.994326 -213.9758) (xy 21.04394 -213.995272) (xy 21.090098 -214.021921) (xy 21.131769 -214.055152)
			(xy 21.168021 -214.094223) (xy 21.198045 -214.13826) (xy 21.221171 -214.186281) (xy 21.236881 -214.237211)
			(xy 21.244824 -214.289915) (xy 21.245322 -214.316564) (xy 21.244824 -214.343213) (xy 35.621204 -214.343213)
			(xy 35.621204 -214.289915) (xy 35.629147 -214.237211) (xy 35.644857 -214.186281) (xy 35.667983 -214.13826)
			(xy 35.698007 -214.094223) (xy 35.734259 -214.055152) (xy 35.77593 -214.021921) (xy 35.822088 -213.995272)
			(xy 35.871702 -213.9758) (xy 35.923664 -213.96394) (xy 35.976814 -213.959957) (xy 36.029964 -213.96394)
			(xy 36.081926 -213.9758) (xy 36.13154 -213.995272) (xy 36.177698 -214.021921) (xy 36.219369 -214.055152)
			(xy 36.255621 -214.094223) (xy 36.285645 -214.13826) (xy 36.308771 -214.186281) (xy 36.324481 -214.237211)
			(xy 36.332424 -214.289915) (xy 36.332922 -214.316564) (xy 36.332424 -214.343213) (xy 50.708804 -214.343213)
			(xy 50.708804 -214.289915) (xy 50.716747 -214.237211) (xy 50.732457 -214.186281) (xy 50.755583 -214.13826)
			(xy 50.785607 -214.094223) (xy 50.821859 -214.055152) (xy 50.86353 -214.021921) (xy 50.909688 -213.995272)
			(xy 50.959302 -213.9758) (xy 51.011264 -213.96394) (xy 51.064414 -213.959957) (xy 51.117564 -213.96394)
			(xy 51.169526 -213.9758) (xy 51.21914 -213.995272) (xy 51.265298 -214.021921) (xy 51.306969 -214.055152)
			(xy 51.343221 -214.094223) (xy 51.373245 -214.13826) (xy 51.396371 -214.186281) (xy 51.412081 -214.237211)
			(xy 51.420024 -214.289915) (xy 51.420522 -214.316564) (xy 51.420024 -214.343213) (xy 51.412081 -214.395917)
			(xy 51.396371 -214.446847) (xy 51.373245 -214.494868) (xy 51.343221 -214.538905) (xy 51.306969 -214.577976)
			(xy 51.265298 -214.611207) (xy 51.21914 -214.637856) (xy 51.169526 -214.657328) (xy 51.117564 -214.669188)
			(xy 51.064414 -214.673172) (xy 51.011264 -214.669188) (xy 50.959302 -214.657328) (xy 50.909688 -214.637856)
			(xy 50.86353 -214.611207) (xy 50.821859 -214.577976) (xy 50.785607 -214.538905) (xy 50.755583 -214.494868)
			(xy 50.732457 -214.446847) (xy 50.716747 -214.395917) (xy 50.708804 -214.343213) (xy 36.332424 -214.343213)
			(xy 36.324481 -214.395917) (xy 36.308771 -214.446847) (xy 36.285645 -214.494868) (xy 36.255621 -214.538905)
			(xy 36.219369 -214.577976) (xy 36.177698 -214.611207) (xy 36.13154 -214.637856) (xy 36.081926 -214.657328)
			(xy 36.029964 -214.669188) (xy 35.976814 -214.673172) (xy 35.923664 -214.669188) (xy 35.871702 -214.657328)
			(xy 35.822088 -214.637856) (xy 35.77593 -214.611207) (xy 35.734259 -214.577976) (xy 35.698007 -214.538905)
			(xy 35.667983 -214.494868) (xy 35.644857 -214.446847) (xy 35.629147 -214.395917) (xy 35.621204 -214.343213)
			(xy 21.244824 -214.343213) (xy 21.236881 -214.395917) (xy 21.221171 -214.446847) (xy 21.198045 -214.494868)
			(xy 21.168021 -214.538905) (xy 21.131769 -214.577976) (xy 21.090098 -214.611207) (xy 21.04394 -214.637856)
			(xy 20.994326 -214.657328) (xy 20.942364 -214.669188) (xy 20.889214 -214.673172) (xy 20.836064 -214.669188)
			(xy 20.784102 -214.657328) (xy 20.734488 -214.637856) (xy 20.68833 -214.611207) (xy 20.646659 -214.577976)
			(xy 20.610407 -214.538905) (xy 20.580383 -214.494868) (xy 20.557257 -214.446847) (xy 20.541547 -214.395917)
			(xy 20.533604 -214.343213) (xy 6.80339 -214.343213) (xy 6.80339 -215.193351) (xy 16.433536 -215.193351)
			(xy 16.433536 -215.140053) (xy 16.441479 -215.087349) (xy 16.457189 -215.036419) (xy 16.480315 -214.988398)
			(xy 16.510339 -214.944361) (xy 16.546591 -214.90529) (xy 16.588262 -214.872059) (xy 16.63442 -214.84541)
			(xy 16.684034 -214.825938) (xy 16.735996 -214.814078) (xy 16.789146 -214.810095) (xy 16.842296 -214.814078)
			(xy 16.894258 -214.825938) (xy 16.943872 -214.84541) (xy 16.99003 -214.872059) (xy 17.031701 -214.90529)
			(xy 17.067953 -214.944361) (xy 17.097977 -214.988398) (xy 17.121103 -215.036419) (xy 17.136813 -215.087349)
			(xy 17.144756 -215.140053) (xy 17.145254 -215.166702) (xy 17.144756 -215.193351) (xy 31.521136 -215.193351)
			(xy 31.521136 -215.140053) (xy 31.529079 -215.087349) (xy 31.544789 -215.036419) (xy 31.567915 -214.988398)
			(xy 31.597939 -214.944361) (xy 31.634191 -214.90529) (xy 31.675862 -214.872059) (xy 31.72202 -214.84541)
			(xy 31.771634 -214.825938) (xy 31.823596 -214.814078) (xy 31.876746 -214.810095) (xy 31.929896 -214.814078)
			(xy 31.981858 -214.825938) (xy 32.031472 -214.84541) (xy 32.07763 -214.872059) (xy 32.119301 -214.90529)
			(xy 32.155553 -214.944361) (xy 32.185577 -214.988398) (xy 32.208703 -215.036419) (xy 32.224413 -215.087349)
			(xy 32.232356 -215.140053) (xy 32.232854 -215.166702) (xy 32.232356 -215.193351) (xy 46.608736 -215.193351)
			(xy 46.608736 -215.140053) (xy 46.616679 -215.087349) (xy 46.632389 -215.036419) (xy 46.655515 -214.988398)
			(xy 46.685539 -214.944361) (xy 46.721791 -214.90529) (xy 46.763462 -214.872059) (xy 46.80962 -214.84541)
			(xy 46.859234 -214.825938) (xy 46.911196 -214.814078) (xy 46.964346 -214.810095) (xy 47.017496 -214.814078)
			(xy 47.069458 -214.825938) (xy 47.119072 -214.84541) (xy 47.16523 -214.872059) (xy 47.206901 -214.90529)
			(xy 47.243153 -214.944361) (xy 47.273177 -214.988398) (xy 47.296303 -215.036419) (xy 47.312013 -215.087349)
			(xy 47.319956 -215.140053) (xy 47.320454 -215.166702) (xy 47.319956 -215.193351) (xy 47.312013 -215.246055)
			(xy 47.296303 -215.296985) (xy 47.273177 -215.345006) (xy 47.243153 -215.389043) (xy 47.206901 -215.428114)
			(xy 47.16523 -215.461345) (xy 47.119072 -215.487994) (xy 47.069458 -215.507466) (xy 47.017496 -215.519326)
			(xy 46.964346 -215.52331) (xy 46.911196 -215.519326) (xy 46.859234 -215.507466) (xy 46.80962 -215.487994)
			(xy 46.763462 -215.461345) (xy 46.721791 -215.428114) (xy 46.685539 -215.389043) (xy 46.655515 -215.345006)
			(xy 46.632389 -215.296985) (xy 46.616679 -215.246055) (xy 46.608736 -215.193351) (xy 32.232356 -215.193351)
			(xy 32.224413 -215.246055) (xy 32.208703 -215.296985) (xy 32.185577 -215.345006) (xy 32.155553 -215.389043)
			(xy 32.119301 -215.428114) (xy 32.07763 -215.461345) (xy 32.031472 -215.487994) (xy 31.981858 -215.507466)
			(xy 31.929896 -215.519326) (xy 31.876746 -215.52331) (xy 31.823596 -215.519326) (xy 31.771634 -215.507466)
			(xy 31.72202 -215.487994) (xy 31.675862 -215.461345) (xy 31.634191 -215.428114) (xy 31.597939 -215.389043)
			(xy 31.567915 -215.345006) (xy 31.544789 -215.296985) (xy 31.529079 -215.246055) (xy 31.521136 -215.193351)
			(xy 17.144756 -215.193351) (xy 17.136813 -215.246055) (xy 17.121103 -215.296985) (xy 17.097977 -215.345006)
			(xy 17.067953 -215.389043) (xy 17.031701 -215.428114) (xy 16.99003 -215.461345) (xy 16.943872 -215.487994)
			(xy 16.894258 -215.507466) (xy 16.842296 -215.519326) (xy 16.789146 -215.52331) (xy 16.735996 -215.519326)
			(xy 16.684034 -215.507466) (xy 16.63442 -215.487994) (xy 16.588262 -215.461345) (xy 16.546591 -215.428114)
			(xy 16.510339 -215.389043) (xy 16.480315 -215.345006) (xy 16.457189 -215.296985) (xy 16.441479 -215.246055)
			(xy 16.433536 -215.193351) (xy 6.80339 -215.193351) (xy 6.80339 -216.043235) (xy 20.533604 -216.043235)
			(xy 20.533604 -215.989937) (xy 20.541547 -215.937233) (xy 20.557257 -215.886303) (xy 20.580383 -215.838282)
			(xy 20.610407 -215.794245) (xy 20.646659 -215.755174) (xy 20.68833 -215.721943) (xy 20.734488 -215.695294)
			(xy 20.784102 -215.675822) (xy 20.836064 -215.663962) (xy 20.889214 -215.659979) (xy 20.942364 -215.663962)
			(xy 20.994326 -215.675822) (xy 21.04394 -215.695294) (xy 21.090098 -215.721943) (xy 21.131769 -215.755174)
			(xy 21.168021 -215.794245) (xy 21.198045 -215.838282) (xy 21.221171 -215.886303) (xy 21.236881 -215.937233)
			(xy 21.244824 -215.989937) (xy 21.245322 -216.016586) (xy 21.244824 -216.043235) (xy 35.621204 -216.043235)
			(xy 35.621204 -215.989937) (xy 35.629147 -215.937233) (xy 35.644857 -215.886303) (xy 35.667983 -215.838282)
			(xy 35.698007 -215.794245) (xy 35.734259 -215.755174) (xy 35.77593 -215.721943) (xy 35.822088 -215.695294)
			(xy 35.871702 -215.675822) (xy 35.923664 -215.663962) (xy 35.976814 -215.659979) (xy 36.029964 -215.663962)
			(xy 36.081926 -215.675822) (xy 36.13154 -215.695294) (xy 36.177698 -215.721943) (xy 36.219369 -215.755174)
			(xy 36.255621 -215.794245) (xy 36.285645 -215.838282) (xy 36.308771 -215.886303) (xy 36.324481 -215.937233)
			(xy 36.332424 -215.989937) (xy 36.332922 -216.016586) (xy 36.332424 -216.043235) (xy 50.708804 -216.043235)
			(xy 50.708804 -215.989937) (xy 50.716747 -215.937233) (xy 50.732457 -215.886303) (xy 50.755583 -215.838282)
			(xy 50.785607 -215.794245) (xy 50.821859 -215.755174) (xy 50.86353 -215.721943) (xy 50.909688 -215.695294)
			(xy 50.959302 -215.675822) (xy 51.011264 -215.663962) (xy 51.064414 -215.659979) (xy 51.117564 -215.663962)
			(xy 51.169526 -215.675822) (xy 51.21914 -215.695294) (xy 51.265298 -215.721943) (xy 51.306969 -215.755174)
			(xy 51.343221 -215.794245) (xy 51.373245 -215.838282) (xy 51.396371 -215.886303) (xy 51.412081 -215.937233)
			(xy 51.420024 -215.989937) (xy 51.420522 -216.016586) (xy 51.420024 -216.043235) (xy 51.412081 -216.095939)
			(xy 51.396371 -216.146869) (xy 51.373245 -216.19489) (xy 51.343221 -216.238927) (xy 51.306969 -216.277998)
			(xy 51.265298 -216.311229) (xy 51.21914 -216.337878) (xy 51.169526 -216.35735) (xy 51.117564 -216.36921)
			(xy 51.064414 -216.373194) (xy 51.011264 -216.36921) (xy 50.959302 -216.35735) (xy 50.909688 -216.337878)
			(xy 50.86353 -216.311229) (xy 50.821859 -216.277998) (xy 50.785607 -216.238927) (xy 50.755583 -216.19489)
			(xy 50.732457 -216.146869) (xy 50.716747 -216.095939) (xy 50.708804 -216.043235) (xy 36.332424 -216.043235)
			(xy 36.324481 -216.095939) (xy 36.308771 -216.146869) (xy 36.285645 -216.19489) (xy 36.255621 -216.238927)
			(xy 36.219369 -216.277998) (xy 36.177698 -216.311229) (xy 36.13154 -216.337878) (xy 36.081926 -216.35735)
			(xy 36.029964 -216.36921) (xy 35.976814 -216.373194) (xy 35.923664 -216.36921) (xy 35.871702 -216.35735)
			(xy 35.822088 -216.337878) (xy 35.77593 -216.311229) (xy 35.734259 -216.277998) (xy 35.698007 -216.238927)
			(xy 35.667983 -216.19489) (xy 35.644857 -216.146869) (xy 35.629147 -216.095939) (xy 35.621204 -216.043235)
			(xy 21.244824 -216.043235) (xy 21.236881 -216.095939) (xy 21.221171 -216.146869) (xy 21.198045 -216.19489)
			(xy 21.168021 -216.238927) (xy 21.131769 -216.277998) (xy 21.090098 -216.311229) (xy 21.04394 -216.337878)
			(xy 20.994326 -216.35735) (xy 20.942364 -216.36921) (xy 20.889214 -216.373194) (xy 20.836064 -216.36921)
			(xy 20.784102 -216.35735) (xy 20.734488 -216.337878) (xy 20.68833 -216.311229) (xy 20.646659 -216.277998)
			(xy 20.610407 -216.238927) (xy 20.580383 -216.19489) (xy 20.557257 -216.146869) (xy 20.541547 -216.095939)
			(xy 20.533604 -216.043235) (xy 6.80339 -216.043235) (xy 6.80339 -216.893373) (xy 16.433536 -216.893373)
			(xy 16.433536 -216.840075) (xy 16.441479 -216.787371) (xy 16.457189 -216.736441) (xy 16.480315 -216.68842)
			(xy 16.510339 -216.644383) (xy 16.546591 -216.605312) (xy 16.588262 -216.572081) (xy 16.63442 -216.545432)
			(xy 16.684034 -216.52596) (xy 16.735996 -216.5141) (xy 16.789146 -216.510117) (xy 16.842296 -216.5141)
			(xy 16.894258 -216.52596) (xy 16.943872 -216.545432) (xy 16.99003 -216.572081) (xy 17.031701 -216.605312)
			(xy 17.067953 -216.644383) (xy 17.097977 -216.68842) (xy 17.121103 -216.736441) (xy 17.136813 -216.787371)
			(xy 17.144756 -216.840075) (xy 17.145254 -216.866724) (xy 17.144756 -216.893373) (xy 31.521136 -216.893373)
			(xy 31.521136 -216.840075) (xy 31.529079 -216.787371) (xy 31.544789 -216.736441) (xy 31.567915 -216.68842)
			(xy 31.597939 -216.644383) (xy 31.634191 -216.605312) (xy 31.675862 -216.572081) (xy 31.72202 -216.545432)
			(xy 31.771634 -216.52596) (xy 31.823596 -216.5141) (xy 31.876746 -216.510117) (xy 31.929896 -216.5141)
			(xy 31.981858 -216.52596) (xy 32.031472 -216.545432) (xy 32.07763 -216.572081) (xy 32.119301 -216.605312)
			(xy 32.155553 -216.644383) (xy 32.185577 -216.68842) (xy 32.208703 -216.736441) (xy 32.224413 -216.787371)
			(xy 32.232356 -216.840075) (xy 32.232854 -216.866724) (xy 32.232356 -216.893373) (xy 46.608736 -216.893373)
			(xy 46.608736 -216.840075) (xy 46.616679 -216.787371) (xy 46.632389 -216.736441) (xy 46.655515 -216.68842)
			(xy 46.685539 -216.644383) (xy 46.721791 -216.605312) (xy 46.763462 -216.572081) (xy 46.80962 -216.545432)
			(xy 46.859234 -216.52596) (xy 46.911196 -216.5141) (xy 46.964346 -216.510117) (xy 47.017496 -216.5141)
			(xy 47.069458 -216.52596) (xy 47.119072 -216.545432) (xy 47.16523 -216.572081) (xy 47.206901 -216.605312)
			(xy 47.243153 -216.644383) (xy 47.273177 -216.68842) (xy 47.296303 -216.736441) (xy 47.312013 -216.787371)
			(xy 47.319956 -216.840075) (xy 47.320454 -216.866724) (xy 47.319956 -216.893373) (xy 47.312013 -216.946077)
			(xy 47.296303 -216.997007) (xy 47.273177 -217.045028) (xy 47.243153 -217.089065) (xy 47.206901 -217.128136)
			(xy 47.16523 -217.161367) (xy 47.119072 -217.188016) (xy 47.069458 -217.207488) (xy 47.017496 -217.219348)
			(xy 46.964346 -217.223332) (xy 46.911196 -217.219348) (xy 46.859234 -217.207488) (xy 46.80962 -217.188016)
			(xy 46.763462 -217.161367) (xy 46.721791 -217.128136) (xy 46.685539 -217.089065) (xy 46.655515 -217.045028)
			(xy 46.632389 -216.997007) (xy 46.616679 -216.946077) (xy 46.608736 -216.893373) (xy 32.232356 -216.893373)
			(xy 32.224413 -216.946077) (xy 32.208703 -216.997007) (xy 32.185577 -217.045028) (xy 32.155553 -217.089065)
			(xy 32.119301 -217.128136) (xy 32.07763 -217.161367) (xy 32.031472 -217.188016) (xy 31.981858 -217.207488)
			(xy 31.929896 -217.219348) (xy 31.876746 -217.223332) (xy 31.823596 -217.219348) (xy 31.771634 -217.207488)
			(xy 31.72202 -217.188016) (xy 31.675862 -217.161367) (xy 31.634191 -217.128136) (xy 31.597939 -217.089065)
			(xy 31.567915 -217.045028) (xy 31.544789 -216.997007) (xy 31.529079 -216.946077) (xy 31.521136 -216.893373)
			(xy 17.144756 -216.893373) (xy 17.136813 -216.946077) (xy 17.121103 -216.997007) (xy 17.097977 -217.045028)
			(xy 17.067953 -217.089065) (xy 17.031701 -217.128136) (xy 16.99003 -217.161367) (xy 16.943872 -217.188016)
			(xy 16.894258 -217.207488) (xy 16.842296 -217.219348) (xy 16.789146 -217.223332) (xy 16.735996 -217.219348)
			(xy 16.684034 -217.207488) (xy 16.63442 -217.188016) (xy 16.588262 -217.161367) (xy 16.546591 -217.128136)
			(xy 16.510339 -217.089065) (xy 16.480315 -217.045028) (xy 16.457189 -216.997007) (xy 16.441479 -216.946077)
			(xy 16.433536 -216.893373) (xy 6.80339 -216.893373) (xy 6.80339 -217.743257) (xy 20.533604 -217.743257)
			(xy 20.533604 -217.689959) (xy 20.541547 -217.637255) (xy 20.557257 -217.586325) (xy 20.580383 -217.538304)
			(xy 20.610407 -217.494267) (xy 20.646659 -217.455196) (xy 20.68833 -217.421965) (xy 20.734488 -217.395316)
			(xy 20.784102 -217.375844) (xy 20.836064 -217.363984) (xy 20.889214 -217.360001) (xy 20.942364 -217.363984)
			(xy 20.994326 -217.375844) (xy 21.04394 -217.395316) (xy 21.090098 -217.421965) (xy 21.131769 -217.455196)
			(xy 21.168021 -217.494267) (xy 21.198045 -217.538304) (xy 21.221171 -217.586325) (xy 21.236881 -217.637255)
			(xy 21.244824 -217.689959) (xy 21.245322 -217.716608) (xy 21.244824 -217.743257) (xy 35.621204 -217.743257)
			(xy 35.621204 -217.689959) (xy 35.629147 -217.637255) (xy 35.644857 -217.586325) (xy 35.667983 -217.538304)
			(xy 35.698007 -217.494267) (xy 35.734259 -217.455196) (xy 35.77593 -217.421965) (xy 35.822088 -217.395316)
			(xy 35.871702 -217.375844) (xy 35.923664 -217.363984) (xy 35.976814 -217.360001) (xy 36.029964 -217.363984)
			(xy 36.081926 -217.375844) (xy 36.13154 -217.395316) (xy 36.177698 -217.421965) (xy 36.219369 -217.455196)
			(xy 36.255621 -217.494267) (xy 36.285645 -217.538304) (xy 36.308771 -217.586325) (xy 36.324481 -217.637255)
			(xy 36.332424 -217.689959) (xy 36.332922 -217.716608) (xy 36.332424 -217.743257) (xy 50.708804 -217.743257)
			(xy 50.708804 -217.689959) (xy 50.716747 -217.637255) (xy 50.732457 -217.586325) (xy 50.755583 -217.538304)
			(xy 50.785607 -217.494267) (xy 50.821859 -217.455196) (xy 50.86353 -217.421965) (xy 50.909688 -217.395316)
			(xy 50.959302 -217.375844) (xy 51.011264 -217.363984) (xy 51.064414 -217.360001) (xy 51.117564 -217.363984)
			(xy 51.169526 -217.375844) (xy 51.21914 -217.395316) (xy 51.265298 -217.421965) (xy 51.306969 -217.455196)
			(xy 51.343221 -217.494267) (xy 51.373245 -217.538304) (xy 51.396371 -217.586325) (xy 51.412081 -217.637255)
			(xy 51.420024 -217.689959) (xy 51.420522 -217.716608) (xy 51.420024 -217.743257) (xy 51.412081 -217.795961)
			(xy 51.396371 -217.846891) (xy 51.373245 -217.894912) (xy 51.343221 -217.938949) (xy 51.306969 -217.97802)
			(xy 51.265298 -218.011251) (xy 51.21914 -218.0379) (xy 51.169526 -218.057372) (xy 51.117564 -218.069232)
			(xy 51.064414 -218.073216) (xy 51.011264 -218.069232) (xy 50.959302 -218.057372) (xy 50.909688 -218.0379)
			(xy 50.86353 -218.011251) (xy 50.821859 -217.97802) (xy 50.785607 -217.938949) (xy 50.755583 -217.894912)
			(xy 50.732457 -217.846891) (xy 50.716747 -217.795961) (xy 50.708804 -217.743257) (xy 36.332424 -217.743257)
			(xy 36.324481 -217.795961) (xy 36.308771 -217.846891) (xy 36.285645 -217.894912) (xy 36.255621 -217.938949)
			(xy 36.219369 -217.97802) (xy 36.177698 -218.011251) (xy 36.13154 -218.0379) (xy 36.081926 -218.057372)
			(xy 36.029964 -218.069232) (xy 35.976814 -218.073216) (xy 35.923664 -218.069232) (xy 35.871702 -218.057372)
			(xy 35.822088 -218.0379) (xy 35.77593 -218.011251) (xy 35.734259 -217.97802) (xy 35.698007 -217.938949)
			(xy 35.667983 -217.894912) (xy 35.644857 -217.846891) (xy 35.629147 -217.795961) (xy 35.621204 -217.743257)
			(xy 21.244824 -217.743257) (xy 21.236881 -217.795961) (xy 21.221171 -217.846891) (xy 21.198045 -217.894912)
			(xy 21.168021 -217.938949) (xy 21.131769 -217.97802) (xy 21.090098 -218.011251) (xy 21.04394 -218.0379)
			(xy 20.994326 -218.057372) (xy 20.942364 -218.069232) (xy 20.889214 -218.073216) (xy 20.836064 -218.069232)
			(xy 20.784102 -218.057372) (xy 20.734488 -218.0379) (xy 20.68833 -218.011251) (xy 20.646659 -217.97802)
			(xy 20.610407 -217.938949) (xy 20.580383 -217.894912) (xy 20.557257 -217.846891) (xy 20.541547 -217.795961)
			(xy 20.533604 -217.743257) (xy 6.80339 -217.743257) (xy 6.80339 -218.593395) (xy 16.433536 -218.593395)
			(xy 16.433536 -218.540097) (xy 16.441479 -218.487393) (xy 16.457189 -218.436463) (xy 16.480315 -218.388442)
			(xy 16.510339 -218.344405) (xy 16.546591 -218.305334) (xy 16.588262 -218.272103) (xy 16.63442 -218.245454)
			(xy 16.684034 -218.225982) (xy 16.735996 -218.214122) (xy 16.789146 -218.210139) (xy 16.842296 -218.214122)
			(xy 16.894258 -218.225982) (xy 16.943872 -218.245454) (xy 16.99003 -218.272103) (xy 17.031701 -218.305334)
			(xy 17.067953 -218.344405) (xy 17.097977 -218.388442) (xy 17.121103 -218.436463) (xy 17.136813 -218.487393)
			(xy 17.144756 -218.540097) (xy 17.145254 -218.566746) (xy 17.144756 -218.593395) (xy 20.533604 -218.593395)
			(xy 20.533604 -218.540097) (xy 20.541547 -218.487393) (xy 20.557257 -218.436463) (xy 20.580383 -218.388442)
			(xy 20.610407 -218.344405) (xy 20.646659 -218.305334) (xy 20.68833 -218.272103) (xy 20.734488 -218.245454)
			(xy 20.784102 -218.225982) (xy 20.836064 -218.214122) (xy 20.889214 -218.210139) (xy 20.942364 -218.214122)
			(xy 20.994326 -218.225982) (xy 21.04394 -218.245454) (xy 21.090098 -218.272103) (xy 21.131769 -218.305334)
			(xy 21.168021 -218.344405) (xy 21.198045 -218.388442) (xy 21.221171 -218.436463) (xy 21.236881 -218.487393)
			(xy 21.244824 -218.540097) (xy 21.245322 -218.566746) (xy 21.244824 -218.593395) (xy 31.521136 -218.593395)
			(xy 31.521136 -218.540097) (xy 31.529079 -218.487393) (xy 31.544789 -218.436463) (xy 31.567915 -218.388442)
			(xy 31.597939 -218.344405) (xy 31.634191 -218.305334) (xy 31.675862 -218.272103) (xy 31.72202 -218.245454)
			(xy 31.771634 -218.225982) (xy 31.823596 -218.214122) (xy 31.876746 -218.210139) (xy 31.929896 -218.214122)
			(xy 31.981858 -218.225982) (xy 32.031472 -218.245454) (xy 32.07763 -218.272103) (xy 32.119301 -218.305334)
			(xy 32.155553 -218.344405) (xy 32.185577 -218.388442) (xy 32.208703 -218.436463) (xy 32.224413 -218.487393)
			(xy 32.232356 -218.540097) (xy 32.232854 -218.566746) (xy 32.232356 -218.593395) (xy 35.621204 -218.593395)
			(xy 35.621204 -218.540097) (xy 35.629147 -218.487393) (xy 35.644857 -218.436463) (xy 35.667983 -218.388442)
			(xy 35.698007 -218.344405) (xy 35.734259 -218.305334) (xy 35.77593 -218.272103) (xy 35.822088 -218.245454)
			(xy 35.871702 -218.225982) (xy 35.923664 -218.214122) (xy 35.976814 -218.210139) (xy 36.029964 -218.214122)
			(xy 36.081926 -218.225982) (xy 36.13154 -218.245454) (xy 36.177698 -218.272103) (xy 36.219369 -218.305334)
			(xy 36.255621 -218.344405) (xy 36.285645 -218.388442) (xy 36.308771 -218.436463) (xy 36.324481 -218.487393)
			(xy 36.332424 -218.540097) (xy 36.332922 -218.566746) (xy 36.332424 -218.593395) (xy 46.608736 -218.593395)
			(xy 46.608736 -218.540097) (xy 46.616679 -218.487393) (xy 46.632389 -218.436463) (xy 46.655515 -218.388442)
			(xy 46.685539 -218.344405) (xy 46.721791 -218.305334) (xy 46.763462 -218.272103) (xy 46.80962 -218.245454)
			(xy 46.859234 -218.225982) (xy 46.911196 -218.214122) (xy 46.964346 -218.210139) (xy 47.017496 -218.214122)
			(xy 47.069458 -218.225982) (xy 47.119072 -218.245454) (xy 47.16523 -218.272103) (xy 47.206901 -218.305334)
			(xy 47.243153 -218.344405) (xy 47.273177 -218.388442) (xy 47.296303 -218.436463) (xy 47.312013 -218.487393)
			(xy 47.319956 -218.540097) (xy 47.320454 -218.566746) (xy 47.319956 -218.593395) (xy 50.708804 -218.593395)
			(xy 50.708804 -218.540097) (xy 50.716747 -218.487393) (xy 50.732457 -218.436463) (xy 50.755583 -218.388442)
			(xy 50.785607 -218.344405) (xy 50.821859 -218.305334) (xy 50.86353 -218.272103) (xy 50.909688 -218.245454)
			(xy 50.959302 -218.225982) (xy 51.011264 -218.214122) (xy 51.064414 -218.210139) (xy 51.117564 -218.214122)
			(xy 51.169526 -218.225982) (xy 51.21914 -218.245454) (xy 51.265298 -218.272103) (xy 51.306969 -218.305334)
			(xy 51.343221 -218.344405) (xy 51.373245 -218.388442) (xy 51.396371 -218.436463) (xy 51.412081 -218.487393)
			(xy 51.420024 -218.540097) (xy 51.420522 -218.566746) (xy 51.420024 -218.593395) (xy 51.412081 -218.646099)
			(xy 51.396371 -218.697029) (xy 51.373245 -218.74505) (xy 51.343221 -218.789087) (xy 51.306969 -218.828158)
			(xy 51.265298 -218.861389) (xy 51.21914 -218.888038) (xy 51.169526 -218.90751) (xy 51.117564 -218.91937)
			(xy 51.064414 -218.923354) (xy 51.011264 -218.91937) (xy 50.959302 -218.90751) (xy 50.909688 -218.888038)
			(xy 50.86353 -218.861389) (xy 50.821859 -218.828158) (xy 50.785607 -218.789087) (xy 50.755583 -218.74505)
			(xy 50.732457 -218.697029) (xy 50.716747 -218.646099) (xy 50.708804 -218.593395) (xy 47.319956 -218.593395)
			(xy 47.312013 -218.646099) (xy 47.296303 -218.697029) (xy 47.273177 -218.74505) (xy 47.243153 -218.789087)
			(xy 47.206901 -218.828158) (xy 47.16523 -218.861389) (xy 47.119072 -218.888038) (xy 47.069458 -218.90751)
			(xy 47.017496 -218.91937) (xy 46.964346 -218.923354) (xy 46.911196 -218.91937) (xy 46.859234 -218.90751)
			(xy 46.80962 -218.888038) (xy 46.763462 -218.861389) (xy 46.721791 -218.828158) (xy 46.685539 -218.789087)
			(xy 46.655515 -218.74505) (xy 46.632389 -218.697029) (xy 46.616679 -218.646099) (xy 46.608736 -218.593395)
			(xy 36.332424 -218.593395) (xy 36.324481 -218.646099) (xy 36.308771 -218.697029) (xy 36.285645 -218.74505)
			(xy 36.255621 -218.789087) (xy 36.219369 -218.828158) (xy 36.177698 -218.861389) (xy 36.13154 -218.888038)
			(xy 36.081926 -218.90751) (xy 36.029964 -218.91937) (xy 35.976814 -218.923354) (xy 35.923664 -218.91937)
			(xy 35.871702 -218.90751) (xy 35.822088 -218.888038) (xy 35.77593 -218.861389) (xy 35.734259 -218.828158)
			(xy 35.698007 -218.789087) (xy 35.667983 -218.74505) (xy 35.644857 -218.697029) (xy 35.629147 -218.646099)
			(xy 35.621204 -218.593395) (xy 32.232356 -218.593395) (xy 32.224413 -218.646099) (xy 32.208703 -218.697029)
			(xy 32.185577 -218.74505) (xy 32.155553 -218.789087) (xy 32.119301 -218.828158) (xy 32.07763 -218.861389)
			(xy 32.031472 -218.888038) (xy 31.981858 -218.90751) (xy 31.929896 -218.91937) (xy 31.876746 -218.923354)
			(xy 31.823596 -218.91937) (xy 31.771634 -218.90751) (xy 31.72202 -218.888038) (xy 31.675862 -218.861389)
			(xy 31.634191 -218.828158) (xy 31.597939 -218.789087) (xy 31.567915 -218.74505) (xy 31.544789 -218.697029)
			(xy 31.529079 -218.646099) (xy 31.521136 -218.593395) (xy 21.244824 -218.593395) (xy 21.236881 -218.646099)
			(xy 21.221171 -218.697029) (xy 21.198045 -218.74505) (xy 21.168021 -218.789087) (xy 21.131769 -218.828158)
			(xy 21.090098 -218.861389) (xy 21.04394 -218.888038) (xy 20.994326 -218.90751) (xy 20.942364 -218.91937)
			(xy 20.889214 -218.923354) (xy 20.836064 -218.91937) (xy 20.784102 -218.90751) (xy 20.734488 -218.888038)
			(xy 20.68833 -218.861389) (xy 20.646659 -218.828158) (xy 20.610407 -218.789087) (xy 20.580383 -218.74505)
			(xy 20.557257 -218.697029) (xy 20.541547 -218.646099) (xy 20.533604 -218.593395) (xy 17.144756 -218.593395)
			(xy 17.136813 -218.646099) (xy 17.121103 -218.697029) (xy 17.097977 -218.74505) (xy 17.067953 -218.789087)
			(xy 17.031701 -218.828158) (xy 16.99003 -218.861389) (xy 16.943872 -218.888038) (xy 16.894258 -218.90751)
			(xy 16.842296 -218.91937) (xy 16.789146 -218.923354) (xy 16.735996 -218.91937) (xy 16.684034 -218.90751)
			(xy 16.63442 -218.888038) (xy 16.588262 -218.861389) (xy 16.546591 -218.828158) (xy 16.510339 -218.789087)
			(xy 16.480315 -218.74505) (xy 16.457189 -218.697029) (xy 16.441479 -218.646099) (xy 16.433536 -218.593395)
			(xy 6.80339 -218.593395) (xy 6.80339 -219.443279) (xy 16.433536 -219.443279) (xy 16.433536 -219.389981)
			(xy 16.441479 -219.337277) (xy 16.457189 -219.286347) (xy 16.480315 -219.238326) (xy 16.510339 -219.194289)
			(xy 16.546591 -219.155218) (xy 16.588262 -219.121987) (xy 16.63442 -219.095338) (xy 16.684034 -219.075866)
			(xy 16.735996 -219.064006) (xy 16.789146 -219.060023) (xy 16.842296 -219.064006) (xy 16.894258 -219.075866)
			(xy 16.943872 -219.095338) (xy 16.99003 -219.121987) (xy 17.031701 -219.155218) (xy 17.067953 -219.194289)
			(xy 17.097977 -219.238326) (xy 17.121103 -219.286347) (xy 17.136813 -219.337277) (xy 17.144756 -219.389981)
			(xy 17.145254 -219.41663) (xy 17.144756 -219.443279) (xy 31.521136 -219.443279) (xy 31.521136 -219.389981)
			(xy 31.529079 -219.337277) (xy 31.544789 -219.286347) (xy 31.567915 -219.238326) (xy 31.597939 -219.194289)
			(xy 31.634191 -219.155218) (xy 31.675862 -219.121987) (xy 31.72202 -219.095338) (xy 31.771634 -219.075866)
			(xy 31.823596 -219.064006) (xy 31.876746 -219.060023) (xy 31.929896 -219.064006) (xy 31.981858 -219.075866)
			(xy 32.031472 -219.095338) (xy 32.07763 -219.121987) (xy 32.119301 -219.155218) (xy 32.155553 -219.194289)
			(xy 32.185577 -219.238326) (xy 32.208703 -219.286347) (xy 32.224413 -219.337277) (xy 32.232356 -219.389981)
			(xy 32.232854 -219.41663) (xy 32.232356 -219.443279) (xy 46.608736 -219.443279) (xy 46.608736 -219.389981)
			(xy 46.616679 -219.337277) (xy 46.632389 -219.286347) (xy 46.655515 -219.238326) (xy 46.685539 -219.194289)
			(xy 46.721791 -219.155218) (xy 46.763462 -219.121987) (xy 46.80962 -219.095338) (xy 46.859234 -219.075866)
			(xy 46.911196 -219.064006) (xy 46.964346 -219.060023) (xy 47.017496 -219.064006) (xy 47.069458 -219.075866)
			(xy 47.119072 -219.095338) (xy 47.16523 -219.121987) (xy 47.206901 -219.155218) (xy 47.243153 -219.194289)
			(xy 47.273177 -219.238326) (xy 47.296303 -219.286347) (xy 47.312013 -219.337277) (xy 47.319956 -219.389981)
			(xy 47.320454 -219.41663) (xy 47.319956 -219.443279) (xy 47.312013 -219.495983) (xy 47.296303 -219.546913)
			(xy 47.273177 -219.594934) (xy 47.243153 -219.638971) (xy 47.206901 -219.678042) (xy 47.16523 -219.711273)
			(xy 47.119072 -219.737922) (xy 47.069458 -219.757394) (xy 47.017496 -219.769254) (xy 46.964346 -219.773238)
			(xy 46.911196 -219.769254) (xy 46.859234 -219.757394) (xy 46.80962 -219.737922) (xy 46.763462 -219.711273)
			(xy 46.721791 -219.678042) (xy 46.685539 -219.638971) (xy 46.655515 -219.594934) (xy 46.632389 -219.546913)
			(xy 46.616679 -219.495983) (xy 46.608736 -219.443279) (xy 32.232356 -219.443279) (xy 32.224413 -219.495983)
			(xy 32.208703 -219.546913) (xy 32.185577 -219.594934) (xy 32.155553 -219.638971) (xy 32.119301 -219.678042)
			(xy 32.07763 -219.711273) (xy 32.031472 -219.737922) (xy 31.981858 -219.757394) (xy 31.929896 -219.769254)
			(xy 31.876746 -219.773238) (xy 31.823596 -219.769254) (xy 31.771634 -219.757394) (xy 31.72202 -219.737922)
			(xy 31.675862 -219.711273) (xy 31.634191 -219.678042) (xy 31.597939 -219.638971) (xy 31.567915 -219.594934)
			(xy 31.544789 -219.546913) (xy 31.529079 -219.495983) (xy 31.521136 -219.443279) (xy 17.144756 -219.443279)
			(xy 17.136813 -219.495983) (xy 17.121103 -219.546913) (xy 17.097977 -219.594934) (xy 17.067953 -219.638971)
			(xy 17.031701 -219.678042) (xy 16.99003 -219.711273) (xy 16.943872 -219.737922) (xy 16.894258 -219.757394)
			(xy 16.842296 -219.769254) (xy 16.789146 -219.773238) (xy 16.735996 -219.769254) (xy 16.684034 -219.757394)
			(xy 16.63442 -219.737922) (xy 16.588262 -219.711273) (xy 16.546591 -219.678042) (xy 16.510339 -219.638971)
			(xy 16.480315 -219.594934) (xy 16.457189 -219.546913) (xy 16.441479 -219.495983) (xy 16.433536 -219.443279)
			(xy 6.80339 -219.443279) (xy 6.80339 -220.293417) (xy 20.533604 -220.293417) (xy 20.533604 -220.240119)
			(xy 20.541547 -220.187415) (xy 20.557257 -220.136485) (xy 20.580383 -220.088464) (xy 20.610407 -220.044427)
			(xy 20.646659 -220.005356) (xy 20.68833 -219.972125) (xy 20.734488 -219.945476) (xy 20.784102 -219.926004)
			(xy 20.836064 -219.914144) (xy 20.889214 -219.910161) (xy 20.942364 -219.914144) (xy 20.994326 -219.926004)
			(xy 21.04394 -219.945476) (xy 21.090098 -219.972125) (xy 21.131769 -220.005356) (xy 21.168021 -220.044427)
			(xy 21.198045 -220.088464) (xy 21.221171 -220.136485) (xy 21.236881 -220.187415) (xy 21.244824 -220.240119)
			(xy 21.245322 -220.266768) (xy 21.244824 -220.293417) (xy 35.621204 -220.293417) (xy 35.621204 -220.240119)
			(xy 35.629147 -220.187415) (xy 35.644857 -220.136485) (xy 35.667983 -220.088464) (xy 35.698007 -220.044427)
			(xy 35.734259 -220.005356) (xy 35.77593 -219.972125) (xy 35.822088 -219.945476) (xy 35.871702 -219.926004)
			(xy 35.923664 -219.914144) (xy 35.976814 -219.910161) (xy 36.029964 -219.914144) (xy 36.081926 -219.926004)
			(xy 36.13154 -219.945476) (xy 36.177698 -219.972125) (xy 36.219369 -220.005356) (xy 36.255621 -220.044427)
			(xy 36.285645 -220.088464) (xy 36.308771 -220.136485) (xy 36.324481 -220.187415) (xy 36.332424 -220.240119)
			(xy 36.332922 -220.266768) (xy 36.332424 -220.293417) (xy 50.708804 -220.293417) (xy 50.708804 -220.240119)
			(xy 50.716747 -220.187415) (xy 50.732457 -220.136485) (xy 50.755583 -220.088464) (xy 50.785607 -220.044427)
			(xy 50.821859 -220.005356) (xy 50.86353 -219.972125) (xy 50.909688 -219.945476) (xy 50.959302 -219.926004)
			(xy 51.011264 -219.914144) (xy 51.064414 -219.910161) (xy 51.117564 -219.914144) (xy 51.169526 -219.926004)
			(xy 51.21914 -219.945476) (xy 51.265298 -219.972125) (xy 51.306969 -220.005356) (xy 51.343221 -220.044427)
			(xy 51.373245 -220.088464) (xy 51.396371 -220.136485) (xy 51.412081 -220.187415) (xy 51.420024 -220.240119)
			(xy 51.420522 -220.266768) (xy 51.420024 -220.293417) (xy 51.412081 -220.346121) (xy 51.396371 -220.397051)
			(xy 51.373245 -220.445072) (xy 51.343221 -220.489109) (xy 51.306969 -220.52818) (xy 51.265298 -220.561411)
			(xy 51.21914 -220.58806) (xy 51.169526 -220.607532) (xy 51.117564 -220.619392) (xy 51.064414 -220.623376)
			(xy 51.011264 -220.619392) (xy 50.959302 -220.607532) (xy 50.909688 -220.58806) (xy 50.86353 -220.561411)
			(xy 50.821859 -220.52818) (xy 50.785607 -220.489109) (xy 50.755583 -220.445072) (xy 50.732457 -220.397051)
			(xy 50.716747 -220.346121) (xy 50.708804 -220.293417) (xy 36.332424 -220.293417) (xy 36.324481 -220.346121)
			(xy 36.308771 -220.397051) (xy 36.285645 -220.445072) (xy 36.255621 -220.489109) (xy 36.219369 -220.52818)
			(xy 36.177698 -220.561411) (xy 36.13154 -220.58806) (xy 36.081926 -220.607532) (xy 36.029964 -220.619392)
			(xy 35.976814 -220.623376) (xy 35.923664 -220.619392) (xy 35.871702 -220.607532) (xy 35.822088 -220.58806)
			(xy 35.77593 -220.561411) (xy 35.734259 -220.52818) (xy 35.698007 -220.489109) (xy 35.667983 -220.445072)
			(xy 35.644857 -220.397051) (xy 35.629147 -220.346121) (xy 35.621204 -220.293417) (xy 21.244824 -220.293417)
			(xy 21.236881 -220.346121) (xy 21.221171 -220.397051) (xy 21.198045 -220.445072) (xy 21.168021 -220.489109)
			(xy 21.131769 -220.52818) (xy 21.090098 -220.561411) (xy 21.04394 -220.58806) (xy 20.994326 -220.607532)
			(xy 20.942364 -220.619392) (xy 20.889214 -220.623376) (xy 20.836064 -220.619392) (xy 20.784102 -220.607532)
			(xy 20.734488 -220.58806) (xy 20.68833 -220.561411) (xy 20.646659 -220.52818) (xy 20.610407 -220.489109)
			(xy 20.580383 -220.445072) (xy 20.557257 -220.397051) (xy 20.541547 -220.346121) (xy 20.533604 -220.293417)
			(xy 6.80339 -220.293417) (xy 6.80339 -221.143301) (xy 16.433536 -221.143301) (xy 16.433536 -221.090003)
			(xy 16.441479 -221.037299) (xy 16.457189 -220.986369) (xy 16.480315 -220.938348) (xy 16.510339 -220.894311)
			(xy 16.546591 -220.85524) (xy 16.588262 -220.822009) (xy 16.63442 -220.79536) (xy 16.684034 -220.775888)
			(xy 16.735996 -220.764028) (xy 16.789146 -220.760045) (xy 16.842296 -220.764028) (xy 16.894258 -220.775888)
			(xy 16.943872 -220.79536) (xy 16.99003 -220.822009) (xy 17.031701 -220.85524) (xy 17.067953 -220.894311)
			(xy 17.097977 -220.938348) (xy 17.121103 -220.986369) (xy 17.136813 -221.037299) (xy 17.144756 -221.090003)
			(xy 17.145254 -221.116652) (xy 17.144756 -221.143301) (xy 31.521136 -221.143301) (xy 31.521136 -221.090003)
			(xy 31.529079 -221.037299) (xy 31.544789 -220.986369) (xy 31.567915 -220.938348) (xy 31.597939 -220.894311)
			(xy 31.634191 -220.85524) (xy 31.675862 -220.822009) (xy 31.72202 -220.79536) (xy 31.771634 -220.775888)
			(xy 31.823596 -220.764028) (xy 31.876746 -220.760045) (xy 31.929896 -220.764028) (xy 31.981858 -220.775888)
			(xy 32.031472 -220.79536) (xy 32.07763 -220.822009) (xy 32.119301 -220.85524) (xy 32.155553 -220.894311)
			(xy 32.185577 -220.938348) (xy 32.208703 -220.986369) (xy 32.224413 -221.037299) (xy 32.232356 -221.090003)
			(xy 32.232854 -221.116652) (xy 32.232356 -221.143301) (xy 46.608736 -221.143301) (xy 46.608736 -221.090003)
			(xy 46.616679 -221.037299) (xy 46.632389 -220.986369) (xy 46.655515 -220.938348) (xy 46.685539 -220.894311)
			(xy 46.721791 -220.85524) (xy 46.763462 -220.822009) (xy 46.80962 -220.79536) (xy 46.859234 -220.775888)
			(xy 46.911196 -220.764028) (xy 46.964346 -220.760045) (xy 47.017496 -220.764028) (xy 47.069458 -220.775888)
			(xy 47.119072 -220.79536) (xy 47.16523 -220.822009) (xy 47.206901 -220.85524) (xy 47.243153 -220.894311)
			(xy 47.273177 -220.938348) (xy 47.296303 -220.986369) (xy 47.312013 -221.037299) (xy 47.319956 -221.090003)
			(xy 47.320454 -221.116652) (xy 47.319956 -221.143301) (xy 47.312013 -221.196005) (xy 47.296303 -221.246935)
			(xy 47.273177 -221.294956) (xy 47.243153 -221.338993) (xy 47.206901 -221.378064) (xy 47.16523 -221.411295)
			(xy 47.119072 -221.437944) (xy 47.069458 -221.457416) (xy 47.017496 -221.469276) (xy 46.964346 -221.47326)
			(xy 46.911196 -221.469276) (xy 46.859234 -221.457416) (xy 46.80962 -221.437944) (xy 46.763462 -221.411295)
			(xy 46.721791 -221.378064) (xy 46.685539 -221.338993) (xy 46.655515 -221.294956) (xy 46.632389 -221.246935)
			(xy 46.616679 -221.196005) (xy 46.608736 -221.143301) (xy 32.232356 -221.143301) (xy 32.224413 -221.196005)
			(xy 32.208703 -221.246935) (xy 32.185577 -221.294956) (xy 32.155553 -221.338993) (xy 32.119301 -221.378064)
			(xy 32.07763 -221.411295) (xy 32.031472 -221.437944) (xy 31.981858 -221.457416) (xy 31.929896 -221.469276)
			(xy 31.876746 -221.47326) (xy 31.823596 -221.469276) (xy 31.771634 -221.457416) (xy 31.72202 -221.437944)
			(xy 31.675862 -221.411295) (xy 31.634191 -221.378064) (xy 31.597939 -221.338993) (xy 31.567915 -221.294956)
			(xy 31.544789 -221.246935) (xy 31.529079 -221.196005) (xy 31.521136 -221.143301) (xy 17.144756 -221.143301)
			(xy 17.136813 -221.196005) (xy 17.121103 -221.246935) (xy 17.097977 -221.294956) (xy 17.067953 -221.338993)
			(xy 17.031701 -221.378064) (xy 16.99003 -221.411295) (xy 16.943872 -221.437944) (xy 16.894258 -221.457416)
			(xy 16.842296 -221.469276) (xy 16.789146 -221.47326) (xy 16.735996 -221.469276) (xy 16.684034 -221.457416)
			(xy 16.63442 -221.437944) (xy 16.588262 -221.411295) (xy 16.546591 -221.378064) (xy 16.510339 -221.338993)
			(xy 16.480315 -221.294956) (xy 16.457189 -221.246935) (xy 16.441479 -221.196005) (xy 16.433536 -221.143301)
			(xy 6.80339 -221.143301) (xy 6.80339 -221.993439) (xy 20.533604 -221.993439) (xy 20.533604 -221.940141)
			(xy 20.541547 -221.887437) (xy 20.557257 -221.836507) (xy 20.580383 -221.788486) (xy 20.610407 -221.744449)
			(xy 20.646659 -221.705378) (xy 20.68833 -221.672147) (xy 20.734488 -221.645498) (xy 20.784102 -221.626026)
			(xy 20.836064 -221.614166) (xy 20.889214 -221.610183) (xy 20.942364 -221.614166) (xy 20.994326 -221.626026)
			(xy 21.04394 -221.645498) (xy 21.090098 -221.672147) (xy 21.131769 -221.705378) (xy 21.168021 -221.744449)
			(xy 21.198045 -221.788486) (xy 21.221171 -221.836507) (xy 21.236881 -221.887437) (xy 21.244824 -221.940141)
			(xy 21.245322 -221.96679) (xy 21.244824 -221.993439) (xy 35.621204 -221.993439) (xy 35.621204 -221.940141)
			(xy 35.629147 -221.887437) (xy 35.644857 -221.836507) (xy 35.667983 -221.788486) (xy 35.698007 -221.744449)
			(xy 35.734259 -221.705378) (xy 35.77593 -221.672147) (xy 35.822088 -221.645498) (xy 35.871702 -221.626026)
			(xy 35.923664 -221.614166) (xy 35.976814 -221.610183) (xy 36.029964 -221.614166) (xy 36.081926 -221.626026)
			(xy 36.13154 -221.645498) (xy 36.177698 -221.672147) (xy 36.219369 -221.705378) (xy 36.255621 -221.744449)
			(xy 36.285645 -221.788486) (xy 36.308771 -221.836507) (xy 36.324481 -221.887437) (xy 36.332424 -221.940141)
			(xy 36.332922 -221.96679) (xy 36.332424 -221.993439) (xy 50.708804 -221.993439) (xy 50.708804 -221.940141)
			(xy 50.716747 -221.887437) (xy 50.732457 -221.836507) (xy 50.755583 -221.788486) (xy 50.785607 -221.744449)
			(xy 50.821859 -221.705378) (xy 50.86353 -221.672147) (xy 50.909688 -221.645498) (xy 50.959302 -221.626026)
			(xy 51.011264 -221.614166) (xy 51.064414 -221.610183) (xy 51.117564 -221.614166) (xy 51.169526 -221.626026)
			(xy 51.21914 -221.645498) (xy 51.265298 -221.672147) (xy 51.306969 -221.705378) (xy 51.343221 -221.744449)
			(xy 51.373245 -221.788486) (xy 51.396371 -221.836507) (xy 51.412081 -221.887437) (xy 51.420024 -221.940141)
			(xy 51.420522 -221.96679) (xy 51.420024 -221.993439) (xy 51.412081 -222.046143) (xy 51.396371 -222.097073)
			(xy 51.373245 -222.145094) (xy 51.343221 -222.189131) (xy 51.306969 -222.228202) (xy 51.265298 -222.261433)
			(xy 51.21914 -222.288082) (xy 51.169526 -222.307554) (xy 51.117564 -222.319414) (xy 51.064414 -222.323398)
			(xy 51.011264 -222.319414) (xy 50.959302 -222.307554) (xy 50.909688 -222.288082) (xy 50.86353 -222.261433)
			(xy 50.821859 -222.228202) (xy 50.785607 -222.189131) (xy 50.755583 -222.145094) (xy 50.732457 -222.097073)
			(xy 50.716747 -222.046143) (xy 50.708804 -221.993439) (xy 36.332424 -221.993439) (xy 36.324481 -222.046143)
			(xy 36.308771 -222.097073) (xy 36.285645 -222.145094) (xy 36.255621 -222.189131) (xy 36.219369 -222.228202)
			(xy 36.177698 -222.261433) (xy 36.13154 -222.288082) (xy 36.081926 -222.307554) (xy 36.029964 -222.319414)
			(xy 35.976814 -222.323398) (xy 35.923664 -222.319414) (xy 35.871702 -222.307554) (xy 35.822088 -222.288082)
			(xy 35.77593 -222.261433) (xy 35.734259 -222.228202) (xy 35.698007 -222.189131) (xy 35.667983 -222.145094)
			(xy 35.644857 -222.097073) (xy 35.629147 -222.046143) (xy 35.621204 -221.993439) (xy 21.244824 -221.993439)
			(xy 21.236881 -222.046143) (xy 21.221171 -222.097073) (xy 21.198045 -222.145094) (xy 21.168021 -222.189131)
			(xy 21.131769 -222.228202) (xy 21.090098 -222.261433) (xy 21.04394 -222.288082) (xy 20.994326 -222.307554)
			(xy 20.942364 -222.319414) (xy 20.889214 -222.323398) (xy 20.836064 -222.319414) (xy 20.784102 -222.307554)
			(xy 20.734488 -222.288082) (xy 20.68833 -222.261433) (xy 20.646659 -222.228202) (xy 20.610407 -222.189131)
			(xy 20.580383 -222.145094) (xy 20.557257 -222.097073) (xy 20.541547 -222.046143) (xy 20.533604 -221.993439)
			(xy 6.80339 -221.993439) (xy 6.80339 -222.843323) (xy 16.433536 -222.843323) (xy 16.433536 -222.790025)
			(xy 16.441479 -222.737321) (xy 16.457189 -222.686391) (xy 16.480315 -222.63837) (xy 16.510339 -222.594333)
			(xy 16.546591 -222.555262) (xy 16.588262 -222.522031) (xy 16.63442 -222.495382) (xy 16.684034 -222.47591)
			(xy 16.735996 -222.46405) (xy 16.789146 -222.460067) (xy 16.842296 -222.46405) (xy 16.894258 -222.47591)
			(xy 16.943872 -222.495382) (xy 16.99003 -222.522031) (xy 17.031701 -222.555262) (xy 17.067953 -222.594333)
			(xy 17.097977 -222.63837) (xy 17.121103 -222.686391) (xy 17.136813 -222.737321) (xy 17.144756 -222.790025)
			(xy 17.145254 -222.816674) (xy 17.144756 -222.843323) (xy 31.521136 -222.843323) (xy 31.521136 -222.790025)
			(xy 31.529079 -222.737321) (xy 31.544789 -222.686391) (xy 31.567915 -222.63837) (xy 31.597939 -222.594333)
			(xy 31.634191 -222.555262) (xy 31.675862 -222.522031) (xy 31.72202 -222.495382) (xy 31.771634 -222.47591)
			(xy 31.823596 -222.46405) (xy 31.876746 -222.460067) (xy 31.929896 -222.46405) (xy 31.981858 -222.47591)
			(xy 32.031472 -222.495382) (xy 32.07763 -222.522031) (xy 32.119301 -222.555262) (xy 32.155553 -222.594333)
			(xy 32.185577 -222.63837) (xy 32.208703 -222.686391) (xy 32.224413 -222.737321) (xy 32.232356 -222.790025)
			(xy 32.232854 -222.816674) (xy 32.232356 -222.843323) (xy 46.608736 -222.843323) (xy 46.608736 -222.790025)
			(xy 46.616679 -222.737321) (xy 46.632389 -222.686391) (xy 46.655515 -222.63837) (xy 46.685539 -222.594333)
			(xy 46.721791 -222.555262) (xy 46.763462 -222.522031) (xy 46.80962 -222.495382) (xy 46.859234 -222.47591)
			(xy 46.911196 -222.46405) (xy 46.964346 -222.460067) (xy 47.017496 -222.46405) (xy 47.069458 -222.47591)
			(xy 47.119072 -222.495382) (xy 47.16523 -222.522031) (xy 47.206901 -222.555262) (xy 47.243153 -222.594333)
			(xy 47.273177 -222.63837) (xy 47.296303 -222.686391) (xy 47.312013 -222.737321) (xy 47.319956 -222.790025)
			(xy 47.320454 -222.816674) (xy 47.319956 -222.843323) (xy 47.312013 -222.896027) (xy 47.296303 -222.946957)
			(xy 47.273177 -222.994978) (xy 47.243153 -223.039015) (xy 47.206901 -223.078086) (xy 47.16523 -223.111317)
			(xy 47.119072 -223.137966) (xy 47.069458 -223.157438) (xy 47.017496 -223.169298) (xy 46.964346 -223.173282)
			(xy 46.911196 -223.169298) (xy 46.859234 -223.157438) (xy 46.80962 -223.137966) (xy 46.763462 -223.111317)
			(xy 46.721791 -223.078086) (xy 46.685539 -223.039015) (xy 46.655515 -222.994978) (xy 46.632389 -222.946957)
			(xy 46.616679 -222.896027) (xy 46.608736 -222.843323) (xy 32.232356 -222.843323) (xy 32.224413 -222.896027)
			(xy 32.208703 -222.946957) (xy 32.185577 -222.994978) (xy 32.155553 -223.039015) (xy 32.119301 -223.078086)
			(xy 32.07763 -223.111317) (xy 32.031472 -223.137966) (xy 31.981858 -223.157438) (xy 31.929896 -223.169298)
			(xy 31.876746 -223.173282) (xy 31.823596 -223.169298) (xy 31.771634 -223.157438) (xy 31.72202 -223.137966)
			(xy 31.675862 -223.111317) (xy 31.634191 -223.078086) (xy 31.597939 -223.039015) (xy 31.567915 -222.994978)
			(xy 31.544789 -222.946957) (xy 31.529079 -222.896027) (xy 31.521136 -222.843323) (xy 17.144756 -222.843323)
			(xy 17.136813 -222.896027) (xy 17.121103 -222.946957) (xy 17.097977 -222.994978) (xy 17.067953 -223.039015)
			(xy 17.031701 -223.078086) (xy 16.99003 -223.111317) (xy 16.943872 -223.137966) (xy 16.894258 -223.157438)
			(xy 16.842296 -223.169298) (xy 16.789146 -223.173282) (xy 16.735996 -223.169298) (xy 16.684034 -223.157438)
			(xy 16.63442 -223.137966) (xy 16.588262 -223.111317) (xy 16.546591 -223.078086) (xy 16.510339 -223.039015)
			(xy 16.480315 -222.994978) (xy 16.457189 -222.946957) (xy 16.441479 -222.896027) (xy 16.433536 -222.843323)
			(xy 6.80339 -222.843323) (xy 6.80339 -223.693207) (xy 20.533604 -223.693207) (xy 20.533604 -223.639909)
			(xy 20.541547 -223.587205) (xy 20.557257 -223.536275) (xy 20.580383 -223.488254) (xy 20.610407 -223.444217)
			(xy 20.646659 -223.405146) (xy 20.68833 -223.371915) (xy 20.734488 -223.345266) (xy 20.784102 -223.325794)
			(xy 20.836064 -223.313934) (xy 20.889214 -223.309951) (xy 20.942364 -223.313934) (xy 20.994326 -223.325794)
			(xy 21.04394 -223.345266) (xy 21.090098 -223.371915) (xy 21.131769 -223.405146) (xy 21.168021 -223.444217)
			(xy 21.198045 -223.488254) (xy 21.221171 -223.536275) (xy 21.236881 -223.587205) (xy 21.244824 -223.639909)
			(xy 21.245322 -223.666558) (xy 21.244824 -223.693207) (xy 35.621204 -223.693207) (xy 35.621204 -223.639909)
			(xy 35.629147 -223.587205) (xy 35.644857 -223.536275) (xy 35.667983 -223.488254) (xy 35.698007 -223.444217)
			(xy 35.734259 -223.405146) (xy 35.77593 -223.371915) (xy 35.822088 -223.345266) (xy 35.871702 -223.325794)
			(xy 35.923664 -223.313934) (xy 35.976814 -223.309951) (xy 36.029964 -223.313934) (xy 36.081926 -223.325794)
			(xy 36.13154 -223.345266) (xy 36.177698 -223.371915) (xy 36.219369 -223.405146) (xy 36.255621 -223.444217)
			(xy 36.285645 -223.488254) (xy 36.308771 -223.536275) (xy 36.324481 -223.587205) (xy 36.332424 -223.639909)
			(xy 36.332922 -223.666558) (xy 36.332424 -223.693207) (xy 50.708804 -223.693207) (xy 50.708804 -223.639909)
			(xy 50.716747 -223.587205) (xy 50.732457 -223.536275) (xy 50.755583 -223.488254) (xy 50.785607 -223.444217)
			(xy 50.821859 -223.405146) (xy 50.86353 -223.371915) (xy 50.909688 -223.345266) (xy 50.959302 -223.325794)
			(xy 51.011264 -223.313934) (xy 51.064414 -223.309951) (xy 51.117564 -223.313934) (xy 51.169526 -223.325794)
			(xy 51.21914 -223.345266) (xy 51.265298 -223.371915) (xy 51.306969 -223.405146) (xy 51.343221 -223.444217)
			(xy 51.373245 -223.488254) (xy 51.396371 -223.536275) (xy 51.412081 -223.587205) (xy 51.420024 -223.639909)
			(xy 51.420522 -223.666558) (xy 51.420024 -223.693207) (xy 51.412081 -223.745911) (xy 51.396371 -223.796841)
			(xy 51.373245 -223.844862) (xy 51.343221 -223.888899) (xy 51.306969 -223.92797) (xy 51.265298 -223.961201)
			(xy 51.21914 -223.98785) (xy 51.169526 -224.007322) (xy 51.117564 -224.019182) (xy 51.064414 -224.023166)
			(xy 51.011264 -224.019182) (xy 50.959302 -224.007322) (xy 50.909688 -223.98785) (xy 50.86353 -223.961201)
			(xy 50.821859 -223.92797) (xy 50.785607 -223.888899) (xy 50.755583 -223.844862) (xy 50.732457 -223.796841)
			(xy 50.716747 -223.745911) (xy 50.708804 -223.693207) (xy 36.332424 -223.693207) (xy 36.324481 -223.745911)
			(xy 36.308771 -223.796841) (xy 36.285645 -223.844862) (xy 36.255621 -223.888899) (xy 36.219369 -223.92797)
			(xy 36.177698 -223.961201) (xy 36.13154 -223.98785) (xy 36.081926 -224.007322) (xy 36.029964 -224.019182)
			(xy 35.976814 -224.023166) (xy 35.923664 -224.019182) (xy 35.871702 -224.007322) (xy 35.822088 -223.98785)
			(xy 35.77593 -223.961201) (xy 35.734259 -223.92797) (xy 35.698007 -223.888899) (xy 35.667983 -223.844862)
			(xy 35.644857 -223.796841) (xy 35.629147 -223.745911) (xy 35.621204 -223.693207) (xy 21.244824 -223.693207)
			(xy 21.236881 -223.745911) (xy 21.221171 -223.796841) (xy 21.198045 -223.844862) (xy 21.168021 -223.888899)
			(xy 21.131769 -223.92797) (xy 21.090098 -223.961201) (xy 21.04394 -223.98785) (xy 20.994326 -224.007322)
			(xy 20.942364 -224.019182) (xy 20.889214 -224.023166) (xy 20.836064 -224.019182) (xy 20.784102 -224.007322)
			(xy 20.734488 -223.98785) (xy 20.68833 -223.961201) (xy 20.646659 -223.92797) (xy 20.610407 -223.888899)
			(xy 20.580383 -223.844862) (xy 20.557257 -223.796841) (xy 20.541547 -223.745911) (xy 20.533604 -223.693207)
			(xy 6.80339 -223.693207) (xy 6.80339 -224.543345) (xy 16.433536 -224.543345) (xy 16.433536 -224.490047)
			(xy 16.441479 -224.437343) (xy 16.457189 -224.386413) (xy 16.480315 -224.338392) (xy 16.510339 -224.294355)
			(xy 16.546591 -224.255284) (xy 16.588262 -224.222053) (xy 16.63442 -224.195404) (xy 16.684034 -224.175932)
			(xy 16.735996 -224.164072) (xy 16.789146 -224.160089) (xy 16.842296 -224.164072) (xy 16.894258 -224.175932)
			(xy 16.943872 -224.195404) (xy 16.99003 -224.222053) (xy 17.031701 -224.255284) (xy 17.067953 -224.294355)
			(xy 17.097977 -224.338392) (xy 17.121103 -224.386413) (xy 17.136813 -224.437343) (xy 17.144756 -224.490047)
			(xy 17.145254 -224.516696) (xy 17.144756 -224.543345) (xy 31.521136 -224.543345) (xy 31.521136 -224.490047)
			(xy 31.529079 -224.437343) (xy 31.544789 -224.386413) (xy 31.567915 -224.338392) (xy 31.597939 -224.294355)
			(xy 31.634191 -224.255284) (xy 31.675862 -224.222053) (xy 31.72202 -224.195404) (xy 31.771634 -224.175932)
			(xy 31.823596 -224.164072) (xy 31.876746 -224.160089) (xy 31.929896 -224.164072) (xy 31.981858 -224.175932)
			(xy 32.031472 -224.195404) (xy 32.07763 -224.222053) (xy 32.119301 -224.255284) (xy 32.155553 -224.294355)
			(xy 32.185577 -224.338392) (xy 32.208703 -224.386413) (xy 32.224413 -224.437343) (xy 32.232356 -224.490047)
			(xy 32.232854 -224.516696) (xy 32.232356 -224.543345) (xy 46.608736 -224.543345) (xy 46.608736 -224.490047)
			(xy 46.616679 -224.437343) (xy 46.632389 -224.386413) (xy 46.655515 -224.338392) (xy 46.685539 -224.294355)
			(xy 46.721791 -224.255284) (xy 46.763462 -224.222053) (xy 46.80962 -224.195404) (xy 46.859234 -224.175932)
			(xy 46.911196 -224.164072) (xy 46.964346 -224.160089) (xy 47.017496 -224.164072) (xy 47.069458 -224.175932)
			(xy 47.119072 -224.195404) (xy 47.16523 -224.222053) (xy 47.206901 -224.255284) (xy 47.243153 -224.294355)
			(xy 47.273177 -224.338392) (xy 47.296303 -224.386413) (xy 47.312013 -224.437343) (xy 47.319956 -224.490047)
			(xy 47.320454 -224.516696) (xy 47.319956 -224.543345) (xy 61.696336 -224.543345) (xy 61.696336 -224.490047)
			(xy 61.704279 -224.437343) (xy 61.719989 -224.386413) (xy 61.743115 -224.338392) (xy 61.773139 -224.294355)
			(xy 61.809391 -224.255284) (xy 61.851062 -224.222053) (xy 61.89722 -224.195404) (xy 61.946834 -224.175932)
			(xy 61.998796 -224.164072) (xy 62.051946 -224.160089) (xy 62.105096 -224.164072) (xy 62.157058 -224.175932)
			(xy 62.206672 -224.195404) (xy 62.25283 -224.222053) (xy 62.294501 -224.255284) (xy 62.330753 -224.294355)
			(xy 62.360777 -224.338392) (xy 62.383903 -224.386413) (xy 62.399613 -224.437343) (xy 62.407556 -224.490047)
			(xy 62.408054 -224.516696) (xy 62.407556 -224.543345) (xy 62.399613 -224.596049) (xy 62.383903 -224.646979)
			(xy 62.360777 -224.695) (xy 62.330753 -224.739037) (xy 62.294501 -224.778108) (xy 62.25283 -224.811339)
			(xy 62.206672 -224.837988) (xy 62.157058 -224.85746) (xy 62.105096 -224.86932) (xy 62.051946 -224.873304)
			(xy 61.998796 -224.86932) (xy 61.946834 -224.85746) (xy 61.89722 -224.837988) (xy 61.851062 -224.811339)
			(xy 61.809391 -224.778108) (xy 61.773139 -224.739037) (xy 61.743115 -224.695) (xy 61.719989 -224.646979)
			(xy 61.704279 -224.596049) (xy 61.696336 -224.543345) (xy 47.319956 -224.543345) (xy 47.312013 -224.596049)
			(xy 47.296303 -224.646979) (xy 47.273177 -224.695) (xy 47.243153 -224.739037) (xy 47.206901 -224.778108)
			(xy 47.16523 -224.811339) (xy 47.119072 -224.837988) (xy 47.069458 -224.85746) (xy 47.017496 -224.86932)
			(xy 46.964346 -224.873304) (xy 46.911196 -224.86932) (xy 46.859234 -224.85746) (xy 46.80962 -224.837988)
			(xy 46.763462 -224.811339) (xy 46.721791 -224.778108) (xy 46.685539 -224.739037) (xy 46.655515 -224.695)
			(xy 46.632389 -224.646979) (xy 46.616679 -224.596049) (xy 46.608736 -224.543345) (xy 32.232356 -224.543345)
			(xy 32.224413 -224.596049) (xy 32.208703 -224.646979) (xy 32.185577 -224.695) (xy 32.155553 -224.739037)
			(xy 32.119301 -224.778108) (xy 32.07763 -224.811339) (xy 32.031472 -224.837988) (xy 31.981858 -224.85746)
			(xy 31.929896 -224.86932) (xy 31.876746 -224.873304) (xy 31.823596 -224.86932) (xy 31.771634 -224.85746)
			(xy 31.72202 -224.837988) (xy 31.675862 -224.811339) (xy 31.634191 -224.778108) (xy 31.597939 -224.739037)
			(xy 31.567915 -224.695) (xy 31.544789 -224.646979) (xy 31.529079 -224.596049) (xy 31.521136 -224.543345)
			(xy 17.144756 -224.543345) (xy 17.136813 -224.596049) (xy 17.121103 -224.646979) (xy 17.097977 -224.695)
			(xy 17.067953 -224.739037) (xy 17.031701 -224.778108) (xy 16.99003 -224.811339) (xy 16.943872 -224.837988)
			(xy 16.894258 -224.85746) (xy 16.842296 -224.86932) (xy 16.789146 -224.873304) (xy 16.735996 -224.86932)
			(xy 16.684034 -224.85746) (xy 16.63442 -224.837988) (xy 16.588262 -224.811339) (xy 16.546591 -224.778108)
			(xy 16.510339 -224.739037) (xy 16.480315 -224.695) (xy 16.457189 -224.646979) (xy 16.441479 -224.596049)
			(xy 16.433536 -224.543345) (xy 6.80339 -224.543345) (xy 6.80339 -225.393229) (xy 20.533604 -225.393229)
			(xy 20.533604 -225.339931) (xy 20.541547 -225.287227) (xy 20.557257 -225.236297) (xy 20.580383 -225.188276)
			(xy 20.610407 -225.144239) (xy 20.646659 -225.105168) (xy 20.68833 -225.071937) (xy 20.734488 -225.045288)
			(xy 20.784102 -225.025816) (xy 20.836064 -225.013956) (xy 20.889214 -225.009973) (xy 20.942364 -225.013956)
			(xy 20.994326 -225.025816) (xy 21.04394 -225.045288) (xy 21.090098 -225.071937) (xy 21.131769 -225.105168)
			(xy 21.168021 -225.144239) (xy 21.198045 -225.188276) (xy 21.221171 -225.236297) (xy 21.236881 -225.287227)
			(xy 21.244824 -225.339931) (xy 21.245322 -225.36658) (xy 21.244824 -225.393229) (xy 35.621204 -225.393229)
			(xy 35.621204 -225.339931) (xy 35.629147 -225.287227) (xy 35.644857 -225.236297) (xy 35.667983 -225.188276)
			(xy 35.698007 -225.144239) (xy 35.734259 -225.105168) (xy 35.77593 -225.071937) (xy 35.822088 -225.045288)
			(xy 35.871702 -225.025816) (xy 35.923664 -225.013956) (xy 35.976814 -225.009973) (xy 36.029964 -225.013956)
			(xy 36.081926 -225.025816) (xy 36.13154 -225.045288) (xy 36.177698 -225.071937) (xy 36.219369 -225.105168)
			(xy 36.255621 -225.144239) (xy 36.285645 -225.188276) (xy 36.308771 -225.236297) (xy 36.324481 -225.287227)
			(xy 36.332424 -225.339931) (xy 36.332922 -225.36658) (xy 36.332424 -225.393229) (xy 50.708804 -225.393229)
			(xy 50.708804 -225.339931) (xy 50.716747 -225.287227) (xy 50.732457 -225.236297) (xy 50.755583 -225.188276)
			(xy 50.785607 -225.144239) (xy 50.821859 -225.105168) (xy 50.86353 -225.071937) (xy 50.909688 -225.045288)
			(xy 50.959302 -225.025816) (xy 51.011264 -225.013956) (xy 51.064414 -225.009973) (xy 51.117564 -225.013956)
			(xy 51.169526 -225.025816) (xy 51.21914 -225.045288) (xy 51.265298 -225.071937) (xy 51.306969 -225.105168)
			(xy 51.343221 -225.144239) (xy 51.373245 -225.188276) (xy 51.396371 -225.236297) (xy 51.412081 -225.287227)
			(xy 51.420024 -225.339931) (xy 51.420522 -225.36658) (xy 51.420024 -225.393229) (xy 51.412081 -225.445933)
			(xy 51.396371 -225.496863) (xy 51.373245 -225.544884) (xy 51.343221 -225.588921) (xy 51.306969 -225.627992)
			(xy 51.265298 -225.661223) (xy 51.21914 -225.687872) (xy 51.169526 -225.707344) (xy 51.117564 -225.719204)
			(xy 51.064414 -225.723188) (xy 51.011264 -225.719204) (xy 50.959302 -225.707344) (xy 50.909688 -225.687872)
			(xy 50.86353 -225.661223) (xy 50.821859 -225.627992) (xy 50.785607 -225.588921) (xy 50.755583 -225.544884)
			(xy 50.732457 -225.496863) (xy 50.716747 -225.445933) (xy 50.708804 -225.393229) (xy 36.332424 -225.393229)
			(xy 36.324481 -225.445933) (xy 36.308771 -225.496863) (xy 36.285645 -225.544884) (xy 36.255621 -225.588921)
			(xy 36.219369 -225.627992) (xy 36.177698 -225.661223) (xy 36.13154 -225.687872) (xy 36.081926 -225.707344)
			(xy 36.029964 -225.719204) (xy 35.976814 -225.723188) (xy 35.923664 -225.719204) (xy 35.871702 -225.707344)
			(xy 35.822088 -225.687872) (xy 35.77593 -225.661223) (xy 35.734259 -225.627992) (xy 35.698007 -225.588921)
			(xy 35.667983 -225.544884) (xy 35.644857 -225.496863) (xy 35.629147 -225.445933) (xy 35.621204 -225.393229)
			(xy 21.244824 -225.393229) (xy 21.236881 -225.445933) (xy 21.221171 -225.496863) (xy 21.198045 -225.544884)
			(xy 21.168021 -225.588921) (xy 21.131769 -225.627992) (xy 21.090098 -225.661223) (xy 21.04394 -225.687872)
			(xy 20.994326 -225.707344) (xy 20.942364 -225.719204) (xy 20.889214 -225.723188) (xy 20.836064 -225.719204)
			(xy 20.784102 -225.707344) (xy 20.734488 -225.687872) (xy 20.68833 -225.661223) (xy 20.646659 -225.627992)
			(xy 20.610407 -225.588921) (xy 20.580383 -225.544884) (xy 20.557257 -225.496863) (xy 20.541547 -225.445933)
			(xy 20.533604 -225.393229) (xy 6.80339 -225.393229) (xy 6.80339 -226.243367) (xy 16.433536 -226.243367)
			(xy 16.433536 -226.190069) (xy 16.441479 -226.137365) (xy 16.457189 -226.086435) (xy 16.480315 -226.038414)
			(xy 16.510339 -225.994377) (xy 16.546591 -225.955306) (xy 16.588262 -225.922075) (xy 16.63442 -225.895426)
			(xy 16.684034 -225.875954) (xy 16.735996 -225.864094) (xy 16.789146 -225.860111) (xy 16.842296 -225.864094)
			(xy 16.894258 -225.875954) (xy 16.943872 -225.895426) (xy 16.99003 -225.922075) (xy 17.031701 -225.955306)
			(xy 17.067953 -225.994377) (xy 17.097977 -226.038414) (xy 17.121103 -226.086435) (xy 17.136813 -226.137365)
			(xy 17.144756 -226.190069) (xy 17.145254 -226.216718) (xy 17.144756 -226.243367) (xy 31.521136 -226.243367)
			(xy 31.521136 -226.190069) (xy 31.529079 -226.137365) (xy 31.544789 -226.086435) (xy 31.567915 -226.038414)
			(xy 31.597939 -225.994377) (xy 31.634191 -225.955306) (xy 31.675862 -225.922075) (xy 31.72202 -225.895426)
			(xy 31.771634 -225.875954) (xy 31.823596 -225.864094) (xy 31.876746 -225.860111) (xy 31.929896 -225.864094)
			(xy 31.981858 -225.875954) (xy 32.031472 -225.895426) (xy 32.07763 -225.922075) (xy 32.119301 -225.955306)
			(xy 32.155553 -225.994377) (xy 32.185577 -226.038414) (xy 32.208703 -226.086435) (xy 32.224413 -226.137365)
			(xy 32.232356 -226.190069) (xy 32.232854 -226.216718) (xy 32.232356 -226.243367) (xy 46.608736 -226.243367)
			(xy 46.608736 -226.190069) (xy 46.616679 -226.137365) (xy 46.632389 -226.086435) (xy 46.655515 -226.038414)
			(xy 46.685539 -225.994377) (xy 46.721791 -225.955306) (xy 46.763462 -225.922075) (xy 46.80962 -225.895426)
			(xy 46.859234 -225.875954) (xy 46.911196 -225.864094) (xy 46.964346 -225.860111) (xy 47.017496 -225.864094)
			(xy 47.069458 -225.875954) (xy 47.119072 -225.895426) (xy 47.16523 -225.922075) (xy 47.206901 -225.955306)
			(xy 47.243153 -225.994377) (xy 47.273177 -226.038414) (xy 47.296303 -226.086435) (xy 47.312013 -226.137365)
			(xy 47.319956 -226.190069) (xy 47.320454 -226.216718) (xy 47.319956 -226.243367) (xy 61.696336 -226.243367)
			(xy 61.696336 -226.190069) (xy 61.704279 -226.137365) (xy 61.719989 -226.086435) (xy 61.743115 -226.038414)
			(xy 61.773139 -225.994377) (xy 61.809391 -225.955306) (xy 61.851062 -225.922075) (xy 61.89722 -225.895426)
			(xy 61.946834 -225.875954) (xy 61.998796 -225.864094) (xy 62.051946 -225.860111) (xy 62.105096 -225.864094)
			(xy 62.157058 -225.875954) (xy 62.206672 -225.895426) (xy 62.25283 -225.922075) (xy 62.294501 -225.955306)
			(xy 62.330753 -225.994377) (xy 62.360777 -226.038414) (xy 62.383903 -226.086435) (xy 62.399613 -226.137365)
			(xy 62.407556 -226.190069) (xy 62.408054 -226.216718) (xy 62.407556 -226.243367) (xy 62.399613 -226.296071)
			(xy 62.383903 -226.347001) (xy 62.360777 -226.395022) (xy 62.330753 -226.439059) (xy 62.294501 -226.47813)
			(xy 62.25283 -226.511361) (xy 62.206672 -226.53801) (xy 62.157058 -226.557482) (xy 62.105096 -226.569342)
			(xy 62.051946 -226.573326) (xy 61.998796 -226.569342) (xy 61.946834 -226.557482) (xy 61.89722 -226.53801)
			(xy 61.851062 -226.511361) (xy 61.809391 -226.47813) (xy 61.773139 -226.439059) (xy 61.743115 -226.395022)
			(xy 61.719989 -226.347001) (xy 61.704279 -226.296071) (xy 61.696336 -226.243367) (xy 47.319956 -226.243367)
			(xy 47.312013 -226.296071) (xy 47.296303 -226.347001) (xy 47.273177 -226.395022) (xy 47.243153 -226.439059)
			(xy 47.206901 -226.47813) (xy 47.16523 -226.511361) (xy 47.119072 -226.53801) (xy 47.069458 -226.557482)
			(xy 47.017496 -226.569342) (xy 46.964346 -226.573326) (xy 46.911196 -226.569342) (xy 46.859234 -226.557482)
			(xy 46.80962 -226.53801) (xy 46.763462 -226.511361) (xy 46.721791 -226.47813) (xy 46.685539 -226.439059)
			(xy 46.655515 -226.395022) (xy 46.632389 -226.347001) (xy 46.616679 -226.296071) (xy 46.608736 -226.243367)
			(xy 32.232356 -226.243367) (xy 32.224413 -226.296071) (xy 32.208703 -226.347001) (xy 32.185577 -226.395022)
			(xy 32.155553 -226.439059) (xy 32.119301 -226.47813) (xy 32.07763 -226.511361) (xy 32.031472 -226.53801)
			(xy 31.981858 -226.557482) (xy 31.929896 -226.569342) (xy 31.876746 -226.573326) (xy 31.823596 -226.569342)
			(xy 31.771634 -226.557482) (xy 31.72202 -226.53801) (xy 31.675862 -226.511361) (xy 31.634191 -226.47813)
			(xy 31.597939 -226.439059) (xy 31.567915 -226.395022) (xy 31.544789 -226.347001) (xy 31.529079 -226.296071)
			(xy 31.521136 -226.243367) (xy 17.144756 -226.243367) (xy 17.136813 -226.296071) (xy 17.121103 -226.347001)
			(xy 17.097977 -226.395022) (xy 17.067953 -226.439059) (xy 17.031701 -226.47813) (xy 16.99003 -226.511361)
			(xy 16.943872 -226.53801) (xy 16.894258 -226.557482) (xy 16.842296 -226.569342) (xy 16.789146 -226.573326)
			(xy 16.735996 -226.569342) (xy 16.684034 -226.557482) (xy 16.63442 -226.53801) (xy 16.588262 -226.511361)
			(xy 16.546591 -226.47813) (xy 16.510339 -226.439059) (xy 16.480315 -226.395022) (xy 16.457189 -226.347001)
			(xy 16.441479 -226.296071) (xy 16.433536 -226.243367) (xy 6.80339 -226.243367) (xy 6.80339 -227.093251)
			(xy 20.533604 -227.093251) (xy 20.533604 -227.039953) (xy 20.541547 -226.987249) (xy 20.557257 -226.936319)
			(xy 20.580383 -226.888298) (xy 20.610407 -226.844261) (xy 20.646659 -226.80519) (xy 20.68833 -226.771959)
			(xy 20.734488 -226.74531) (xy 20.784102 -226.725838) (xy 20.836064 -226.713978) (xy 20.889214 -226.709995)
			(xy 20.942364 -226.713978) (xy 20.994326 -226.725838) (xy 21.04394 -226.74531) (xy 21.090098 -226.771959)
			(xy 21.131769 -226.80519) (xy 21.168021 -226.844261) (xy 21.198045 -226.888298) (xy 21.221171 -226.936319)
			(xy 21.236881 -226.987249) (xy 21.244824 -227.039953) (xy 21.245322 -227.066602) (xy 21.244824 -227.093251)
			(xy 35.621204 -227.093251) (xy 35.621204 -227.039953) (xy 35.629147 -226.987249) (xy 35.644857 -226.936319)
			(xy 35.667983 -226.888298) (xy 35.698007 -226.844261) (xy 35.734259 -226.80519) (xy 35.77593 -226.771959)
			(xy 35.822088 -226.74531) (xy 35.871702 -226.725838) (xy 35.923664 -226.713978) (xy 35.976814 -226.709995)
			(xy 36.029964 -226.713978) (xy 36.081926 -226.725838) (xy 36.13154 -226.74531) (xy 36.177698 -226.771959)
			(xy 36.219369 -226.80519) (xy 36.255621 -226.844261) (xy 36.285645 -226.888298) (xy 36.308771 -226.936319)
			(xy 36.324481 -226.987249) (xy 36.332424 -227.039953) (xy 36.332922 -227.066602) (xy 36.332424 -227.093251)
			(xy 50.708804 -227.093251) (xy 50.708804 -227.039953) (xy 50.716747 -226.987249) (xy 50.732457 -226.936319)
			(xy 50.755583 -226.888298) (xy 50.785607 -226.844261) (xy 50.821859 -226.80519) (xy 50.86353 -226.771959)
			(xy 50.909688 -226.74531) (xy 50.959302 -226.725838) (xy 51.011264 -226.713978) (xy 51.064414 -226.709995)
			(xy 51.117564 -226.713978) (xy 51.169526 -226.725838) (xy 51.21914 -226.74531) (xy 51.265298 -226.771959)
			(xy 51.306969 -226.80519) (xy 51.343221 -226.844261) (xy 51.373245 -226.888298) (xy 51.396371 -226.936319)
			(xy 51.412081 -226.987249) (xy 51.420024 -227.039953) (xy 51.420522 -227.066602) (xy 51.420024 -227.093251)
			(xy 51.412081 -227.145955) (xy 51.396371 -227.196885) (xy 51.373245 -227.244906) (xy 51.343221 -227.288943)
			(xy 51.306969 -227.328014) (xy 51.265298 -227.361245) (xy 51.21914 -227.387894) (xy 51.169526 -227.407366)
			(xy 51.117564 -227.419226) (xy 51.064414 -227.42321) (xy 51.011264 -227.419226) (xy 50.959302 -227.407366)
			(xy 50.909688 -227.387894) (xy 50.86353 -227.361245) (xy 50.821859 -227.328014) (xy 50.785607 -227.288943)
			(xy 50.755583 -227.244906) (xy 50.732457 -227.196885) (xy 50.716747 -227.145955) (xy 50.708804 -227.093251)
			(xy 36.332424 -227.093251) (xy 36.324481 -227.145955) (xy 36.308771 -227.196885) (xy 36.285645 -227.244906)
			(xy 36.255621 -227.288943) (xy 36.219369 -227.328014) (xy 36.177698 -227.361245) (xy 36.13154 -227.387894)
			(xy 36.081926 -227.407366) (xy 36.029964 -227.419226) (xy 35.976814 -227.42321) (xy 35.923664 -227.419226)
			(xy 35.871702 -227.407366) (xy 35.822088 -227.387894) (xy 35.77593 -227.361245) (xy 35.734259 -227.328014)
			(xy 35.698007 -227.288943) (xy 35.667983 -227.244906) (xy 35.644857 -227.196885) (xy 35.629147 -227.145955)
			(xy 35.621204 -227.093251) (xy 21.244824 -227.093251) (xy 21.236881 -227.145955) (xy 21.221171 -227.196885)
			(xy 21.198045 -227.244906) (xy 21.168021 -227.288943) (xy 21.131769 -227.328014) (xy 21.090098 -227.361245)
			(xy 21.04394 -227.387894) (xy 20.994326 -227.407366) (xy 20.942364 -227.419226) (xy 20.889214 -227.42321)
			(xy 20.836064 -227.419226) (xy 20.784102 -227.407366) (xy 20.734488 -227.387894) (xy 20.68833 -227.361245)
			(xy 20.646659 -227.328014) (xy 20.610407 -227.288943) (xy 20.580383 -227.244906) (xy 20.557257 -227.196885)
			(xy 20.541547 -227.145955) (xy 20.533604 -227.093251) (xy 6.80339 -227.093251) (xy 6.80339 -227.943389)
			(xy 16.433536 -227.943389) (xy 16.433536 -227.890091) (xy 16.441479 -227.837387) (xy 16.457189 -227.786457)
			(xy 16.480315 -227.738436) (xy 16.510339 -227.694399) (xy 16.546591 -227.655328) (xy 16.588262 -227.622097)
			(xy 16.63442 -227.595448) (xy 16.684034 -227.575976) (xy 16.735996 -227.564116) (xy 16.789146 -227.560133)
			(xy 16.842296 -227.564116) (xy 16.894258 -227.575976) (xy 16.943872 -227.595448) (xy 16.99003 -227.622097)
			(xy 17.031701 -227.655328) (xy 17.067953 -227.694399) (xy 17.097977 -227.738436) (xy 17.121103 -227.786457)
			(xy 17.136813 -227.837387) (xy 17.144756 -227.890091) (xy 17.145254 -227.91674) (xy 17.144756 -227.943389)
			(xy 20.533604 -227.943389) (xy 20.533604 -227.890091) (xy 20.541547 -227.837387) (xy 20.557257 -227.786457)
			(xy 20.580383 -227.738436) (xy 20.610407 -227.694399) (xy 20.646659 -227.655328) (xy 20.68833 -227.622097)
			(xy 20.734488 -227.595448) (xy 20.784102 -227.575976) (xy 20.836064 -227.564116) (xy 20.889214 -227.560133)
			(xy 20.942364 -227.564116) (xy 20.994326 -227.575976) (xy 21.04394 -227.595448) (xy 21.090098 -227.622097)
			(xy 21.131769 -227.655328) (xy 21.168021 -227.694399) (xy 21.198045 -227.738436) (xy 21.221171 -227.786457)
			(xy 21.236881 -227.837387) (xy 21.244824 -227.890091) (xy 21.245322 -227.91674) (xy 21.244824 -227.943389)
			(xy 31.521136 -227.943389) (xy 31.521136 -227.890091) (xy 31.529079 -227.837387) (xy 31.544789 -227.786457)
			(xy 31.567915 -227.738436) (xy 31.597939 -227.694399) (xy 31.634191 -227.655328) (xy 31.675862 -227.622097)
			(xy 31.72202 -227.595448) (xy 31.771634 -227.575976) (xy 31.823596 -227.564116) (xy 31.876746 -227.560133)
			(xy 31.929896 -227.564116) (xy 31.981858 -227.575976) (xy 32.031472 -227.595448) (xy 32.07763 -227.622097)
			(xy 32.119301 -227.655328) (xy 32.155553 -227.694399) (xy 32.185577 -227.738436) (xy 32.208703 -227.786457)
			(xy 32.224413 -227.837387) (xy 32.232356 -227.890091) (xy 32.232854 -227.91674) (xy 32.232356 -227.943389)
			(xy 35.621204 -227.943389) (xy 35.621204 -227.890091) (xy 35.629147 -227.837387) (xy 35.644857 -227.786457)
			(xy 35.667983 -227.738436) (xy 35.698007 -227.694399) (xy 35.734259 -227.655328) (xy 35.77593 -227.622097)
			(xy 35.822088 -227.595448) (xy 35.871702 -227.575976) (xy 35.923664 -227.564116) (xy 35.976814 -227.560133)
			(xy 36.029964 -227.564116) (xy 36.081926 -227.575976) (xy 36.13154 -227.595448) (xy 36.177698 -227.622097)
			(xy 36.219369 -227.655328) (xy 36.255621 -227.694399) (xy 36.285645 -227.738436) (xy 36.308771 -227.786457)
			(xy 36.324481 -227.837387) (xy 36.332424 -227.890091) (xy 36.332922 -227.91674) (xy 36.332424 -227.943389)
			(xy 46.608736 -227.943389) (xy 46.608736 -227.890091) (xy 46.616679 -227.837387) (xy 46.632389 -227.786457)
			(xy 46.655515 -227.738436) (xy 46.685539 -227.694399) (xy 46.721791 -227.655328) (xy 46.763462 -227.622097)
			(xy 46.80962 -227.595448) (xy 46.859234 -227.575976) (xy 46.911196 -227.564116) (xy 46.964346 -227.560133)
			(xy 47.017496 -227.564116) (xy 47.069458 -227.575976) (xy 47.119072 -227.595448) (xy 47.16523 -227.622097)
			(xy 47.206901 -227.655328) (xy 47.243153 -227.694399) (xy 47.273177 -227.738436) (xy 47.296303 -227.786457)
			(xy 47.312013 -227.837387) (xy 47.319956 -227.890091) (xy 47.320454 -227.91674) (xy 47.319956 -227.943389)
			(xy 50.708804 -227.943389) (xy 50.708804 -227.890091) (xy 50.716747 -227.837387) (xy 50.732457 -227.786457)
			(xy 50.755583 -227.738436) (xy 50.785607 -227.694399) (xy 50.821859 -227.655328) (xy 50.86353 -227.622097)
			(xy 50.909688 -227.595448) (xy 50.959302 -227.575976) (xy 51.011264 -227.564116) (xy 51.064414 -227.560133)
			(xy 51.117564 -227.564116) (xy 51.169526 -227.575976) (xy 51.21914 -227.595448) (xy 51.265298 -227.622097)
			(xy 51.306969 -227.655328) (xy 51.343221 -227.694399) (xy 51.373245 -227.738436) (xy 51.396371 -227.786457)
			(xy 51.412081 -227.837387) (xy 51.420024 -227.890091) (xy 51.420522 -227.91674) (xy 51.420024 -227.943389)
			(xy 61.696336 -227.943389) (xy 61.696336 -227.890091) (xy 61.704279 -227.837387) (xy 61.719989 -227.786457)
			(xy 61.743115 -227.738436) (xy 61.773139 -227.694399) (xy 61.809391 -227.655328) (xy 61.851062 -227.622097)
			(xy 61.89722 -227.595448) (xy 61.946834 -227.575976) (xy 61.998796 -227.564116) (xy 62.051946 -227.560133)
			(xy 62.105096 -227.564116) (xy 62.157058 -227.575976) (xy 62.206672 -227.595448) (xy 62.25283 -227.622097)
			(xy 62.294501 -227.655328) (xy 62.330753 -227.694399) (xy 62.360777 -227.738436) (xy 62.383903 -227.786457)
			(xy 62.399613 -227.837387) (xy 62.407556 -227.890091) (xy 62.408054 -227.91674) (xy 62.407556 -227.943389)
			(xy 62.399613 -227.996093) (xy 62.383903 -228.047023) (xy 62.360777 -228.095044) (xy 62.330753 -228.139081)
			(xy 62.294501 -228.178152) (xy 62.25283 -228.211383) (xy 62.206672 -228.238032) (xy 62.157058 -228.257504)
			(xy 62.105096 -228.269364) (xy 62.051946 -228.273348) (xy 61.998796 -228.269364) (xy 61.946834 -228.257504)
			(xy 61.89722 -228.238032) (xy 61.851062 -228.211383) (xy 61.809391 -228.178152) (xy 61.773139 -228.139081)
			(xy 61.743115 -228.095044) (xy 61.719989 -228.047023) (xy 61.704279 -227.996093) (xy 61.696336 -227.943389)
			(xy 51.420024 -227.943389) (xy 51.412081 -227.996093) (xy 51.396371 -228.047023) (xy 51.373245 -228.095044)
			(xy 51.343221 -228.139081) (xy 51.306969 -228.178152) (xy 51.265298 -228.211383) (xy 51.21914 -228.238032)
			(xy 51.169526 -228.257504) (xy 51.117564 -228.269364) (xy 51.064414 -228.273348) (xy 51.011264 -228.269364)
			(xy 50.959302 -228.257504) (xy 50.909688 -228.238032) (xy 50.86353 -228.211383) (xy 50.821859 -228.178152)
			(xy 50.785607 -228.139081) (xy 50.755583 -228.095044) (xy 50.732457 -228.047023) (xy 50.716747 -227.996093)
			(xy 50.708804 -227.943389) (xy 47.319956 -227.943389) (xy 47.312013 -227.996093) (xy 47.296303 -228.047023)
			(xy 47.273177 -228.095044) (xy 47.243153 -228.139081) (xy 47.206901 -228.178152) (xy 47.16523 -228.211383)
			(xy 47.119072 -228.238032) (xy 47.069458 -228.257504) (xy 47.017496 -228.269364) (xy 46.964346 -228.273348)
			(xy 46.911196 -228.269364) (xy 46.859234 -228.257504) (xy 46.80962 -228.238032) (xy 46.763462 -228.211383)
			(xy 46.721791 -228.178152) (xy 46.685539 -228.139081) (xy 46.655515 -228.095044) (xy 46.632389 -228.047023)
			(xy 46.616679 -227.996093) (xy 46.608736 -227.943389) (xy 36.332424 -227.943389) (xy 36.324481 -227.996093)
			(xy 36.308771 -228.047023) (xy 36.285645 -228.095044) (xy 36.255621 -228.139081) (xy 36.219369 -228.178152)
			(xy 36.177698 -228.211383) (xy 36.13154 -228.238032) (xy 36.081926 -228.257504) (xy 36.029964 -228.269364)
			(xy 35.976814 -228.273348) (xy 35.923664 -228.269364) (xy 35.871702 -228.257504) (xy 35.822088 -228.238032)
			(xy 35.77593 -228.211383) (xy 35.734259 -228.178152) (xy 35.698007 -228.139081) (xy 35.667983 -228.095044)
			(xy 35.644857 -228.047023) (xy 35.629147 -227.996093) (xy 35.621204 -227.943389) (xy 32.232356 -227.943389)
			(xy 32.224413 -227.996093) (xy 32.208703 -228.047023) (xy 32.185577 -228.095044) (xy 32.155553 -228.139081)
			(xy 32.119301 -228.178152) (xy 32.07763 -228.211383) (xy 32.031472 -228.238032) (xy 31.981858 -228.257504)
			(xy 31.929896 -228.269364) (xy 31.876746 -228.273348) (xy 31.823596 -228.269364) (xy 31.771634 -228.257504)
			(xy 31.72202 -228.238032) (xy 31.675862 -228.211383) (xy 31.634191 -228.178152) (xy 31.597939 -228.139081)
			(xy 31.567915 -228.095044) (xy 31.544789 -228.047023) (xy 31.529079 -227.996093) (xy 31.521136 -227.943389)
			(xy 21.244824 -227.943389) (xy 21.236881 -227.996093) (xy 21.221171 -228.047023) (xy 21.198045 -228.095044)
			(xy 21.168021 -228.139081) (xy 21.131769 -228.178152) (xy 21.090098 -228.211383) (xy 21.04394 -228.238032)
			(xy 20.994326 -228.257504) (xy 20.942364 -228.269364) (xy 20.889214 -228.273348) (xy 20.836064 -228.269364)
			(xy 20.784102 -228.257504) (xy 20.734488 -228.238032) (xy 20.68833 -228.211383) (xy 20.646659 -228.178152)
			(xy 20.610407 -228.139081) (xy 20.580383 -228.095044) (xy 20.557257 -228.047023) (xy 20.541547 -227.996093)
			(xy 20.533604 -227.943389) (xy 17.144756 -227.943389) (xy 17.136813 -227.996093) (xy 17.121103 -228.047023)
			(xy 17.097977 -228.095044) (xy 17.067953 -228.139081) (xy 17.031701 -228.178152) (xy 16.99003 -228.211383)
			(xy 16.943872 -228.238032) (xy 16.894258 -228.257504) (xy 16.842296 -228.269364) (xy 16.789146 -228.273348)
			(xy 16.735996 -228.269364) (xy 16.684034 -228.257504) (xy 16.63442 -228.238032) (xy 16.588262 -228.211383)
			(xy 16.546591 -228.178152) (xy 16.510339 -228.139081) (xy 16.480315 -228.095044) (xy 16.457189 -228.047023)
			(xy 16.441479 -227.996093) (xy 16.433536 -227.943389) (xy 6.80339 -227.943389) (xy 6.80339 -228.793273)
			(xy 16.433536 -228.793273) (xy 16.433536 -228.739975) (xy 16.441479 -228.687271) (xy 16.457189 -228.636341)
			(xy 16.480315 -228.58832) (xy 16.510339 -228.544283) (xy 16.546591 -228.505212) (xy 16.588262 -228.471981)
			(xy 16.63442 -228.445332) (xy 16.684034 -228.42586) (xy 16.735996 -228.414) (xy 16.789146 -228.410017)
			(xy 16.842296 -228.414) (xy 16.894258 -228.42586) (xy 16.943872 -228.445332) (xy 16.99003 -228.471981)
			(xy 17.031701 -228.505212) (xy 17.067953 -228.544283) (xy 17.097977 -228.58832) (xy 17.121103 -228.636341)
			(xy 17.136813 -228.687271) (xy 17.144756 -228.739975) (xy 17.145254 -228.766624) (xy 17.144756 -228.793273)
			(xy 31.521136 -228.793273) (xy 31.521136 -228.739975) (xy 31.529079 -228.687271) (xy 31.544789 -228.636341)
			(xy 31.567915 -228.58832) (xy 31.597939 -228.544283) (xy 31.634191 -228.505212) (xy 31.675862 -228.471981)
			(xy 31.72202 -228.445332) (xy 31.771634 -228.42586) (xy 31.823596 -228.414) (xy 31.876746 -228.410017)
			(xy 31.929896 -228.414) (xy 31.981858 -228.42586) (xy 32.031472 -228.445332) (xy 32.07763 -228.471981)
			(xy 32.119301 -228.505212) (xy 32.155553 -228.544283) (xy 32.185577 -228.58832) (xy 32.208703 -228.636341)
			(xy 32.224413 -228.687271) (xy 32.232356 -228.739975) (xy 32.232854 -228.766624) (xy 32.232356 -228.793273)
			(xy 46.608736 -228.793273) (xy 46.608736 -228.739975) (xy 46.616679 -228.687271) (xy 46.632389 -228.636341)
			(xy 46.655515 -228.58832) (xy 46.685539 -228.544283) (xy 46.721791 -228.505212) (xy 46.763462 -228.471981)
			(xy 46.80962 -228.445332) (xy 46.859234 -228.42586) (xy 46.911196 -228.414) (xy 46.964346 -228.410017)
			(xy 47.017496 -228.414) (xy 47.069458 -228.42586) (xy 47.119072 -228.445332) (xy 47.16523 -228.471981)
			(xy 47.206901 -228.505212) (xy 47.243153 -228.544283) (xy 47.273177 -228.58832) (xy 47.296303 -228.636341)
			(xy 47.312013 -228.687271) (xy 47.319956 -228.739975) (xy 47.320454 -228.766624) (xy 47.319956 -228.793273)
			(xy 61.696336 -228.793273) (xy 61.696336 -228.739975) (xy 61.704279 -228.687271) (xy 61.719989 -228.636341)
			(xy 61.743115 -228.58832) (xy 61.773139 -228.544283) (xy 61.809391 -228.505212) (xy 61.851062 -228.471981)
			(xy 61.89722 -228.445332) (xy 61.946834 -228.42586) (xy 61.998796 -228.414) (xy 62.051946 -228.410017)
			(xy 62.105096 -228.414) (xy 62.157058 -228.42586) (xy 62.206672 -228.445332) (xy 62.25283 -228.471981)
			(xy 62.294501 -228.505212) (xy 62.330753 -228.544283) (xy 62.360777 -228.58832) (xy 62.383903 -228.636341)
			(xy 62.399613 -228.687271) (xy 62.407556 -228.739975) (xy 62.408054 -228.766624) (xy 62.407556 -228.793273)
			(xy 62.399613 -228.845977) (xy 62.383903 -228.896907) (xy 62.360777 -228.944928) (xy 62.330753 -228.988965)
			(xy 62.294501 -229.028036) (xy 62.25283 -229.061267) (xy 62.206672 -229.087916) (xy 62.157058 -229.107388)
			(xy 62.105096 -229.119248) (xy 62.051946 -229.123232) (xy 61.998796 -229.119248) (xy 61.946834 -229.107388)
			(xy 61.89722 -229.087916) (xy 61.851062 -229.061267) (xy 61.809391 -229.028036) (xy 61.773139 -228.988965)
			(xy 61.743115 -228.944928) (xy 61.719989 -228.896907) (xy 61.704279 -228.845977) (xy 61.696336 -228.793273)
			(xy 47.319956 -228.793273) (xy 47.312013 -228.845977) (xy 47.296303 -228.896907) (xy 47.273177 -228.944928)
			(xy 47.243153 -228.988965) (xy 47.206901 -229.028036) (xy 47.16523 -229.061267) (xy 47.119072 -229.087916)
			(xy 47.069458 -229.107388) (xy 47.017496 -229.119248) (xy 46.964346 -229.123232) (xy 46.911196 -229.119248)
			(xy 46.859234 -229.107388) (xy 46.80962 -229.087916) (xy 46.763462 -229.061267) (xy 46.721791 -229.028036)
			(xy 46.685539 -228.988965) (xy 46.655515 -228.944928) (xy 46.632389 -228.896907) (xy 46.616679 -228.845977)
			(xy 46.608736 -228.793273) (xy 32.232356 -228.793273) (xy 32.224413 -228.845977) (xy 32.208703 -228.896907)
			(xy 32.185577 -228.944928) (xy 32.155553 -228.988965) (xy 32.119301 -229.028036) (xy 32.07763 -229.061267)
			(xy 32.031472 -229.087916) (xy 31.981858 -229.107388) (xy 31.929896 -229.119248) (xy 31.876746 -229.123232)
			(xy 31.823596 -229.119248) (xy 31.771634 -229.107388) (xy 31.72202 -229.087916) (xy 31.675862 -229.061267)
			(xy 31.634191 -229.028036) (xy 31.597939 -228.988965) (xy 31.567915 -228.944928) (xy 31.544789 -228.896907)
			(xy 31.529079 -228.845977) (xy 31.521136 -228.793273) (xy 17.144756 -228.793273) (xy 17.136813 -228.845977)
			(xy 17.121103 -228.896907) (xy 17.097977 -228.944928) (xy 17.067953 -228.988965) (xy 17.031701 -229.028036)
			(xy 16.99003 -229.061267) (xy 16.943872 -229.087916) (xy 16.894258 -229.107388) (xy 16.842296 -229.119248)
			(xy 16.789146 -229.123232) (xy 16.735996 -229.119248) (xy 16.684034 -229.107388) (xy 16.63442 -229.087916)
			(xy 16.588262 -229.061267) (xy 16.546591 -229.028036) (xy 16.510339 -228.988965) (xy 16.480315 -228.944928)
			(xy 16.457189 -228.896907) (xy 16.441479 -228.845977) (xy 16.433536 -228.793273) (xy 6.80339 -228.793273)
			(xy 6.80339 -229.643411) (xy 20.533604 -229.643411) (xy 20.533604 -229.590113) (xy 20.541547 -229.537409)
			(xy 20.557257 -229.486479) (xy 20.580383 -229.438458) (xy 20.610407 -229.394421) (xy 20.646659 -229.35535)
			(xy 20.68833 -229.322119) (xy 20.734488 -229.29547) (xy 20.784102 -229.275998) (xy 20.836064 -229.264138)
			(xy 20.889214 -229.260155) (xy 20.942364 -229.264138) (xy 20.994326 -229.275998) (xy 21.04394 -229.29547)
			(xy 21.090098 -229.322119) (xy 21.131769 -229.35535) (xy 21.168021 -229.394421) (xy 21.198045 -229.438458)
			(xy 21.221171 -229.486479) (xy 21.236881 -229.537409) (xy 21.244824 -229.590113) (xy 21.245322 -229.616762)
			(xy 21.244824 -229.643411) (xy 35.621204 -229.643411) (xy 35.621204 -229.590113) (xy 35.629147 -229.537409)
			(xy 35.644857 -229.486479) (xy 35.667983 -229.438458) (xy 35.698007 -229.394421) (xy 35.734259 -229.35535)
			(xy 35.77593 -229.322119) (xy 35.822088 -229.29547) (xy 35.871702 -229.275998) (xy 35.923664 -229.264138)
			(xy 35.976814 -229.260155) (xy 36.029964 -229.264138) (xy 36.081926 -229.275998) (xy 36.13154 -229.29547)
			(xy 36.177698 -229.322119) (xy 36.219369 -229.35535) (xy 36.255621 -229.394421) (xy 36.285645 -229.438458)
			(xy 36.308771 -229.486479) (xy 36.324481 -229.537409) (xy 36.332424 -229.590113) (xy 36.332922 -229.616762)
			(xy 36.332424 -229.643411) (xy 50.708804 -229.643411) (xy 50.708804 -229.590113) (xy 50.716747 -229.537409)
			(xy 50.732457 -229.486479) (xy 50.755583 -229.438458) (xy 50.785607 -229.394421) (xy 50.821859 -229.35535)
			(xy 50.86353 -229.322119) (xy 50.909688 -229.29547) (xy 50.959302 -229.275998) (xy 51.011264 -229.264138)
			(xy 51.064414 -229.260155) (xy 51.117564 -229.264138) (xy 51.169526 -229.275998) (xy 51.21914 -229.29547)
			(xy 51.265298 -229.322119) (xy 51.306969 -229.35535) (xy 51.343221 -229.394421) (xy 51.373245 -229.438458)
			(xy 51.396371 -229.486479) (xy 51.412081 -229.537409) (xy 51.420024 -229.590113) (xy 51.420522 -229.616762)
			(xy 51.420024 -229.643411) (xy 51.412081 -229.696115) (xy 51.396371 -229.747045) (xy 51.373245 -229.795066)
			(xy 51.343221 -229.839103) (xy 51.306969 -229.878174) (xy 51.265298 -229.911405) (xy 51.21914 -229.938054)
			(xy 51.169526 -229.957526) (xy 51.117564 -229.969386) (xy 51.064414 -229.97337) (xy 51.011264 -229.969386)
			(xy 50.959302 -229.957526) (xy 50.909688 -229.938054) (xy 50.86353 -229.911405) (xy 50.821859 -229.878174)
			(xy 50.785607 -229.839103) (xy 50.755583 -229.795066) (xy 50.732457 -229.747045) (xy 50.716747 -229.696115)
			(xy 50.708804 -229.643411) (xy 36.332424 -229.643411) (xy 36.324481 -229.696115) (xy 36.308771 -229.747045)
			(xy 36.285645 -229.795066) (xy 36.255621 -229.839103) (xy 36.219369 -229.878174) (xy 36.177698 -229.911405)
			(xy 36.13154 -229.938054) (xy 36.081926 -229.957526) (xy 36.029964 -229.969386) (xy 35.976814 -229.97337)
			(xy 35.923664 -229.969386) (xy 35.871702 -229.957526) (xy 35.822088 -229.938054) (xy 35.77593 -229.911405)
			(xy 35.734259 -229.878174) (xy 35.698007 -229.839103) (xy 35.667983 -229.795066) (xy 35.644857 -229.747045)
			(xy 35.629147 -229.696115) (xy 35.621204 -229.643411) (xy 21.244824 -229.643411) (xy 21.236881 -229.696115)
			(xy 21.221171 -229.747045) (xy 21.198045 -229.795066) (xy 21.168021 -229.839103) (xy 21.131769 -229.878174)
			(xy 21.090098 -229.911405) (xy 21.04394 -229.938054) (xy 20.994326 -229.957526) (xy 20.942364 -229.969386)
			(xy 20.889214 -229.97337) (xy 20.836064 -229.969386) (xy 20.784102 -229.957526) (xy 20.734488 -229.938054)
			(xy 20.68833 -229.911405) (xy 20.646659 -229.878174) (xy 20.610407 -229.839103) (xy 20.580383 -229.795066)
			(xy 20.557257 -229.747045) (xy 20.541547 -229.696115) (xy 20.533604 -229.643411) (xy 6.80339 -229.643411)
			(xy 6.80339 -230.493295) (xy 16.433536 -230.493295) (xy 16.433536 -230.439997) (xy 16.441479 -230.387293)
			(xy 16.457189 -230.336363) (xy 16.480315 -230.288342) (xy 16.510339 -230.244305) (xy 16.546591 -230.205234)
			(xy 16.588262 -230.172003) (xy 16.63442 -230.145354) (xy 16.684034 -230.125882) (xy 16.735996 -230.114022)
			(xy 16.789146 -230.110039) (xy 16.842296 -230.114022) (xy 16.894258 -230.125882) (xy 16.943872 -230.145354)
			(xy 16.99003 -230.172003) (xy 17.031701 -230.205234) (xy 17.067953 -230.244305) (xy 17.097977 -230.288342)
			(xy 17.121103 -230.336363) (xy 17.136813 -230.387293) (xy 17.144756 -230.439997) (xy 17.145254 -230.466646)
			(xy 17.144756 -230.493295) (xy 31.521136 -230.493295) (xy 31.521136 -230.439997) (xy 31.529079 -230.387293)
			(xy 31.544789 -230.336363) (xy 31.567915 -230.288342) (xy 31.597939 -230.244305) (xy 31.634191 -230.205234)
			(xy 31.675862 -230.172003) (xy 31.72202 -230.145354) (xy 31.771634 -230.125882) (xy 31.823596 -230.114022)
			(xy 31.876746 -230.110039) (xy 31.929896 -230.114022) (xy 31.981858 -230.125882) (xy 32.031472 -230.145354)
			(xy 32.07763 -230.172003) (xy 32.119301 -230.205234) (xy 32.155553 -230.244305) (xy 32.185577 -230.288342)
			(xy 32.208703 -230.336363) (xy 32.224413 -230.387293) (xy 32.232356 -230.439997) (xy 32.232854 -230.466646)
			(xy 32.232356 -230.493295) (xy 46.608736 -230.493295) (xy 46.608736 -230.439997) (xy 46.616679 -230.387293)
			(xy 46.632389 -230.336363) (xy 46.655515 -230.288342) (xy 46.685539 -230.244305) (xy 46.721791 -230.205234)
			(xy 46.763462 -230.172003) (xy 46.80962 -230.145354) (xy 46.859234 -230.125882) (xy 46.911196 -230.114022)
			(xy 46.964346 -230.110039) (xy 47.017496 -230.114022) (xy 47.069458 -230.125882) (xy 47.119072 -230.145354)
			(xy 47.16523 -230.172003) (xy 47.206901 -230.205234) (xy 47.243153 -230.244305) (xy 47.273177 -230.288342)
			(xy 47.296303 -230.336363) (xy 47.312013 -230.387293) (xy 47.319956 -230.439997) (xy 47.320454 -230.466646)
			(xy 47.319956 -230.493295) (xy 61.696336 -230.493295) (xy 61.696336 -230.439997) (xy 61.704279 -230.387293)
			(xy 61.719989 -230.336363) (xy 61.743115 -230.288342) (xy 61.773139 -230.244305) (xy 61.809391 -230.205234)
			(xy 61.851062 -230.172003) (xy 61.89722 -230.145354) (xy 61.946834 -230.125882) (xy 61.998796 -230.114022)
			(xy 62.051946 -230.110039) (xy 62.105096 -230.114022) (xy 62.157058 -230.125882) (xy 62.206672 -230.145354)
			(xy 62.25283 -230.172003) (xy 62.294501 -230.205234) (xy 62.330753 -230.244305) (xy 62.360777 -230.288342)
			(xy 62.383903 -230.336363) (xy 62.399613 -230.387293) (xy 62.407556 -230.439997) (xy 62.408054 -230.466646)
			(xy 62.407556 -230.493295) (xy 62.399613 -230.545999) (xy 62.383903 -230.596929) (xy 62.360777 -230.64495)
			(xy 62.330753 -230.688987) (xy 62.294501 -230.728058) (xy 62.25283 -230.761289) (xy 62.206672 -230.787938)
			(xy 62.157058 -230.80741) (xy 62.105096 -230.81927) (xy 62.051946 -230.823254) (xy 61.998796 -230.81927)
			(xy 61.946834 -230.80741) (xy 61.89722 -230.787938) (xy 61.851062 -230.761289) (xy 61.809391 -230.728058)
			(xy 61.773139 -230.688987) (xy 61.743115 -230.64495) (xy 61.719989 -230.596929) (xy 61.704279 -230.545999)
			(xy 61.696336 -230.493295) (xy 47.319956 -230.493295) (xy 47.312013 -230.545999) (xy 47.296303 -230.596929)
			(xy 47.273177 -230.64495) (xy 47.243153 -230.688987) (xy 47.206901 -230.728058) (xy 47.16523 -230.761289)
			(xy 47.119072 -230.787938) (xy 47.069458 -230.80741) (xy 47.017496 -230.81927) (xy 46.964346 -230.823254)
			(xy 46.911196 -230.81927) (xy 46.859234 -230.80741) (xy 46.80962 -230.787938) (xy 46.763462 -230.761289)
			(xy 46.721791 -230.728058) (xy 46.685539 -230.688987) (xy 46.655515 -230.64495) (xy 46.632389 -230.596929)
			(xy 46.616679 -230.545999) (xy 46.608736 -230.493295) (xy 32.232356 -230.493295) (xy 32.224413 -230.545999)
			(xy 32.208703 -230.596929) (xy 32.185577 -230.64495) (xy 32.155553 -230.688987) (xy 32.119301 -230.728058)
			(xy 32.07763 -230.761289) (xy 32.031472 -230.787938) (xy 31.981858 -230.80741) (xy 31.929896 -230.81927)
			(xy 31.876746 -230.823254) (xy 31.823596 -230.81927) (xy 31.771634 -230.80741) (xy 31.72202 -230.787938)
			(xy 31.675862 -230.761289) (xy 31.634191 -230.728058) (xy 31.597939 -230.688987) (xy 31.567915 -230.64495)
			(xy 31.544789 -230.596929) (xy 31.529079 -230.545999) (xy 31.521136 -230.493295) (xy 17.144756 -230.493295)
			(xy 17.136813 -230.545999) (xy 17.121103 -230.596929) (xy 17.097977 -230.64495) (xy 17.067953 -230.688987)
			(xy 17.031701 -230.728058) (xy 16.99003 -230.761289) (xy 16.943872 -230.787938) (xy 16.894258 -230.80741)
			(xy 16.842296 -230.81927) (xy 16.789146 -230.823254) (xy 16.735996 -230.81927) (xy 16.684034 -230.80741)
			(xy 16.63442 -230.787938) (xy 16.588262 -230.761289) (xy 16.546591 -230.728058) (xy 16.510339 -230.688987)
			(xy 16.480315 -230.64495) (xy 16.457189 -230.596929) (xy 16.441479 -230.545999) (xy 16.433536 -230.493295)
			(xy 6.80339 -230.493295) (xy 6.80339 -231.343433) (xy 20.533604 -231.343433) (xy 20.533604 -231.290135)
			(xy 20.541547 -231.237431) (xy 20.557257 -231.186501) (xy 20.580383 -231.13848) (xy 20.610407 -231.094443)
			(xy 20.646659 -231.055372) (xy 20.68833 -231.022141) (xy 20.734488 -230.995492) (xy 20.784102 -230.97602)
			(xy 20.836064 -230.96416) (xy 20.889214 -230.960177) (xy 20.942364 -230.96416) (xy 20.994326 -230.97602)
			(xy 21.04394 -230.995492) (xy 21.090098 -231.022141) (xy 21.131769 -231.055372) (xy 21.168021 -231.094443)
			(xy 21.198045 -231.13848) (xy 21.221171 -231.186501) (xy 21.236881 -231.237431) (xy 21.244824 -231.290135)
			(xy 21.245322 -231.316784) (xy 21.244824 -231.343433) (xy 35.621204 -231.343433) (xy 35.621204 -231.290135)
			(xy 35.629147 -231.237431) (xy 35.644857 -231.186501) (xy 35.667983 -231.13848) (xy 35.698007 -231.094443)
			(xy 35.734259 -231.055372) (xy 35.77593 -231.022141) (xy 35.822088 -230.995492) (xy 35.871702 -230.97602)
			(xy 35.923664 -230.96416) (xy 35.976814 -230.960177) (xy 36.029964 -230.96416) (xy 36.081926 -230.97602)
			(xy 36.13154 -230.995492) (xy 36.177698 -231.022141) (xy 36.219369 -231.055372) (xy 36.255621 -231.094443)
			(xy 36.285645 -231.13848) (xy 36.308771 -231.186501) (xy 36.324481 -231.237431) (xy 36.332424 -231.290135)
			(xy 36.332922 -231.316784) (xy 36.332424 -231.343433) (xy 50.708804 -231.343433) (xy 50.708804 -231.290135)
			(xy 50.716747 -231.237431) (xy 50.732457 -231.186501) (xy 50.755583 -231.13848) (xy 50.785607 -231.094443)
			(xy 50.821859 -231.055372) (xy 50.86353 -231.022141) (xy 50.909688 -230.995492) (xy 50.959302 -230.97602)
			(xy 51.011264 -230.96416) (xy 51.064414 -230.960177) (xy 51.117564 -230.96416) (xy 51.169526 -230.97602)
			(xy 51.21914 -230.995492) (xy 51.265298 -231.022141) (xy 51.306969 -231.055372) (xy 51.343221 -231.094443)
			(xy 51.373245 -231.13848) (xy 51.396371 -231.186501) (xy 51.412081 -231.237431) (xy 51.420024 -231.290135)
			(xy 51.420522 -231.316784) (xy 51.420024 -231.343433) (xy 51.412081 -231.396137) (xy 51.396371 -231.447067)
			(xy 51.373245 -231.495088) (xy 51.343221 -231.539125) (xy 51.306969 -231.578196) (xy 51.265298 -231.611427)
			(xy 51.21914 -231.638076) (xy 51.169526 -231.657548) (xy 51.117564 -231.669408) (xy 51.064414 -231.673392)
			(xy 51.011264 -231.669408) (xy 50.959302 -231.657548) (xy 50.909688 -231.638076) (xy 50.86353 -231.611427)
			(xy 50.821859 -231.578196) (xy 50.785607 -231.539125) (xy 50.755583 -231.495088) (xy 50.732457 -231.447067)
			(xy 50.716747 -231.396137) (xy 50.708804 -231.343433) (xy 36.332424 -231.343433) (xy 36.324481 -231.396137)
			(xy 36.308771 -231.447067) (xy 36.285645 -231.495088) (xy 36.255621 -231.539125) (xy 36.219369 -231.578196)
			(xy 36.177698 -231.611427) (xy 36.13154 -231.638076) (xy 36.081926 -231.657548) (xy 36.029964 -231.669408)
			(xy 35.976814 -231.673392) (xy 35.923664 -231.669408) (xy 35.871702 -231.657548) (xy 35.822088 -231.638076)
			(xy 35.77593 -231.611427) (xy 35.734259 -231.578196) (xy 35.698007 -231.539125) (xy 35.667983 -231.495088)
			(xy 35.644857 -231.447067) (xy 35.629147 -231.396137) (xy 35.621204 -231.343433) (xy 21.244824 -231.343433)
			(xy 21.236881 -231.396137) (xy 21.221171 -231.447067) (xy 21.198045 -231.495088) (xy 21.168021 -231.539125)
			(xy 21.131769 -231.578196) (xy 21.090098 -231.611427) (xy 21.04394 -231.638076) (xy 20.994326 -231.657548)
			(xy 20.942364 -231.669408) (xy 20.889214 -231.673392) (xy 20.836064 -231.669408) (xy 20.784102 -231.657548)
			(xy 20.734488 -231.638076) (xy 20.68833 -231.611427) (xy 20.646659 -231.578196) (xy 20.610407 -231.539125)
			(xy 20.580383 -231.495088) (xy 20.557257 -231.447067) (xy 20.541547 -231.396137) (xy 20.533604 -231.343433)
			(xy 6.80339 -231.343433) (xy 6.80339 -232.193317) (xy 16.433536 -232.193317) (xy 16.433536 -232.140019)
			(xy 16.441479 -232.087315) (xy 16.457189 -232.036385) (xy 16.480315 -231.988364) (xy 16.510339 -231.944327)
			(xy 16.546591 -231.905256) (xy 16.588262 -231.872025) (xy 16.63442 -231.845376) (xy 16.684034 -231.825904)
			(xy 16.735996 -231.814044) (xy 16.789146 -231.810061) (xy 16.842296 -231.814044) (xy 16.894258 -231.825904)
			(xy 16.943872 -231.845376) (xy 16.99003 -231.872025) (xy 17.031701 -231.905256) (xy 17.067953 -231.944327)
			(xy 17.097977 -231.988364) (xy 17.121103 -232.036385) (xy 17.136813 -232.087315) (xy 17.144756 -232.140019)
			(xy 17.145254 -232.166668) (xy 17.144756 -232.193317) (xy 31.521136 -232.193317) (xy 31.521136 -232.140019)
			(xy 31.529079 -232.087315) (xy 31.544789 -232.036385) (xy 31.567915 -231.988364) (xy 31.597939 -231.944327)
			(xy 31.634191 -231.905256) (xy 31.675862 -231.872025) (xy 31.72202 -231.845376) (xy 31.771634 -231.825904)
			(xy 31.823596 -231.814044) (xy 31.876746 -231.810061) (xy 31.929896 -231.814044) (xy 31.981858 -231.825904)
			(xy 32.031472 -231.845376) (xy 32.07763 -231.872025) (xy 32.119301 -231.905256) (xy 32.155553 -231.944327)
			(xy 32.185577 -231.988364) (xy 32.208703 -232.036385) (xy 32.224413 -232.087315) (xy 32.232356 -232.140019)
			(xy 32.232854 -232.166668) (xy 32.232356 -232.193317) (xy 46.608736 -232.193317) (xy 46.608736 -232.140019)
			(xy 46.616679 -232.087315) (xy 46.632389 -232.036385) (xy 46.655515 -231.988364) (xy 46.685539 -231.944327)
			(xy 46.721791 -231.905256) (xy 46.763462 -231.872025) (xy 46.80962 -231.845376) (xy 46.859234 -231.825904)
			(xy 46.911196 -231.814044) (xy 46.964346 -231.810061) (xy 47.017496 -231.814044) (xy 47.069458 -231.825904)
			(xy 47.119072 -231.845376) (xy 47.16523 -231.872025) (xy 47.206901 -231.905256) (xy 47.243153 -231.944327)
			(xy 47.273177 -231.988364) (xy 47.296303 -232.036385) (xy 47.312013 -232.087315) (xy 47.319956 -232.140019)
			(xy 47.320454 -232.166668) (xy 47.319956 -232.193317) (xy 61.696336 -232.193317) (xy 61.696336 -232.140019)
			(xy 61.704279 -232.087315) (xy 61.719989 -232.036385) (xy 61.743115 -231.988364) (xy 61.773139 -231.944327)
			(xy 61.809391 -231.905256) (xy 61.851062 -231.872025) (xy 61.89722 -231.845376) (xy 61.946834 -231.825904)
			(xy 61.998796 -231.814044) (xy 62.051946 -231.810061) (xy 62.105096 -231.814044) (xy 62.157058 -231.825904)
			(xy 62.206672 -231.845376) (xy 62.25283 -231.872025) (xy 62.294501 -231.905256) (xy 62.330753 -231.944327)
			(xy 62.360777 -231.988364) (xy 62.383903 -232.036385) (xy 62.399613 -232.087315) (xy 62.407556 -232.140019)
			(xy 62.408054 -232.166668) (xy 62.407556 -232.193317) (xy 62.399613 -232.246021) (xy 62.383903 -232.296951)
			(xy 62.360777 -232.344972) (xy 62.330753 -232.389009) (xy 62.294501 -232.42808) (xy 62.25283 -232.461311)
			(xy 62.206672 -232.48796) (xy 62.157058 -232.507432) (xy 62.105096 -232.519292) (xy 62.051946 -232.523276)
			(xy 61.998796 -232.519292) (xy 61.946834 -232.507432) (xy 61.89722 -232.48796) (xy 61.851062 -232.461311)
			(xy 61.809391 -232.42808) (xy 61.773139 -232.389009) (xy 61.743115 -232.344972) (xy 61.719989 -232.296951)
			(xy 61.704279 -232.246021) (xy 61.696336 -232.193317) (xy 47.319956 -232.193317) (xy 47.312013 -232.246021)
			(xy 47.296303 -232.296951) (xy 47.273177 -232.344972) (xy 47.243153 -232.389009) (xy 47.206901 -232.42808)
			(xy 47.16523 -232.461311) (xy 47.119072 -232.48796) (xy 47.069458 -232.507432) (xy 47.017496 -232.519292)
			(xy 46.964346 -232.523276) (xy 46.911196 -232.519292) (xy 46.859234 -232.507432) (xy 46.80962 -232.48796)
			(xy 46.763462 -232.461311) (xy 46.721791 -232.42808) (xy 46.685539 -232.389009) (xy 46.655515 -232.344972)
			(xy 46.632389 -232.296951) (xy 46.616679 -232.246021) (xy 46.608736 -232.193317) (xy 32.232356 -232.193317)
			(xy 32.224413 -232.246021) (xy 32.208703 -232.296951) (xy 32.185577 -232.344972) (xy 32.155553 -232.389009)
			(xy 32.119301 -232.42808) (xy 32.07763 -232.461311) (xy 32.031472 -232.48796) (xy 31.981858 -232.507432)
			(xy 31.929896 -232.519292) (xy 31.876746 -232.523276) (xy 31.823596 -232.519292) (xy 31.771634 -232.507432)
			(xy 31.72202 -232.48796) (xy 31.675862 -232.461311) (xy 31.634191 -232.42808) (xy 31.597939 -232.389009)
			(xy 31.567915 -232.344972) (xy 31.544789 -232.296951) (xy 31.529079 -232.246021) (xy 31.521136 -232.193317)
			(xy 17.144756 -232.193317) (xy 17.136813 -232.246021) (xy 17.121103 -232.296951) (xy 17.097977 -232.344972)
			(xy 17.067953 -232.389009) (xy 17.031701 -232.42808) (xy 16.99003 -232.461311) (xy 16.943872 -232.48796)
			(xy 16.894258 -232.507432) (xy 16.842296 -232.519292) (xy 16.789146 -232.523276) (xy 16.735996 -232.519292)
			(xy 16.684034 -232.507432) (xy 16.63442 -232.48796) (xy 16.588262 -232.461311) (xy 16.546591 -232.42808)
			(xy 16.510339 -232.389009) (xy 16.480315 -232.344972) (xy 16.457189 -232.296951) (xy 16.441479 -232.246021)
			(xy 16.433536 -232.193317) (xy 6.80339 -232.193317) (xy 6.80339 -233.043455) (xy 20.533604 -233.043455)
			(xy 20.533604 -232.990157) (xy 20.541547 -232.937453) (xy 20.557257 -232.886523) (xy 20.580383 -232.838502)
			(xy 20.610407 -232.794465) (xy 20.646659 -232.755394) (xy 20.68833 -232.722163) (xy 20.734488 -232.695514)
			(xy 20.784102 -232.676042) (xy 20.836064 -232.664182) (xy 20.889214 -232.660199) (xy 20.942364 -232.664182)
			(xy 20.994326 -232.676042) (xy 21.04394 -232.695514) (xy 21.090098 -232.722163) (xy 21.131769 -232.755394)
			(xy 21.168021 -232.794465) (xy 21.198045 -232.838502) (xy 21.221171 -232.886523) (xy 21.236881 -232.937453)
			(xy 21.244824 -232.990157) (xy 21.245322 -233.016806) (xy 21.244824 -233.043455) (xy 35.621204 -233.043455)
			(xy 35.621204 -232.990157) (xy 35.629147 -232.937453) (xy 35.644857 -232.886523) (xy 35.667983 -232.838502)
			(xy 35.698007 -232.794465) (xy 35.734259 -232.755394) (xy 35.77593 -232.722163) (xy 35.822088 -232.695514)
			(xy 35.871702 -232.676042) (xy 35.923664 -232.664182) (xy 35.976814 -232.660199) (xy 36.029964 -232.664182)
			(xy 36.081926 -232.676042) (xy 36.13154 -232.695514) (xy 36.177698 -232.722163) (xy 36.219369 -232.755394)
			(xy 36.255621 -232.794465) (xy 36.285645 -232.838502) (xy 36.308771 -232.886523) (xy 36.324481 -232.937453)
			(xy 36.332424 -232.990157) (xy 36.332922 -233.016806) (xy 36.332424 -233.043455) (xy 50.708804 -233.043455)
			(xy 50.708804 -232.990157) (xy 50.716747 -232.937453) (xy 50.732457 -232.886523) (xy 50.755583 -232.838502)
			(xy 50.785607 -232.794465) (xy 50.821859 -232.755394) (xy 50.86353 -232.722163) (xy 50.909688 -232.695514)
			(xy 50.959302 -232.676042) (xy 51.011264 -232.664182) (xy 51.064414 -232.660199) (xy 51.117564 -232.664182)
			(xy 51.169526 -232.676042) (xy 51.21914 -232.695514) (xy 51.265298 -232.722163) (xy 51.306969 -232.755394)
			(xy 51.343221 -232.794465) (xy 51.373245 -232.838502) (xy 51.396371 -232.886523) (xy 51.412081 -232.937453)
			(xy 51.420024 -232.990157) (xy 51.420522 -233.016806) (xy 51.420024 -233.043455) (xy 51.412081 -233.096159)
			(xy 51.396371 -233.147089) (xy 51.373245 -233.19511) (xy 51.343221 -233.239147) (xy 51.306969 -233.278218)
			(xy 51.265298 -233.311449) (xy 51.21914 -233.338098) (xy 51.169526 -233.35757) (xy 51.117564 -233.36943)
			(xy 51.064414 -233.373414) (xy 51.011264 -233.36943) (xy 50.959302 -233.35757) (xy 50.909688 -233.338098)
			(xy 50.86353 -233.311449) (xy 50.821859 -233.278218) (xy 50.785607 -233.239147) (xy 50.755583 -233.19511)
			(xy 50.732457 -233.147089) (xy 50.716747 -233.096159) (xy 50.708804 -233.043455) (xy 36.332424 -233.043455)
			(xy 36.324481 -233.096159) (xy 36.308771 -233.147089) (xy 36.285645 -233.19511) (xy 36.255621 -233.239147)
			(xy 36.219369 -233.278218) (xy 36.177698 -233.311449) (xy 36.13154 -233.338098) (xy 36.081926 -233.35757)
			(xy 36.029964 -233.36943) (xy 35.976814 -233.373414) (xy 35.923664 -233.36943) (xy 35.871702 -233.35757)
			(xy 35.822088 -233.338098) (xy 35.77593 -233.311449) (xy 35.734259 -233.278218) (xy 35.698007 -233.239147)
			(xy 35.667983 -233.19511) (xy 35.644857 -233.147089) (xy 35.629147 -233.096159) (xy 35.621204 -233.043455)
			(xy 21.244824 -233.043455) (xy 21.236881 -233.096159) (xy 21.221171 -233.147089) (xy 21.198045 -233.19511)
			(xy 21.168021 -233.239147) (xy 21.131769 -233.278218) (xy 21.090098 -233.311449) (xy 21.04394 -233.338098)
			(xy 20.994326 -233.35757) (xy 20.942364 -233.36943) (xy 20.889214 -233.373414) (xy 20.836064 -233.36943)
			(xy 20.784102 -233.35757) (xy 20.734488 -233.338098) (xy 20.68833 -233.311449) (xy 20.646659 -233.278218)
			(xy 20.610407 -233.239147) (xy 20.580383 -233.19511) (xy 20.557257 -233.147089) (xy 20.541547 -233.096159)
			(xy 20.533604 -233.043455) (xy 6.80339 -233.043455) (xy 6.80339 -233.893339) (xy 16.433536 -233.893339)
			(xy 16.433536 -233.840041) (xy 16.441479 -233.787337) (xy 16.457189 -233.736407) (xy 16.480315 -233.688386)
			(xy 16.510339 -233.644349) (xy 16.546591 -233.605278) (xy 16.588262 -233.572047) (xy 16.63442 -233.545398)
			(xy 16.684034 -233.525926) (xy 16.735996 -233.514066) (xy 16.789146 -233.510083) (xy 16.842296 -233.514066)
			(xy 16.894258 -233.525926) (xy 16.943872 -233.545398) (xy 16.99003 -233.572047) (xy 17.031701 -233.605278)
			(xy 17.067953 -233.644349) (xy 17.097977 -233.688386) (xy 17.121103 -233.736407) (xy 17.136813 -233.787337)
			(xy 17.144756 -233.840041) (xy 17.145254 -233.86669) (xy 17.144756 -233.893339) (xy 31.521136 -233.893339)
			(xy 31.521136 -233.840041) (xy 31.529079 -233.787337) (xy 31.544789 -233.736407) (xy 31.567915 -233.688386)
			(xy 31.597939 -233.644349) (xy 31.634191 -233.605278) (xy 31.675862 -233.572047) (xy 31.72202 -233.545398)
			(xy 31.771634 -233.525926) (xy 31.823596 -233.514066) (xy 31.876746 -233.510083) (xy 31.929896 -233.514066)
			(xy 31.981858 -233.525926) (xy 32.031472 -233.545398) (xy 32.07763 -233.572047) (xy 32.119301 -233.605278)
			(xy 32.155553 -233.644349) (xy 32.185577 -233.688386) (xy 32.208703 -233.736407) (xy 32.224413 -233.787337)
			(xy 32.232356 -233.840041) (xy 32.232854 -233.86669) (xy 32.232356 -233.893339) (xy 46.608736 -233.893339)
			(xy 46.608736 -233.840041) (xy 46.616679 -233.787337) (xy 46.632389 -233.736407) (xy 46.655515 -233.688386)
			(xy 46.685539 -233.644349) (xy 46.721791 -233.605278) (xy 46.763462 -233.572047) (xy 46.80962 -233.545398)
			(xy 46.859234 -233.525926) (xy 46.911196 -233.514066) (xy 46.964346 -233.510083) (xy 47.017496 -233.514066)
			(xy 47.069458 -233.525926) (xy 47.119072 -233.545398) (xy 47.16523 -233.572047) (xy 47.206901 -233.605278)
			(xy 47.243153 -233.644349) (xy 47.273177 -233.688386) (xy 47.296303 -233.736407) (xy 47.312013 -233.787337)
			(xy 47.319956 -233.840041) (xy 47.320454 -233.86669) (xy 47.319956 -233.893339) (xy 47.312013 -233.946043)
			(xy 47.296303 -233.996973) (xy 47.273177 -234.044994) (xy 47.243153 -234.089031) (xy 47.206901 -234.128102)
			(xy 47.16523 -234.161333) (xy 47.119072 -234.187982) (xy 47.069458 -234.207454) (xy 47.017496 -234.219314)
			(xy 46.964346 -234.223298) (xy 46.911196 -234.219314) (xy 46.859234 -234.207454) (xy 46.80962 -234.187982)
			(xy 46.763462 -234.161333) (xy 46.721791 -234.128102) (xy 46.685539 -234.089031) (xy 46.655515 -234.044994)
			(xy 46.632389 -233.996973) (xy 46.616679 -233.946043) (xy 46.608736 -233.893339) (xy 32.232356 -233.893339)
			(xy 32.224413 -233.946043) (xy 32.208703 -233.996973) (xy 32.185577 -234.044994) (xy 32.155553 -234.089031)
			(xy 32.119301 -234.128102) (xy 32.07763 -234.161333) (xy 32.031472 -234.187982) (xy 31.981858 -234.207454)
			(xy 31.929896 -234.219314) (xy 31.876746 -234.223298) (xy 31.823596 -234.219314) (xy 31.771634 -234.207454)
			(xy 31.72202 -234.187982) (xy 31.675862 -234.161333) (xy 31.634191 -234.128102) (xy 31.597939 -234.089031)
			(xy 31.567915 -234.044994) (xy 31.544789 -233.996973) (xy 31.529079 -233.946043) (xy 31.521136 -233.893339)
			(xy 17.144756 -233.893339) (xy 17.136813 -233.946043) (xy 17.121103 -233.996973) (xy 17.097977 -234.044994)
			(xy 17.067953 -234.089031) (xy 17.031701 -234.128102) (xy 16.99003 -234.161333) (xy 16.943872 -234.187982)
			(xy 16.894258 -234.207454) (xy 16.842296 -234.219314) (xy 16.789146 -234.223298) (xy 16.735996 -234.219314)
			(xy 16.684034 -234.207454) (xy 16.63442 -234.187982) (xy 16.588262 -234.161333) (xy 16.546591 -234.128102)
			(xy 16.510339 -234.089031) (xy 16.480315 -234.044994) (xy 16.457189 -233.996973) (xy 16.441479 -233.946043)
			(xy 16.433536 -233.893339) (xy 6.80339 -233.893339) (xy 6.80339 -234.743223) (xy 20.533604 -234.743223)
			(xy 20.533604 -234.689925) (xy 20.541547 -234.637221) (xy 20.557257 -234.586291) (xy 20.580383 -234.53827)
			(xy 20.610407 -234.494233) (xy 20.646659 -234.455162) (xy 20.68833 -234.421931) (xy 20.734488 -234.395282)
			(xy 20.784102 -234.37581) (xy 20.836064 -234.36395) (xy 20.889214 -234.359967) (xy 20.942364 -234.36395)
			(xy 20.994326 -234.37581) (xy 21.04394 -234.395282) (xy 21.090098 -234.421931) (xy 21.131769 -234.455162)
			(xy 21.168021 -234.494233) (xy 21.198045 -234.53827) (xy 21.221171 -234.586291) (xy 21.236881 -234.637221)
			(xy 21.244824 -234.689925) (xy 21.245322 -234.716574) (xy 21.244824 -234.743223) (xy 35.621204 -234.743223)
			(xy 35.621204 -234.689925) (xy 35.629147 -234.637221) (xy 35.644857 -234.586291) (xy 35.667983 -234.53827)
			(xy 35.698007 -234.494233) (xy 35.734259 -234.455162) (xy 35.77593 -234.421931) (xy 35.822088 -234.395282)
			(xy 35.871702 -234.37581) (xy 35.923664 -234.36395) (xy 35.976814 -234.359967) (xy 36.029964 -234.36395)
			(xy 36.081926 -234.37581) (xy 36.13154 -234.395282) (xy 36.177698 -234.421931) (xy 36.219369 -234.455162)
			(xy 36.255621 -234.494233) (xy 36.285645 -234.53827) (xy 36.308771 -234.586291) (xy 36.324481 -234.637221)
			(xy 36.332424 -234.689925) (xy 36.332922 -234.716574) (xy 36.332424 -234.743223) (xy 50.708804 -234.743223)
			(xy 50.708804 -234.689925) (xy 50.716747 -234.637221) (xy 50.732457 -234.586291) (xy 50.755583 -234.53827)
			(xy 50.785607 -234.494233) (xy 50.821859 -234.455162) (xy 50.86353 -234.421931) (xy 50.909688 -234.395282)
			(xy 50.959302 -234.37581) (xy 51.011264 -234.36395) (xy 51.064414 -234.359967) (xy 51.117564 -234.36395)
			(xy 51.169526 -234.37581) (xy 51.21914 -234.395282) (xy 51.265298 -234.421931) (xy 51.306969 -234.455162)
			(xy 51.343221 -234.494233) (xy 51.373245 -234.53827) (xy 51.396371 -234.586291) (xy 51.412081 -234.637221)
			(xy 51.420024 -234.689925) (xy 51.420522 -234.716574) (xy 51.420024 -234.743223) (xy 51.412081 -234.795927)
			(xy 51.396371 -234.846857) (xy 51.373245 -234.894878) (xy 51.343221 -234.938915) (xy 51.306969 -234.977986)
			(xy 51.265298 -235.011217) (xy 51.21914 -235.037866) (xy 51.169526 -235.057338) (xy 51.117564 -235.069198)
			(xy 51.064414 -235.073182) (xy 51.011264 -235.069198) (xy 50.959302 -235.057338) (xy 50.909688 -235.037866)
			(xy 50.86353 -235.011217) (xy 50.821859 -234.977986) (xy 50.785607 -234.938915) (xy 50.755583 -234.894878)
			(xy 50.732457 -234.846857) (xy 50.716747 -234.795927) (xy 50.708804 -234.743223) (xy 36.332424 -234.743223)
			(xy 36.324481 -234.795927) (xy 36.308771 -234.846857) (xy 36.285645 -234.894878) (xy 36.255621 -234.938915)
			(xy 36.219369 -234.977986) (xy 36.177698 -235.011217) (xy 36.13154 -235.037866) (xy 36.081926 -235.057338)
			(xy 36.029964 -235.069198) (xy 35.976814 -235.073182) (xy 35.923664 -235.069198) (xy 35.871702 -235.057338)
			(xy 35.822088 -235.037866) (xy 35.77593 -235.011217) (xy 35.734259 -234.977986) (xy 35.698007 -234.938915)
			(xy 35.667983 -234.894878) (xy 35.644857 -234.846857) (xy 35.629147 -234.795927) (xy 35.621204 -234.743223)
			(xy 21.244824 -234.743223) (xy 21.236881 -234.795927) (xy 21.221171 -234.846857) (xy 21.198045 -234.894878)
			(xy 21.168021 -234.938915) (xy 21.131769 -234.977986) (xy 21.090098 -235.011217) (xy 21.04394 -235.037866)
			(xy 20.994326 -235.057338) (xy 20.942364 -235.069198) (xy 20.889214 -235.073182) (xy 20.836064 -235.069198)
			(xy 20.784102 -235.057338) (xy 20.734488 -235.037866) (xy 20.68833 -235.011217) (xy 20.646659 -234.977986)
			(xy 20.610407 -234.938915) (xy 20.580383 -234.894878) (xy 20.557257 -234.846857) (xy 20.541547 -234.795927)
			(xy 20.533604 -234.743223) (xy 6.80339 -234.743223) (xy 6.80339 -235.593361) (xy 16.433536 -235.593361)
			(xy 16.433536 -235.540063) (xy 16.441479 -235.487359) (xy 16.457189 -235.436429) (xy 16.480315 -235.388408)
			(xy 16.510339 -235.344371) (xy 16.546591 -235.3053) (xy 16.588262 -235.272069) (xy 16.63442 -235.24542)
			(xy 16.684034 -235.225948) (xy 16.735996 -235.214088) (xy 16.789146 -235.210105) (xy 16.842296 -235.214088)
			(xy 16.894258 -235.225948) (xy 16.943872 -235.24542) (xy 16.99003 -235.272069) (xy 17.031701 -235.3053)
			(xy 17.067953 -235.344371) (xy 17.097977 -235.388408) (xy 17.121103 -235.436429) (xy 17.136813 -235.487359)
			(xy 17.144756 -235.540063) (xy 17.145254 -235.566712) (xy 17.144756 -235.593361) (xy 31.521136 -235.593361)
			(xy 31.521136 -235.540063) (xy 31.529079 -235.487359) (xy 31.544789 -235.436429) (xy 31.567915 -235.388408)
			(xy 31.597939 -235.344371) (xy 31.634191 -235.3053) (xy 31.675862 -235.272069) (xy 31.72202 -235.24542)
			(xy 31.771634 -235.225948) (xy 31.823596 -235.214088) (xy 31.876746 -235.210105) (xy 31.929896 -235.214088)
			(xy 31.981858 -235.225948) (xy 32.031472 -235.24542) (xy 32.07763 -235.272069) (xy 32.119301 -235.3053)
			(xy 32.155553 -235.344371) (xy 32.185577 -235.388408) (xy 32.208703 -235.436429) (xy 32.224413 -235.487359)
			(xy 32.232356 -235.540063) (xy 32.232854 -235.566712) (xy 32.232356 -235.593361) (xy 46.608736 -235.593361)
			(xy 46.608736 -235.540063) (xy 46.616679 -235.487359) (xy 46.632389 -235.436429) (xy 46.655515 -235.388408)
			(xy 46.685539 -235.344371) (xy 46.721791 -235.3053) (xy 46.763462 -235.272069) (xy 46.80962 -235.24542)
			(xy 46.859234 -235.225948) (xy 46.911196 -235.214088) (xy 46.964346 -235.210105) (xy 47.017496 -235.214088)
			(xy 47.069458 -235.225948) (xy 47.119072 -235.24542) (xy 47.16523 -235.272069) (xy 47.206901 -235.3053)
			(xy 47.243153 -235.344371) (xy 47.273177 -235.388408) (xy 47.296303 -235.436429) (xy 47.312013 -235.487359)
			(xy 47.319956 -235.540063) (xy 47.320454 -235.566712) (xy 47.319956 -235.593361) (xy 47.312013 -235.646065)
			(xy 47.296303 -235.696995) (xy 47.273177 -235.745016) (xy 47.243153 -235.789053) (xy 47.206901 -235.828124)
			(xy 47.16523 -235.861355) (xy 47.119072 -235.888004) (xy 47.069458 -235.907476) (xy 47.017496 -235.919336)
			(xy 46.964346 -235.92332) (xy 46.911196 -235.919336) (xy 46.859234 -235.907476) (xy 46.80962 -235.888004)
			(xy 46.763462 -235.861355) (xy 46.721791 -235.828124) (xy 46.685539 -235.789053) (xy 46.655515 -235.745016)
			(xy 46.632389 -235.696995) (xy 46.616679 -235.646065) (xy 46.608736 -235.593361) (xy 32.232356 -235.593361)
			(xy 32.224413 -235.646065) (xy 32.208703 -235.696995) (xy 32.185577 -235.745016) (xy 32.155553 -235.789053)
			(xy 32.119301 -235.828124) (xy 32.07763 -235.861355) (xy 32.031472 -235.888004) (xy 31.981858 -235.907476)
			(xy 31.929896 -235.919336) (xy 31.876746 -235.92332) (xy 31.823596 -235.919336) (xy 31.771634 -235.907476)
			(xy 31.72202 -235.888004) (xy 31.675862 -235.861355) (xy 31.634191 -235.828124) (xy 31.597939 -235.789053)
			(xy 31.567915 -235.745016) (xy 31.544789 -235.696995) (xy 31.529079 -235.646065) (xy 31.521136 -235.593361)
			(xy 17.144756 -235.593361) (xy 17.136813 -235.646065) (xy 17.121103 -235.696995) (xy 17.097977 -235.745016)
			(xy 17.067953 -235.789053) (xy 17.031701 -235.828124) (xy 16.99003 -235.861355) (xy 16.943872 -235.888004)
			(xy 16.894258 -235.907476) (xy 16.842296 -235.919336) (xy 16.789146 -235.92332) (xy 16.735996 -235.919336)
			(xy 16.684034 -235.907476) (xy 16.63442 -235.888004) (xy 16.588262 -235.861355) (xy 16.546591 -235.828124)
			(xy 16.510339 -235.789053) (xy 16.480315 -235.745016) (xy 16.457189 -235.696995) (xy 16.441479 -235.646065)
			(xy 16.433536 -235.593361) (xy 6.80339 -235.593361) (xy 6.80339 -236.443245) (xy 20.533604 -236.443245)
			(xy 20.533604 -236.389947) (xy 20.541547 -236.337243) (xy 20.557257 -236.286313) (xy 20.580383 -236.238292)
			(xy 20.610407 -236.194255) (xy 20.646659 -236.155184) (xy 20.68833 -236.121953) (xy 20.734488 -236.095304)
			(xy 20.784102 -236.075832) (xy 20.836064 -236.063972) (xy 20.889214 -236.059989) (xy 20.942364 -236.063972)
			(xy 20.994326 -236.075832) (xy 21.04394 -236.095304) (xy 21.090098 -236.121953) (xy 21.131769 -236.155184)
			(xy 21.168021 -236.194255) (xy 21.198045 -236.238292) (xy 21.221171 -236.286313) (xy 21.236881 -236.337243)
			(xy 21.244824 -236.389947) (xy 21.245322 -236.416596) (xy 21.244824 -236.443245) (xy 35.621204 -236.443245)
			(xy 35.621204 -236.389947) (xy 35.629147 -236.337243) (xy 35.644857 -236.286313) (xy 35.667983 -236.238292)
			(xy 35.698007 -236.194255) (xy 35.734259 -236.155184) (xy 35.77593 -236.121953) (xy 35.822088 -236.095304)
			(xy 35.871702 -236.075832) (xy 35.923664 -236.063972) (xy 35.976814 -236.059989) (xy 36.029964 -236.063972)
			(xy 36.081926 -236.075832) (xy 36.13154 -236.095304) (xy 36.177698 -236.121953) (xy 36.219369 -236.155184)
			(xy 36.255621 -236.194255) (xy 36.285645 -236.238292) (xy 36.308771 -236.286313) (xy 36.324481 -236.337243)
			(xy 36.332424 -236.389947) (xy 36.332922 -236.416596) (xy 36.332424 -236.443245) (xy 50.708804 -236.443245)
			(xy 50.708804 -236.389947) (xy 50.716747 -236.337243) (xy 50.732457 -236.286313) (xy 50.755583 -236.238292)
			(xy 50.785607 -236.194255) (xy 50.821859 -236.155184) (xy 50.86353 -236.121953) (xy 50.909688 -236.095304)
			(xy 50.959302 -236.075832) (xy 51.011264 -236.063972) (xy 51.064414 -236.059989) (xy 51.117564 -236.063972)
			(xy 51.169526 -236.075832) (xy 51.21914 -236.095304) (xy 51.265298 -236.121953) (xy 51.306969 -236.155184)
			(xy 51.343221 -236.194255) (xy 51.373245 -236.238292) (xy 51.396371 -236.286313) (xy 51.412081 -236.337243)
			(xy 51.420024 -236.389947) (xy 51.420522 -236.416596) (xy 51.420024 -236.443245) (xy 51.412081 -236.495949)
			(xy 51.396371 -236.546879) (xy 51.373245 -236.5949) (xy 51.343221 -236.638937) (xy 51.306969 -236.678008)
			(xy 51.265298 -236.711239) (xy 51.21914 -236.737888) (xy 51.169526 -236.75736) (xy 51.117564 -236.76922)
			(xy 51.064414 -236.773204) (xy 51.011264 -236.76922) (xy 50.959302 -236.75736) (xy 50.909688 -236.737888)
			(xy 50.86353 -236.711239) (xy 50.821859 -236.678008) (xy 50.785607 -236.638937) (xy 50.755583 -236.5949)
			(xy 50.732457 -236.546879) (xy 50.716747 -236.495949) (xy 50.708804 -236.443245) (xy 36.332424 -236.443245)
			(xy 36.324481 -236.495949) (xy 36.308771 -236.546879) (xy 36.285645 -236.5949) (xy 36.255621 -236.638937)
			(xy 36.219369 -236.678008) (xy 36.177698 -236.711239) (xy 36.13154 -236.737888) (xy 36.081926 -236.75736)
			(xy 36.029964 -236.76922) (xy 35.976814 -236.773204) (xy 35.923664 -236.76922) (xy 35.871702 -236.75736)
			(xy 35.822088 -236.737888) (xy 35.77593 -236.711239) (xy 35.734259 -236.678008) (xy 35.698007 -236.638937)
			(xy 35.667983 -236.5949) (xy 35.644857 -236.546879) (xy 35.629147 -236.495949) (xy 35.621204 -236.443245)
			(xy 21.244824 -236.443245) (xy 21.236881 -236.495949) (xy 21.221171 -236.546879) (xy 21.198045 -236.5949)
			(xy 21.168021 -236.638937) (xy 21.131769 -236.678008) (xy 21.090098 -236.711239) (xy 21.04394 -236.737888)
			(xy 20.994326 -236.75736) (xy 20.942364 -236.76922) (xy 20.889214 -236.773204) (xy 20.836064 -236.76922)
			(xy 20.784102 -236.75736) (xy 20.734488 -236.737888) (xy 20.68833 -236.711239) (xy 20.646659 -236.678008)
			(xy 20.610407 -236.638937) (xy 20.580383 -236.5949) (xy 20.557257 -236.546879) (xy 20.541547 -236.495949)
			(xy 20.533604 -236.443245) (xy 6.80339 -236.443245) (xy 6.80339 -237.293383) (xy 16.433536 -237.293383)
			(xy 16.433536 -237.240085) (xy 16.441479 -237.187381) (xy 16.457189 -237.136451) (xy 16.480315 -237.08843)
			(xy 16.510339 -237.044393) (xy 16.546591 -237.005322) (xy 16.588262 -236.972091) (xy 16.63442 -236.945442)
			(xy 16.684034 -236.92597) (xy 16.735996 -236.91411) (xy 16.789146 -236.910127) (xy 16.842296 -236.91411)
			(xy 16.894258 -236.92597) (xy 16.943872 -236.945442) (xy 16.99003 -236.972091) (xy 17.031701 -237.005322)
			(xy 17.067953 -237.044393) (xy 17.097977 -237.08843) (xy 17.121103 -237.136451) (xy 17.136813 -237.187381)
			(xy 17.144756 -237.240085) (xy 17.145254 -237.266734) (xy 17.144756 -237.293383) (xy 20.533604 -237.293383)
			(xy 20.533604 -237.240085) (xy 20.541547 -237.187381) (xy 20.557257 -237.136451) (xy 20.580383 -237.08843)
			(xy 20.610407 -237.044393) (xy 20.646659 -237.005322) (xy 20.68833 -236.972091) (xy 20.734488 -236.945442)
			(xy 20.784102 -236.92597) (xy 20.836064 -236.91411) (xy 20.889214 -236.910127) (xy 20.942364 -236.91411)
			(xy 20.994326 -236.92597) (xy 21.04394 -236.945442) (xy 21.090098 -236.972091) (xy 21.131769 -237.005322)
			(xy 21.168021 -237.044393) (xy 21.198045 -237.08843) (xy 21.221171 -237.136451) (xy 21.236881 -237.187381)
			(xy 21.244824 -237.240085) (xy 21.245322 -237.266734) (xy 21.244824 -237.293383) (xy 31.521136 -237.293383)
			(xy 31.521136 -237.240085) (xy 31.529079 -237.187381) (xy 31.544789 -237.136451) (xy 31.567915 -237.08843)
			(xy 31.597939 -237.044393) (xy 31.634191 -237.005322) (xy 31.675862 -236.972091) (xy 31.72202 -236.945442)
			(xy 31.771634 -236.92597) (xy 31.823596 -236.91411) (xy 31.876746 -236.910127) (xy 31.929896 -236.91411)
			(xy 31.981858 -236.92597) (xy 32.031472 -236.945442) (xy 32.07763 -236.972091) (xy 32.119301 -237.005322)
			(xy 32.155553 -237.044393) (xy 32.185577 -237.08843) (xy 32.208703 -237.136451) (xy 32.224413 -237.187381)
			(xy 32.232356 -237.240085) (xy 32.232854 -237.266734) (xy 32.232356 -237.293383) (xy 35.621204 -237.293383)
			(xy 35.621204 -237.240085) (xy 35.629147 -237.187381) (xy 35.644857 -237.136451) (xy 35.667983 -237.08843)
			(xy 35.698007 -237.044393) (xy 35.734259 -237.005322) (xy 35.77593 -236.972091) (xy 35.822088 -236.945442)
			(xy 35.871702 -236.92597) (xy 35.923664 -236.91411) (xy 35.976814 -236.910127) (xy 36.029964 -236.91411)
			(xy 36.081926 -236.92597) (xy 36.13154 -236.945442) (xy 36.177698 -236.972091) (xy 36.219369 -237.005322)
			(xy 36.255621 -237.044393) (xy 36.285645 -237.08843) (xy 36.308771 -237.136451) (xy 36.324481 -237.187381)
			(xy 36.332424 -237.240085) (xy 36.332922 -237.266734) (xy 36.332424 -237.293383) (xy 46.608736 -237.293383)
			(xy 46.608736 -237.240085) (xy 46.616679 -237.187381) (xy 46.632389 -237.136451) (xy 46.655515 -237.08843)
			(xy 46.685539 -237.044393) (xy 46.721791 -237.005322) (xy 46.763462 -236.972091) (xy 46.80962 -236.945442)
			(xy 46.859234 -236.92597) (xy 46.911196 -236.91411) (xy 46.964346 -236.910127) (xy 47.017496 -236.91411)
			(xy 47.069458 -236.92597) (xy 47.119072 -236.945442) (xy 47.16523 -236.972091) (xy 47.206901 -237.005322)
			(xy 47.243153 -237.044393) (xy 47.273177 -237.08843) (xy 47.296303 -237.136451) (xy 47.312013 -237.187381)
			(xy 47.319956 -237.240085) (xy 47.320454 -237.266734) (xy 47.319956 -237.293383) (xy 50.708804 -237.293383)
			(xy 50.708804 -237.240085) (xy 50.716747 -237.187381) (xy 50.732457 -237.136451) (xy 50.755583 -237.08843)
			(xy 50.785607 -237.044393) (xy 50.821859 -237.005322) (xy 50.86353 -236.972091) (xy 50.909688 -236.945442)
			(xy 50.959302 -236.92597) (xy 51.011264 -236.91411) (xy 51.064414 -236.910127) (xy 51.117564 -236.91411)
			(xy 51.169526 -236.92597) (xy 51.21914 -236.945442) (xy 51.265298 -236.972091) (xy 51.306969 -237.005322)
			(xy 51.343221 -237.044393) (xy 51.373245 -237.08843) (xy 51.396371 -237.136451) (xy 51.412081 -237.187381)
			(xy 51.420024 -237.240085) (xy 51.420522 -237.266734) (xy 51.420024 -237.293383) (xy 51.412081 -237.346087)
			(xy 51.396371 -237.397017) (xy 51.373245 -237.445038) (xy 51.343221 -237.489075) (xy 51.306969 -237.528146)
			(xy 51.265298 -237.561377) (xy 51.21914 -237.588026) (xy 51.169526 -237.607498) (xy 51.117564 -237.619358)
			(xy 51.064414 -237.623342) (xy 51.011264 -237.619358) (xy 50.959302 -237.607498) (xy 50.909688 -237.588026)
			(xy 50.86353 -237.561377) (xy 50.821859 -237.528146) (xy 50.785607 -237.489075) (xy 50.755583 -237.445038)
			(xy 50.732457 -237.397017) (xy 50.716747 -237.346087) (xy 50.708804 -237.293383) (xy 47.319956 -237.293383)
			(xy 47.312013 -237.346087) (xy 47.296303 -237.397017) (xy 47.273177 -237.445038) (xy 47.243153 -237.489075)
			(xy 47.206901 -237.528146) (xy 47.16523 -237.561377) (xy 47.119072 -237.588026) (xy 47.069458 -237.607498)
			(xy 47.017496 -237.619358) (xy 46.964346 -237.623342) (xy 46.911196 -237.619358) (xy 46.859234 -237.607498)
			(xy 46.80962 -237.588026) (xy 46.763462 -237.561377) (xy 46.721791 -237.528146) (xy 46.685539 -237.489075)
			(xy 46.655515 -237.445038) (xy 46.632389 -237.397017) (xy 46.616679 -237.346087) (xy 46.608736 -237.293383)
			(xy 36.332424 -237.293383) (xy 36.324481 -237.346087) (xy 36.308771 -237.397017) (xy 36.285645 -237.445038)
			(xy 36.255621 -237.489075) (xy 36.219369 -237.528146) (xy 36.177698 -237.561377) (xy 36.13154 -237.588026)
			(xy 36.081926 -237.607498) (xy 36.029964 -237.619358) (xy 35.976814 -237.623342) (xy 35.923664 -237.619358)
			(xy 35.871702 -237.607498) (xy 35.822088 -237.588026) (xy 35.77593 -237.561377) (xy 35.734259 -237.528146)
			(xy 35.698007 -237.489075) (xy 35.667983 -237.445038) (xy 35.644857 -237.397017) (xy 35.629147 -237.346087)
			(xy 35.621204 -237.293383) (xy 32.232356 -237.293383) (xy 32.224413 -237.346087) (xy 32.208703 -237.397017)
			(xy 32.185577 -237.445038) (xy 32.155553 -237.489075) (xy 32.119301 -237.528146) (xy 32.07763 -237.561377)
			(xy 32.031472 -237.588026) (xy 31.981858 -237.607498) (xy 31.929896 -237.619358) (xy 31.876746 -237.623342)
			(xy 31.823596 -237.619358) (xy 31.771634 -237.607498) (xy 31.72202 -237.588026) (xy 31.675862 -237.561377)
			(xy 31.634191 -237.528146) (xy 31.597939 -237.489075) (xy 31.567915 -237.445038) (xy 31.544789 -237.397017)
			(xy 31.529079 -237.346087) (xy 31.521136 -237.293383) (xy 21.244824 -237.293383) (xy 21.236881 -237.346087)
			(xy 21.221171 -237.397017) (xy 21.198045 -237.445038) (xy 21.168021 -237.489075) (xy 21.131769 -237.528146)
			(xy 21.090098 -237.561377) (xy 21.04394 -237.588026) (xy 20.994326 -237.607498) (xy 20.942364 -237.619358)
			(xy 20.889214 -237.623342) (xy 20.836064 -237.619358) (xy 20.784102 -237.607498) (xy 20.734488 -237.588026)
			(xy 20.68833 -237.561377) (xy 20.646659 -237.528146) (xy 20.610407 -237.489075) (xy 20.580383 -237.445038)
			(xy 20.557257 -237.397017) (xy 20.541547 -237.346087) (xy 20.533604 -237.293383) (xy 17.144756 -237.293383)
			(xy 17.136813 -237.346087) (xy 17.121103 -237.397017) (xy 17.097977 -237.445038) (xy 17.067953 -237.489075)
			(xy 17.031701 -237.528146) (xy 16.99003 -237.561377) (xy 16.943872 -237.588026) (xy 16.894258 -237.607498)
			(xy 16.842296 -237.619358) (xy 16.789146 -237.623342) (xy 16.735996 -237.619358) (xy 16.684034 -237.607498)
			(xy 16.63442 -237.588026) (xy 16.588262 -237.561377) (xy 16.546591 -237.528146) (xy 16.510339 -237.489075)
			(xy 16.480315 -237.445038) (xy 16.457189 -237.397017) (xy 16.441479 -237.346087) (xy 16.433536 -237.293383)
			(xy 6.80339 -237.293383) (xy 6.80339 -238.143267) (xy 16.433536 -238.143267) (xy 16.433536 -238.089969)
			(xy 16.441479 -238.037265) (xy 16.457189 -237.986335) (xy 16.480315 -237.938314) (xy 16.510339 -237.894277)
			(xy 16.546591 -237.855206) (xy 16.588262 -237.821975) (xy 16.63442 -237.795326) (xy 16.684034 -237.775854)
			(xy 16.735996 -237.763994) (xy 16.789146 -237.760011) (xy 16.842296 -237.763994) (xy 16.894258 -237.775854)
			(xy 16.943872 -237.795326) (xy 16.99003 -237.821975) (xy 17.031701 -237.855206) (xy 17.067953 -237.894277)
			(xy 17.097977 -237.938314) (xy 17.121103 -237.986335) (xy 17.136813 -238.037265) (xy 17.144756 -238.089969)
			(xy 17.145254 -238.116618) (xy 17.144756 -238.143267) (xy 31.521136 -238.143267) (xy 31.521136 -238.089969)
			(xy 31.529079 -238.037265) (xy 31.544789 -237.986335) (xy 31.567915 -237.938314) (xy 31.597939 -237.894277)
			(xy 31.634191 -237.855206) (xy 31.675862 -237.821975) (xy 31.72202 -237.795326) (xy 31.771634 -237.775854)
			(xy 31.823596 -237.763994) (xy 31.876746 -237.760011) (xy 31.929896 -237.763994) (xy 31.981858 -237.775854)
			(xy 32.031472 -237.795326) (xy 32.07763 -237.821975) (xy 32.119301 -237.855206) (xy 32.155553 -237.894277)
			(xy 32.185577 -237.938314) (xy 32.208703 -237.986335) (xy 32.224413 -238.037265) (xy 32.232356 -238.089969)
			(xy 32.232854 -238.116618) (xy 32.232356 -238.143267) (xy 46.608736 -238.143267) (xy 46.608736 -238.089969)
			(xy 46.616679 -238.037265) (xy 46.632389 -237.986335) (xy 46.655515 -237.938314) (xy 46.685539 -237.894277)
			(xy 46.721791 -237.855206) (xy 46.763462 -237.821975) (xy 46.80962 -237.795326) (xy 46.859234 -237.775854)
			(xy 46.911196 -237.763994) (xy 46.964346 -237.760011) (xy 47.017496 -237.763994) (xy 47.069458 -237.775854)
			(xy 47.119072 -237.795326) (xy 47.16523 -237.821975) (xy 47.206901 -237.855206) (xy 47.243153 -237.894277)
			(xy 47.273177 -237.938314) (xy 47.296303 -237.986335) (xy 47.312013 -238.037265) (xy 47.319956 -238.089969)
			(xy 47.320454 -238.116618) (xy 47.319956 -238.143267) (xy 47.312013 -238.195971) (xy 47.296303 -238.246901)
			(xy 47.273177 -238.294922) (xy 47.243153 -238.338959) (xy 47.206901 -238.37803) (xy 47.16523 -238.411261)
			(xy 47.119072 -238.43791) (xy 47.069458 -238.457382) (xy 47.017496 -238.469242) (xy 46.964346 -238.473226)
			(xy 46.911196 -238.469242) (xy 46.859234 -238.457382) (xy 46.80962 -238.43791) (xy 46.763462 -238.411261)
			(xy 46.721791 -238.37803) (xy 46.685539 -238.338959) (xy 46.655515 -238.294922) (xy 46.632389 -238.246901)
			(xy 46.616679 -238.195971) (xy 46.608736 -238.143267) (xy 32.232356 -238.143267) (xy 32.224413 -238.195971)
			(xy 32.208703 -238.246901) (xy 32.185577 -238.294922) (xy 32.155553 -238.338959) (xy 32.119301 -238.37803)
			(xy 32.07763 -238.411261) (xy 32.031472 -238.43791) (xy 31.981858 -238.457382) (xy 31.929896 -238.469242)
			(xy 31.876746 -238.473226) (xy 31.823596 -238.469242) (xy 31.771634 -238.457382) (xy 31.72202 -238.43791)
			(xy 31.675862 -238.411261) (xy 31.634191 -238.37803) (xy 31.597939 -238.338959) (xy 31.567915 -238.294922)
			(xy 31.544789 -238.246901) (xy 31.529079 -238.195971) (xy 31.521136 -238.143267) (xy 17.144756 -238.143267)
			(xy 17.136813 -238.195971) (xy 17.121103 -238.246901) (xy 17.097977 -238.294922) (xy 17.067953 -238.338959)
			(xy 17.031701 -238.37803) (xy 16.99003 -238.411261) (xy 16.943872 -238.43791) (xy 16.894258 -238.457382)
			(xy 16.842296 -238.469242) (xy 16.789146 -238.473226) (xy 16.735996 -238.469242) (xy 16.684034 -238.457382)
			(xy 16.63442 -238.43791) (xy 16.588262 -238.411261) (xy 16.546591 -238.37803) (xy 16.510339 -238.338959)
			(xy 16.480315 -238.294922) (xy 16.457189 -238.246901) (xy 16.441479 -238.195971) (xy 16.433536 -238.143267)
			(xy 6.80339 -238.143267) (xy 6.80339 -238.627158) (xy 6.7818 -238.648748) (xy 6.7818 -238.993405)
			(xy 20.533604 -238.993405) (xy 20.533604 -238.940107) (xy 20.541547 -238.887403) (xy 20.557257 -238.836473)
			(xy 20.580383 -238.788452) (xy 20.610407 -238.744415) (xy 20.646659 -238.705344) (xy 20.68833 -238.672113)
			(xy 20.734488 -238.645464) (xy 20.784102 -238.625992) (xy 20.836064 -238.614132) (xy 20.889214 -238.610149)
			(xy 20.942364 -238.614132) (xy 20.994326 -238.625992) (xy 21.04394 -238.645464) (xy 21.090098 -238.672113)
			(xy 21.131769 -238.705344) (xy 21.168021 -238.744415) (xy 21.198045 -238.788452) (xy 21.221171 -238.836473)
			(xy 21.236881 -238.887403) (xy 21.244824 -238.940107) (xy 21.245322 -238.966756) (xy 21.244824 -238.993405)
			(xy 35.621204 -238.993405) (xy 35.621204 -238.940107) (xy 35.629147 -238.887403) (xy 35.644857 -238.836473)
			(xy 35.667983 -238.788452) (xy 35.698007 -238.744415) (xy 35.734259 -238.705344) (xy 35.77593 -238.672113)
			(xy 35.822088 -238.645464) (xy 35.871702 -238.625992) (xy 35.923664 -238.614132) (xy 35.976814 -238.610149)
			(xy 36.029964 -238.614132) (xy 36.081926 -238.625992) (xy 36.13154 -238.645464) (xy 36.177698 -238.672113)
			(xy 36.219369 -238.705344) (xy 36.255621 -238.744415) (xy 36.285645 -238.788452) (xy 36.308771 -238.836473)
			(xy 36.324481 -238.887403) (xy 36.332424 -238.940107) (xy 36.332922 -238.966756) (xy 36.332424 -238.993405)
			(xy 50.708804 -238.993405) (xy 50.708804 -238.940107) (xy 50.716747 -238.887403) (xy 50.732457 -238.836473)
			(xy 50.755583 -238.788452) (xy 50.785607 -238.744415) (xy 50.821859 -238.705344) (xy 50.86353 -238.672113)
			(xy 50.909688 -238.645464) (xy 50.959302 -238.625992) (xy 51.011264 -238.614132) (xy 51.064414 -238.610149)
			(xy 51.117564 -238.614132) (xy 51.169526 -238.625992) (xy 51.21914 -238.645464) (xy 51.265298 -238.672113)
			(xy 51.306969 -238.705344) (xy 51.343221 -238.744415) (xy 51.373245 -238.788452) (xy 51.396371 -238.836473)
			(xy 51.412081 -238.887403) (xy 51.420024 -238.940107) (xy 51.420522 -238.966756) (xy 51.420024 -238.993405)
			(xy 51.412081 -239.046109) (xy 51.396371 -239.097039) (xy 51.373245 -239.14506) (xy 51.343221 -239.189097)
			(xy 51.306969 -239.228168) (xy 51.265298 -239.261399) (xy 51.21914 -239.288048) (xy 51.169526 -239.30752)
			(xy 51.117564 -239.31938) (xy 51.064414 -239.323364) (xy 51.011264 -239.31938) (xy 50.959302 -239.30752)
			(xy 50.909688 -239.288048) (xy 50.86353 -239.261399) (xy 50.821859 -239.228168) (xy 50.785607 -239.189097)
			(xy 50.755583 -239.14506) (xy 50.732457 -239.097039) (xy 50.716747 -239.046109) (xy 50.708804 -238.993405)
			(xy 36.332424 -238.993405) (xy 36.324481 -239.046109) (xy 36.308771 -239.097039) (xy 36.285645 -239.14506)
			(xy 36.255621 -239.189097) (xy 36.219369 -239.228168) (xy 36.177698 -239.261399) (xy 36.13154 -239.288048)
			(xy 36.081926 -239.30752) (xy 36.029964 -239.31938) (xy 35.976814 -239.323364) (xy 35.923664 -239.31938)
			(xy 35.871702 -239.30752) (xy 35.822088 -239.288048) (xy 35.77593 -239.261399) (xy 35.734259 -239.228168)
			(xy 35.698007 -239.189097) (xy 35.667983 -239.14506) (xy 35.644857 -239.097039) (xy 35.629147 -239.046109)
			(xy 35.621204 -238.993405) (xy 21.244824 -238.993405) (xy 21.236881 -239.046109) (xy 21.221171 -239.097039)
			(xy 21.198045 -239.14506) (xy 21.168021 -239.189097) (xy 21.131769 -239.228168) (xy 21.090098 -239.261399)
			(xy 21.04394 -239.288048) (xy 20.994326 -239.30752) (xy 20.942364 -239.31938) (xy 20.889214 -239.323364)
			(xy 20.836064 -239.31938) (xy 20.784102 -239.30752) (xy 20.734488 -239.288048) (xy 20.68833 -239.261399)
			(xy 20.646659 -239.228168) (xy 20.610407 -239.189097) (xy 20.580383 -239.14506) (xy 20.557257 -239.097039)
			(xy 20.541547 -239.046109) (xy 20.533604 -238.993405) (xy 6.7818 -238.993405) (xy 6.7818 -239.843289)
			(xy 16.433536 -239.843289) (xy 16.433536 -239.789991) (xy 16.441479 -239.737287) (xy 16.457189 -239.686357)
			(xy 16.480315 -239.638336) (xy 16.510339 -239.594299) (xy 16.546591 -239.555228) (xy 16.588262 -239.521997)
			(xy 16.63442 -239.495348) (xy 16.684034 -239.475876) (xy 16.735996 -239.464016) (xy 16.789146 -239.460033)
			(xy 16.842296 -239.464016) (xy 16.894258 -239.475876) (xy 16.943872 -239.495348) (xy 16.99003 -239.521997)
			(xy 17.031701 -239.555228) (xy 17.067953 -239.594299) (xy 17.097977 -239.638336) (xy 17.121103 -239.686357)
			(xy 17.136813 -239.737287) (xy 17.144756 -239.789991) (xy 17.145254 -239.81664) (xy 17.144756 -239.843289)
			(xy 31.521136 -239.843289) (xy 31.521136 -239.789991) (xy 31.529079 -239.737287) (xy 31.544789 -239.686357)
			(xy 31.567915 -239.638336) (xy 31.597939 -239.594299) (xy 31.634191 -239.555228) (xy 31.675862 -239.521997)
			(xy 31.72202 -239.495348) (xy 31.771634 -239.475876) (xy 31.823596 -239.464016) (xy 31.876746 -239.460033)
			(xy 31.929896 -239.464016) (xy 31.981858 -239.475876) (xy 32.031472 -239.495348) (xy 32.07763 -239.521997)
			(xy 32.119301 -239.555228) (xy 32.155553 -239.594299) (xy 32.185577 -239.638336) (xy 32.208703 -239.686357)
			(xy 32.224413 -239.737287) (xy 32.232356 -239.789991) (xy 32.232854 -239.81664) (xy 32.232356 -239.843289)
			(xy 46.608736 -239.843289) (xy 46.608736 -239.789991) (xy 46.616679 -239.737287) (xy 46.632389 -239.686357)
			(xy 46.655515 -239.638336) (xy 46.685539 -239.594299) (xy 46.721791 -239.555228) (xy 46.763462 -239.521997)
			(xy 46.80962 -239.495348) (xy 46.859234 -239.475876) (xy 46.911196 -239.464016) (xy 46.964346 -239.460033)
			(xy 47.017496 -239.464016) (xy 47.069458 -239.475876) (xy 47.119072 -239.495348) (xy 47.16523 -239.521997)
			(xy 47.206901 -239.555228) (xy 47.243153 -239.594299) (xy 47.273177 -239.638336) (xy 47.296303 -239.686357)
			(xy 47.312013 -239.737287) (xy 47.319956 -239.789991) (xy 47.320454 -239.81664) (xy 47.319956 -239.843289)
			(xy 47.312013 -239.895993) (xy 47.296303 -239.946923) (xy 47.273177 -239.994944) (xy 47.243153 -240.038981)
			(xy 47.206901 -240.078052) (xy 47.16523 -240.111283) (xy 47.119072 -240.137932) (xy 47.069458 -240.157404)
			(xy 47.017496 -240.169264) (xy 46.964346 -240.173248) (xy 46.911196 -240.169264) (xy 46.859234 -240.157404)
			(xy 46.80962 -240.137932) (xy 46.763462 -240.111283) (xy 46.721791 -240.078052) (xy 46.685539 -240.038981)
			(xy 46.655515 -239.994944) (xy 46.632389 -239.946923) (xy 46.616679 -239.895993) (xy 46.608736 -239.843289)
			(xy 32.232356 -239.843289) (xy 32.224413 -239.895993) (xy 32.208703 -239.946923) (xy 32.185577 -239.994944)
			(xy 32.155553 -240.038981) (xy 32.119301 -240.078052) (xy 32.07763 -240.111283) (xy 32.031472 -240.137932)
			(xy 31.981858 -240.157404) (xy 31.929896 -240.169264) (xy 31.876746 -240.173248) (xy 31.823596 -240.169264)
			(xy 31.771634 -240.157404) (xy 31.72202 -240.137932) (xy 31.675862 -240.111283) (xy 31.634191 -240.078052)
			(xy 31.597939 -240.038981) (xy 31.567915 -239.994944) (xy 31.544789 -239.946923) (xy 31.529079 -239.895993)
			(xy 31.521136 -239.843289) (xy 17.144756 -239.843289) (xy 17.136813 -239.895993) (xy 17.121103 -239.946923)
			(xy 17.097977 -239.994944) (xy 17.067953 -240.038981) (xy 17.031701 -240.078052) (xy 16.99003 -240.111283)
			(xy 16.943872 -240.137932) (xy 16.894258 -240.157404) (xy 16.842296 -240.169264) (xy 16.789146 -240.173248)
			(xy 16.735996 -240.169264) (xy 16.684034 -240.157404) (xy 16.63442 -240.137932) (xy 16.588262 -240.111283)
			(xy 16.546591 -240.078052) (xy 16.510339 -240.038981) (xy 16.480315 -239.994944) (xy 16.457189 -239.946923)
			(xy 16.441479 -239.895993) (xy 16.433536 -239.843289) (xy 6.7818 -239.843289) (xy 6.7818 -240.693427)
			(xy 20.533604 -240.693427) (xy 20.533604 -240.640129) (xy 20.541547 -240.587425) (xy 20.557257 -240.536495)
			(xy 20.580383 -240.488474) (xy 20.610407 -240.444437) (xy 20.646659 -240.405366) (xy 20.68833 -240.372135)
			(xy 20.734488 -240.345486) (xy 20.784102 -240.326014) (xy 20.836064 -240.314154) (xy 20.889214 -240.310171)
			(xy 20.942364 -240.314154) (xy 20.994326 -240.326014) (xy 21.04394 -240.345486) (xy 21.090098 -240.372135)
			(xy 21.131769 -240.405366) (xy 21.168021 -240.444437) (xy 21.198045 -240.488474) (xy 21.221171 -240.536495)
			(xy 21.236881 -240.587425) (xy 21.244824 -240.640129) (xy 21.245322 -240.666778) (xy 21.244824 -240.693427)
			(xy 35.621204 -240.693427) (xy 35.621204 -240.640129) (xy 35.629147 -240.587425) (xy 35.644857 -240.536495)
			(xy 35.667983 -240.488474) (xy 35.698007 -240.444437) (xy 35.734259 -240.405366) (xy 35.77593 -240.372135)
			(xy 35.822088 -240.345486) (xy 35.871702 -240.326014) (xy 35.923664 -240.314154) (xy 35.976814 -240.310171)
			(xy 36.029964 -240.314154) (xy 36.081926 -240.326014) (xy 36.13154 -240.345486) (xy 36.177698 -240.372135)
			(xy 36.219369 -240.405366) (xy 36.255621 -240.444437) (xy 36.285645 -240.488474) (xy 36.308771 -240.536495)
			(xy 36.324481 -240.587425) (xy 36.332424 -240.640129) (xy 36.332922 -240.666778) (xy 36.332424 -240.693427)
			(xy 50.708804 -240.693427) (xy 50.708804 -240.640129) (xy 50.716747 -240.587425) (xy 50.732457 -240.536495)
			(xy 50.755583 -240.488474) (xy 50.785607 -240.444437) (xy 50.821859 -240.405366) (xy 50.86353 -240.372135)
			(xy 50.909688 -240.345486) (xy 50.959302 -240.326014) (xy 51.011264 -240.314154) (xy 51.064414 -240.310171)
			(xy 51.117564 -240.314154) (xy 51.169526 -240.326014) (xy 51.21914 -240.345486) (xy 51.265298 -240.372135)
			(xy 51.306969 -240.405366) (xy 51.343221 -240.444437) (xy 51.373245 -240.488474) (xy 51.396371 -240.536495)
			(xy 51.412081 -240.587425) (xy 51.420024 -240.640129) (xy 51.420522 -240.666778) (xy 51.420024 -240.693427)
			(xy 51.412081 -240.746131) (xy 51.396371 -240.797061) (xy 51.373245 -240.845082) (xy 51.343221 -240.889119)
			(xy 51.306969 -240.92819) (xy 51.265298 -240.961421) (xy 51.21914 -240.98807) (xy 51.169526 -241.007542)
			(xy 51.117564 -241.019402) (xy 51.064414 -241.023386) (xy 51.011264 -241.019402) (xy 50.959302 -241.007542)
			(xy 50.909688 -240.98807) (xy 50.86353 -240.961421) (xy 50.821859 -240.92819) (xy 50.785607 -240.889119)
			(xy 50.755583 -240.845082) (xy 50.732457 -240.797061) (xy 50.716747 -240.746131) (xy 50.708804 -240.693427)
			(xy 36.332424 -240.693427) (xy 36.324481 -240.746131) (xy 36.308771 -240.797061) (xy 36.285645 -240.845082)
			(xy 36.255621 -240.889119) (xy 36.219369 -240.92819) (xy 36.177698 -240.961421) (xy 36.13154 -240.98807)
			(xy 36.081926 -241.007542) (xy 36.029964 -241.019402) (xy 35.976814 -241.023386) (xy 35.923664 -241.019402)
			(xy 35.871702 -241.007542) (xy 35.822088 -240.98807) (xy 35.77593 -240.961421) (xy 35.734259 -240.92819)
			(xy 35.698007 -240.889119) (xy 35.667983 -240.845082) (xy 35.644857 -240.797061) (xy 35.629147 -240.746131)
			(xy 35.621204 -240.693427) (xy 21.244824 -240.693427) (xy 21.236881 -240.746131) (xy 21.221171 -240.797061)
			(xy 21.198045 -240.845082) (xy 21.168021 -240.889119) (xy 21.131769 -240.92819) (xy 21.090098 -240.961421)
			(xy 21.04394 -240.98807) (xy 20.994326 -241.007542) (xy 20.942364 -241.019402) (xy 20.889214 -241.023386)
			(xy 20.836064 -241.019402) (xy 20.784102 -241.007542) (xy 20.734488 -240.98807) (xy 20.68833 -240.961421)
			(xy 20.646659 -240.92819) (xy 20.610407 -240.889119) (xy 20.580383 -240.845082) (xy 20.557257 -240.797061)
			(xy 20.541547 -240.746131) (xy 20.533604 -240.693427) (xy 6.7818 -240.693427) (xy 6.7818 -241.543311)
			(xy 16.433536 -241.543311) (xy 16.433536 -241.490013) (xy 16.441479 -241.437309) (xy 16.457189 -241.386379)
			(xy 16.480315 -241.338358) (xy 16.510339 -241.294321) (xy 16.546591 -241.25525) (xy 16.588262 -241.222019)
			(xy 16.63442 -241.19537) (xy 16.684034 -241.175898) (xy 16.735996 -241.164038) (xy 16.789146 -241.160055)
			(xy 16.842296 -241.164038) (xy 16.894258 -241.175898) (xy 16.943872 -241.19537) (xy 16.99003 -241.222019)
			(xy 17.031701 -241.25525) (xy 17.067953 -241.294321) (xy 17.097977 -241.338358) (xy 17.121103 -241.386379)
			(xy 17.136813 -241.437309) (xy 17.144756 -241.490013) (xy 17.145254 -241.516662) (xy 17.144756 -241.543311)
			(xy 31.521136 -241.543311) (xy 31.521136 -241.490013) (xy 31.529079 -241.437309) (xy 31.544789 -241.386379)
			(xy 31.567915 -241.338358) (xy 31.597939 -241.294321) (xy 31.634191 -241.25525) (xy 31.675862 -241.222019)
			(xy 31.72202 -241.19537) (xy 31.771634 -241.175898) (xy 31.823596 -241.164038) (xy 31.876746 -241.160055)
			(xy 31.929896 -241.164038) (xy 31.981858 -241.175898) (xy 32.031472 -241.19537) (xy 32.07763 -241.222019)
			(xy 32.119301 -241.25525) (xy 32.155553 -241.294321) (xy 32.185577 -241.338358) (xy 32.208703 -241.386379)
			(xy 32.224413 -241.437309) (xy 32.232356 -241.490013) (xy 32.232854 -241.516662) (xy 32.232356 -241.543311)
			(xy 46.608736 -241.543311) (xy 46.608736 -241.490013) (xy 46.616679 -241.437309) (xy 46.632389 -241.386379)
			(xy 46.655515 -241.338358) (xy 46.685539 -241.294321) (xy 46.721791 -241.25525) (xy 46.763462 -241.222019)
			(xy 46.80962 -241.19537) (xy 46.859234 -241.175898) (xy 46.911196 -241.164038) (xy 46.964346 -241.160055)
			(xy 47.017496 -241.164038) (xy 47.069458 -241.175898) (xy 47.119072 -241.19537) (xy 47.16523 -241.222019)
			(xy 47.206901 -241.25525) (xy 47.243153 -241.294321) (xy 47.273177 -241.338358) (xy 47.296303 -241.386379)
			(xy 47.312013 -241.437309) (xy 47.319956 -241.490013) (xy 47.320454 -241.516662) (xy 47.319956 -241.543311)
			(xy 47.312013 -241.596015) (xy 47.296303 -241.646945) (xy 47.273177 -241.694966) (xy 47.243153 -241.739003)
			(xy 47.206901 -241.778074) (xy 47.16523 -241.811305) (xy 47.119072 -241.837954) (xy 47.069458 -241.857426)
			(xy 47.017496 -241.869286) (xy 46.964346 -241.87327) (xy 46.911196 -241.869286) (xy 46.859234 -241.857426)
			(xy 46.80962 -241.837954) (xy 46.763462 -241.811305) (xy 46.721791 -241.778074) (xy 46.685539 -241.739003)
			(xy 46.655515 -241.694966) (xy 46.632389 -241.646945) (xy 46.616679 -241.596015) (xy 46.608736 -241.543311)
			(xy 32.232356 -241.543311) (xy 32.224413 -241.596015) (xy 32.208703 -241.646945) (xy 32.185577 -241.694966)
			(xy 32.155553 -241.739003) (xy 32.119301 -241.778074) (xy 32.07763 -241.811305) (xy 32.031472 -241.837954)
			(xy 31.981858 -241.857426) (xy 31.929896 -241.869286) (xy 31.876746 -241.87327) (xy 31.823596 -241.869286)
			(xy 31.771634 -241.857426) (xy 31.72202 -241.837954) (xy 31.675862 -241.811305) (xy 31.634191 -241.778074)
			(xy 31.597939 -241.739003) (xy 31.567915 -241.694966) (xy 31.544789 -241.646945) (xy 31.529079 -241.596015)
			(xy 31.521136 -241.543311) (xy 17.144756 -241.543311) (xy 17.136813 -241.596015) (xy 17.121103 -241.646945)
			(xy 17.097977 -241.694966) (xy 17.067953 -241.739003) (xy 17.031701 -241.778074) (xy 16.99003 -241.811305)
			(xy 16.943872 -241.837954) (xy 16.894258 -241.857426) (xy 16.842296 -241.869286) (xy 16.789146 -241.87327)
			(xy 16.735996 -241.869286) (xy 16.684034 -241.857426) (xy 16.63442 -241.837954) (xy 16.588262 -241.811305)
			(xy 16.546591 -241.778074) (xy 16.510339 -241.739003) (xy 16.480315 -241.694966) (xy 16.457189 -241.646945)
			(xy 16.441479 -241.596015) (xy 16.433536 -241.543311) (xy 6.7818 -241.543311) (xy 6.7818 -242.393449)
			(xy 12.989804 -242.393449) (xy 12.989804 -242.340151) (xy 12.997747 -242.287447) (xy 13.013457 -242.236517)
			(xy 13.036583 -242.188496) (xy 13.066607 -242.144459) (xy 13.102859 -242.105388) (xy 13.14453 -242.072157)
			(xy 13.190688 -242.045508) (xy 13.240302 -242.026036) (xy 13.292264 -242.014176) (xy 13.345414 -242.010193)
			(xy 13.398564 -242.014176) (xy 13.450526 -242.026036) (xy 13.50014 -242.045508) (xy 13.546298 -242.072157)
			(xy 13.587969 -242.105388) (xy 13.624221 -242.144459) (xy 13.654245 -242.188496) (xy 13.677371 -242.236517)
			(xy 13.693081 -242.287447) (xy 13.701024 -242.340151) (xy 13.701522 -242.3668) (xy 13.701024 -242.393449)
			(xy 20.533604 -242.393449) (xy 20.533604 -242.340151) (xy 20.541547 -242.287447) (xy 20.557257 -242.236517)
			(xy 20.580383 -242.188496) (xy 20.610407 -242.144459) (xy 20.646659 -242.105388) (xy 20.68833 -242.072157)
			(xy 20.734488 -242.045508) (xy 20.784102 -242.026036) (xy 20.836064 -242.014176) (xy 20.889214 -242.010193)
			(xy 20.942364 -242.014176) (xy 20.994326 -242.026036) (xy 21.04394 -242.045508) (xy 21.090098 -242.072157)
			(xy 21.131769 -242.105388) (xy 21.168021 -242.144459) (xy 21.198045 -242.188496) (xy 21.221171 -242.236517)
			(xy 21.236881 -242.287447) (xy 21.244824 -242.340151) (xy 21.245322 -242.3668) (xy 21.244824 -242.393449)
			(xy 28.077404 -242.393449) (xy 28.077404 -242.340151) (xy 28.085347 -242.287447) (xy 28.101057 -242.236517)
			(xy 28.124183 -242.188496) (xy 28.154207 -242.144459) (xy 28.190459 -242.105388) (xy 28.23213 -242.072157)
			(xy 28.278288 -242.045508) (xy 28.327902 -242.026036) (xy 28.379864 -242.014176) (xy 28.433014 -242.010193)
			(xy 28.486164 -242.014176) (xy 28.538126 -242.026036) (xy 28.58774 -242.045508) (xy 28.633898 -242.072157)
			(xy 28.675569 -242.105388) (xy 28.711821 -242.144459) (xy 28.741845 -242.188496) (xy 28.764971 -242.236517)
			(xy 28.780681 -242.287447) (xy 28.788624 -242.340151) (xy 28.789122 -242.3668) (xy 28.788624 -242.393449)
			(xy 35.621204 -242.393449) (xy 35.621204 -242.340151) (xy 35.629147 -242.287447) (xy 35.644857 -242.236517)
			(xy 35.667983 -242.188496) (xy 35.698007 -242.144459) (xy 35.734259 -242.105388) (xy 35.77593 -242.072157)
			(xy 35.822088 -242.045508) (xy 35.871702 -242.026036) (xy 35.923664 -242.014176) (xy 35.976814 -242.010193)
			(xy 36.029964 -242.014176) (xy 36.081926 -242.026036) (xy 36.13154 -242.045508) (xy 36.177698 -242.072157)
			(xy 36.219369 -242.105388) (xy 36.255621 -242.144459) (xy 36.285645 -242.188496) (xy 36.308771 -242.236517)
			(xy 36.324481 -242.287447) (xy 36.332424 -242.340151) (xy 36.332922 -242.3668) (xy 36.332424 -242.393449)
			(xy 43.165004 -242.393449) (xy 43.165004 -242.340151) (xy 43.172947 -242.287447) (xy 43.188657 -242.236517)
			(xy 43.211783 -242.188496) (xy 43.241807 -242.144459) (xy 43.278059 -242.105388) (xy 43.31973 -242.072157)
			(xy 43.365888 -242.045508) (xy 43.415502 -242.026036) (xy 43.467464 -242.014176) (xy 43.520614 -242.010193)
			(xy 43.573764 -242.014176) (xy 43.625726 -242.026036) (xy 43.67534 -242.045508) (xy 43.721498 -242.072157)
			(xy 43.763169 -242.105388) (xy 43.799421 -242.144459) (xy 43.829445 -242.188496) (xy 43.852571 -242.236517)
			(xy 43.868281 -242.287447) (xy 43.876224 -242.340151) (xy 43.876722 -242.3668) (xy 43.876224 -242.393449)
			(xy 50.708804 -242.393449) (xy 50.708804 -242.340151) (xy 50.716747 -242.287447) (xy 50.732457 -242.236517)
			(xy 50.755583 -242.188496) (xy 50.785607 -242.144459) (xy 50.821859 -242.105388) (xy 50.86353 -242.072157)
			(xy 50.909688 -242.045508) (xy 50.959302 -242.026036) (xy 51.011264 -242.014176) (xy 51.064414 -242.010193)
			(xy 51.117564 -242.014176) (xy 51.169526 -242.026036) (xy 51.21914 -242.045508) (xy 51.265298 -242.072157)
			(xy 51.306969 -242.105388) (xy 51.343221 -242.144459) (xy 51.373245 -242.188496) (xy 51.396371 -242.236517)
			(xy 51.412081 -242.287447) (xy 51.420024 -242.340151) (xy 51.420522 -242.3668) (xy 51.420024 -242.393449)
			(xy 56.042804 -242.393449) (xy 56.042804 -242.340151) (xy 56.050747 -242.287447) (xy 56.066457 -242.236517)
			(xy 56.089583 -242.188496) (xy 56.119607 -242.144459) (xy 56.155859 -242.105388) (xy 56.19753 -242.072157)
			(xy 56.243688 -242.045508) (xy 56.293302 -242.026036) (xy 56.345264 -242.014176) (xy 56.398414 -242.010193)
			(xy 56.451564 -242.014176) (xy 56.503526 -242.026036) (xy 56.55314 -242.045508) (xy 56.599298 -242.072157)
			(xy 56.640969 -242.105388) (xy 56.677221 -242.144459) (xy 56.707245 -242.188496) (xy 56.730371 -242.236517)
			(xy 56.746081 -242.287447) (xy 56.754024 -242.340151) (xy 56.754522 -242.3668) (xy 56.754024 -242.393449)
			(xy 56.746081 -242.446153) (xy 56.730371 -242.497083) (xy 56.707245 -242.545104) (xy 56.677221 -242.589141)
			(xy 56.640969 -242.628212) (xy 56.599298 -242.661443) (xy 56.55314 -242.688092) (xy 56.503526 -242.707564)
			(xy 56.451564 -242.719424) (xy 56.398414 -242.723408) (xy 56.345264 -242.719424) (xy 56.293302 -242.707564)
			(xy 56.243688 -242.688092) (xy 56.19753 -242.661443) (xy 56.155859 -242.628212) (xy 56.119607 -242.589141)
			(xy 56.089583 -242.545104) (xy 56.066457 -242.497083) (xy 56.050747 -242.446153) (xy 56.042804 -242.393449)
			(xy 51.420024 -242.393449) (xy 51.412081 -242.446153) (xy 51.396371 -242.497083) (xy 51.373245 -242.545104)
			(xy 51.343221 -242.589141) (xy 51.306969 -242.628212) (xy 51.265298 -242.661443) (xy 51.21914 -242.688092)
			(xy 51.169526 -242.707564) (xy 51.117564 -242.719424) (xy 51.064414 -242.723408) (xy 51.011264 -242.719424)
			(xy 50.959302 -242.707564) (xy 50.909688 -242.688092) (xy 50.86353 -242.661443) (xy 50.821859 -242.628212)
			(xy 50.785607 -242.589141) (xy 50.755583 -242.545104) (xy 50.732457 -242.497083) (xy 50.716747 -242.446153)
			(xy 50.708804 -242.393449) (xy 43.876224 -242.393449) (xy 43.868281 -242.446153) (xy 43.852571 -242.497083)
			(xy 43.829445 -242.545104) (xy 43.799421 -242.589141) (xy 43.763169 -242.628212) (xy 43.721498 -242.661443)
			(xy 43.67534 -242.688092) (xy 43.625726 -242.707564) (xy 43.573764 -242.719424) (xy 43.520614 -242.723408)
			(xy 43.467464 -242.719424) (xy 43.415502 -242.707564) (xy 43.365888 -242.688092) (xy 43.31973 -242.661443)
			(xy 43.278059 -242.628212) (xy 43.241807 -242.589141) (xy 43.211783 -242.545104) (xy 43.188657 -242.497083)
			(xy 43.172947 -242.446153) (xy 43.165004 -242.393449) (xy 36.332424 -242.393449) (xy 36.324481 -242.446153)
			(xy 36.308771 -242.497083) (xy 36.285645 -242.545104) (xy 36.255621 -242.589141) (xy 36.219369 -242.628212)
			(xy 36.177698 -242.661443) (xy 36.13154 -242.688092) (xy 36.081926 -242.707564) (xy 36.029964 -242.719424)
			(xy 35.976814 -242.723408) (xy 35.923664 -242.719424) (xy 35.871702 -242.707564) (xy 35.822088 -242.688092)
			(xy 35.77593 -242.661443) (xy 35.734259 -242.628212) (xy 35.698007 -242.589141) (xy 35.667983 -242.545104)
			(xy 35.644857 -242.497083) (xy 35.629147 -242.446153) (xy 35.621204 -242.393449) (xy 28.788624 -242.393449)
			(xy 28.780681 -242.446153) (xy 28.764971 -242.497083) (xy 28.741845 -242.545104) (xy 28.711821 -242.589141)
			(xy 28.675569 -242.628212) (xy 28.633898 -242.661443) (xy 28.58774 -242.688092) (xy 28.538126 -242.707564)
			(xy 28.486164 -242.719424) (xy 28.433014 -242.723408) (xy 28.379864 -242.719424) (xy 28.327902 -242.707564)
			(xy 28.278288 -242.688092) (xy 28.23213 -242.661443) (xy 28.190459 -242.628212) (xy 28.154207 -242.589141)
			(xy 28.124183 -242.545104) (xy 28.101057 -242.497083) (xy 28.085347 -242.446153) (xy 28.077404 -242.393449)
			(xy 21.244824 -242.393449) (xy 21.236881 -242.446153) (xy 21.221171 -242.497083) (xy 21.198045 -242.545104)
			(xy 21.168021 -242.589141) (xy 21.131769 -242.628212) (xy 21.090098 -242.661443) (xy 21.04394 -242.688092)
			(xy 20.994326 -242.707564) (xy 20.942364 -242.719424) (xy 20.889214 -242.723408) (xy 20.836064 -242.719424)
			(xy 20.784102 -242.707564) (xy 20.734488 -242.688092) (xy 20.68833 -242.661443) (xy 20.646659 -242.628212)
			(xy 20.610407 -242.589141) (xy 20.580383 -242.545104) (xy 20.557257 -242.497083) (xy 20.541547 -242.446153)
			(xy 20.533604 -242.393449) (xy 13.701024 -242.393449) (xy 13.693081 -242.446153) (xy 13.677371 -242.497083)
			(xy 13.654245 -242.545104) (xy 13.624221 -242.589141) (xy 13.587969 -242.628212) (xy 13.546298 -242.661443)
			(xy 13.50014 -242.688092) (xy 13.450526 -242.707564) (xy 13.398564 -242.719424) (xy 13.345414 -242.723408)
			(xy 13.292264 -242.719424) (xy 13.240302 -242.707564) (xy 13.190688 -242.688092) (xy 13.14453 -242.661443)
			(xy 13.102859 -242.628212) (xy 13.066607 -242.589141) (xy 13.036583 -242.545104) (xy 13.013457 -242.497083)
			(xy 12.997747 -242.446153) (xy 12.989804 -242.393449) (xy 6.7818 -242.393449) (xy 6.7818 -243.243333)
			(xy 8.889736 -243.243333) (xy 8.889736 -243.190035) (xy 8.897679 -243.137331) (xy 8.913389 -243.086401)
			(xy 8.936515 -243.03838) (xy 8.966539 -242.994343) (xy 9.002791 -242.955272) (xy 9.044462 -242.922041)
			(xy 9.09062 -242.895392) (xy 9.140234 -242.87592) (xy 9.192196 -242.86406) (xy 9.245346 -242.860077)
			(xy 9.298496 -242.86406) (xy 9.350458 -242.87592) (xy 9.400072 -242.895392) (xy 9.44623 -242.922041)
			(xy 9.487901 -242.955272) (xy 9.524153 -242.994343) (xy 9.554177 -243.03838) (xy 9.577303 -243.086401)
			(xy 9.593013 -243.137331) (xy 9.600956 -243.190035) (xy 9.601454 -243.216684) (xy 9.600956 -243.243333)
			(xy 12.989804 -243.243333) (xy 12.989804 -243.190035) (xy 12.997747 -243.137331) (xy 13.013457 -243.086401)
			(xy 13.036583 -243.03838) (xy 13.066607 -242.994343) (xy 13.102859 -242.955272) (xy 13.14453 -242.922041)
			(xy 13.190688 -242.895392) (xy 13.240302 -242.87592) (xy 13.292264 -242.86406) (xy 13.345414 -242.860077)
			(xy 13.398564 -242.86406) (xy 13.450526 -242.87592) (xy 13.50014 -242.895392) (xy 13.546298 -242.922041)
			(xy 13.587969 -242.955272) (xy 13.624221 -242.994343) (xy 13.654245 -243.03838) (xy 13.677371 -243.086401)
			(xy 13.693081 -243.137331) (xy 13.701024 -243.190035) (xy 13.701522 -243.216684) (xy 13.701024 -243.243333)
			(xy 16.433536 -243.243333) (xy 16.433536 -243.190035) (xy 16.441479 -243.137331) (xy 16.457189 -243.086401)
			(xy 16.480315 -243.03838) (xy 16.510339 -242.994343) (xy 16.546591 -242.955272) (xy 16.588262 -242.922041)
			(xy 16.63442 -242.895392) (xy 16.684034 -242.87592) (xy 16.735996 -242.86406) (xy 16.789146 -242.860077)
			(xy 16.842296 -242.86406) (xy 16.894258 -242.87592) (xy 16.943872 -242.895392) (xy 16.99003 -242.922041)
			(xy 17.031701 -242.955272) (xy 17.067953 -242.994343) (xy 17.097977 -243.03838) (xy 17.121103 -243.086401)
			(xy 17.136813 -243.137331) (xy 17.144756 -243.190035) (xy 17.145254 -243.216684) (xy 17.144756 -243.243333)
			(xy 20.533604 -243.243333) (xy 20.533604 -243.190035) (xy 20.541547 -243.137331) (xy 20.557257 -243.086401)
			(xy 20.580383 -243.03838) (xy 20.610407 -242.994343) (xy 20.646659 -242.955272) (xy 20.68833 -242.922041)
			(xy 20.734488 -242.895392) (xy 20.784102 -242.87592) (xy 20.836064 -242.86406) (xy 20.889214 -242.860077)
			(xy 20.942364 -242.86406) (xy 20.994326 -242.87592) (xy 21.04394 -242.895392) (xy 21.090098 -242.922041)
			(xy 21.131769 -242.955272) (xy 21.168021 -242.994343) (xy 21.198045 -243.03838) (xy 21.221171 -243.086401)
			(xy 21.236881 -243.137331) (xy 21.244824 -243.190035) (xy 21.245322 -243.216684) (xy 21.244824 -243.243333)
			(xy 23.977336 -243.243333) (xy 23.977336 -243.190035) (xy 23.985279 -243.137331) (xy 24.000989 -243.086401)
			(xy 24.024115 -243.03838) (xy 24.054139 -242.994343) (xy 24.090391 -242.955272) (xy 24.132062 -242.922041)
			(xy 24.17822 -242.895392) (xy 24.227834 -242.87592) (xy 24.279796 -242.86406) (xy 24.332946 -242.860077)
			(xy 24.386096 -242.86406) (xy 24.438058 -242.87592) (xy 24.487672 -242.895392) (xy 24.53383 -242.922041)
			(xy 24.575501 -242.955272) (xy 24.611753 -242.994343) (xy 24.641777 -243.03838) (xy 24.664903 -243.086401)
			(xy 24.680613 -243.137331) (xy 24.688556 -243.190035) (xy 24.689054 -243.216684) (xy 24.688556 -243.243333)
			(xy 28.077404 -243.243333) (xy 28.077404 -243.190035) (xy 28.085347 -243.137331) (xy 28.101057 -243.086401)
			(xy 28.124183 -243.03838) (xy 28.154207 -242.994343) (xy 28.190459 -242.955272) (xy 28.23213 -242.922041)
			(xy 28.278288 -242.895392) (xy 28.327902 -242.87592) (xy 28.379864 -242.86406) (xy 28.433014 -242.860077)
			(xy 28.486164 -242.86406) (xy 28.538126 -242.87592) (xy 28.58774 -242.895392) (xy 28.633898 -242.922041)
			(xy 28.675569 -242.955272) (xy 28.711821 -242.994343) (xy 28.741845 -243.03838) (xy 28.764971 -243.086401)
			(xy 28.780681 -243.137331) (xy 28.788624 -243.190035) (xy 28.789122 -243.216684) (xy 28.788624 -243.243333)
			(xy 31.521136 -243.243333) (xy 31.521136 -243.190035) (xy 31.529079 -243.137331) (xy 31.544789 -243.086401)
			(xy 31.567915 -243.03838) (xy 31.597939 -242.994343) (xy 31.634191 -242.955272) (xy 31.675862 -242.922041)
			(xy 31.72202 -242.895392) (xy 31.771634 -242.87592) (xy 31.823596 -242.86406) (xy 31.876746 -242.860077)
			(xy 31.929896 -242.86406) (xy 31.981858 -242.87592) (xy 32.031472 -242.895392) (xy 32.07763 -242.922041)
			(xy 32.119301 -242.955272) (xy 32.155553 -242.994343) (xy 32.185577 -243.03838) (xy 32.208703 -243.086401)
			(xy 32.224413 -243.137331) (xy 32.232356 -243.190035) (xy 32.232854 -243.216684) (xy 32.232356 -243.243333)
			(xy 35.621204 -243.243333) (xy 35.621204 -243.190035) (xy 35.629147 -243.137331) (xy 35.644857 -243.086401)
			(xy 35.667983 -243.03838) (xy 35.698007 -242.994343) (xy 35.734259 -242.955272) (xy 35.77593 -242.922041)
			(xy 35.822088 -242.895392) (xy 35.871702 -242.87592) (xy 35.923664 -242.86406) (xy 35.976814 -242.860077)
			(xy 36.029964 -242.86406) (xy 36.081926 -242.87592) (xy 36.13154 -242.895392) (xy 36.177698 -242.922041)
			(xy 36.219369 -242.955272) (xy 36.255621 -242.994343) (xy 36.285645 -243.03838) (xy 36.308771 -243.086401)
			(xy 36.324481 -243.137331) (xy 36.332424 -243.190035) (xy 36.332922 -243.216684) (xy 36.332424 -243.243333)
			(xy 39.064936 -243.243333) (xy 39.064936 -243.190035) (xy 39.072879 -243.137331) (xy 39.088589 -243.086401)
			(xy 39.111715 -243.03838) (xy 39.141739 -242.994343) (xy 39.177991 -242.955272) (xy 39.219662 -242.922041)
			(xy 39.26582 -242.895392) (xy 39.315434 -242.87592) (xy 39.367396 -242.86406) (xy 39.420546 -242.860077)
			(xy 39.473696 -242.86406) (xy 39.525658 -242.87592) (xy 39.575272 -242.895392) (xy 39.62143 -242.922041)
			(xy 39.663101 -242.955272) (xy 39.699353 -242.994343) (xy 39.729377 -243.03838) (xy 39.752503 -243.086401)
			(xy 39.768213 -243.137331) (xy 39.776156 -243.190035) (xy 39.776654 -243.216684) (xy 39.776156 -243.243333)
			(xy 43.165004 -243.243333) (xy 43.165004 -243.190035) (xy 43.172947 -243.137331) (xy 43.188657 -243.086401)
			(xy 43.211783 -243.03838) (xy 43.241807 -242.994343) (xy 43.278059 -242.955272) (xy 43.31973 -242.922041)
			(xy 43.365888 -242.895392) (xy 43.415502 -242.87592) (xy 43.467464 -242.86406) (xy 43.520614 -242.860077)
			(xy 43.573764 -242.86406) (xy 43.625726 -242.87592) (xy 43.67534 -242.895392) (xy 43.721498 -242.922041)
			(xy 43.763169 -242.955272) (xy 43.799421 -242.994343) (xy 43.829445 -243.03838) (xy 43.852571 -243.086401)
			(xy 43.868281 -243.137331) (xy 43.876224 -243.190035) (xy 43.876722 -243.216684) (xy 43.876224 -243.243333)
			(xy 46.608736 -243.243333) (xy 46.608736 -243.190035) (xy 46.616679 -243.137331) (xy 46.632389 -243.086401)
			(xy 46.655515 -243.03838) (xy 46.685539 -242.994343) (xy 46.721791 -242.955272) (xy 46.763462 -242.922041)
			(xy 46.80962 -242.895392) (xy 46.859234 -242.87592) (xy 46.911196 -242.86406) (xy 46.964346 -242.860077)
			(xy 47.017496 -242.86406) (xy 47.069458 -242.87592) (xy 47.119072 -242.895392) (xy 47.16523 -242.922041)
			(xy 47.206901 -242.955272) (xy 47.243153 -242.994343) (xy 47.273177 -243.03838) (xy 47.296303 -243.086401)
			(xy 47.312013 -243.137331) (xy 47.319956 -243.190035) (xy 47.320454 -243.216684) (xy 47.319956 -243.243333)
			(xy 50.708804 -243.243333) (xy 50.708804 -243.190035) (xy 50.716747 -243.137331) (xy 50.732457 -243.086401)
			(xy 50.755583 -243.03838) (xy 50.785607 -242.994343) (xy 50.821859 -242.955272) (xy 50.86353 -242.922041)
			(xy 50.909688 -242.895392) (xy 50.959302 -242.87592) (xy 51.011264 -242.86406) (xy 51.064414 -242.860077)
			(xy 51.117564 -242.86406) (xy 51.169526 -242.87592) (xy 51.21914 -242.895392) (xy 51.265298 -242.922041)
			(xy 51.306969 -242.955272) (xy 51.343221 -242.994343) (xy 51.373245 -243.03838) (xy 51.396371 -243.086401)
			(xy 51.412081 -243.137331) (xy 51.420024 -243.190035) (xy 51.420522 -243.216684) (xy 51.420024 -243.243333)
			(xy 54.152536 -243.243333) (xy 54.152536 -243.190035) (xy 54.160479 -243.137331) (xy 54.176189 -243.086401)
			(xy 54.199315 -243.03838) (xy 54.229339 -242.994343) (xy 54.265591 -242.955272) (xy 54.307262 -242.922041)
			(xy 54.35342 -242.895392) (xy 54.403034 -242.87592) (xy 54.454996 -242.86406) (xy 54.508146 -242.860077)
			(xy 54.561296 -242.86406) (xy 54.613258 -242.87592) (xy 54.662872 -242.895392) (xy 54.70903 -242.922041)
			(xy 54.750701 -242.955272) (xy 54.786953 -242.994343) (xy 54.816977 -243.03838) (xy 54.840103 -243.086401)
			(xy 54.855813 -243.137331) (xy 54.863756 -243.190035) (xy 54.864254 -243.216684) (xy 54.863756 -243.243333)
			(xy 56.042804 -243.243333) (xy 56.042804 -243.190035) (xy 56.050747 -243.137331) (xy 56.066457 -243.086401)
			(xy 56.089583 -243.03838) (xy 56.119607 -242.994343) (xy 56.155859 -242.955272) (xy 56.19753 -242.922041)
			(xy 56.243688 -242.895392) (xy 56.293302 -242.87592) (xy 56.345264 -242.86406) (xy 56.398414 -242.860077)
			(xy 56.451564 -242.86406) (xy 56.503526 -242.87592) (xy 56.55314 -242.895392) (xy 56.599298 -242.922041)
			(xy 56.640969 -242.955272) (xy 56.677221 -242.994343) (xy 56.707245 -243.03838) (xy 56.730371 -243.086401)
			(xy 56.746081 -243.137331) (xy 56.754024 -243.190035) (xy 56.754522 -243.216684) (xy 56.754024 -243.243333)
			(xy 61.696336 -243.243333) (xy 61.696336 -243.190035) (xy 61.704279 -243.137331) (xy 61.719989 -243.086401)
			(xy 61.743115 -243.03838) (xy 61.773139 -242.994343) (xy 61.809391 -242.955272) (xy 61.851062 -242.922041)
			(xy 61.89722 -242.895392) (xy 61.946834 -242.87592) (xy 61.998796 -242.86406) (xy 62.051946 -242.860077)
			(xy 62.105096 -242.86406) (xy 62.157058 -242.87592) (xy 62.206672 -242.895392) (xy 62.25283 -242.922041)
			(xy 62.294501 -242.955272) (xy 62.330753 -242.994343) (xy 62.360777 -243.03838) (xy 62.383903 -243.086401)
			(xy 62.399613 -243.137331) (xy 62.407556 -243.190035) (xy 62.408054 -243.216684) (xy 62.407556 -243.243333)
			(xy 62.399613 -243.296037) (xy 62.383903 -243.346967) (xy 62.360777 -243.394988) (xy 62.330753 -243.439025)
			(xy 62.294501 -243.478096) (xy 62.25283 -243.511327) (xy 62.206672 -243.537976) (xy 62.157058 -243.557448)
			(xy 62.105096 -243.569308) (xy 62.051946 -243.573292) (xy 61.998796 -243.569308) (xy 61.946834 -243.557448)
			(xy 61.89722 -243.537976) (xy 61.851062 -243.511327) (xy 61.809391 -243.478096) (xy 61.773139 -243.439025)
			(xy 61.743115 -243.394988) (xy 61.719989 -243.346967) (xy 61.704279 -243.296037) (xy 61.696336 -243.243333)
			(xy 56.754024 -243.243333) (xy 56.746081 -243.296037) (xy 56.730371 -243.346967) (xy 56.707245 -243.394988)
			(xy 56.677221 -243.439025) (xy 56.640969 -243.478096) (xy 56.599298 -243.511327) (xy 56.55314 -243.537976)
			(xy 56.503526 -243.557448) (xy 56.451564 -243.569308) (xy 56.398414 -243.573292) (xy 56.345264 -243.569308)
			(xy 56.293302 -243.557448) (xy 56.243688 -243.537976) (xy 56.19753 -243.511327) (xy 56.155859 -243.478096)
			(xy 56.119607 -243.439025) (xy 56.089583 -243.394988) (xy 56.066457 -243.346967) (xy 56.050747 -243.296037)
			(xy 56.042804 -243.243333) (xy 54.863756 -243.243333) (xy 54.855813 -243.296037) (xy 54.840103 -243.346967)
			(xy 54.816977 -243.394988) (xy 54.786953 -243.439025) (xy 54.750701 -243.478096) (xy 54.70903 -243.511327)
			(xy 54.662872 -243.537976) (xy 54.613258 -243.557448) (xy 54.561296 -243.569308) (xy 54.508146 -243.573292)
			(xy 54.454996 -243.569308) (xy 54.403034 -243.557448) (xy 54.35342 -243.537976) (xy 54.307262 -243.511327)
			(xy 54.265591 -243.478096) (xy 54.229339 -243.439025) (xy 54.199315 -243.394988) (xy 54.176189 -243.346967)
			(xy 54.160479 -243.296037) (xy 54.152536 -243.243333) (xy 51.420024 -243.243333) (xy 51.412081 -243.296037)
			(xy 51.396371 -243.346967) (xy 51.373245 -243.394988) (xy 51.343221 -243.439025) (xy 51.306969 -243.478096)
			(xy 51.265298 -243.511327) (xy 51.21914 -243.537976) (xy 51.169526 -243.557448) (xy 51.117564 -243.569308)
			(xy 51.064414 -243.573292) (xy 51.011264 -243.569308) (xy 50.959302 -243.557448) (xy 50.909688 -243.537976)
			(xy 50.86353 -243.511327) (xy 50.821859 -243.478096) (xy 50.785607 -243.439025) (xy 50.755583 -243.394988)
			(xy 50.732457 -243.346967) (xy 50.716747 -243.296037) (xy 50.708804 -243.243333) (xy 47.319956 -243.243333)
			(xy 47.312013 -243.296037) (xy 47.296303 -243.346967) (xy 47.273177 -243.394988) (xy 47.243153 -243.439025)
			(xy 47.206901 -243.478096) (xy 47.16523 -243.511327) (xy 47.119072 -243.537976) (xy 47.069458 -243.557448)
			(xy 47.017496 -243.569308) (xy 46.964346 -243.573292) (xy 46.911196 -243.569308) (xy 46.859234 -243.557448)
			(xy 46.80962 -243.537976) (xy 46.763462 -243.511327) (xy 46.721791 -243.478096) (xy 46.685539 -243.439025)
			(xy 46.655515 -243.394988) (xy 46.632389 -243.346967) (xy 46.616679 -243.296037) (xy 46.608736 -243.243333)
			(xy 43.876224 -243.243333) (xy 43.868281 -243.296037) (xy 43.852571 -243.346967) (xy 43.829445 -243.394988)
			(xy 43.799421 -243.439025) (xy 43.763169 -243.478096) (xy 43.721498 -243.511327) (xy 43.67534 -243.537976)
			(xy 43.625726 -243.557448) (xy 43.573764 -243.569308) (xy 43.520614 -243.573292) (xy 43.467464 -243.569308)
			(xy 43.415502 -243.557448) (xy 43.365888 -243.537976) (xy 43.31973 -243.511327) (xy 43.278059 -243.478096)
			(xy 43.241807 -243.439025) (xy 43.211783 -243.394988) (xy 43.188657 -243.346967) (xy 43.172947 -243.296037)
			(xy 43.165004 -243.243333) (xy 39.776156 -243.243333) (xy 39.768213 -243.296037) (xy 39.752503 -243.346967)
			(xy 39.729377 -243.394988) (xy 39.699353 -243.439025) (xy 39.663101 -243.478096) (xy 39.62143 -243.511327)
			(xy 39.575272 -243.537976) (xy 39.525658 -243.557448) (xy 39.473696 -243.569308) (xy 39.420546 -243.573292)
			(xy 39.367396 -243.569308) (xy 39.315434 -243.557448) (xy 39.26582 -243.537976) (xy 39.219662 -243.511327)
			(xy 39.177991 -243.478096) (xy 39.141739 -243.439025) (xy 39.111715 -243.394988) (xy 39.088589 -243.346967)
			(xy 39.072879 -243.296037) (xy 39.064936 -243.243333) (xy 36.332424 -243.243333) (xy 36.324481 -243.296037)
			(xy 36.308771 -243.346967) (xy 36.285645 -243.394988) (xy 36.255621 -243.439025) (xy 36.219369 -243.478096)
			(xy 36.177698 -243.511327) (xy 36.13154 -243.537976) (xy 36.081926 -243.557448) (xy 36.029964 -243.569308)
			(xy 35.976814 -243.573292) (xy 35.923664 -243.569308) (xy 35.871702 -243.557448) (xy 35.822088 -243.537976)
			(xy 35.77593 -243.511327) (xy 35.734259 -243.478096) (xy 35.698007 -243.439025) (xy 35.667983 -243.394988)
			(xy 35.644857 -243.346967) (xy 35.629147 -243.296037) (xy 35.621204 -243.243333) (xy 32.232356 -243.243333)
			(xy 32.224413 -243.296037) (xy 32.208703 -243.346967) (xy 32.185577 -243.394988) (xy 32.155553 -243.439025)
			(xy 32.119301 -243.478096) (xy 32.07763 -243.511327) (xy 32.031472 -243.537976) (xy 31.981858 -243.557448)
			(xy 31.929896 -243.569308) (xy 31.876746 -243.573292) (xy 31.823596 -243.569308) (xy 31.771634 -243.557448)
			(xy 31.72202 -243.537976) (xy 31.675862 -243.511327) (xy 31.634191 -243.478096) (xy 31.597939 -243.439025)
			(xy 31.567915 -243.394988) (xy 31.544789 -243.346967) (xy 31.529079 -243.296037) (xy 31.521136 -243.243333)
			(xy 28.788624 -243.243333) (xy 28.780681 -243.296037) (xy 28.764971 -243.346967) (xy 28.741845 -243.394988)
			(xy 28.711821 -243.439025) (xy 28.675569 -243.478096) (xy 28.633898 -243.511327) (xy 28.58774 -243.537976)
			(xy 28.538126 -243.557448) (xy 28.486164 -243.569308) (xy 28.433014 -243.573292) (xy 28.379864 -243.569308)
			(xy 28.327902 -243.557448) (xy 28.278288 -243.537976) (xy 28.23213 -243.511327) (xy 28.190459 -243.478096)
			(xy 28.154207 -243.439025) (xy 28.124183 -243.394988) (xy 28.101057 -243.346967) (xy 28.085347 -243.296037)
			(xy 28.077404 -243.243333) (xy 24.688556 -243.243333) (xy 24.680613 -243.296037) (xy 24.664903 -243.346967)
			(xy 24.641777 -243.394988) (xy 24.611753 -243.439025) (xy 24.575501 -243.478096) (xy 24.53383 -243.511327)
			(xy 24.487672 -243.537976) (xy 24.438058 -243.557448) (xy 24.386096 -243.569308) (xy 24.332946 -243.573292)
			(xy 24.279796 -243.569308) (xy 24.227834 -243.557448) (xy 24.17822 -243.537976) (xy 24.132062 -243.511327)
			(xy 24.090391 -243.478096) (xy 24.054139 -243.439025) (xy 24.024115 -243.394988) (xy 24.000989 -243.346967)
			(xy 23.985279 -243.296037) (xy 23.977336 -243.243333) (xy 21.244824 -243.243333) (xy 21.236881 -243.296037)
			(xy 21.221171 -243.346967) (xy 21.198045 -243.394988) (xy 21.168021 -243.439025) (xy 21.131769 -243.478096)
			(xy 21.090098 -243.511327) (xy 21.04394 -243.537976) (xy 20.994326 -243.557448) (xy 20.942364 -243.569308)
			(xy 20.889214 -243.573292) (xy 20.836064 -243.569308) (xy 20.784102 -243.557448) (xy 20.734488 -243.537976)
			(xy 20.68833 -243.511327) (xy 20.646659 -243.478096) (xy 20.610407 -243.439025) (xy 20.580383 -243.394988)
			(xy 20.557257 -243.346967) (xy 20.541547 -243.296037) (xy 20.533604 -243.243333) (xy 17.144756 -243.243333)
			(xy 17.136813 -243.296037) (xy 17.121103 -243.346967) (xy 17.097977 -243.394988) (xy 17.067953 -243.439025)
			(xy 17.031701 -243.478096) (xy 16.99003 -243.511327) (xy 16.943872 -243.537976) (xy 16.894258 -243.557448)
			(xy 16.842296 -243.569308) (xy 16.789146 -243.573292) (xy 16.735996 -243.569308) (xy 16.684034 -243.557448)
			(xy 16.63442 -243.537976) (xy 16.588262 -243.511327) (xy 16.546591 -243.478096) (xy 16.510339 -243.439025)
			(xy 16.480315 -243.394988) (xy 16.457189 -243.346967) (xy 16.441479 -243.296037) (xy 16.433536 -243.243333)
			(xy 13.701024 -243.243333) (xy 13.693081 -243.296037) (xy 13.677371 -243.346967) (xy 13.654245 -243.394988)
			(xy 13.624221 -243.439025) (xy 13.587969 -243.478096) (xy 13.546298 -243.511327) (xy 13.50014 -243.537976)
			(xy 13.450526 -243.557448) (xy 13.398564 -243.569308) (xy 13.345414 -243.573292) (xy 13.292264 -243.569308)
			(xy 13.240302 -243.557448) (xy 13.190688 -243.537976) (xy 13.14453 -243.511327) (xy 13.102859 -243.478096)
			(xy 13.066607 -243.439025) (xy 13.036583 -243.394988) (xy 13.013457 -243.346967) (xy 12.997747 -243.296037)
			(xy 12.989804 -243.243333) (xy 9.600956 -243.243333) (xy 9.593013 -243.296037) (xy 9.577303 -243.346967)
			(xy 9.554177 -243.394988) (xy 9.524153 -243.439025) (xy 9.487901 -243.478096) (xy 9.44623 -243.511327)
			(xy 9.400072 -243.537976) (xy 9.350458 -243.557448) (xy 9.298496 -243.569308) (xy 9.245346 -243.573292)
			(xy 9.192196 -243.569308) (xy 9.140234 -243.557448) (xy 9.09062 -243.537976) (xy 9.044462 -243.511327)
			(xy 9.002791 -243.478096) (xy 8.966539 -243.439025) (xy 8.936515 -243.394988) (xy 8.913389 -243.346967)
			(xy 8.897679 -243.296037) (xy 8.889736 -243.243333) (xy 6.7818 -243.243333) (xy 6.7818 -244.093217)
			(xy 8.889736 -244.093217) (xy 8.889736 -244.039919) (xy 8.897679 -243.987215) (xy 8.913389 -243.936285)
			(xy 8.936515 -243.888264) (xy 8.966539 -243.844227) (xy 9.002791 -243.805156) (xy 9.044462 -243.771925)
			(xy 9.09062 -243.745276) (xy 9.140234 -243.725804) (xy 9.192196 -243.713944) (xy 9.245346 -243.709961)
			(xy 9.298496 -243.713944) (xy 9.350458 -243.725804) (xy 9.400072 -243.745276) (xy 9.44623 -243.771925)
			(xy 9.487901 -243.805156) (xy 9.524153 -243.844227) (xy 9.554177 -243.888264) (xy 9.577303 -243.936285)
			(xy 9.593013 -243.987215) (xy 9.600956 -244.039919) (xy 9.601454 -244.066568) (xy 9.600956 -244.093217)
			(xy 16.433536 -244.093217) (xy 16.433536 -244.039919) (xy 16.441479 -243.987215) (xy 16.457189 -243.936285)
			(xy 16.480315 -243.888264) (xy 16.510339 -243.844227) (xy 16.546591 -243.805156) (xy 16.588262 -243.771925)
			(xy 16.63442 -243.745276) (xy 16.684034 -243.725804) (xy 16.735996 -243.713944) (xy 16.789146 -243.709961)
			(xy 16.842296 -243.713944) (xy 16.894258 -243.725804) (xy 16.943872 -243.745276) (xy 16.99003 -243.771925)
			(xy 17.031701 -243.805156) (xy 17.067953 -243.844227) (xy 17.097977 -243.888264) (xy 17.121103 -243.936285)
			(xy 17.136813 -243.987215) (xy 17.144756 -244.039919) (xy 17.145254 -244.066568) (xy 17.144756 -244.093217)
			(xy 23.977336 -244.093217) (xy 23.977336 -244.039919) (xy 23.985279 -243.987215) (xy 24.000989 -243.936285)
			(xy 24.024115 -243.888264) (xy 24.054139 -243.844227) (xy 24.090391 -243.805156) (xy 24.132062 -243.771925)
			(xy 24.17822 -243.745276) (xy 24.227834 -243.725804) (xy 24.279796 -243.713944) (xy 24.332946 -243.709961)
			(xy 24.386096 -243.713944) (xy 24.438058 -243.725804) (xy 24.487672 -243.745276) (xy 24.53383 -243.771925)
			(xy 24.575501 -243.805156) (xy 24.611753 -243.844227) (xy 24.641777 -243.888264) (xy 24.664903 -243.936285)
			(xy 24.680613 -243.987215) (xy 24.688556 -244.039919) (xy 24.689054 -244.066568) (xy 24.688556 -244.093217)
			(xy 31.521136 -244.093217) (xy 31.521136 -244.039919) (xy 31.529079 -243.987215) (xy 31.544789 -243.936285)
			(xy 31.567915 -243.888264) (xy 31.597939 -243.844227) (xy 31.634191 -243.805156) (xy 31.675862 -243.771925)
			(xy 31.72202 -243.745276) (xy 31.771634 -243.725804) (xy 31.823596 -243.713944) (xy 31.876746 -243.709961)
			(xy 31.929896 -243.713944) (xy 31.981858 -243.725804) (xy 32.031472 -243.745276) (xy 32.07763 -243.771925)
			(xy 32.119301 -243.805156) (xy 32.155553 -243.844227) (xy 32.185577 -243.888264) (xy 32.208703 -243.936285)
			(xy 32.224413 -243.987215) (xy 32.232356 -244.039919) (xy 32.232854 -244.066568) (xy 32.232356 -244.093217)
			(xy 39.064936 -244.093217) (xy 39.064936 -244.039919) (xy 39.072879 -243.987215) (xy 39.088589 -243.936285)
			(xy 39.111715 -243.888264) (xy 39.141739 -243.844227) (xy 39.177991 -243.805156) (xy 39.219662 -243.771925)
			(xy 39.26582 -243.745276) (xy 39.315434 -243.725804) (xy 39.367396 -243.713944) (xy 39.420546 -243.709961)
			(xy 39.473696 -243.713944) (xy 39.525658 -243.725804) (xy 39.575272 -243.745276) (xy 39.62143 -243.771925)
			(xy 39.663101 -243.805156) (xy 39.699353 -243.844227) (xy 39.729377 -243.888264) (xy 39.752503 -243.936285)
			(xy 39.768213 -243.987215) (xy 39.776156 -244.039919) (xy 39.776654 -244.066568) (xy 39.776156 -244.093217)
			(xy 46.608736 -244.093217) (xy 46.608736 -244.039919) (xy 46.616679 -243.987215) (xy 46.632389 -243.936285)
			(xy 46.655515 -243.888264) (xy 46.685539 -243.844227) (xy 46.721791 -243.805156) (xy 46.763462 -243.771925)
			(xy 46.80962 -243.745276) (xy 46.859234 -243.725804) (xy 46.911196 -243.713944) (xy 46.964346 -243.709961)
			(xy 47.017496 -243.713944) (xy 47.069458 -243.725804) (xy 47.119072 -243.745276) (xy 47.16523 -243.771925)
			(xy 47.206901 -243.805156) (xy 47.243153 -243.844227) (xy 47.273177 -243.888264) (xy 47.296303 -243.936285)
			(xy 47.312013 -243.987215) (xy 47.319956 -244.039919) (xy 47.320454 -244.066568) (xy 47.319956 -244.093217)
			(xy 54.152536 -244.093217) (xy 54.152536 -244.039919) (xy 54.160479 -243.987215) (xy 54.176189 -243.936285)
			(xy 54.199315 -243.888264) (xy 54.229339 -243.844227) (xy 54.265591 -243.805156) (xy 54.307262 -243.771925)
			(xy 54.35342 -243.745276) (xy 54.403034 -243.725804) (xy 54.454996 -243.713944) (xy 54.508146 -243.709961)
			(xy 54.561296 -243.713944) (xy 54.613258 -243.725804) (xy 54.662872 -243.745276) (xy 54.70903 -243.771925)
			(xy 54.750701 -243.805156) (xy 54.786953 -243.844227) (xy 54.816977 -243.888264) (xy 54.840103 -243.936285)
			(xy 54.855813 -243.987215) (xy 54.863756 -244.039919) (xy 54.864254 -244.066568) (xy 54.863756 -244.093217)
			(xy 61.696336 -244.093217) (xy 61.696336 -244.039919) (xy 61.704279 -243.987215) (xy 61.719989 -243.936285)
			(xy 61.743115 -243.888264) (xy 61.773139 -243.844227) (xy 61.809391 -243.805156) (xy 61.851062 -243.771925)
			(xy 61.89722 -243.745276) (xy 61.946834 -243.725804) (xy 61.998796 -243.713944) (xy 62.051946 -243.709961)
			(xy 62.105096 -243.713944) (xy 62.157058 -243.725804) (xy 62.206672 -243.745276) (xy 62.25283 -243.771925)
			(xy 62.294501 -243.805156) (xy 62.330753 -243.844227) (xy 62.360777 -243.888264) (xy 62.383903 -243.936285)
			(xy 62.399613 -243.987215) (xy 62.407556 -244.039919) (xy 62.408054 -244.066568) (xy 62.407556 -244.093217)
			(xy 62.399613 -244.145921) (xy 62.383903 -244.196851) (xy 62.360777 -244.244872) (xy 62.330753 -244.288909)
			(xy 62.294501 -244.32798) (xy 62.25283 -244.361211) (xy 62.206672 -244.38786) (xy 62.157058 -244.407332)
			(xy 62.105096 -244.419192) (xy 62.051946 -244.423176) (xy 61.998796 -244.419192) (xy 61.946834 -244.407332)
			(xy 61.89722 -244.38786) (xy 61.851062 -244.361211) (xy 61.809391 -244.32798) (xy 61.773139 -244.288909)
			(xy 61.743115 -244.244872) (xy 61.719989 -244.196851) (xy 61.704279 -244.145921) (xy 61.696336 -244.093217)
			(xy 54.863756 -244.093217) (xy 54.855813 -244.145921) (xy 54.840103 -244.196851) (xy 54.816977 -244.244872)
			(xy 54.786953 -244.288909) (xy 54.750701 -244.32798) (xy 54.70903 -244.361211) (xy 54.662872 -244.38786)
			(xy 54.613258 -244.407332) (xy 54.561296 -244.419192) (xy 54.508146 -244.423176) (xy 54.454996 -244.419192)
			(xy 54.403034 -244.407332) (xy 54.35342 -244.38786) (xy 54.307262 -244.361211) (xy 54.265591 -244.32798)
			(xy 54.229339 -244.288909) (xy 54.199315 -244.244872) (xy 54.176189 -244.196851) (xy 54.160479 -244.145921)
			(xy 54.152536 -244.093217) (xy 47.319956 -244.093217) (xy 47.312013 -244.145921) (xy 47.296303 -244.196851)
			(xy 47.273177 -244.244872) (xy 47.243153 -244.288909) (xy 47.206901 -244.32798) (xy 47.16523 -244.361211)
			(xy 47.119072 -244.38786) (xy 47.069458 -244.407332) (xy 47.017496 -244.419192) (xy 46.964346 -244.423176)
			(xy 46.911196 -244.419192) (xy 46.859234 -244.407332) (xy 46.80962 -244.38786) (xy 46.763462 -244.361211)
			(xy 46.721791 -244.32798) (xy 46.685539 -244.288909) (xy 46.655515 -244.244872) (xy 46.632389 -244.196851)
			(xy 46.616679 -244.145921) (xy 46.608736 -244.093217) (xy 39.776156 -244.093217) (xy 39.768213 -244.145921)
			(xy 39.752503 -244.196851) (xy 39.729377 -244.244872) (xy 39.699353 -244.288909) (xy 39.663101 -244.32798)
			(xy 39.62143 -244.361211) (xy 39.575272 -244.38786) (xy 39.525658 -244.407332) (xy 39.473696 -244.419192)
			(xy 39.420546 -244.423176) (xy 39.367396 -244.419192) (xy 39.315434 -244.407332) (xy 39.26582 -244.38786)
			(xy 39.219662 -244.361211) (xy 39.177991 -244.32798) (xy 39.141739 -244.288909) (xy 39.111715 -244.244872)
			(xy 39.088589 -244.196851) (xy 39.072879 -244.145921) (xy 39.064936 -244.093217) (xy 32.232356 -244.093217)
			(xy 32.224413 -244.145921) (xy 32.208703 -244.196851) (xy 32.185577 -244.244872) (xy 32.155553 -244.288909)
			(xy 32.119301 -244.32798) (xy 32.07763 -244.361211) (xy 32.031472 -244.38786) (xy 31.981858 -244.407332)
			(xy 31.929896 -244.419192) (xy 31.876746 -244.423176) (xy 31.823596 -244.419192) (xy 31.771634 -244.407332)
			(xy 31.72202 -244.38786) (xy 31.675862 -244.361211) (xy 31.634191 -244.32798) (xy 31.597939 -244.288909)
			(xy 31.567915 -244.244872) (xy 31.544789 -244.196851) (xy 31.529079 -244.145921) (xy 31.521136 -244.093217)
			(xy 24.688556 -244.093217) (xy 24.680613 -244.145921) (xy 24.664903 -244.196851) (xy 24.641777 -244.244872)
			(xy 24.611753 -244.288909) (xy 24.575501 -244.32798) (xy 24.53383 -244.361211) (xy 24.487672 -244.38786)
			(xy 24.438058 -244.407332) (xy 24.386096 -244.419192) (xy 24.332946 -244.423176) (xy 24.279796 -244.419192)
			(xy 24.227834 -244.407332) (xy 24.17822 -244.38786) (xy 24.132062 -244.361211) (xy 24.090391 -244.32798)
			(xy 24.054139 -244.288909) (xy 24.024115 -244.244872) (xy 24.000989 -244.196851) (xy 23.985279 -244.145921)
			(xy 23.977336 -244.093217) (xy 17.144756 -244.093217) (xy 17.136813 -244.145921) (xy 17.121103 -244.196851)
			(xy 17.097977 -244.244872) (xy 17.067953 -244.288909) (xy 17.031701 -244.32798) (xy 16.99003 -244.361211)
			(xy 16.943872 -244.38786) (xy 16.894258 -244.407332) (xy 16.842296 -244.419192) (xy 16.789146 -244.423176)
			(xy 16.735996 -244.419192) (xy 16.684034 -244.407332) (xy 16.63442 -244.38786) (xy 16.588262 -244.361211)
			(xy 16.546591 -244.32798) (xy 16.510339 -244.288909) (xy 16.480315 -244.244872) (xy 16.457189 -244.196851)
			(xy 16.441479 -244.145921) (xy 16.433536 -244.093217) (xy 9.600956 -244.093217) (xy 9.593013 -244.145921)
			(xy 9.577303 -244.196851) (xy 9.554177 -244.244872) (xy 9.524153 -244.288909) (xy 9.487901 -244.32798)
			(xy 9.44623 -244.361211) (xy 9.400072 -244.38786) (xy 9.350458 -244.407332) (xy 9.298496 -244.419192)
			(xy 9.245346 -244.423176) (xy 9.192196 -244.419192) (xy 9.140234 -244.407332) (xy 9.09062 -244.38786)
			(xy 9.044462 -244.361211) (xy 9.002791 -244.32798) (xy 8.966539 -244.288909) (xy 8.936515 -244.244872)
			(xy 8.913389 -244.196851) (xy 8.897679 -244.145921) (xy 8.889736 -244.093217) (xy 6.7818 -244.093217)
			(xy 6.7818 -244.943355) (xy 12.989804 -244.943355) (xy 12.989804 -244.890057) (xy 12.997747 -244.837353)
			(xy 13.013457 -244.786423) (xy 13.036583 -244.738402) (xy 13.066607 -244.694365) (xy 13.102859 -244.655294)
			(xy 13.14453 -244.622063) (xy 13.190688 -244.595414) (xy 13.240302 -244.575942) (xy 13.292264 -244.564082)
			(xy 13.345414 -244.560099) (xy 13.398564 -244.564082) (xy 13.450526 -244.575942) (xy 13.50014 -244.595414)
			(xy 13.546298 -244.622063) (xy 13.587969 -244.655294) (xy 13.624221 -244.694365) (xy 13.654245 -244.738402)
			(xy 13.677371 -244.786423) (xy 13.693081 -244.837353) (xy 13.701024 -244.890057) (xy 13.701522 -244.916706)
			(xy 13.701024 -244.943355) (xy 20.533604 -244.943355) (xy 20.533604 -244.890057) (xy 20.541547 -244.837353)
			(xy 20.557257 -244.786423) (xy 20.580383 -244.738402) (xy 20.610407 -244.694365) (xy 20.646659 -244.655294)
			(xy 20.68833 -244.622063) (xy 20.734488 -244.595414) (xy 20.784102 -244.575942) (xy 20.836064 -244.564082)
			(xy 20.889214 -244.560099) (xy 20.942364 -244.564082) (xy 20.994326 -244.575942) (xy 21.04394 -244.595414)
			(xy 21.090098 -244.622063) (xy 21.131769 -244.655294) (xy 21.168021 -244.694365) (xy 21.198045 -244.738402)
			(xy 21.221171 -244.786423) (xy 21.236881 -244.837353) (xy 21.244824 -244.890057) (xy 21.245322 -244.916706)
			(xy 21.244824 -244.943355) (xy 28.077404 -244.943355) (xy 28.077404 -244.890057) (xy 28.085347 -244.837353)
			(xy 28.101057 -244.786423) (xy 28.124183 -244.738402) (xy 28.154207 -244.694365) (xy 28.190459 -244.655294)
			(xy 28.23213 -244.622063) (xy 28.278288 -244.595414) (xy 28.327902 -244.575942) (xy 28.379864 -244.564082)
			(xy 28.433014 -244.560099) (xy 28.486164 -244.564082) (xy 28.538126 -244.575942) (xy 28.58774 -244.595414)
			(xy 28.633898 -244.622063) (xy 28.675569 -244.655294) (xy 28.711821 -244.694365) (xy 28.741845 -244.738402)
			(xy 28.764971 -244.786423) (xy 28.780681 -244.837353) (xy 28.788624 -244.890057) (xy 28.789122 -244.916706)
			(xy 28.788624 -244.943355) (xy 35.621204 -244.943355) (xy 35.621204 -244.890057) (xy 35.629147 -244.837353)
			(xy 35.644857 -244.786423) (xy 35.667983 -244.738402) (xy 35.698007 -244.694365) (xy 35.734259 -244.655294)
			(xy 35.77593 -244.622063) (xy 35.822088 -244.595414) (xy 35.871702 -244.575942) (xy 35.923664 -244.564082)
			(xy 35.976814 -244.560099) (xy 36.029964 -244.564082) (xy 36.081926 -244.575942) (xy 36.13154 -244.595414)
			(xy 36.177698 -244.622063) (xy 36.219369 -244.655294) (xy 36.255621 -244.694365) (xy 36.285645 -244.738402)
			(xy 36.308771 -244.786423) (xy 36.324481 -244.837353) (xy 36.332424 -244.890057) (xy 36.332922 -244.916706)
			(xy 36.332424 -244.943355) (xy 43.165004 -244.943355) (xy 43.165004 -244.890057) (xy 43.172947 -244.837353)
			(xy 43.188657 -244.786423) (xy 43.211783 -244.738402) (xy 43.241807 -244.694365) (xy 43.278059 -244.655294)
			(xy 43.31973 -244.622063) (xy 43.365888 -244.595414) (xy 43.415502 -244.575942) (xy 43.467464 -244.564082)
			(xy 43.520614 -244.560099) (xy 43.573764 -244.564082) (xy 43.625726 -244.575942) (xy 43.67534 -244.595414)
			(xy 43.721498 -244.622063) (xy 43.763169 -244.655294) (xy 43.799421 -244.694365) (xy 43.829445 -244.738402)
			(xy 43.852571 -244.786423) (xy 43.868281 -244.837353) (xy 43.876224 -244.890057) (xy 43.876722 -244.916706)
			(xy 43.876224 -244.943355) (xy 50.708804 -244.943355) (xy 50.708804 -244.890057) (xy 50.716747 -244.837353)
			(xy 50.732457 -244.786423) (xy 50.755583 -244.738402) (xy 50.785607 -244.694365) (xy 50.821859 -244.655294)
			(xy 50.86353 -244.622063) (xy 50.909688 -244.595414) (xy 50.959302 -244.575942) (xy 51.011264 -244.564082)
			(xy 51.064414 -244.560099) (xy 51.117564 -244.564082) (xy 51.169526 -244.575942) (xy 51.21914 -244.595414)
			(xy 51.265298 -244.622063) (xy 51.306969 -244.655294) (xy 51.343221 -244.694365) (xy 51.373245 -244.738402)
			(xy 51.396371 -244.786423) (xy 51.412081 -244.837353) (xy 51.420024 -244.890057) (xy 51.420522 -244.916706)
			(xy 51.420024 -244.943355) (xy 51.412081 -244.996059) (xy 51.396371 -245.046989) (xy 51.373245 -245.09501)
			(xy 51.343221 -245.139047) (xy 51.306969 -245.178118) (xy 51.265298 -245.211349) (xy 51.21914 -245.237998)
			(xy 51.169526 -245.25747) (xy 51.117564 -245.26933) (xy 51.064414 -245.273314) (xy 51.011264 -245.26933)
			(xy 50.959302 -245.25747) (xy 50.909688 -245.237998) (xy 50.86353 -245.211349) (xy 50.821859 -245.178118)
			(xy 50.785607 -245.139047) (xy 50.755583 -245.09501) (xy 50.732457 -245.046989) (xy 50.716747 -244.996059)
			(xy 50.708804 -244.943355) (xy 43.876224 -244.943355) (xy 43.868281 -244.996059) (xy 43.852571 -245.046989)
			(xy 43.829445 -245.09501) (xy 43.799421 -245.139047) (xy 43.763169 -245.178118) (xy 43.721498 -245.211349)
			(xy 43.67534 -245.237998) (xy 43.625726 -245.25747) (xy 43.573764 -245.26933) (xy 43.520614 -245.273314)
			(xy 43.467464 -245.26933) (xy 43.415502 -245.25747) (xy 43.365888 -245.237998) (xy 43.31973 -245.211349)
			(xy 43.278059 -245.178118) (xy 43.241807 -245.139047) (xy 43.211783 -245.09501) (xy 43.188657 -245.046989)
			(xy 43.172947 -244.996059) (xy 43.165004 -244.943355) (xy 36.332424 -244.943355) (xy 36.324481 -244.996059)
			(xy 36.308771 -245.046989) (xy 36.285645 -245.09501) (xy 36.255621 -245.139047) (xy 36.219369 -245.178118)
			(xy 36.177698 -245.211349) (xy 36.13154 -245.237998) (xy 36.081926 -245.25747) (xy 36.029964 -245.26933)
			(xy 35.976814 -245.273314) (xy 35.923664 -245.26933) (xy 35.871702 -245.25747) (xy 35.822088 -245.237998)
			(xy 35.77593 -245.211349) (xy 35.734259 -245.178118) (xy 35.698007 -245.139047) (xy 35.667983 -245.09501)
			(xy 35.644857 -245.046989) (xy 35.629147 -244.996059) (xy 35.621204 -244.943355) (xy 28.788624 -244.943355)
			(xy 28.780681 -244.996059) (xy 28.764971 -245.046989) (xy 28.741845 -245.09501) (xy 28.711821 -245.139047)
			(xy 28.675569 -245.178118) (xy 28.633898 -245.211349) (xy 28.58774 -245.237998) (xy 28.538126 -245.25747)
			(xy 28.486164 -245.26933) (xy 28.433014 -245.273314) (xy 28.379864 -245.26933) (xy 28.327902 -245.25747)
			(xy 28.278288 -245.237998) (xy 28.23213 -245.211349) (xy 28.190459 -245.178118) (xy 28.154207 -245.139047)
			(xy 28.124183 -245.09501) (xy 28.101057 -245.046989) (xy 28.085347 -244.996059) (xy 28.077404 -244.943355)
			(xy 21.244824 -244.943355) (xy 21.236881 -244.996059) (xy 21.221171 -245.046989) (xy 21.198045 -245.09501)
			(xy 21.168021 -245.139047) (xy 21.131769 -245.178118) (xy 21.090098 -245.211349) (xy 21.04394 -245.237998)
			(xy 20.994326 -245.25747) (xy 20.942364 -245.26933) (xy 20.889214 -245.273314) (xy 20.836064 -245.26933)
			(xy 20.784102 -245.25747) (xy 20.734488 -245.237998) (xy 20.68833 -245.211349) (xy 20.646659 -245.178118)
			(xy 20.610407 -245.139047) (xy 20.580383 -245.09501) (xy 20.557257 -245.046989) (xy 20.541547 -244.996059)
			(xy 20.533604 -244.943355) (xy 13.701024 -244.943355) (xy 13.693081 -244.996059) (xy 13.677371 -245.046989)
			(xy 13.654245 -245.09501) (xy 13.624221 -245.139047) (xy 13.587969 -245.178118) (xy 13.546298 -245.211349)
			(xy 13.50014 -245.237998) (xy 13.450526 -245.25747) (xy 13.398564 -245.26933) (xy 13.345414 -245.273314)
			(xy 13.292264 -245.26933) (xy 13.240302 -245.25747) (xy 13.190688 -245.237998) (xy 13.14453 -245.211349)
			(xy 13.102859 -245.178118) (xy 13.066607 -245.139047) (xy 13.036583 -245.09501) (xy 13.013457 -245.046989)
			(xy 12.997747 -244.996059) (xy 12.989804 -244.943355) (xy 6.7818 -244.943355) (xy 6.7818 -245.793239)
			(xy 8.889736 -245.793239) (xy 8.889736 -245.739941) (xy 8.897679 -245.687237) (xy 8.913389 -245.636307)
			(xy 8.936515 -245.588286) (xy 8.966539 -245.544249) (xy 9.002791 -245.505178) (xy 9.044462 -245.471947)
			(xy 9.09062 -245.445298) (xy 9.140234 -245.425826) (xy 9.192196 -245.413966) (xy 9.245346 -245.409983)
			(xy 9.298496 -245.413966) (xy 9.350458 -245.425826) (xy 9.400072 -245.445298) (xy 9.44623 -245.471947)
			(xy 9.487901 -245.505178) (xy 9.524153 -245.544249) (xy 9.554177 -245.588286) (xy 9.577303 -245.636307)
			(xy 9.593013 -245.687237) (xy 9.600956 -245.739941) (xy 9.601454 -245.76659) (xy 9.600956 -245.793239)
			(xy 16.433536 -245.793239) (xy 16.433536 -245.739941) (xy 16.441479 -245.687237) (xy 16.457189 -245.636307)
			(xy 16.480315 -245.588286) (xy 16.510339 -245.544249) (xy 16.546591 -245.505178) (xy 16.588262 -245.471947)
			(xy 16.63442 -245.445298) (xy 16.684034 -245.425826) (xy 16.735996 -245.413966) (xy 16.789146 -245.409983)
			(xy 16.842296 -245.413966) (xy 16.894258 -245.425826) (xy 16.943872 -245.445298) (xy 16.99003 -245.471947)
			(xy 17.031701 -245.505178) (xy 17.067953 -245.544249) (xy 17.097977 -245.588286) (xy 17.121103 -245.636307)
			(xy 17.136813 -245.687237) (xy 17.144756 -245.739941) (xy 17.145254 -245.76659) (xy 17.144756 -245.793239)
			(xy 23.977336 -245.793239) (xy 23.977336 -245.739941) (xy 23.985279 -245.687237) (xy 24.000989 -245.636307)
			(xy 24.024115 -245.588286) (xy 24.054139 -245.544249) (xy 24.090391 -245.505178) (xy 24.132062 -245.471947)
			(xy 24.17822 -245.445298) (xy 24.227834 -245.425826) (xy 24.279796 -245.413966) (xy 24.332946 -245.409983)
			(xy 24.386096 -245.413966) (xy 24.438058 -245.425826) (xy 24.487672 -245.445298) (xy 24.53383 -245.471947)
			(xy 24.575501 -245.505178) (xy 24.611753 -245.544249) (xy 24.641777 -245.588286) (xy 24.664903 -245.636307)
			(xy 24.680613 -245.687237) (xy 24.688556 -245.739941) (xy 24.689054 -245.76659) (xy 24.688556 -245.793239)
			(xy 31.521136 -245.793239) (xy 31.521136 -245.739941) (xy 31.529079 -245.687237) (xy 31.544789 -245.636307)
			(xy 31.567915 -245.588286) (xy 31.597939 -245.544249) (xy 31.634191 -245.505178) (xy 31.675862 -245.471947)
			(xy 31.72202 -245.445298) (xy 31.771634 -245.425826) (xy 31.823596 -245.413966) (xy 31.876746 -245.409983)
			(xy 31.929896 -245.413966) (xy 31.981858 -245.425826) (xy 32.031472 -245.445298) (xy 32.07763 -245.471947)
			(xy 32.119301 -245.505178) (xy 32.155553 -245.544249) (xy 32.185577 -245.588286) (xy 32.208703 -245.636307)
			(xy 32.224413 -245.687237) (xy 32.232356 -245.739941) (xy 32.232854 -245.76659) (xy 32.232356 -245.793239)
			(xy 39.064936 -245.793239) (xy 39.064936 -245.739941) (xy 39.072879 -245.687237) (xy 39.088589 -245.636307)
			(xy 39.111715 -245.588286) (xy 39.141739 -245.544249) (xy 39.177991 -245.505178) (xy 39.219662 -245.471947)
			(xy 39.26582 -245.445298) (xy 39.315434 -245.425826) (xy 39.367396 -245.413966) (xy 39.420546 -245.409983)
			(xy 39.473696 -245.413966) (xy 39.525658 -245.425826) (xy 39.575272 -245.445298) (xy 39.62143 -245.471947)
			(xy 39.663101 -245.505178) (xy 39.699353 -245.544249) (xy 39.729377 -245.588286) (xy 39.752503 -245.636307)
			(xy 39.768213 -245.687237) (xy 39.776156 -245.739941) (xy 39.776654 -245.76659) (xy 39.776156 -245.793239)
			(xy 46.608736 -245.793239) (xy 46.608736 -245.739941) (xy 46.616679 -245.687237) (xy 46.632389 -245.636307)
			(xy 46.655515 -245.588286) (xy 46.685539 -245.544249) (xy 46.721791 -245.505178) (xy 46.763462 -245.471947)
			(xy 46.80962 -245.445298) (xy 46.859234 -245.425826) (xy 46.911196 -245.413966) (xy 46.964346 -245.409983)
			(xy 47.017496 -245.413966) (xy 47.069458 -245.425826) (xy 47.119072 -245.445298) (xy 47.16523 -245.471947)
			(xy 47.206901 -245.505178) (xy 47.243153 -245.544249) (xy 47.273177 -245.588286) (xy 47.296303 -245.636307)
			(xy 47.312013 -245.687237) (xy 47.319956 -245.739941) (xy 47.320454 -245.76659) (xy 47.319956 -245.793239)
			(xy 47.312013 -245.845943) (xy 47.296303 -245.896873) (xy 47.273177 -245.944894) (xy 47.243153 -245.988931)
			(xy 47.206901 -246.028002) (xy 47.16523 -246.061233) (xy 47.119072 -246.087882) (xy 47.069458 -246.107354)
			(xy 47.017496 -246.119214) (xy 46.964346 -246.123198) (xy 46.911196 -246.119214) (xy 46.859234 -246.107354)
			(xy 46.80962 -246.087882) (xy 46.763462 -246.061233) (xy 46.721791 -246.028002) (xy 46.685539 -245.988931)
			(xy 46.655515 -245.944894) (xy 46.632389 -245.896873) (xy 46.616679 -245.845943) (xy 46.608736 -245.793239)
			(xy 39.776156 -245.793239) (xy 39.768213 -245.845943) (xy 39.752503 -245.896873) (xy 39.729377 -245.944894)
			(xy 39.699353 -245.988931) (xy 39.663101 -246.028002) (xy 39.62143 -246.061233) (xy 39.575272 -246.087882)
			(xy 39.525658 -246.107354) (xy 39.473696 -246.119214) (xy 39.420546 -246.123198) (xy 39.367396 -246.119214)
			(xy 39.315434 -246.107354) (xy 39.26582 -246.087882) (xy 39.219662 -246.061233) (xy 39.177991 -246.028002)
			(xy 39.141739 -245.988931) (xy 39.111715 -245.944894) (xy 39.088589 -245.896873) (xy 39.072879 -245.845943)
			(xy 39.064936 -245.793239) (xy 32.232356 -245.793239) (xy 32.224413 -245.845943) (xy 32.208703 -245.896873)
			(xy 32.185577 -245.944894) (xy 32.155553 -245.988931) (xy 32.119301 -246.028002) (xy 32.07763 -246.061233)
			(xy 32.031472 -246.087882) (xy 31.981858 -246.107354) (xy 31.929896 -246.119214) (xy 31.876746 -246.123198)
			(xy 31.823596 -246.119214) (xy 31.771634 -246.107354) (xy 31.72202 -246.087882) (xy 31.675862 -246.061233)
			(xy 31.634191 -246.028002) (xy 31.597939 -245.988931) (xy 31.567915 -245.944894) (xy 31.544789 -245.896873)
			(xy 31.529079 -245.845943) (xy 31.521136 -245.793239) (xy 24.688556 -245.793239) (xy 24.680613 -245.845943)
			(xy 24.664903 -245.896873) (xy 24.641777 -245.944894) (xy 24.611753 -245.988931) (xy 24.575501 -246.028002)
			(xy 24.53383 -246.061233) (xy 24.487672 -246.087882) (xy 24.438058 -246.107354) (xy 24.386096 -246.119214)
			(xy 24.332946 -246.123198) (xy 24.279796 -246.119214) (xy 24.227834 -246.107354) (xy 24.17822 -246.087882)
			(xy 24.132062 -246.061233) (xy 24.090391 -246.028002) (xy 24.054139 -245.988931) (xy 24.024115 -245.944894)
			(xy 24.000989 -245.896873) (xy 23.985279 -245.845943) (xy 23.977336 -245.793239) (xy 17.144756 -245.793239)
			(xy 17.136813 -245.845943) (xy 17.121103 -245.896873) (xy 17.097977 -245.944894) (xy 17.067953 -245.988931)
			(xy 17.031701 -246.028002) (xy 16.99003 -246.061233) (xy 16.943872 -246.087882) (xy 16.894258 -246.107354)
			(xy 16.842296 -246.119214) (xy 16.789146 -246.123198) (xy 16.735996 -246.119214) (xy 16.684034 -246.107354)
			(xy 16.63442 -246.087882) (xy 16.588262 -246.061233) (xy 16.546591 -246.028002) (xy 16.510339 -245.988931)
			(xy 16.480315 -245.944894) (xy 16.457189 -245.896873) (xy 16.441479 -245.845943) (xy 16.433536 -245.793239)
			(xy 9.600956 -245.793239) (xy 9.593013 -245.845943) (xy 9.577303 -245.896873) (xy 9.554177 -245.944894)
			(xy 9.524153 -245.988931) (xy 9.487901 -246.028002) (xy 9.44623 -246.061233) (xy 9.400072 -246.087882)
			(xy 9.350458 -246.107354) (xy 9.298496 -246.119214) (xy 9.245346 -246.123198) (xy 9.192196 -246.119214)
			(xy 9.140234 -246.107354) (xy 9.09062 -246.087882) (xy 9.044462 -246.061233) (xy 9.002791 -246.028002)
			(xy 8.966539 -245.988931) (xy 8.936515 -245.944894) (xy 8.913389 -245.896873) (xy 8.897679 -245.845943)
			(xy 8.889736 -245.793239) (xy 6.7818 -245.793239) (xy 6.7818 -246.643377) (xy 20.533604 -246.643377)
			(xy 20.533604 -246.590079) (xy 20.541547 -246.537375) (xy 20.557257 -246.486445) (xy 20.580383 -246.438424)
			(xy 20.610407 -246.394387) (xy 20.646659 -246.355316) (xy 20.68833 -246.322085) (xy 20.734488 -246.295436)
			(xy 20.784102 -246.275964) (xy 20.836064 -246.264104) (xy 20.889214 -246.260121) (xy 20.942364 -246.264104)
			(xy 20.994326 -246.275964) (xy 21.04394 -246.295436) (xy 21.090098 -246.322085) (xy 21.131769 -246.355316)
			(xy 21.168021 -246.394387) (xy 21.198045 -246.438424) (xy 21.221171 -246.486445) (xy 21.236881 -246.537375)
			(xy 21.244824 -246.590079) (xy 21.245322 -246.616728) (xy 21.244824 -246.643377) (xy 35.621204 -246.643377)
			(xy 35.621204 -246.590079) (xy 35.629147 -246.537375) (xy 35.644857 -246.486445) (xy 35.667983 -246.438424)
			(xy 35.698007 -246.394387) (xy 35.734259 -246.355316) (xy 35.77593 -246.322085) (xy 35.822088 -246.295436)
			(xy 35.871702 -246.275964) (xy 35.923664 -246.264104) (xy 35.976814 -246.260121) (xy 36.029964 -246.264104)
			(xy 36.081926 -246.275964) (xy 36.13154 -246.295436) (xy 36.177698 -246.322085) (xy 36.219369 -246.355316)
			(xy 36.255621 -246.394387) (xy 36.285645 -246.438424) (xy 36.308771 -246.486445) (xy 36.324481 -246.537375)
			(xy 36.332424 -246.590079) (xy 36.332922 -246.616728) (xy 36.332424 -246.643377) (xy 50.708804 -246.643377)
			(xy 50.708804 -246.590079) (xy 50.716747 -246.537375) (xy 50.732457 -246.486445) (xy 50.755583 -246.438424)
			(xy 50.785607 -246.394387) (xy 50.821859 -246.355316) (xy 50.86353 -246.322085) (xy 50.909688 -246.295436)
			(xy 50.959302 -246.275964) (xy 51.011264 -246.264104) (xy 51.064414 -246.260121) (xy 51.117564 -246.264104)
			(xy 51.169526 -246.275964) (xy 51.21914 -246.295436) (xy 51.265298 -246.322085) (xy 51.306969 -246.355316)
			(xy 51.343221 -246.394387) (xy 51.373245 -246.438424) (xy 51.396371 -246.486445) (xy 51.412081 -246.537375)
			(xy 51.420024 -246.590079) (xy 51.420522 -246.616728) (xy 51.420024 -246.643377) (xy 51.412081 -246.696081)
			(xy 51.396371 -246.747011) (xy 51.373245 -246.795032) (xy 51.343221 -246.839069) (xy 51.306969 -246.87814)
			(xy 51.265298 -246.911371) (xy 51.21914 -246.93802) (xy 51.169526 -246.957492) (xy 51.117564 -246.969352)
			(xy 51.064414 -246.973336) (xy 51.011264 -246.969352) (xy 50.959302 -246.957492) (xy 50.909688 -246.93802)
			(xy 50.86353 -246.911371) (xy 50.821859 -246.87814) (xy 50.785607 -246.839069) (xy 50.755583 -246.795032)
			(xy 50.732457 -246.747011) (xy 50.716747 -246.696081) (xy 50.708804 -246.643377) (xy 36.332424 -246.643377)
			(xy 36.324481 -246.696081) (xy 36.308771 -246.747011) (xy 36.285645 -246.795032) (xy 36.255621 -246.839069)
			(xy 36.219369 -246.87814) (xy 36.177698 -246.911371) (xy 36.13154 -246.93802) (xy 36.081926 -246.957492)
			(xy 36.029964 -246.969352) (xy 35.976814 -246.973336) (xy 35.923664 -246.969352) (xy 35.871702 -246.957492)
			(xy 35.822088 -246.93802) (xy 35.77593 -246.911371) (xy 35.734259 -246.87814) (xy 35.698007 -246.839069)
			(xy 35.667983 -246.795032) (xy 35.644857 -246.747011) (xy 35.629147 -246.696081) (xy 35.621204 -246.643377)
			(xy 21.244824 -246.643377) (xy 21.236881 -246.696081) (xy 21.221171 -246.747011) (xy 21.198045 -246.795032)
			(xy 21.168021 -246.839069) (xy 21.131769 -246.87814) (xy 21.090098 -246.911371) (xy 21.04394 -246.93802)
			(xy 20.994326 -246.957492) (xy 20.942364 -246.969352) (xy 20.889214 -246.973336) (xy 20.836064 -246.969352)
			(xy 20.784102 -246.957492) (xy 20.734488 -246.93802) (xy 20.68833 -246.911371) (xy 20.646659 -246.87814)
			(xy 20.610407 -246.839069) (xy 20.580383 -246.795032) (xy 20.557257 -246.747011) (xy 20.541547 -246.696081)
			(xy 20.533604 -246.643377) (xy 6.7818 -246.643377) (xy 6.7818 -247.493261) (xy 16.433536 -247.493261)
			(xy 16.433536 -247.439963) (xy 16.441479 -247.387259) (xy 16.457189 -247.336329) (xy 16.480315 -247.288308)
			(xy 16.510339 -247.244271) (xy 16.546591 -247.2052) (xy 16.588262 -247.171969) (xy 16.63442 -247.14532)
			(xy 16.684034 -247.125848) (xy 16.735996 -247.113988) (xy 16.789146 -247.110005) (xy 16.842296 -247.113988)
			(xy 16.894258 -247.125848) (xy 16.943872 -247.14532) (xy 16.99003 -247.171969) (xy 17.031701 -247.2052)
			(xy 17.067953 -247.244271) (xy 17.097977 -247.288308) (xy 17.121103 -247.336329) (xy 17.136813 -247.387259)
			(xy 17.144756 -247.439963) (xy 17.145254 -247.466612) (xy 17.144756 -247.493261) (xy 31.521136 -247.493261)
			(xy 31.521136 -247.439963) (xy 31.529079 -247.387259) (xy 31.544789 -247.336329) (xy 31.567915 -247.288308)
			(xy 31.597939 -247.244271) (xy 31.634191 -247.2052) (xy 31.675862 -247.171969) (xy 31.72202 -247.14532)
			(xy 31.771634 -247.125848) (xy 31.823596 -247.113988) (xy 31.876746 -247.110005) (xy 31.929896 -247.113988)
			(xy 31.981858 -247.125848) (xy 32.031472 -247.14532) (xy 32.07763 -247.171969) (xy 32.119301 -247.2052)
			(xy 32.155553 -247.244271) (xy 32.185577 -247.288308) (xy 32.208703 -247.336329) (xy 32.224413 -247.387259)
			(xy 32.232356 -247.439963) (xy 32.232854 -247.466612) (xy 32.232356 -247.493261) (xy 46.608736 -247.493261)
			(xy 46.608736 -247.439963) (xy 46.616679 -247.387259) (xy 46.632389 -247.336329) (xy 46.655515 -247.288308)
			(xy 46.685539 -247.244271) (xy 46.721791 -247.2052) (xy 46.763462 -247.171969) (xy 46.80962 -247.14532)
			(xy 46.859234 -247.125848) (xy 46.911196 -247.113988) (xy 46.964346 -247.110005) (xy 47.017496 -247.113988)
			(xy 47.069458 -247.125848) (xy 47.119072 -247.14532) (xy 47.16523 -247.171969) (xy 47.206901 -247.2052)
			(xy 47.243153 -247.244271) (xy 47.273177 -247.288308) (xy 47.296303 -247.336329) (xy 47.312013 -247.387259)
			(xy 47.319956 -247.439963) (xy 47.320454 -247.466612) (xy 47.319956 -247.493261) (xy 47.312013 -247.545965)
			(xy 47.296303 -247.596895) (xy 47.273177 -247.644916) (xy 47.243153 -247.688953) (xy 47.206901 -247.728024)
			(xy 47.16523 -247.761255) (xy 47.119072 -247.787904) (xy 47.069458 -247.807376) (xy 47.017496 -247.819236)
			(xy 46.964346 -247.82322) (xy 46.911196 -247.819236) (xy 46.859234 -247.807376) (xy 46.80962 -247.787904)
			(xy 46.763462 -247.761255) (xy 46.721791 -247.728024) (xy 46.685539 -247.688953) (xy 46.655515 -247.644916)
			(xy 46.632389 -247.596895) (xy 46.616679 -247.545965) (xy 46.608736 -247.493261) (xy 32.232356 -247.493261)
			(xy 32.224413 -247.545965) (xy 32.208703 -247.596895) (xy 32.185577 -247.644916) (xy 32.155553 -247.688953)
			(xy 32.119301 -247.728024) (xy 32.07763 -247.761255) (xy 32.031472 -247.787904) (xy 31.981858 -247.807376)
			(xy 31.929896 -247.819236) (xy 31.876746 -247.82322) (xy 31.823596 -247.819236) (xy 31.771634 -247.807376)
			(xy 31.72202 -247.787904) (xy 31.675862 -247.761255) (xy 31.634191 -247.728024) (xy 31.597939 -247.688953)
			(xy 31.567915 -247.644916) (xy 31.544789 -247.596895) (xy 31.529079 -247.545965) (xy 31.521136 -247.493261)
			(xy 17.144756 -247.493261) (xy 17.136813 -247.545965) (xy 17.121103 -247.596895) (xy 17.097977 -247.644916)
			(xy 17.067953 -247.688953) (xy 17.031701 -247.728024) (xy 16.99003 -247.761255) (xy 16.943872 -247.787904)
			(xy 16.894258 -247.807376) (xy 16.842296 -247.819236) (xy 16.789146 -247.82322) (xy 16.735996 -247.819236)
			(xy 16.684034 -247.807376) (xy 16.63442 -247.787904) (xy 16.588262 -247.761255) (xy 16.546591 -247.728024)
			(xy 16.510339 -247.688953) (xy 16.480315 -247.644916) (xy 16.457189 -247.596895) (xy 16.441479 -247.545965)
			(xy 16.433536 -247.493261) (xy 6.7818 -247.493261) (xy 6.7818 -248.343399) (xy 20.533604 -248.343399)
			(xy 20.533604 -248.290101) (xy 20.541547 -248.237397) (xy 20.557257 -248.186467) (xy 20.580383 -248.138446)
			(xy 20.610407 -248.094409) (xy 20.646659 -248.055338) (xy 20.68833 -248.022107) (xy 20.734488 -247.995458)
			(xy 20.784102 -247.975986) (xy 20.836064 -247.964126) (xy 20.889214 -247.960143) (xy 20.942364 -247.964126)
			(xy 20.994326 -247.975986) (xy 21.04394 -247.995458) (xy 21.090098 -248.022107) (xy 21.131769 -248.055338)
			(xy 21.168021 -248.094409) (xy 21.198045 -248.138446) (xy 21.221171 -248.186467) (xy 21.236881 -248.237397)
			(xy 21.244824 -248.290101) (xy 21.245322 -248.31675) (xy 21.244824 -248.343399) (xy 35.621204 -248.343399)
			(xy 35.621204 -248.290101) (xy 35.629147 -248.237397) (xy 35.644857 -248.186467) (xy 35.667983 -248.138446)
			(xy 35.698007 -248.094409) (xy 35.734259 -248.055338) (xy 35.77593 -248.022107) (xy 35.822088 -247.995458)
			(xy 35.871702 -247.975986) (xy 35.923664 -247.964126) (xy 35.976814 -247.960143) (xy 36.029964 -247.964126)
			(xy 36.081926 -247.975986) (xy 36.13154 -247.995458) (xy 36.177698 -248.022107) (xy 36.219369 -248.055338)
			(xy 36.255621 -248.094409) (xy 36.285645 -248.138446) (xy 36.308771 -248.186467) (xy 36.324481 -248.237397)
			(xy 36.332424 -248.290101) (xy 36.332922 -248.31675) (xy 36.332424 -248.343399) (xy 50.708804 -248.343399)
			(xy 50.708804 -248.290101) (xy 50.716747 -248.237397) (xy 50.732457 -248.186467) (xy 50.755583 -248.138446)
			(xy 50.785607 -248.094409) (xy 50.821859 -248.055338) (xy 50.86353 -248.022107) (xy 50.909688 -247.995458)
			(xy 50.959302 -247.975986) (xy 51.011264 -247.964126) (xy 51.064414 -247.960143) (xy 51.117564 -247.964126)
			(xy 51.169526 -247.975986) (xy 51.21914 -247.995458) (xy 51.265298 -248.022107) (xy 51.306969 -248.055338)
			(xy 51.343221 -248.094409) (xy 51.373245 -248.138446) (xy 51.396371 -248.186467) (xy 51.412081 -248.237397)
			(xy 51.420024 -248.290101) (xy 51.420522 -248.31675) (xy 51.420024 -248.343399) (xy 51.412081 -248.396103)
			(xy 51.396371 -248.447033) (xy 51.373245 -248.495054) (xy 51.343221 -248.539091) (xy 51.306969 -248.578162)
			(xy 51.265298 -248.611393) (xy 51.21914 -248.638042) (xy 51.169526 -248.657514) (xy 51.117564 -248.669374)
			(xy 51.064414 -248.673358) (xy 51.011264 -248.669374) (xy 50.959302 -248.657514) (xy 50.909688 -248.638042)
			(xy 50.86353 -248.611393) (xy 50.821859 -248.578162) (xy 50.785607 -248.539091) (xy 50.755583 -248.495054)
			(xy 50.732457 -248.447033) (xy 50.716747 -248.396103) (xy 50.708804 -248.343399) (xy 36.332424 -248.343399)
			(xy 36.324481 -248.396103) (xy 36.308771 -248.447033) (xy 36.285645 -248.495054) (xy 36.255621 -248.539091)
			(xy 36.219369 -248.578162) (xy 36.177698 -248.611393) (xy 36.13154 -248.638042) (xy 36.081926 -248.657514)
			(xy 36.029964 -248.669374) (xy 35.976814 -248.673358) (xy 35.923664 -248.669374) (xy 35.871702 -248.657514)
			(xy 35.822088 -248.638042) (xy 35.77593 -248.611393) (xy 35.734259 -248.578162) (xy 35.698007 -248.539091)
			(xy 35.667983 -248.495054) (xy 35.644857 -248.447033) (xy 35.629147 -248.396103) (xy 35.621204 -248.343399)
			(xy 21.244824 -248.343399) (xy 21.236881 -248.396103) (xy 21.221171 -248.447033) (xy 21.198045 -248.495054)
			(xy 21.168021 -248.539091) (xy 21.131769 -248.578162) (xy 21.090098 -248.611393) (xy 21.04394 -248.638042)
			(xy 20.994326 -248.657514) (xy 20.942364 -248.669374) (xy 20.889214 -248.673358) (xy 20.836064 -248.669374)
			(xy 20.784102 -248.657514) (xy 20.734488 -248.638042) (xy 20.68833 -248.611393) (xy 20.646659 -248.578162)
			(xy 20.610407 -248.539091) (xy 20.580383 -248.495054) (xy 20.557257 -248.447033) (xy 20.541547 -248.396103)
			(xy 20.533604 -248.343399) (xy 6.7818 -248.343399) (xy 6.7818 -249.193283) (xy 16.433536 -249.193283)
			(xy 16.433536 -249.139985) (xy 16.441479 -249.087281) (xy 16.457189 -249.036351) (xy 16.480315 -248.98833)
			(xy 16.510339 -248.944293) (xy 16.546591 -248.905222) (xy 16.588262 -248.871991) (xy 16.63442 -248.845342)
			(xy 16.684034 -248.82587) (xy 16.735996 -248.81401) (xy 16.789146 -248.810027) (xy 16.842296 -248.81401)
			(xy 16.894258 -248.82587) (xy 16.943872 -248.845342) (xy 16.99003 -248.871991) (xy 17.031701 -248.905222)
			(xy 17.067953 -248.944293) (xy 17.097977 -248.98833) (xy 17.121103 -249.036351) (xy 17.136813 -249.087281)
			(xy 17.144756 -249.139985) (xy 17.145254 -249.166634) (xy 17.144756 -249.193283) (xy 31.521136 -249.193283)
			(xy 31.521136 -249.139985) (xy 31.529079 -249.087281) (xy 31.544789 -249.036351) (xy 31.567915 -248.98833)
			(xy 31.597939 -248.944293) (xy 31.634191 -248.905222) (xy 31.675862 -248.871991) (xy 31.72202 -248.845342)
			(xy 31.771634 -248.82587) (xy 31.823596 -248.81401) (xy 31.876746 -248.810027) (xy 31.929896 -248.81401)
			(xy 31.981858 -248.82587) (xy 32.031472 -248.845342) (xy 32.07763 -248.871991) (xy 32.119301 -248.905222)
			(xy 32.155553 -248.944293) (xy 32.185577 -248.98833) (xy 32.208703 -249.036351) (xy 32.224413 -249.087281)
			(xy 32.232356 -249.139985) (xy 32.232854 -249.166634) (xy 32.232356 -249.193283) (xy 46.608736 -249.193283)
			(xy 46.608736 -249.139985) (xy 46.616679 -249.087281) (xy 46.632389 -249.036351) (xy 46.655515 -248.98833)
			(xy 46.685539 -248.944293) (xy 46.721791 -248.905222) (xy 46.763462 -248.871991) (xy 46.80962 -248.845342)
			(xy 46.859234 -248.82587) (xy 46.911196 -248.81401) (xy 46.964346 -248.810027) (xy 47.017496 -248.81401)
			(xy 47.069458 -248.82587) (xy 47.119072 -248.845342) (xy 47.16523 -248.871991) (xy 47.206901 -248.905222)
			(xy 47.243153 -248.944293) (xy 47.273177 -248.98833) (xy 47.296303 -249.036351) (xy 47.312013 -249.087281)
			(xy 47.319956 -249.139985) (xy 47.320454 -249.166634) (xy 47.319956 -249.193283) (xy 47.312013 -249.245987)
			(xy 47.296303 -249.296917) (xy 47.273177 -249.344938) (xy 47.243153 -249.388975) (xy 47.206901 -249.428046)
			(xy 47.16523 -249.461277) (xy 47.119072 -249.487926) (xy 47.069458 -249.507398) (xy 47.017496 -249.519258)
			(xy 46.964346 -249.523242) (xy 46.911196 -249.519258) (xy 46.859234 -249.507398) (xy 46.80962 -249.487926)
			(xy 46.763462 -249.461277) (xy 46.721791 -249.428046) (xy 46.685539 -249.388975) (xy 46.655515 -249.344938)
			(xy 46.632389 -249.296917) (xy 46.616679 -249.245987) (xy 46.608736 -249.193283) (xy 32.232356 -249.193283)
			(xy 32.224413 -249.245987) (xy 32.208703 -249.296917) (xy 32.185577 -249.344938) (xy 32.155553 -249.388975)
			(xy 32.119301 -249.428046) (xy 32.07763 -249.461277) (xy 32.031472 -249.487926) (xy 31.981858 -249.507398)
			(xy 31.929896 -249.519258) (xy 31.876746 -249.523242) (xy 31.823596 -249.519258) (xy 31.771634 -249.507398)
			(xy 31.72202 -249.487926) (xy 31.675862 -249.461277) (xy 31.634191 -249.428046) (xy 31.597939 -249.388975)
			(xy 31.567915 -249.344938) (xy 31.544789 -249.296917) (xy 31.529079 -249.245987) (xy 31.521136 -249.193283)
			(xy 17.144756 -249.193283) (xy 17.136813 -249.245987) (xy 17.121103 -249.296917) (xy 17.097977 -249.344938)
			(xy 17.067953 -249.388975) (xy 17.031701 -249.428046) (xy 16.99003 -249.461277) (xy 16.943872 -249.487926)
			(xy 16.894258 -249.507398) (xy 16.842296 -249.519258) (xy 16.789146 -249.523242) (xy 16.735996 -249.519258)
			(xy 16.684034 -249.507398) (xy 16.63442 -249.487926) (xy 16.588262 -249.461277) (xy 16.546591 -249.428046)
			(xy 16.510339 -249.388975) (xy 16.480315 -249.344938) (xy 16.457189 -249.296917) (xy 16.441479 -249.245987)
			(xy 16.433536 -249.193283) (xy 6.7818 -249.193283) (xy 6.7818 -250.043421) (xy 20.533604 -250.043421)
			(xy 20.533604 -249.990123) (xy 20.541547 -249.937419) (xy 20.557257 -249.886489) (xy 20.580383 -249.838468)
			(xy 20.610407 -249.794431) (xy 20.646659 -249.75536) (xy 20.68833 -249.722129) (xy 20.734488 -249.69548)
			(xy 20.784102 -249.676008) (xy 20.836064 -249.664148) (xy 20.889214 -249.660165) (xy 20.942364 -249.664148)
			(xy 20.994326 -249.676008) (xy 21.04394 -249.69548) (xy 21.090098 -249.722129) (xy 21.131769 -249.75536)
			(xy 21.168021 -249.794431) (xy 21.198045 -249.838468) (xy 21.221171 -249.886489) (xy 21.236881 -249.937419)
			(xy 21.244824 -249.990123) (xy 21.245322 -250.016772) (xy 21.244824 -250.043421) (xy 35.621204 -250.043421)
			(xy 35.621204 -249.990123) (xy 35.629147 -249.937419) (xy 35.644857 -249.886489) (xy 35.667983 -249.838468)
			(xy 35.698007 -249.794431) (xy 35.734259 -249.75536) (xy 35.77593 -249.722129) (xy 35.822088 -249.69548)
			(xy 35.871702 -249.676008) (xy 35.923664 -249.664148) (xy 35.976814 -249.660165) (xy 36.029964 -249.664148)
			(xy 36.081926 -249.676008) (xy 36.13154 -249.69548) (xy 36.177698 -249.722129) (xy 36.219369 -249.75536)
			(xy 36.255621 -249.794431) (xy 36.285645 -249.838468) (xy 36.308771 -249.886489) (xy 36.324481 -249.937419)
			(xy 36.332424 -249.990123) (xy 36.332922 -250.016772) (xy 36.332424 -250.043421) (xy 50.708804 -250.043421)
			(xy 50.708804 -249.990123) (xy 50.716747 -249.937419) (xy 50.732457 -249.886489) (xy 50.755583 -249.838468)
			(xy 50.785607 -249.794431) (xy 50.821859 -249.75536) (xy 50.86353 -249.722129) (xy 50.909688 -249.69548)
			(xy 50.959302 -249.676008) (xy 51.011264 -249.664148) (xy 51.064414 -249.660165) (xy 51.117564 -249.664148)
			(xy 51.169526 -249.676008) (xy 51.21914 -249.69548) (xy 51.265298 -249.722129) (xy 51.306969 -249.75536)
			(xy 51.343221 -249.794431) (xy 51.373245 -249.838468) (xy 51.396371 -249.886489) (xy 51.412081 -249.937419)
			(xy 51.420024 -249.990123) (xy 51.420522 -250.016772) (xy 51.420024 -250.043421) (xy 51.412081 -250.096125)
			(xy 51.396371 -250.147055) (xy 51.373245 -250.195076) (xy 51.343221 -250.239113) (xy 51.306969 -250.278184)
			(xy 51.265298 -250.311415) (xy 51.21914 -250.338064) (xy 51.169526 -250.357536) (xy 51.117564 -250.369396)
			(xy 51.064414 -250.37338) (xy 51.011264 -250.369396) (xy 50.959302 -250.357536) (xy 50.909688 -250.338064)
			(xy 50.86353 -250.311415) (xy 50.821859 -250.278184) (xy 50.785607 -250.239113) (xy 50.755583 -250.195076)
			(xy 50.732457 -250.147055) (xy 50.716747 -250.096125) (xy 50.708804 -250.043421) (xy 36.332424 -250.043421)
			(xy 36.324481 -250.096125) (xy 36.308771 -250.147055) (xy 36.285645 -250.195076) (xy 36.255621 -250.239113)
			(xy 36.219369 -250.278184) (xy 36.177698 -250.311415) (xy 36.13154 -250.338064) (xy 36.081926 -250.357536)
			(xy 36.029964 -250.369396) (xy 35.976814 -250.37338) (xy 35.923664 -250.369396) (xy 35.871702 -250.357536)
			(xy 35.822088 -250.338064) (xy 35.77593 -250.311415) (xy 35.734259 -250.278184) (xy 35.698007 -250.239113)
			(xy 35.667983 -250.195076) (xy 35.644857 -250.147055) (xy 35.629147 -250.096125) (xy 35.621204 -250.043421)
			(xy 21.244824 -250.043421) (xy 21.236881 -250.096125) (xy 21.221171 -250.147055) (xy 21.198045 -250.195076)
			(xy 21.168021 -250.239113) (xy 21.131769 -250.278184) (xy 21.090098 -250.311415) (xy 21.04394 -250.338064)
			(xy 20.994326 -250.357536) (xy 20.942364 -250.369396) (xy 20.889214 -250.37338) (xy 20.836064 -250.369396)
			(xy 20.784102 -250.357536) (xy 20.734488 -250.338064) (xy 20.68833 -250.311415) (xy 20.646659 -250.278184)
			(xy 20.610407 -250.239113) (xy 20.580383 -250.195076) (xy 20.557257 -250.147055) (xy 20.541547 -250.096125)
			(xy 20.533604 -250.043421) (xy 6.7818 -250.043421) (xy 6.7818 -250.893305) (xy 16.433536 -250.893305)
			(xy 16.433536 -250.840007) (xy 16.441479 -250.787303) (xy 16.457189 -250.736373) (xy 16.480315 -250.688352)
			(xy 16.510339 -250.644315) (xy 16.546591 -250.605244) (xy 16.588262 -250.572013) (xy 16.63442 -250.545364)
			(xy 16.684034 -250.525892) (xy 16.735996 -250.514032) (xy 16.789146 -250.510049) (xy 16.842296 -250.514032)
			(xy 16.894258 -250.525892) (xy 16.943872 -250.545364) (xy 16.99003 -250.572013) (xy 17.031701 -250.605244)
			(xy 17.067953 -250.644315) (xy 17.097977 -250.688352) (xy 17.121103 -250.736373) (xy 17.136813 -250.787303)
			(xy 17.144756 -250.840007) (xy 17.145254 -250.866656) (xy 17.144756 -250.893305) (xy 31.521136 -250.893305)
			(xy 31.521136 -250.840007) (xy 31.529079 -250.787303) (xy 31.544789 -250.736373) (xy 31.567915 -250.688352)
			(xy 31.597939 -250.644315) (xy 31.634191 -250.605244) (xy 31.675862 -250.572013) (xy 31.72202 -250.545364)
			(xy 31.771634 -250.525892) (xy 31.823596 -250.514032) (xy 31.876746 -250.510049) (xy 31.929896 -250.514032)
			(xy 31.981858 -250.525892) (xy 32.031472 -250.545364) (xy 32.07763 -250.572013) (xy 32.119301 -250.605244)
			(xy 32.155553 -250.644315) (xy 32.185577 -250.688352) (xy 32.208703 -250.736373) (xy 32.224413 -250.787303)
			(xy 32.232356 -250.840007) (xy 32.232854 -250.866656) (xy 32.232356 -250.893305) (xy 46.608736 -250.893305)
			(xy 46.608736 -250.840007) (xy 46.616679 -250.787303) (xy 46.632389 -250.736373) (xy 46.655515 -250.688352)
			(xy 46.685539 -250.644315) (xy 46.721791 -250.605244) (xy 46.763462 -250.572013) (xy 46.80962 -250.545364)
			(xy 46.859234 -250.525892) (xy 46.911196 -250.514032) (xy 46.964346 -250.510049) (xy 47.017496 -250.514032)
			(xy 47.069458 -250.525892) (xy 47.119072 -250.545364) (xy 47.16523 -250.572013) (xy 47.206901 -250.605244)
			(xy 47.243153 -250.644315) (xy 47.273177 -250.688352) (xy 47.296303 -250.736373) (xy 47.312013 -250.787303)
			(xy 47.319956 -250.840007) (xy 47.320454 -250.866656) (xy 47.319956 -250.893305) (xy 47.312013 -250.946009)
			(xy 47.296303 -250.996939) (xy 47.273177 -251.04496) (xy 47.243153 -251.088997) (xy 47.206901 -251.128068)
			(xy 47.16523 -251.161299) (xy 47.119072 -251.187948) (xy 47.069458 -251.20742) (xy 47.017496 -251.21928)
			(xy 46.964346 -251.223264) (xy 46.911196 -251.21928) (xy 46.859234 -251.20742) (xy 46.80962 -251.187948)
			(xy 46.763462 -251.161299) (xy 46.721791 -251.128068) (xy 46.685539 -251.088997) (xy 46.655515 -251.04496)
			(xy 46.632389 -250.996939) (xy 46.616679 -250.946009) (xy 46.608736 -250.893305) (xy 32.232356 -250.893305)
			(xy 32.224413 -250.946009) (xy 32.208703 -250.996939) (xy 32.185577 -251.04496) (xy 32.155553 -251.088997)
			(xy 32.119301 -251.128068) (xy 32.07763 -251.161299) (xy 32.031472 -251.187948) (xy 31.981858 -251.20742)
			(xy 31.929896 -251.21928) (xy 31.876746 -251.223264) (xy 31.823596 -251.21928) (xy 31.771634 -251.20742)
			(xy 31.72202 -251.187948) (xy 31.675862 -251.161299) (xy 31.634191 -251.128068) (xy 31.597939 -251.088997)
			(xy 31.567915 -251.04496) (xy 31.544789 -250.996939) (xy 31.529079 -250.946009) (xy 31.521136 -250.893305)
			(xy 17.144756 -250.893305) (xy 17.136813 -250.946009) (xy 17.121103 -250.996939) (xy 17.097977 -251.04496)
			(xy 17.067953 -251.088997) (xy 17.031701 -251.128068) (xy 16.99003 -251.161299) (xy 16.943872 -251.187948)
			(xy 16.894258 -251.20742) (xy 16.842296 -251.21928) (xy 16.789146 -251.223264) (xy 16.735996 -251.21928)
			(xy 16.684034 -251.20742) (xy 16.63442 -251.187948) (xy 16.588262 -251.161299) (xy 16.546591 -251.128068)
			(xy 16.510339 -251.088997) (xy 16.480315 -251.04496) (xy 16.457189 -250.996939) (xy 16.441479 -250.946009)
			(xy 16.433536 -250.893305) (xy 6.7818 -250.893305) (xy 6.7818 -251.743443) (xy 20.533604 -251.743443)
			(xy 20.533604 -251.690145) (xy 20.541547 -251.637441) (xy 20.557257 -251.586511) (xy 20.580383 -251.53849)
			(xy 20.610407 -251.494453) (xy 20.646659 -251.455382) (xy 20.68833 -251.422151) (xy 20.734488 -251.395502)
			(xy 20.784102 -251.37603) (xy 20.836064 -251.36417) (xy 20.889214 -251.360187) (xy 20.942364 -251.36417)
			(xy 20.994326 -251.37603) (xy 21.04394 -251.395502) (xy 21.090098 -251.422151) (xy 21.131769 -251.455382)
			(xy 21.168021 -251.494453) (xy 21.198045 -251.53849) (xy 21.221171 -251.586511) (xy 21.236881 -251.637441)
			(xy 21.244824 -251.690145) (xy 21.245322 -251.716794) (xy 21.244824 -251.743443) (xy 35.621204 -251.743443)
			(xy 35.621204 -251.690145) (xy 35.629147 -251.637441) (xy 35.644857 -251.586511) (xy 35.667983 -251.53849)
			(xy 35.698007 -251.494453) (xy 35.734259 -251.455382) (xy 35.77593 -251.422151) (xy 35.822088 -251.395502)
			(xy 35.871702 -251.37603) (xy 35.923664 -251.36417) (xy 35.976814 -251.360187) (xy 36.029964 -251.36417)
			(xy 36.081926 -251.37603) (xy 36.13154 -251.395502) (xy 36.177698 -251.422151) (xy 36.219369 -251.455382)
			(xy 36.255621 -251.494453) (xy 36.285645 -251.53849) (xy 36.308771 -251.586511) (xy 36.324481 -251.637441)
			(xy 36.332424 -251.690145) (xy 36.332922 -251.716794) (xy 36.332424 -251.743443) (xy 50.708804 -251.743443)
			(xy 50.708804 -251.690145) (xy 50.716747 -251.637441) (xy 50.732457 -251.586511) (xy 50.755583 -251.53849)
			(xy 50.785607 -251.494453) (xy 50.821859 -251.455382) (xy 50.86353 -251.422151) (xy 50.909688 -251.395502)
			(xy 50.959302 -251.37603) (xy 51.011264 -251.36417) (xy 51.064414 -251.360187) (xy 51.117564 -251.36417)
			(xy 51.169526 -251.37603) (xy 51.21914 -251.395502) (xy 51.265298 -251.422151) (xy 51.306969 -251.455382)
			(xy 51.343221 -251.494453) (xy 51.373245 -251.53849) (xy 51.396371 -251.586511) (xy 51.412081 -251.637441)
			(xy 51.420024 -251.690145) (xy 51.420522 -251.716794) (xy 51.420024 -251.743443) (xy 51.412081 -251.796147)
			(xy 51.396371 -251.847077) (xy 51.373245 -251.895098) (xy 51.343221 -251.939135) (xy 51.306969 -251.978206)
			(xy 51.265298 -252.011437) (xy 51.21914 -252.038086) (xy 51.169526 -252.057558) (xy 51.117564 -252.069418)
			(xy 51.064414 -252.073402) (xy 51.011264 -252.069418) (xy 50.959302 -252.057558) (xy 50.909688 -252.038086)
			(xy 50.86353 -252.011437) (xy 50.821859 -251.978206) (xy 50.785607 -251.939135) (xy 50.755583 -251.895098)
			(xy 50.732457 -251.847077) (xy 50.716747 -251.796147) (xy 50.708804 -251.743443) (xy 36.332424 -251.743443)
			(xy 36.324481 -251.796147) (xy 36.308771 -251.847077) (xy 36.285645 -251.895098) (xy 36.255621 -251.939135)
			(xy 36.219369 -251.978206) (xy 36.177698 -252.011437) (xy 36.13154 -252.038086) (xy 36.081926 -252.057558)
			(xy 36.029964 -252.069418) (xy 35.976814 -252.073402) (xy 35.923664 -252.069418) (xy 35.871702 -252.057558)
			(xy 35.822088 -252.038086) (xy 35.77593 -252.011437) (xy 35.734259 -251.978206) (xy 35.698007 -251.939135)
			(xy 35.667983 -251.895098) (xy 35.644857 -251.847077) (xy 35.629147 -251.796147) (xy 35.621204 -251.743443)
			(xy 21.244824 -251.743443) (xy 21.236881 -251.796147) (xy 21.221171 -251.847077) (xy 21.198045 -251.895098)
			(xy 21.168021 -251.939135) (xy 21.131769 -251.978206) (xy 21.090098 -252.011437) (xy 21.04394 -252.038086)
			(xy 20.994326 -252.057558) (xy 20.942364 -252.069418) (xy 20.889214 -252.073402) (xy 20.836064 -252.069418)
			(xy 20.784102 -252.057558) (xy 20.734488 -252.038086) (xy 20.68833 -252.011437) (xy 20.646659 -251.978206)
			(xy 20.610407 -251.939135) (xy 20.580383 -251.895098) (xy 20.557257 -251.847077) (xy 20.541547 -251.796147)
			(xy 20.533604 -251.743443) (xy 6.7818 -251.743443) (xy 6.7818 -252.593327) (xy 10.780004 -252.593327)
			(xy 10.780004 -252.540029) (xy 10.787947 -252.487325) (xy 10.803657 -252.436395) (xy 10.826783 -252.388374)
			(xy 10.856807 -252.344337) (xy 10.893059 -252.305266) (xy 10.93473 -252.272035) (xy 10.980888 -252.245386)
			(xy 11.030502 -252.225914) (xy 11.082464 -252.214054) (xy 11.135614 -252.210071) (xy 11.188764 -252.214054)
			(xy 11.240726 -252.225914) (xy 11.29034 -252.245386) (xy 11.336498 -252.272035) (xy 11.378169 -252.305266)
			(xy 11.414421 -252.344337) (xy 11.444445 -252.388374) (xy 11.467571 -252.436395) (xy 11.483281 -252.487325)
			(xy 11.491224 -252.540029) (xy 11.491722 -252.566678) (xy 11.491224 -252.593327) (xy 16.433536 -252.593327)
			(xy 16.433536 -252.540029) (xy 16.441479 -252.487325) (xy 16.457189 -252.436395) (xy 16.480315 -252.388374)
			(xy 16.510339 -252.344337) (xy 16.546591 -252.305266) (xy 16.588262 -252.272035) (xy 16.63442 -252.245386)
			(xy 16.684034 -252.225914) (xy 16.735996 -252.214054) (xy 16.789146 -252.210071) (xy 16.842296 -252.214054)
			(xy 16.894258 -252.225914) (xy 16.943872 -252.245386) (xy 16.99003 -252.272035) (xy 17.031701 -252.305266)
			(xy 17.067953 -252.344337) (xy 17.097977 -252.388374) (xy 17.121103 -252.436395) (xy 17.136813 -252.487325)
			(xy 17.144756 -252.540029) (xy 17.145254 -252.566678) (xy 17.144756 -252.593327) (xy 20.533604 -252.593327)
			(xy 20.533604 -252.540029) (xy 20.541547 -252.487325) (xy 20.557257 -252.436395) (xy 20.580383 -252.388374)
			(xy 20.610407 -252.344337) (xy 20.646659 -252.305266) (xy 20.68833 -252.272035) (xy 20.734488 -252.245386)
			(xy 20.784102 -252.225914) (xy 20.836064 -252.214054) (xy 20.889214 -252.210071) (xy 20.942364 -252.214054)
			(xy 20.994326 -252.225914) (xy 21.04394 -252.245386) (xy 21.090098 -252.272035) (xy 21.131769 -252.305266)
			(xy 21.168021 -252.344337) (xy 21.198045 -252.388374) (xy 21.221171 -252.436395) (xy 21.236881 -252.487325)
			(xy 21.244824 -252.540029) (xy 21.245322 -252.566678) (xy 21.244824 -252.593327) (xy 25.867604 -252.593327)
			(xy 25.867604 -252.540029) (xy 25.875547 -252.487325) (xy 25.891257 -252.436395) (xy 25.914383 -252.388374)
			(xy 25.944407 -252.344337) (xy 25.980659 -252.305266) (xy 26.02233 -252.272035) (xy 26.068488 -252.245386)
			(xy 26.118102 -252.225914) (xy 26.170064 -252.214054) (xy 26.223214 -252.210071) (xy 26.276364 -252.214054)
			(xy 26.328326 -252.225914) (xy 26.37794 -252.245386) (xy 26.424098 -252.272035) (xy 26.465769 -252.305266)
			(xy 26.502021 -252.344337) (xy 26.532045 -252.388374) (xy 26.555171 -252.436395) (xy 26.570881 -252.487325)
			(xy 26.578824 -252.540029) (xy 26.579322 -252.566678) (xy 26.578824 -252.593327) (xy 31.521136 -252.593327)
			(xy 31.521136 -252.540029) (xy 31.529079 -252.487325) (xy 31.544789 -252.436395) (xy 31.567915 -252.388374)
			(xy 31.597939 -252.344337) (xy 31.634191 -252.305266) (xy 31.675862 -252.272035) (xy 31.72202 -252.245386)
			(xy 31.771634 -252.225914) (xy 31.823596 -252.214054) (xy 31.876746 -252.210071) (xy 31.929896 -252.214054)
			(xy 31.981858 -252.225914) (xy 32.031472 -252.245386) (xy 32.07763 -252.272035) (xy 32.119301 -252.305266)
			(xy 32.155553 -252.344337) (xy 32.185577 -252.388374) (xy 32.208703 -252.436395) (xy 32.224413 -252.487325)
			(xy 32.232356 -252.540029) (xy 32.232854 -252.566678) (xy 32.232356 -252.593327) (xy 35.621204 -252.593327)
			(xy 35.621204 -252.540029) (xy 35.629147 -252.487325) (xy 35.644857 -252.436395) (xy 35.667983 -252.388374)
			(xy 35.698007 -252.344337) (xy 35.734259 -252.305266) (xy 35.77593 -252.272035) (xy 35.822088 -252.245386)
			(xy 35.871702 -252.225914) (xy 35.923664 -252.214054) (xy 35.976814 -252.210071) (xy 36.029964 -252.214054)
			(xy 36.081926 -252.225914) (xy 36.13154 -252.245386) (xy 36.177698 -252.272035) (xy 36.219369 -252.305266)
			(xy 36.255621 -252.344337) (xy 36.285645 -252.388374) (xy 36.308771 -252.436395) (xy 36.324481 -252.487325)
			(xy 36.332424 -252.540029) (xy 36.332922 -252.566678) (xy 36.332424 -252.593327) (xy 40.955204 -252.593327)
			(xy 40.955204 -252.540029) (xy 40.963147 -252.487325) (xy 40.978857 -252.436395) (xy 41.001983 -252.388374)
			(xy 41.032007 -252.344337) (xy 41.068259 -252.305266) (xy 41.10993 -252.272035) (xy 41.156088 -252.245386)
			(xy 41.205702 -252.225914) (xy 41.257664 -252.214054) (xy 41.310814 -252.210071) (xy 41.363964 -252.214054)
			(xy 41.415926 -252.225914) (xy 41.46554 -252.245386) (xy 41.511698 -252.272035) (xy 41.553369 -252.305266)
			(xy 41.589621 -252.344337) (xy 41.619645 -252.388374) (xy 41.642771 -252.436395) (xy 41.658481 -252.487325)
			(xy 41.666424 -252.540029) (xy 41.666922 -252.566678) (xy 41.666424 -252.593327) (xy 46.608736 -252.593327)
			(xy 46.608736 -252.540029) (xy 46.616679 -252.487325) (xy 46.632389 -252.436395) (xy 46.655515 -252.388374)
			(xy 46.685539 -252.344337) (xy 46.721791 -252.305266) (xy 46.763462 -252.272035) (xy 46.80962 -252.245386)
			(xy 46.859234 -252.225914) (xy 46.911196 -252.214054) (xy 46.964346 -252.210071) (xy 47.017496 -252.214054)
			(xy 47.069458 -252.225914) (xy 47.119072 -252.245386) (xy 47.16523 -252.272035) (xy 47.206901 -252.305266)
			(xy 47.243153 -252.344337) (xy 47.273177 -252.388374) (xy 47.296303 -252.436395) (xy 47.312013 -252.487325)
			(xy 47.319956 -252.540029) (xy 47.320454 -252.566678) (xy 47.319956 -252.593327) (xy 50.708804 -252.593327)
			(xy 50.708804 -252.540029) (xy 50.716747 -252.487325) (xy 50.732457 -252.436395) (xy 50.755583 -252.388374)
			(xy 50.785607 -252.344337) (xy 50.821859 -252.305266) (xy 50.86353 -252.272035) (xy 50.909688 -252.245386)
			(xy 50.959302 -252.225914) (xy 51.011264 -252.214054) (xy 51.064414 -252.210071) (xy 51.117564 -252.214054)
			(xy 51.169526 -252.225914) (xy 51.21914 -252.245386) (xy 51.265298 -252.272035) (xy 51.306969 -252.305266)
			(xy 51.343221 -252.344337) (xy 51.373245 -252.388374) (xy 51.396371 -252.436395) (xy 51.412081 -252.487325)
			(xy 51.420024 -252.540029) (xy 51.420522 -252.566678) (xy 51.420024 -252.593327) (xy 56.042804 -252.593327)
			(xy 56.042804 -252.540029) (xy 56.050747 -252.487325) (xy 56.066457 -252.436395) (xy 56.089583 -252.388374)
			(xy 56.119607 -252.344337) (xy 56.155859 -252.305266) (xy 56.19753 -252.272035) (xy 56.243688 -252.245386)
			(xy 56.293302 -252.225914) (xy 56.345264 -252.214054) (xy 56.398414 -252.210071) (xy 56.451564 -252.214054)
			(xy 56.503526 -252.225914) (xy 56.55314 -252.245386) (xy 56.599298 -252.272035) (xy 56.640969 -252.305266)
			(xy 56.677221 -252.344337) (xy 56.707245 -252.388374) (xy 56.730371 -252.436395) (xy 56.746081 -252.487325)
			(xy 56.754024 -252.540029) (xy 56.754522 -252.566678) (xy 56.754024 -252.593327) (xy 56.746081 -252.646031)
			(xy 56.730371 -252.696961) (xy 56.707245 -252.744982) (xy 56.677221 -252.789019) (xy 56.640969 -252.82809)
			(xy 56.599298 -252.861321) (xy 56.55314 -252.88797) (xy 56.503526 -252.907442) (xy 56.451564 -252.919302)
			(xy 56.398414 -252.923286) (xy 56.345264 -252.919302) (xy 56.293302 -252.907442) (xy 56.243688 -252.88797)
			(xy 56.19753 -252.861321) (xy 56.155859 -252.82809) (xy 56.119607 -252.789019) (xy 56.089583 -252.744982)
			(xy 56.066457 -252.696961) (xy 56.050747 -252.646031) (xy 56.042804 -252.593327) (xy 51.420024 -252.593327)
			(xy 51.412081 -252.646031) (xy 51.396371 -252.696961) (xy 51.373245 -252.744982) (xy 51.343221 -252.789019)
			(xy 51.306969 -252.82809) (xy 51.265298 -252.861321) (xy 51.21914 -252.88797) (xy 51.169526 -252.907442)
			(xy 51.117564 -252.919302) (xy 51.064414 -252.923286) (xy 51.011264 -252.919302) (xy 50.959302 -252.907442)
			(xy 50.909688 -252.88797) (xy 50.86353 -252.861321) (xy 50.821859 -252.82809) (xy 50.785607 -252.789019)
			(xy 50.755583 -252.744982) (xy 50.732457 -252.696961) (xy 50.716747 -252.646031) (xy 50.708804 -252.593327)
			(xy 47.319956 -252.593327) (xy 47.312013 -252.646031) (xy 47.296303 -252.696961) (xy 47.273177 -252.744982)
			(xy 47.243153 -252.789019) (xy 47.206901 -252.82809) (xy 47.16523 -252.861321) (xy 47.119072 -252.88797)
			(xy 47.069458 -252.907442) (xy 47.017496 -252.919302) (xy 46.964346 -252.923286) (xy 46.911196 -252.919302)
			(xy 46.859234 -252.907442) (xy 46.80962 -252.88797) (xy 46.763462 -252.861321) (xy 46.721791 -252.82809)
			(xy 46.685539 -252.789019) (xy 46.655515 -252.744982) (xy 46.632389 -252.696961) (xy 46.616679 -252.646031)
			(xy 46.608736 -252.593327) (xy 41.666424 -252.593327) (xy 41.658481 -252.646031) (xy 41.642771 -252.696961)
			(xy 41.619645 -252.744982) (xy 41.589621 -252.789019) (xy 41.553369 -252.82809) (xy 41.511698 -252.861321)
			(xy 41.46554 -252.88797) (xy 41.415926 -252.907442) (xy 41.363964 -252.919302) (xy 41.310814 -252.923286)
			(xy 41.257664 -252.919302) (xy 41.205702 -252.907442) (xy 41.156088 -252.88797) (xy 41.10993 -252.861321)
			(xy 41.068259 -252.82809) (xy 41.032007 -252.789019) (xy 41.001983 -252.744982) (xy 40.978857 -252.696961)
			(xy 40.963147 -252.646031) (xy 40.955204 -252.593327) (xy 36.332424 -252.593327) (xy 36.324481 -252.646031)
			(xy 36.308771 -252.696961) (xy 36.285645 -252.744982) (xy 36.255621 -252.789019) (xy 36.219369 -252.82809)
			(xy 36.177698 -252.861321) (xy 36.13154 -252.88797) (xy 36.081926 -252.907442) (xy 36.029964 -252.919302)
			(xy 35.976814 -252.923286) (xy 35.923664 -252.919302) (xy 35.871702 -252.907442) (xy 35.822088 -252.88797)
			(xy 35.77593 -252.861321) (xy 35.734259 -252.82809) (xy 35.698007 -252.789019) (xy 35.667983 -252.744982)
			(xy 35.644857 -252.696961) (xy 35.629147 -252.646031) (xy 35.621204 -252.593327) (xy 32.232356 -252.593327)
			(xy 32.224413 -252.646031) (xy 32.208703 -252.696961) (xy 32.185577 -252.744982) (xy 32.155553 -252.789019)
			(xy 32.119301 -252.82809) (xy 32.07763 -252.861321) (xy 32.031472 -252.88797) (xy 31.981858 -252.907442)
			(xy 31.929896 -252.919302) (xy 31.876746 -252.923286) (xy 31.823596 -252.919302) (xy 31.771634 -252.907442)
			(xy 31.72202 -252.88797) (xy 31.675862 -252.861321) (xy 31.634191 -252.82809) (xy 31.597939 -252.789019)
			(xy 31.567915 -252.744982) (xy 31.544789 -252.696961) (xy 31.529079 -252.646031) (xy 31.521136 -252.593327)
			(xy 26.578824 -252.593327) (xy 26.570881 -252.646031) (xy 26.555171 -252.696961) (xy 26.532045 -252.744982)
			(xy 26.502021 -252.789019) (xy 26.465769 -252.82809) (xy 26.424098 -252.861321) (xy 26.37794 -252.88797)
			(xy 26.328326 -252.907442) (xy 26.276364 -252.919302) (xy 26.223214 -252.923286) (xy 26.170064 -252.919302)
			(xy 26.118102 -252.907442) (xy 26.068488 -252.88797) (xy 26.02233 -252.861321) (xy 25.980659 -252.82809)
			(xy 25.944407 -252.789019) (xy 25.914383 -252.744982) (xy 25.891257 -252.696961) (xy 25.875547 -252.646031)
			(xy 25.867604 -252.593327) (xy 21.244824 -252.593327) (xy 21.236881 -252.646031) (xy 21.221171 -252.696961)
			(xy 21.198045 -252.744982) (xy 21.168021 -252.789019) (xy 21.131769 -252.82809) (xy 21.090098 -252.861321)
			(xy 21.04394 -252.88797) (xy 20.994326 -252.907442) (xy 20.942364 -252.919302) (xy 20.889214 -252.923286)
			(xy 20.836064 -252.919302) (xy 20.784102 -252.907442) (xy 20.734488 -252.88797) (xy 20.68833 -252.861321)
			(xy 20.646659 -252.82809) (xy 20.610407 -252.789019) (xy 20.580383 -252.744982) (xy 20.557257 -252.696961)
			(xy 20.541547 -252.646031) (xy 20.533604 -252.593327) (xy 17.144756 -252.593327) (xy 17.136813 -252.646031)
			(xy 17.121103 -252.696961) (xy 17.097977 -252.744982) (xy 17.067953 -252.789019) (xy 17.031701 -252.82809)
			(xy 16.99003 -252.861321) (xy 16.943872 -252.88797) (xy 16.894258 -252.907442) (xy 16.842296 -252.919302)
			(xy 16.789146 -252.923286) (xy 16.735996 -252.919302) (xy 16.684034 -252.907442) (xy 16.63442 -252.88797)
			(xy 16.588262 -252.861321) (xy 16.546591 -252.82809) (xy 16.510339 -252.789019) (xy 16.480315 -252.744982)
			(xy 16.457189 -252.696961) (xy 16.441479 -252.646031) (xy 16.433536 -252.593327) (xy 11.491224 -252.593327)
			(xy 11.483281 -252.646031) (xy 11.467571 -252.696961) (xy 11.444445 -252.744982) (xy 11.414421 -252.789019)
			(xy 11.378169 -252.82809) (xy 11.336498 -252.861321) (xy 11.29034 -252.88797) (xy 11.240726 -252.907442)
			(xy 11.188764 -252.919302) (xy 11.135614 -252.923286) (xy 11.082464 -252.919302) (xy 11.030502 -252.907442)
			(xy 10.980888 -252.88797) (xy 10.93473 -252.861321) (xy 10.893059 -252.82809) (xy 10.856807 -252.789019)
			(xy 10.826783 -252.744982) (xy 10.803657 -252.696961) (xy 10.787947 -252.646031) (xy 10.780004 -252.593327)
			(xy 6.7818 -252.593327) (xy 6.7818 -254.6495) (xy 57.781646 -254.6495) (xy 57.78563 -254.596342)
			(xy 57.797492 -254.544372) (xy 57.816968 -254.49475) (xy 57.843622 -254.448585) (xy 57.876859 -254.406909)
			(xy 57.915936 -254.370652) (xy 57.959981 -254.340624) (xy 58.00801 -254.317496) (xy 58.058949 -254.301785)
			(xy 58.111661 -254.293842) (xy 58.138314 -254.29337) (xy 58.165635 -254.293891) (xy 58.219636 -254.30223)
			(xy 58.271732 -254.318712) (xy 58.320703 -254.342949) (xy 58.365403 -254.374375) (xy 58.385456 -254.392938)
			(xy 58.397078 -254.403335) (xy 58.425012 -254.417159) (xy 58.455814 -254.421915) (xy 58.486616 -254.417159)
			(xy 58.51455 -254.403335) (xy 58.526172 -254.392938) (xy 58.54621 -254.374353) (xy 58.590896 -254.342892)
			(xy 58.639868 -254.318636) (xy 58.691975 -254.302158) (xy 58.745989 -254.293846) (xy 58.773314 -254.29337)
			(xy 58.800635 -254.293891) (xy 58.854636 -254.30223) (xy 58.906732 -254.318712) (xy 58.955703 -254.342949)
			(xy 59.000403 -254.374375) (xy 59.020456 -254.392938) (xy 59.032078 -254.403335) (xy 59.060012 -254.417159)
			(xy 59.090814 -254.421915) (xy 59.121616 -254.417159) (xy 59.14955 -254.403335) (xy 59.161172 -254.392938)
			(xy 59.18121 -254.374353) (xy 59.225896 -254.342892) (xy 59.274868 -254.318636) (xy 59.326975 -254.302158)
			(xy 59.380989 -254.293846) (xy 59.408314 -254.29337) (xy 59.435635 -254.293891) (xy 59.489636 -254.30223)
			(xy 59.541732 -254.318712) (xy 59.590703 -254.342949) (xy 59.635403 -254.374375) (xy 59.655456 -254.392938)
			(xy 59.667078 -254.403335) (xy 59.695012 -254.417159) (xy 59.725814 -254.421915) (xy 59.756616 -254.417159)
			(xy 59.78455 -254.403335) (xy 59.796172 -254.392938) (xy 59.815387 -254.37507) (xy 59.85811 -254.344611)
			(xy 59.904846 -254.32076) (xy 59.954579 -254.304037) (xy 59.980322 -254.298958) (xy 59.993498 -254.296162)
			(xy 60.017824 -254.284619) (xy 60.038295 -254.267127) (xy 60.05349 -254.244898) (xy 60.062358 -254.219474)
			(xy 60.064282 -254.192617) (xy 60.06211 -254.179324) (xy 60.059026 -254.162411) (xy 60.055715 -254.128189)
			(xy 60.055506 -254.110998) (xy 60.05601 -254.083012) (xy 60.064767 -254.027729) (xy 60.082064 -253.974496)
			(xy 60.107475 -253.924625) (xy 60.140376 -253.879343) (xy 60.179955 -253.839766) (xy 60.225239 -253.806867)
			(xy 60.275111 -253.781458) (xy 60.328344 -253.764163) (xy 60.383628 -253.755409) (xy 60.411614 -253.75489)
			(xy 60.440947 -253.755474) (xy 60.498821 -253.765086) (xy 60.554333 -253.784064) (xy 60.605978 -253.811893)
			(xy 60.652358 -253.847819) (xy 60.672726 -253.868936) (xy 60.682801 -253.879) (xy 60.707161 -253.893713)
			(xy 60.734638 -253.901124) (xy 60.763093 -253.900655) (xy 60.790311 -253.892342) (xy 60.814173 -253.876833)
			(xy 60.823856 -253.866396) (xy 60.840832 -253.847556) (xy 60.879234 -253.814435) (xy 60.921947 -253.787098)
			(xy 60.968106 -253.766097) (xy 61.016778 -253.751857) (xy 61.066978 -253.744667) (xy 61.092334 -253.744222)
			(xy 61.118984 -253.744662) (xy 61.171688 -253.752611) (xy 61.222618 -253.768325) (xy 61.270638 -253.791454)
			(xy 61.314675 -253.821482) (xy 61.353745 -253.857737) (xy 61.386975 -253.89941) (xy 61.413624 -253.94557)
			(xy 61.433095 -253.995185) (xy 61.444955 -254.047149) (xy 61.448938 -254.1003) (xy 61.444955 -254.153451)
			(xy 61.433095 -254.205415) (xy 61.413624 -254.25503) (xy 61.386975 -254.30119) (xy 61.353745 -254.342863)
			(xy 61.314675 -254.379118) (xy 61.270638 -254.409146) (xy 61.222618 -254.432275) (xy 61.171688 -254.447989)
			(xy 61.118984 -254.455938) (xy 61.092334 -254.456438) (xy 61.063002 -254.455814) (xy 61.005131 -254.446211)
			(xy 60.94962 -254.427242) (xy 60.897974 -254.399422) (xy 60.851592 -254.363505) (xy 60.831222 -254.342392)
			(xy 60.821192 -254.332283) (xy 60.796817 -254.317583) (xy 60.76933 -254.310185) (xy 60.740869 -254.310664)
			(xy 60.713646 -254.318982) (xy 60.689779 -254.334494) (xy 60.680092 -254.344932) (xy 60.663963 -254.362833)
			(xy 60.627712 -254.394575) (xy 60.587509 -254.421134) (xy 60.544089 -254.442025) (xy 60.498248 -254.456865)
			(xy 60.474606 -254.461518) (xy 60.461441 -254.464359) (xy 60.437117 -254.475892) (xy 60.416647 -254.493375)
			(xy 60.401449 -254.515595) (xy 60.392578 -254.541011) (xy 60.390649 -254.567862) (xy 60.392818 -254.581152)
			(xy 60.395913 -254.598063) (xy 60.399217 -254.632287) (xy 60.399422 -254.649478) (xy 60.398867 -254.677462)
			(xy 60.390115 -254.732742) (xy 60.372823 -254.785971) (xy 60.347417 -254.835841) (xy 60.314522 -254.881121)
			(xy 60.274949 -254.920699) (xy 60.229671 -254.953598) (xy 60.179805 -254.979009) (xy 60.126577 -254.996307)
			(xy 60.071298 -255.005064) (xy 60.043314 -255.005586) (xy 60.015993 -255.00506) (xy 59.961992 -254.996724)
			(xy 59.909895 -254.980244) (xy 59.860924 -254.956007) (xy 59.816224 -254.924581) (xy 59.796172 -254.906018)
			(xy 59.78455 -254.895621) (xy 59.756616 -254.881797) (xy 59.725814 -254.877041) (xy 59.695012 -254.881797)
			(xy 59.667078 -254.895621) (xy 59.655456 -254.906018) (xy 59.635457 -254.924647) (xy 59.59076 -254.9561)
			(xy 59.541777 -254.980346) (xy 59.489662 -254.996814) (xy 59.435642 -255.005116) (xy 59.408314 -255.005586)
			(xy 59.380993 -255.00506) (xy 59.326992 -254.996724) (xy 59.274895 -254.980244) (xy 59.225924 -254.956007)
			(xy 59.181224 -254.924581) (xy 59.161172 -254.906018) (xy 59.14955 -254.895621) (xy 59.121616 -254.881797)
			(xy 59.090814 -254.877041) (xy 59.060012 -254.881797) (xy 59.032078 -254.895621) (xy 59.020456 -254.906018)
			(xy 59.000457 -254.924647) (xy 58.95576 -254.9561) (xy 58.906777 -254.980346) (xy 58.854662 -254.996814)
			(xy 58.800642 -255.005116) (xy 58.773314 -255.005586) (xy 58.745993 -255.00506) (xy 58.691992 -254.996724)
			(xy 58.639895 -254.980244) (xy 58.590924 -254.956007) (xy 58.546224 -254.924581) (xy 58.526172 -254.906018)
			(xy 58.51455 -254.895621) (xy 58.486616 -254.881797) (xy 58.455814 -254.877041) (xy 58.425012 -254.881797)
			(xy 58.397078 -254.895621) (xy 58.385456 -254.906018) (xy 58.365457 -254.924647) (xy 58.32076 -254.9561)
			(xy 58.271777 -254.980346) (xy 58.219662 -254.996814) (xy 58.165642 -255.005116) (xy 58.138314 -255.005586)
			(xy 58.111661 -255.005158) (xy 58.058949 -254.997215) (xy 58.00801 -254.981504) (xy 57.959981 -254.958376)
			(xy 57.915936 -254.928348) (xy 57.876859 -254.892091) (xy 57.843622 -254.850415) (xy 57.816968 -254.80425)
			(xy 57.797492 -254.754628) (xy 57.78563 -254.702658) (xy 57.781646 -254.6495) (xy 6.7818 -254.6495)
			(xy 6.7818 -259.393415) (xy 12.989804 -259.393415) (xy 12.989804 -259.340117) (xy 12.997747 -259.287413)
			(xy 13.013457 -259.236483) (xy 13.036583 -259.188462) (xy 13.066607 -259.144425) (xy 13.102859 -259.105354)
			(xy 13.14453 -259.072123) (xy 13.190688 -259.045474) (xy 13.240302 -259.026002) (xy 13.292264 -259.014142)
			(xy 13.345414 -259.010159) (xy 13.398564 -259.014142) (xy 13.450526 -259.026002) (xy 13.50014 -259.045474)
			(xy 13.546298 -259.072123) (xy 13.587969 -259.105354) (xy 13.624221 -259.144425) (xy 13.654245 -259.188462)
			(xy 13.677371 -259.236483) (xy 13.693081 -259.287413) (xy 13.701024 -259.340117) (xy 13.701522 -259.366766)
			(xy 13.701024 -259.393415) (xy 16.433536 -259.393415) (xy 16.433536 -259.340117) (xy 16.441479 -259.287413)
			(xy 16.457189 -259.236483) (xy 16.480315 -259.188462) (xy 16.510339 -259.144425) (xy 16.546591 -259.105354)
			(xy 16.588262 -259.072123) (xy 16.63442 -259.045474) (xy 16.684034 -259.026002) (xy 16.735996 -259.014142)
			(xy 16.789146 -259.010159) (xy 16.842296 -259.014142) (xy 16.894258 -259.026002) (xy 16.943872 -259.045474)
			(xy 16.99003 -259.072123) (xy 17.031701 -259.105354) (xy 17.067953 -259.144425) (xy 17.097977 -259.188462)
			(xy 17.121103 -259.236483) (xy 17.136813 -259.287413) (xy 17.144756 -259.340117) (xy 17.145254 -259.366766)
			(xy 17.144756 -259.393415) (xy 20.533604 -259.393415) (xy 20.533604 -259.340117) (xy 20.541547 -259.287413)
			(xy 20.557257 -259.236483) (xy 20.580383 -259.188462) (xy 20.610407 -259.144425) (xy 20.646659 -259.105354)
			(xy 20.68833 -259.072123) (xy 20.734488 -259.045474) (xy 20.784102 -259.026002) (xy 20.836064 -259.014142)
			(xy 20.889214 -259.010159) (xy 20.942364 -259.014142) (xy 20.994326 -259.026002) (xy 21.04394 -259.045474)
			(xy 21.090098 -259.072123) (xy 21.131769 -259.105354) (xy 21.168021 -259.144425) (xy 21.198045 -259.188462)
			(xy 21.221171 -259.236483) (xy 21.236881 -259.287413) (xy 21.244824 -259.340117) (xy 21.245322 -259.366766)
			(xy 21.244824 -259.393415) (xy 28.077404 -259.393415) (xy 28.077404 -259.340117) (xy 28.085347 -259.287413)
			(xy 28.101057 -259.236483) (xy 28.124183 -259.188462) (xy 28.154207 -259.144425) (xy 28.190459 -259.105354)
			(xy 28.23213 -259.072123) (xy 28.278288 -259.045474) (xy 28.327902 -259.026002) (xy 28.379864 -259.014142)
			(xy 28.433014 -259.010159) (xy 28.486164 -259.014142) (xy 28.538126 -259.026002) (xy 28.58774 -259.045474)
			(xy 28.633898 -259.072123) (xy 28.675569 -259.105354) (xy 28.711821 -259.144425) (xy 28.741845 -259.188462)
			(xy 28.764971 -259.236483) (xy 28.780681 -259.287413) (xy 28.788624 -259.340117) (xy 28.789122 -259.366766)
			(xy 28.788624 -259.393415) (xy 31.521136 -259.393415) (xy 31.521136 -259.340117) (xy 31.529079 -259.287413)
			(xy 31.544789 -259.236483) (xy 31.567915 -259.188462) (xy 31.597939 -259.144425) (xy 31.634191 -259.105354)
			(xy 31.675862 -259.072123) (xy 31.72202 -259.045474) (xy 31.771634 -259.026002) (xy 31.823596 -259.014142)
			(xy 31.876746 -259.010159) (xy 31.929896 -259.014142) (xy 31.981858 -259.026002) (xy 32.031472 -259.045474)
			(xy 32.07763 -259.072123) (xy 32.119301 -259.105354) (xy 32.155553 -259.144425) (xy 32.185577 -259.188462)
			(xy 32.208703 -259.236483) (xy 32.224413 -259.287413) (xy 32.232356 -259.340117) (xy 32.232854 -259.366766)
			(xy 32.232356 -259.393415) (xy 35.621204 -259.393415) (xy 35.621204 -259.340117) (xy 35.629147 -259.287413)
			(xy 35.644857 -259.236483) (xy 35.667983 -259.188462) (xy 35.698007 -259.144425) (xy 35.734259 -259.105354)
			(xy 35.77593 -259.072123) (xy 35.822088 -259.045474) (xy 35.871702 -259.026002) (xy 35.923664 -259.014142)
			(xy 35.976814 -259.010159) (xy 36.029964 -259.014142) (xy 36.081926 -259.026002) (xy 36.13154 -259.045474)
			(xy 36.177698 -259.072123) (xy 36.219369 -259.105354) (xy 36.255621 -259.144425) (xy 36.285645 -259.188462)
			(xy 36.308771 -259.236483) (xy 36.324481 -259.287413) (xy 36.332424 -259.340117) (xy 36.332922 -259.366766)
			(xy 36.332424 -259.393415) (xy 43.165004 -259.393415) (xy 43.165004 -259.340117) (xy 43.172947 -259.287413)
			(xy 43.188657 -259.236483) (xy 43.211783 -259.188462) (xy 43.241807 -259.144425) (xy 43.278059 -259.105354)
			(xy 43.31973 -259.072123) (xy 43.365888 -259.045474) (xy 43.415502 -259.026002) (xy 43.467464 -259.014142)
			(xy 43.520614 -259.010159) (xy 43.573764 -259.014142) (xy 43.625726 -259.026002) (xy 43.67534 -259.045474)
			(xy 43.721498 -259.072123) (xy 43.763169 -259.105354) (xy 43.799421 -259.144425) (xy 43.829445 -259.188462)
			(xy 43.852571 -259.236483) (xy 43.868281 -259.287413) (xy 43.876224 -259.340117) (xy 43.876722 -259.366766)
			(xy 43.876224 -259.393415) (xy 46.608736 -259.393415) (xy 46.608736 -259.340117) (xy 46.616679 -259.287413)
			(xy 46.632389 -259.236483) (xy 46.655515 -259.188462) (xy 46.685539 -259.144425) (xy 46.721791 -259.105354)
			(xy 46.763462 -259.072123) (xy 46.80962 -259.045474) (xy 46.859234 -259.026002) (xy 46.911196 -259.014142)
			(xy 46.964346 -259.010159) (xy 47.017496 -259.014142) (xy 47.069458 -259.026002) (xy 47.119072 -259.045474)
			(xy 47.16523 -259.072123) (xy 47.206901 -259.105354) (xy 47.243153 -259.144425) (xy 47.273177 -259.188462)
			(xy 47.296303 -259.236483) (xy 47.312013 -259.287413) (xy 47.319956 -259.340117) (xy 47.320454 -259.366766)
			(xy 47.319956 -259.393415) (xy 50.734204 -259.393415) (xy 50.734204 -259.340117) (xy 50.742147 -259.287413)
			(xy 50.757857 -259.236483) (xy 50.780983 -259.188462) (xy 50.811007 -259.144425) (xy 50.847259 -259.105354)
			(xy 50.88893 -259.072123) (xy 50.935088 -259.045474) (xy 50.984702 -259.026002) (xy 51.036664 -259.014142)
			(xy 51.089814 -259.010159) (xy 51.142964 -259.014142) (xy 51.194926 -259.026002) (xy 51.24454 -259.045474)
			(xy 51.290698 -259.072123) (xy 51.332369 -259.105354) (xy 51.368621 -259.144425) (xy 51.398645 -259.188462)
			(xy 51.421771 -259.236483) (xy 51.437481 -259.287413) (xy 51.445424 -259.340117) (xy 51.445922 -259.366766)
			(xy 51.445424 -259.393415) (xy 51.437481 -259.446119) (xy 51.421771 -259.497049) (xy 51.398645 -259.54507)
			(xy 51.368621 -259.589107) (xy 51.332369 -259.628178) (xy 51.290698 -259.661409) (xy 51.24454 -259.688058)
			(xy 51.194926 -259.70753) (xy 51.142964 -259.71939) (xy 51.089814 -259.723374) (xy 51.036664 -259.71939)
			(xy 50.984702 -259.70753) (xy 50.935088 -259.688058) (xy 50.88893 -259.661409) (xy 50.847259 -259.628178)
			(xy 50.811007 -259.589107) (xy 50.780983 -259.54507) (xy 50.757857 -259.497049) (xy 50.742147 -259.446119)
			(xy 50.734204 -259.393415) (xy 47.319956 -259.393415) (xy 47.312013 -259.446119) (xy 47.296303 -259.497049)
			(xy 47.273177 -259.54507) (xy 47.243153 -259.589107) (xy 47.206901 -259.628178) (xy 47.16523 -259.661409)
			(xy 47.119072 -259.688058) (xy 47.069458 -259.70753) (xy 47.017496 -259.71939) (xy 46.964346 -259.723374)
			(xy 46.911196 -259.71939) (xy 46.859234 -259.70753) (xy 46.80962 -259.688058) (xy 46.763462 -259.661409)
			(xy 46.721791 -259.628178) (xy 46.685539 -259.589107) (xy 46.655515 -259.54507) (xy 46.632389 -259.497049)
			(xy 46.616679 -259.446119) (xy 46.608736 -259.393415) (xy 43.876224 -259.393415) (xy 43.868281 -259.446119)
			(xy 43.852571 -259.497049) (xy 43.829445 -259.54507) (xy 43.799421 -259.589107) (xy 43.763169 -259.628178)
			(xy 43.721498 -259.661409) (xy 43.67534 -259.688058) (xy 43.625726 -259.70753) (xy 43.573764 -259.71939)
			(xy 43.520614 -259.723374) (xy 43.467464 -259.71939) (xy 43.415502 -259.70753) (xy 43.365888 -259.688058)
			(xy 43.31973 -259.661409) (xy 43.278059 -259.628178) (xy 43.241807 -259.589107) (xy 43.211783 -259.54507)
			(xy 43.188657 -259.497049) (xy 43.172947 -259.446119) (xy 43.165004 -259.393415) (xy 36.332424 -259.393415)
			(xy 36.324481 -259.446119) (xy 36.308771 -259.497049) (xy 36.285645 -259.54507) (xy 36.255621 -259.589107)
			(xy 36.219369 -259.628178) (xy 36.177698 -259.661409) (xy 36.13154 -259.688058) (xy 36.081926 -259.70753)
			(xy 36.029964 -259.71939) (xy 35.976814 -259.723374) (xy 35.923664 -259.71939) (xy 35.871702 -259.70753)
			(xy 35.822088 -259.688058) (xy 35.77593 -259.661409) (xy 35.734259 -259.628178) (xy 35.698007 -259.589107)
			(xy 35.667983 -259.54507) (xy 35.644857 -259.497049) (xy 35.629147 -259.446119) (xy 35.621204 -259.393415)
			(xy 32.232356 -259.393415) (xy 32.224413 -259.446119) (xy 32.208703 -259.497049) (xy 32.185577 -259.54507)
			(xy 32.155553 -259.589107) (xy 32.119301 -259.628178) (xy 32.07763 -259.661409) (xy 32.031472 -259.688058)
			(xy 31.981858 -259.70753) (xy 31.929896 -259.71939) (xy 31.876746 -259.723374) (xy 31.823596 -259.71939)
			(xy 31.771634 -259.70753) (xy 31.72202 -259.688058) (xy 31.675862 -259.661409) (xy 31.634191 -259.628178)
			(xy 31.597939 -259.589107) (xy 31.567915 -259.54507) (xy 31.544789 -259.497049) (xy 31.529079 -259.446119)
			(xy 31.521136 -259.393415) (xy 28.788624 -259.393415) (xy 28.780681 -259.446119) (xy 28.764971 -259.497049)
			(xy 28.741845 -259.54507) (xy 28.711821 -259.589107) (xy 28.675569 -259.628178) (xy 28.633898 -259.661409)
			(xy 28.58774 -259.688058) (xy 28.538126 -259.70753) (xy 28.486164 -259.71939) (xy 28.433014 -259.723374)
			(xy 28.379864 -259.71939) (xy 28.327902 -259.70753) (xy 28.278288 -259.688058) (xy 28.23213 -259.661409)
			(xy 28.190459 -259.628178) (xy 28.154207 -259.589107) (xy 28.124183 -259.54507) (xy 28.101057 -259.497049)
			(xy 28.085347 -259.446119) (xy 28.077404 -259.393415) (xy 21.244824 -259.393415) (xy 21.236881 -259.446119)
			(xy 21.221171 -259.497049) (xy 21.198045 -259.54507) (xy 21.168021 -259.589107) (xy 21.131769 -259.628178)
			(xy 21.090098 -259.661409) (xy 21.04394 -259.688058) (xy 20.994326 -259.70753) (xy 20.942364 -259.71939)
			(xy 20.889214 -259.723374) (xy 20.836064 -259.71939) (xy 20.784102 -259.70753) (xy 20.734488 -259.688058)
			(xy 20.68833 -259.661409) (xy 20.646659 -259.628178) (xy 20.610407 -259.589107) (xy 20.580383 -259.54507)
			(xy 20.557257 -259.497049) (xy 20.541547 -259.446119) (xy 20.533604 -259.393415) (xy 17.144756 -259.393415)
			(xy 17.136813 -259.446119) (xy 17.121103 -259.497049) (xy 17.097977 -259.54507) (xy 17.067953 -259.589107)
			(xy 17.031701 -259.628178) (xy 16.99003 -259.661409) (xy 16.943872 -259.688058) (xy 16.894258 -259.70753)
			(xy 16.842296 -259.71939) (xy 16.789146 -259.723374) (xy 16.735996 -259.71939) (xy 16.684034 -259.70753)
			(xy 16.63442 -259.688058) (xy 16.588262 -259.661409) (xy 16.546591 -259.628178) (xy 16.510339 -259.589107)
			(xy 16.480315 -259.54507) (xy 16.457189 -259.497049) (xy 16.441479 -259.446119) (xy 16.433536 -259.393415)
			(xy 13.701024 -259.393415) (xy 13.693081 -259.446119) (xy 13.677371 -259.497049) (xy 13.654245 -259.54507)
			(xy 13.624221 -259.589107) (xy 13.587969 -259.628178) (xy 13.546298 -259.661409) (xy 13.50014 -259.688058)
			(xy 13.450526 -259.70753) (xy 13.398564 -259.71939) (xy 13.345414 -259.723374) (xy 13.292264 -259.71939)
			(xy 13.240302 -259.70753) (xy 13.190688 -259.688058) (xy 13.14453 -259.661409) (xy 13.102859 -259.628178)
			(xy 13.066607 -259.589107) (xy 13.036583 -259.54507) (xy 13.013457 -259.497049) (xy 12.997747 -259.446119)
			(xy 12.989804 -259.393415) (xy 6.7818 -259.393415) (xy 6.7818 -260.243299) (xy 12.989804 -260.243299)
			(xy 12.989804 -260.190001) (xy 12.997747 -260.137297) (xy 13.013457 -260.086367) (xy 13.036583 -260.038346)
			(xy 13.066607 -259.994309) (xy 13.102859 -259.955238) (xy 13.14453 -259.922007) (xy 13.190688 -259.895358)
			(xy 13.240302 -259.875886) (xy 13.292264 -259.864026) (xy 13.345414 -259.860043) (xy 13.398564 -259.864026)
			(xy 13.450526 -259.875886) (xy 13.50014 -259.895358) (xy 13.546298 -259.922007) (xy 13.587969 -259.955238)
			(xy 13.624221 -259.994309) (xy 13.654245 -260.038346) (xy 13.677371 -260.086367) (xy 13.693081 -260.137297)
			(xy 13.701024 -260.190001) (xy 13.701522 -260.21665) (xy 13.701024 -260.243299) (xy 20.533604 -260.243299)
			(xy 20.533604 -260.190001) (xy 20.541547 -260.137297) (xy 20.557257 -260.086367) (xy 20.580383 -260.038346)
			(xy 20.610407 -259.994309) (xy 20.646659 -259.955238) (xy 20.68833 -259.922007) (xy 20.734488 -259.895358)
			(xy 20.784102 -259.875886) (xy 20.836064 -259.864026) (xy 20.889214 -259.860043) (xy 20.942364 -259.864026)
			(xy 20.994326 -259.875886) (xy 21.04394 -259.895358) (xy 21.090098 -259.922007) (xy 21.131769 -259.955238)
			(xy 21.168021 -259.994309) (xy 21.198045 -260.038346) (xy 21.221171 -260.086367) (xy 21.236881 -260.137297)
			(xy 21.244824 -260.190001) (xy 21.245322 -260.21665) (xy 21.244824 -260.243299) (xy 28.077404 -260.243299)
			(xy 28.077404 -260.190001) (xy 28.085347 -260.137297) (xy 28.101057 -260.086367) (xy 28.124183 -260.038346)
			(xy 28.154207 -259.994309) (xy 28.190459 -259.955238) (xy 28.23213 -259.922007) (xy 28.278288 -259.895358)
			(xy 28.327902 -259.875886) (xy 28.379864 -259.864026) (xy 28.433014 -259.860043) (xy 28.486164 -259.864026)
			(xy 28.538126 -259.875886) (xy 28.58774 -259.895358) (xy 28.633898 -259.922007) (xy 28.675569 -259.955238)
			(xy 28.711821 -259.994309) (xy 28.741845 -260.038346) (xy 28.764971 -260.086367) (xy 28.780681 -260.137297)
			(xy 28.788624 -260.190001) (xy 28.789122 -260.21665) (xy 28.788624 -260.243299) (xy 35.621204 -260.243299)
			(xy 35.621204 -260.190001) (xy 35.629147 -260.137297) (xy 35.644857 -260.086367) (xy 35.667983 -260.038346)
			(xy 35.698007 -259.994309) (xy 35.734259 -259.955238) (xy 35.77593 -259.922007) (xy 35.822088 -259.895358)
			(xy 35.871702 -259.875886) (xy 35.923664 -259.864026) (xy 35.976814 -259.860043) (xy 36.029964 -259.864026)
			(xy 36.081926 -259.875886) (xy 36.13154 -259.895358) (xy 36.177698 -259.922007) (xy 36.219369 -259.955238)
			(xy 36.255621 -259.994309) (xy 36.285645 -260.038346) (xy 36.308771 -260.086367) (xy 36.324481 -260.137297)
			(xy 36.332424 -260.190001) (xy 36.332922 -260.21665) (xy 36.332424 -260.243299) (xy 43.165004 -260.243299)
			(xy 43.165004 -260.190001) (xy 43.172947 -260.137297) (xy 43.188657 -260.086367) (xy 43.211783 -260.038346)
			(xy 43.241807 -259.994309) (xy 43.278059 -259.955238) (xy 43.31973 -259.922007) (xy 43.365888 -259.895358)
			(xy 43.415502 -259.875886) (xy 43.467464 -259.864026) (xy 43.520614 -259.860043) (xy 43.573764 -259.864026)
			(xy 43.625726 -259.875886) (xy 43.67534 -259.895358) (xy 43.721498 -259.922007) (xy 43.763169 -259.955238)
			(xy 43.799421 -259.994309) (xy 43.829445 -260.038346) (xy 43.852571 -260.086367) (xy 43.868281 -260.137297)
			(xy 43.876224 -260.190001) (xy 43.876722 -260.21665) (xy 43.876224 -260.243299) (xy 50.734204 -260.243299)
			(xy 50.734204 -260.190001) (xy 50.742147 -260.137297) (xy 50.757857 -260.086367) (xy 50.780983 -260.038346)
			(xy 50.811007 -259.994309) (xy 50.847259 -259.955238) (xy 50.88893 -259.922007) (xy 50.935088 -259.895358)
			(xy 50.984702 -259.875886) (xy 51.036664 -259.864026) (xy 51.089814 -259.860043) (xy 51.142964 -259.864026)
			(xy 51.194926 -259.875886) (xy 51.24454 -259.895358) (xy 51.290698 -259.922007) (xy 51.332369 -259.955238)
			(xy 51.368621 -259.994309) (xy 51.398645 -260.038346) (xy 51.421771 -260.086367) (xy 51.437481 -260.137297)
			(xy 51.445424 -260.190001) (xy 51.445922 -260.21665) (xy 51.445424 -260.243299) (xy 51.437481 -260.296003)
			(xy 51.421771 -260.346933) (xy 51.398645 -260.394954) (xy 51.368621 -260.438991) (xy 51.332369 -260.478062)
			(xy 51.290698 -260.511293) (xy 51.24454 -260.537942) (xy 51.194926 -260.557414) (xy 51.142964 -260.569274)
			(xy 51.089814 -260.573258) (xy 51.036664 -260.569274) (xy 50.984702 -260.557414) (xy 50.935088 -260.537942)
			(xy 50.88893 -260.511293) (xy 50.847259 -260.478062) (xy 50.811007 -260.438991) (xy 50.780983 -260.394954)
			(xy 50.757857 -260.346933) (xy 50.742147 -260.296003) (xy 50.734204 -260.243299) (xy 43.876224 -260.243299)
			(xy 43.868281 -260.296003) (xy 43.852571 -260.346933) (xy 43.829445 -260.394954) (xy 43.799421 -260.438991)
			(xy 43.763169 -260.478062) (xy 43.721498 -260.511293) (xy 43.67534 -260.537942) (xy 43.625726 -260.557414)
			(xy 43.573764 -260.569274) (xy 43.520614 -260.573258) (xy 43.467464 -260.569274) (xy 43.415502 -260.557414)
			(xy 43.365888 -260.537942) (xy 43.31973 -260.511293) (xy 43.278059 -260.478062) (xy 43.241807 -260.438991)
			(xy 43.211783 -260.394954) (xy 43.188657 -260.346933) (xy 43.172947 -260.296003) (xy 43.165004 -260.243299)
			(xy 36.332424 -260.243299) (xy 36.324481 -260.296003) (xy 36.308771 -260.346933) (xy 36.285645 -260.394954)
			(xy 36.255621 -260.438991) (xy 36.219369 -260.478062) (xy 36.177698 -260.511293) (xy 36.13154 -260.537942)
			(xy 36.081926 -260.557414) (xy 36.029964 -260.569274) (xy 35.976814 -260.573258) (xy 35.923664 -260.569274)
			(xy 35.871702 -260.557414) (xy 35.822088 -260.537942) (xy 35.77593 -260.511293) (xy 35.734259 -260.478062)
			(xy 35.698007 -260.438991) (xy 35.667983 -260.394954) (xy 35.644857 -260.346933) (xy 35.629147 -260.296003)
			(xy 35.621204 -260.243299) (xy 28.788624 -260.243299) (xy 28.780681 -260.296003) (xy 28.764971 -260.346933)
			(xy 28.741845 -260.394954) (xy 28.711821 -260.438991) (xy 28.675569 -260.478062) (xy 28.633898 -260.511293)
			(xy 28.58774 -260.537942) (xy 28.538126 -260.557414) (xy 28.486164 -260.569274) (xy 28.433014 -260.573258)
			(xy 28.379864 -260.569274) (xy 28.327902 -260.557414) (xy 28.278288 -260.537942) (xy 28.23213 -260.511293)
			(xy 28.190459 -260.478062) (xy 28.154207 -260.438991) (xy 28.124183 -260.394954) (xy 28.101057 -260.346933)
			(xy 28.085347 -260.296003) (xy 28.077404 -260.243299) (xy 21.244824 -260.243299) (xy 21.236881 -260.296003)
			(xy 21.221171 -260.346933) (xy 21.198045 -260.394954) (xy 21.168021 -260.438991) (xy 21.131769 -260.478062)
			(xy 21.090098 -260.511293) (xy 21.04394 -260.537942) (xy 20.994326 -260.557414) (xy 20.942364 -260.569274)
			(xy 20.889214 -260.573258) (xy 20.836064 -260.569274) (xy 20.784102 -260.557414) (xy 20.734488 -260.537942)
			(xy 20.68833 -260.511293) (xy 20.646659 -260.478062) (xy 20.610407 -260.438991) (xy 20.580383 -260.394954)
			(xy 20.557257 -260.346933) (xy 20.541547 -260.296003) (xy 20.533604 -260.243299) (xy 13.701024 -260.243299)
			(xy 13.693081 -260.296003) (xy 13.677371 -260.346933) (xy 13.654245 -260.394954) (xy 13.624221 -260.438991)
			(xy 13.587969 -260.478062) (xy 13.546298 -260.511293) (xy 13.50014 -260.537942) (xy 13.450526 -260.557414)
			(xy 13.398564 -260.569274) (xy 13.345414 -260.573258) (xy 13.292264 -260.569274) (xy 13.240302 -260.557414)
			(xy 13.190688 -260.537942) (xy 13.14453 -260.511293) (xy 13.102859 -260.478062) (xy 13.066607 -260.438991)
			(xy 13.036583 -260.394954) (xy 13.013457 -260.346933) (xy 12.997747 -260.296003) (xy 12.989804 -260.243299)
			(xy 6.7818 -260.243299) (xy 6.7818 -261.093437) (xy 16.433536 -261.093437) (xy 16.433536 -261.040139)
			(xy 16.441479 -260.987435) (xy 16.457189 -260.936505) (xy 16.480315 -260.888484) (xy 16.510339 -260.844447)
			(xy 16.546591 -260.805376) (xy 16.588262 -260.772145) (xy 16.63442 -260.745496) (xy 16.684034 -260.726024)
			(xy 16.735996 -260.714164) (xy 16.789146 -260.710181) (xy 16.842296 -260.714164) (xy 16.894258 -260.726024)
			(xy 16.943872 -260.745496) (xy 16.99003 -260.772145) (xy 17.031701 -260.805376) (xy 17.067953 -260.844447)
			(xy 17.097977 -260.888484) (xy 17.121103 -260.936505) (xy 17.136813 -260.987435) (xy 17.144756 -261.040139)
			(xy 17.145254 -261.066788) (xy 17.144756 -261.093437) (xy 31.521136 -261.093437) (xy 31.521136 -261.040139)
			(xy 31.529079 -260.987435) (xy 31.544789 -260.936505) (xy 31.567915 -260.888484) (xy 31.597939 -260.844447)
			(xy 31.634191 -260.805376) (xy 31.675862 -260.772145) (xy 31.72202 -260.745496) (xy 31.771634 -260.726024)
			(xy 31.823596 -260.714164) (xy 31.876746 -260.710181) (xy 31.929896 -260.714164) (xy 31.981858 -260.726024)
			(xy 32.031472 -260.745496) (xy 32.07763 -260.772145) (xy 32.119301 -260.805376) (xy 32.155553 -260.844447)
			(xy 32.185577 -260.888484) (xy 32.208703 -260.936505) (xy 32.224413 -260.987435) (xy 32.232356 -261.040139)
			(xy 32.232854 -261.066788) (xy 32.232356 -261.093437) (xy 46.608736 -261.093437) (xy 46.608736 -261.040139)
			(xy 46.616679 -260.987435) (xy 46.632389 -260.936505) (xy 46.655515 -260.888484) (xy 46.685539 -260.844447)
			(xy 46.721791 -260.805376) (xy 46.763462 -260.772145) (xy 46.80962 -260.745496) (xy 46.859234 -260.726024)
			(xy 46.911196 -260.714164) (xy 46.964346 -260.710181) (xy 47.017496 -260.714164) (xy 47.069458 -260.726024)
			(xy 47.119072 -260.745496) (xy 47.16523 -260.772145) (xy 47.206901 -260.805376) (xy 47.243153 -260.844447)
			(xy 47.273177 -260.888484) (xy 47.296303 -260.936505) (xy 47.312013 -260.987435) (xy 47.319956 -261.040139)
			(xy 47.320454 -261.066788) (xy 47.319956 -261.093437) (xy 47.312013 -261.146141) (xy 47.296303 -261.197071)
			(xy 47.273177 -261.245092) (xy 47.243153 -261.289129) (xy 47.206901 -261.3282) (xy 47.16523 -261.361431)
			(xy 47.119072 -261.38808) (xy 47.069458 -261.407552) (xy 47.017496 -261.419412) (xy 46.964346 -261.423396)
			(xy 46.911196 -261.419412) (xy 46.859234 -261.407552) (xy 46.80962 -261.38808) (xy 46.763462 -261.361431)
			(xy 46.721791 -261.3282) (xy 46.685539 -261.289129) (xy 46.655515 -261.245092) (xy 46.632389 -261.197071)
			(xy 46.616679 -261.146141) (xy 46.608736 -261.093437) (xy 32.232356 -261.093437) (xy 32.224413 -261.146141)
			(xy 32.208703 -261.197071) (xy 32.185577 -261.245092) (xy 32.155553 -261.289129) (xy 32.119301 -261.3282)
			(xy 32.07763 -261.361431) (xy 32.031472 -261.38808) (xy 31.981858 -261.407552) (xy 31.929896 -261.419412)
			(xy 31.876746 -261.423396) (xy 31.823596 -261.419412) (xy 31.771634 -261.407552) (xy 31.72202 -261.38808)
			(xy 31.675862 -261.361431) (xy 31.634191 -261.3282) (xy 31.597939 -261.289129) (xy 31.567915 -261.245092)
			(xy 31.544789 -261.197071) (xy 31.529079 -261.146141) (xy 31.521136 -261.093437) (xy 17.144756 -261.093437)
			(xy 17.136813 -261.146141) (xy 17.121103 -261.197071) (xy 17.097977 -261.245092) (xy 17.067953 -261.289129)
			(xy 17.031701 -261.3282) (xy 16.99003 -261.361431) (xy 16.943872 -261.38808) (xy 16.894258 -261.407552)
			(xy 16.842296 -261.419412) (xy 16.789146 -261.423396) (xy 16.735996 -261.419412) (xy 16.684034 -261.407552)
			(xy 16.63442 -261.38808) (xy 16.588262 -261.361431) (xy 16.546591 -261.3282) (xy 16.510339 -261.289129)
			(xy 16.480315 -261.245092) (xy 16.457189 -261.197071) (xy 16.441479 -261.146141) (xy 16.433536 -261.093437)
			(xy 6.7818 -261.093437) (xy 6.7818 -261.943321) (xy 20.533604 -261.943321) (xy 20.533604 -261.890023)
			(xy 20.541547 -261.837319) (xy 20.557257 -261.786389) (xy 20.580383 -261.738368) (xy 20.610407 -261.694331)
			(xy 20.646659 -261.65526) (xy 20.68833 -261.622029) (xy 20.734488 -261.59538) (xy 20.784102 -261.575908)
			(xy 20.836064 -261.564048) (xy 20.889214 -261.560065) (xy 20.942364 -261.564048) (xy 20.994326 -261.575908)
			(xy 21.04394 -261.59538) (xy 21.090098 -261.622029) (xy 21.131769 -261.65526) (xy 21.168021 -261.694331)
			(xy 21.198045 -261.738368) (xy 21.221171 -261.786389) (xy 21.236881 -261.837319) (xy 21.244824 -261.890023)
			(xy 21.245322 -261.916672) (xy 21.244824 -261.943321) (xy 35.621204 -261.943321) (xy 35.621204 -261.890023)
			(xy 35.629147 -261.837319) (xy 35.644857 -261.786389) (xy 35.667983 -261.738368) (xy 35.698007 -261.694331)
			(xy 35.734259 -261.65526) (xy 35.77593 -261.622029) (xy 35.822088 -261.59538) (xy 35.871702 -261.575908)
			(xy 35.923664 -261.564048) (xy 35.976814 -261.560065) (xy 36.029964 -261.564048) (xy 36.081926 -261.575908)
			(xy 36.13154 -261.59538) (xy 36.177698 -261.622029) (xy 36.219369 -261.65526) (xy 36.255621 -261.694331)
			(xy 36.285645 -261.738368) (xy 36.308771 -261.786389) (xy 36.324481 -261.837319) (xy 36.332424 -261.890023)
			(xy 36.332922 -261.916672) (xy 36.332424 -261.943321) (xy 50.734204 -261.943321) (xy 50.734204 -261.890023)
			(xy 50.742147 -261.837319) (xy 50.757857 -261.786389) (xy 50.780983 -261.738368) (xy 50.811007 -261.694331)
			(xy 50.847259 -261.65526) (xy 50.88893 -261.622029) (xy 50.935088 -261.59538) (xy 50.984702 -261.575908)
			(xy 51.036664 -261.564048) (xy 51.089814 -261.560065) (xy 51.142964 -261.564048) (xy 51.194926 -261.575908)
			(xy 51.24454 -261.59538) (xy 51.290698 -261.622029) (xy 51.332369 -261.65526) (xy 51.368621 -261.694331)
			(xy 51.398645 -261.738368) (xy 51.421771 -261.786389) (xy 51.437481 -261.837319) (xy 51.445424 -261.890023)
			(xy 51.445922 -261.916672) (xy 51.445424 -261.943321) (xy 51.437481 -261.996025) (xy 51.421771 -262.046955)
			(xy 51.398645 -262.094976) (xy 51.368621 -262.139013) (xy 51.332369 -262.178084) (xy 51.290698 -262.211315)
			(xy 51.24454 -262.237964) (xy 51.194926 -262.257436) (xy 51.142964 -262.269296) (xy 51.089814 -262.27328)
			(xy 51.036664 -262.269296) (xy 50.984702 -262.257436) (xy 50.935088 -262.237964) (xy 50.88893 -262.211315)
			(xy 50.847259 -262.178084) (xy 50.811007 -262.139013) (xy 50.780983 -262.094976) (xy 50.757857 -262.046955)
			(xy 50.742147 -261.996025) (xy 50.734204 -261.943321) (xy 36.332424 -261.943321) (xy 36.324481 -261.996025)
			(xy 36.308771 -262.046955) (xy 36.285645 -262.094976) (xy 36.255621 -262.139013) (xy 36.219369 -262.178084)
			(xy 36.177698 -262.211315) (xy 36.13154 -262.237964) (xy 36.081926 -262.257436) (xy 36.029964 -262.269296)
			(xy 35.976814 -262.27328) (xy 35.923664 -262.269296) (xy 35.871702 -262.257436) (xy 35.822088 -262.237964)
			(xy 35.77593 -262.211315) (xy 35.734259 -262.178084) (xy 35.698007 -262.139013) (xy 35.667983 -262.094976)
			(xy 35.644857 -262.046955) (xy 35.629147 -261.996025) (xy 35.621204 -261.943321) (xy 21.244824 -261.943321)
			(xy 21.236881 -261.996025) (xy 21.221171 -262.046955) (xy 21.198045 -262.094976) (xy 21.168021 -262.139013)
			(xy 21.131769 -262.178084) (xy 21.090098 -262.211315) (xy 21.04394 -262.237964) (xy 20.994326 -262.257436)
			(xy 20.942364 -262.269296) (xy 20.889214 -262.27328) (xy 20.836064 -262.269296) (xy 20.784102 -262.257436)
			(xy 20.734488 -262.237964) (xy 20.68833 -262.211315) (xy 20.646659 -262.178084) (xy 20.610407 -262.139013)
			(xy 20.580383 -262.094976) (xy 20.557257 -262.046955) (xy 20.541547 -261.996025) (xy 20.533604 -261.943321)
			(xy 6.7818 -261.943321) (xy 6.7818 -262.793459) (xy 16.433536 -262.793459) (xy 16.433536 -262.740161)
			(xy 16.441479 -262.687457) (xy 16.457189 -262.636527) (xy 16.480315 -262.588506) (xy 16.510339 -262.544469)
			(xy 16.546591 -262.505398) (xy 16.588262 -262.472167) (xy 16.63442 -262.445518) (xy 16.684034 -262.426046)
			(xy 16.735996 -262.414186) (xy 16.789146 -262.410203) (xy 16.842296 -262.414186) (xy 16.894258 -262.426046)
			(xy 16.943872 -262.445518) (xy 16.99003 -262.472167) (xy 17.031701 -262.505398) (xy 17.067953 -262.544469)
			(xy 17.097977 -262.588506) (xy 17.121103 -262.636527) (xy 17.136813 -262.687457) (xy 17.144756 -262.740161)
			(xy 17.145254 -262.76681) (xy 17.144756 -262.793459) (xy 31.521136 -262.793459) (xy 31.521136 -262.740161)
			(xy 31.529079 -262.687457) (xy 31.544789 -262.636527) (xy 31.567915 -262.588506) (xy 31.597939 -262.544469)
			(xy 31.634191 -262.505398) (xy 31.675862 -262.472167) (xy 31.72202 -262.445518) (xy 31.771634 -262.426046)
			(xy 31.823596 -262.414186) (xy 31.876746 -262.410203) (xy 31.929896 -262.414186) (xy 31.981858 -262.426046)
			(xy 32.031472 -262.445518) (xy 32.07763 -262.472167) (xy 32.119301 -262.505398) (xy 32.155553 -262.544469)
			(xy 32.185577 -262.588506) (xy 32.208703 -262.636527) (xy 32.224413 -262.687457) (xy 32.232356 -262.740161)
			(xy 32.232854 -262.76681) (xy 32.232356 -262.793459) (xy 46.608736 -262.793459) (xy 46.608736 -262.740161)
			(xy 46.616679 -262.687457) (xy 46.632389 -262.636527) (xy 46.655515 -262.588506) (xy 46.685539 -262.544469)
			(xy 46.721791 -262.505398) (xy 46.763462 -262.472167) (xy 46.80962 -262.445518) (xy 46.859234 -262.426046)
			(xy 46.911196 -262.414186) (xy 46.964346 -262.410203) (xy 47.017496 -262.414186) (xy 47.069458 -262.426046)
			(xy 47.119072 -262.445518) (xy 47.16523 -262.472167) (xy 47.206901 -262.505398) (xy 47.243153 -262.544469)
			(xy 47.273177 -262.588506) (xy 47.296303 -262.636527) (xy 47.312013 -262.687457) (xy 47.319956 -262.740161)
			(xy 47.320454 -262.76681) (xy 47.319956 -262.793459) (xy 47.312013 -262.846163) (xy 47.296303 -262.897093)
			(xy 47.273177 -262.945114) (xy 47.243153 -262.989151) (xy 47.206901 -263.028222) (xy 47.16523 -263.061453)
			(xy 47.119072 -263.088102) (xy 47.069458 -263.107574) (xy 47.017496 -263.119434) (xy 46.964346 -263.123418)
			(xy 46.911196 -263.119434) (xy 46.859234 -263.107574) (xy 46.80962 -263.088102) (xy 46.763462 -263.061453)
			(xy 46.721791 -263.028222) (xy 46.685539 -262.989151) (xy 46.655515 -262.945114) (xy 46.632389 -262.897093)
			(xy 46.616679 -262.846163) (xy 46.608736 -262.793459) (xy 32.232356 -262.793459) (xy 32.224413 -262.846163)
			(xy 32.208703 -262.897093) (xy 32.185577 -262.945114) (xy 32.155553 -262.989151) (xy 32.119301 -263.028222)
			(xy 32.07763 -263.061453) (xy 32.031472 -263.088102) (xy 31.981858 -263.107574) (xy 31.929896 -263.119434)
			(xy 31.876746 -263.123418) (xy 31.823596 -263.119434) (xy 31.771634 -263.107574) (xy 31.72202 -263.088102)
			(xy 31.675862 -263.061453) (xy 31.634191 -263.028222) (xy 31.597939 -262.989151) (xy 31.567915 -262.945114)
			(xy 31.544789 -262.897093) (xy 31.529079 -262.846163) (xy 31.521136 -262.793459) (xy 17.144756 -262.793459)
			(xy 17.136813 -262.846163) (xy 17.121103 -262.897093) (xy 17.097977 -262.945114) (xy 17.067953 -262.989151)
			(xy 17.031701 -263.028222) (xy 16.99003 -263.061453) (xy 16.943872 -263.088102) (xy 16.894258 -263.107574)
			(xy 16.842296 -263.119434) (xy 16.789146 -263.123418) (xy 16.735996 -263.119434) (xy 16.684034 -263.107574)
			(xy 16.63442 -263.088102) (xy 16.588262 -263.061453) (xy 16.546591 -263.028222) (xy 16.510339 -262.989151)
			(xy 16.480315 -262.945114) (xy 16.457189 -262.897093) (xy 16.441479 -262.846163) (xy 16.433536 -262.793459)
			(xy 6.7818 -262.793459) (xy 6.7818 -263.643343) (xy 20.533604 -263.643343) (xy 20.533604 -263.590045)
			(xy 20.541547 -263.537341) (xy 20.557257 -263.486411) (xy 20.580383 -263.43839) (xy 20.610407 -263.394353)
			(xy 20.646659 -263.355282) (xy 20.68833 -263.322051) (xy 20.734488 -263.295402) (xy 20.784102 -263.27593)
			(xy 20.836064 -263.26407) (xy 20.889214 -263.260087) (xy 20.942364 -263.26407) (xy 20.994326 -263.27593)
			(xy 21.04394 -263.295402) (xy 21.090098 -263.322051) (xy 21.131769 -263.355282) (xy 21.168021 -263.394353)
			(xy 21.198045 -263.43839) (xy 21.221171 -263.486411) (xy 21.236881 -263.537341) (xy 21.244824 -263.590045)
			(xy 21.245322 -263.616694) (xy 21.244824 -263.643343) (xy 35.621204 -263.643343) (xy 35.621204 -263.590045)
			(xy 35.629147 -263.537341) (xy 35.644857 -263.486411) (xy 35.667983 -263.43839) (xy 35.698007 -263.394353)
			(xy 35.734259 -263.355282) (xy 35.77593 -263.322051) (xy 35.822088 -263.295402) (xy 35.871702 -263.27593)
			(xy 35.923664 -263.26407) (xy 35.976814 -263.260087) (xy 36.029964 -263.26407) (xy 36.081926 -263.27593)
			(xy 36.13154 -263.295402) (xy 36.177698 -263.322051) (xy 36.219369 -263.355282) (xy 36.255621 -263.394353)
			(xy 36.285645 -263.43839) (xy 36.308771 -263.486411) (xy 36.324481 -263.537341) (xy 36.332424 -263.590045)
			(xy 36.332922 -263.616694) (xy 36.332424 -263.643343) (xy 50.734204 -263.643343) (xy 50.734204 -263.590045)
			(xy 50.742147 -263.537341) (xy 50.757857 -263.486411) (xy 50.780983 -263.43839) (xy 50.811007 -263.394353)
			(xy 50.847259 -263.355282) (xy 50.88893 -263.322051) (xy 50.935088 -263.295402) (xy 50.984702 -263.27593)
			(xy 51.036664 -263.26407) (xy 51.089814 -263.260087) (xy 51.142964 -263.26407) (xy 51.194926 -263.27593)
			(xy 51.24454 -263.295402) (xy 51.290698 -263.322051) (xy 51.332369 -263.355282) (xy 51.368621 -263.394353)
			(xy 51.398645 -263.43839) (xy 51.421771 -263.486411) (xy 51.437481 -263.537341) (xy 51.445424 -263.590045)
			(xy 51.445922 -263.616694) (xy 51.445424 -263.643343) (xy 51.437481 -263.696047) (xy 51.421771 -263.746977)
			(xy 51.398645 -263.794998) (xy 51.368621 -263.839035) (xy 51.332369 -263.878106) (xy 51.290698 -263.911337)
			(xy 51.24454 -263.937986) (xy 51.194926 -263.957458) (xy 51.142964 -263.969318) (xy 51.089814 -263.973302)
			(xy 51.036664 -263.969318) (xy 50.984702 -263.957458) (xy 50.935088 -263.937986) (xy 50.88893 -263.911337)
			(xy 50.847259 -263.878106) (xy 50.811007 -263.839035) (xy 50.780983 -263.794998) (xy 50.757857 -263.746977)
			(xy 50.742147 -263.696047) (xy 50.734204 -263.643343) (xy 36.332424 -263.643343) (xy 36.324481 -263.696047)
			(xy 36.308771 -263.746977) (xy 36.285645 -263.794998) (xy 36.255621 -263.839035) (xy 36.219369 -263.878106)
			(xy 36.177698 -263.911337) (xy 36.13154 -263.937986) (xy 36.081926 -263.957458) (xy 36.029964 -263.969318)
			(xy 35.976814 -263.973302) (xy 35.923664 -263.969318) (xy 35.871702 -263.957458) (xy 35.822088 -263.937986)
			(xy 35.77593 -263.911337) (xy 35.734259 -263.878106) (xy 35.698007 -263.839035) (xy 35.667983 -263.794998)
			(xy 35.644857 -263.746977) (xy 35.629147 -263.696047) (xy 35.621204 -263.643343) (xy 21.244824 -263.643343)
			(xy 21.236881 -263.696047) (xy 21.221171 -263.746977) (xy 21.198045 -263.794998) (xy 21.168021 -263.839035)
			(xy 21.131769 -263.878106) (xy 21.090098 -263.911337) (xy 21.04394 -263.937986) (xy 20.994326 -263.957458)
			(xy 20.942364 -263.969318) (xy 20.889214 -263.973302) (xy 20.836064 -263.969318) (xy 20.784102 -263.957458)
			(xy 20.734488 -263.937986) (xy 20.68833 -263.911337) (xy 20.646659 -263.878106) (xy 20.610407 -263.839035)
			(xy 20.580383 -263.794998) (xy 20.557257 -263.746977) (xy 20.541547 -263.696047) (xy 20.533604 -263.643343)
			(xy 6.7818 -263.643343) (xy 6.7818 -264.493227) (xy 16.433536 -264.493227) (xy 16.433536 -264.439929)
			(xy 16.441479 -264.387225) (xy 16.457189 -264.336295) (xy 16.480315 -264.288274) (xy 16.510339 -264.244237)
			(xy 16.546591 -264.205166) (xy 16.588262 -264.171935) (xy 16.63442 -264.145286) (xy 16.684034 -264.125814)
			(xy 16.735996 -264.113954) (xy 16.789146 -264.109971) (xy 16.842296 -264.113954) (xy 16.894258 -264.125814)
			(xy 16.943872 -264.145286) (xy 16.99003 -264.171935) (xy 17.031701 -264.205166) (xy 17.067953 -264.244237)
			(xy 17.097977 -264.288274) (xy 17.121103 -264.336295) (xy 17.136813 -264.387225) (xy 17.144756 -264.439929)
			(xy 17.145254 -264.466578) (xy 17.144756 -264.493227) (xy 31.521136 -264.493227) (xy 31.521136 -264.439929)
			(xy 31.529079 -264.387225) (xy 31.544789 -264.336295) (xy 31.567915 -264.288274) (xy 31.597939 -264.244237)
			(xy 31.634191 -264.205166) (xy 31.675862 -264.171935) (xy 31.72202 -264.145286) (xy 31.771634 -264.125814)
			(xy 31.823596 -264.113954) (xy 31.876746 -264.109971) (xy 31.929896 -264.113954) (xy 31.981858 -264.125814)
			(xy 32.031472 -264.145286) (xy 32.07763 -264.171935) (xy 32.119301 -264.205166) (xy 32.155553 -264.244237)
			(xy 32.185577 -264.288274) (xy 32.208703 -264.336295) (xy 32.224413 -264.387225) (xy 32.232356 -264.439929)
			(xy 32.232854 -264.466578) (xy 32.232356 -264.493227) (xy 46.608736 -264.493227) (xy 46.608736 -264.439929)
			(xy 46.616679 -264.387225) (xy 46.632389 -264.336295) (xy 46.655515 -264.288274) (xy 46.685539 -264.244237)
			(xy 46.721791 -264.205166) (xy 46.763462 -264.171935) (xy 46.80962 -264.145286) (xy 46.859234 -264.125814)
			(xy 46.911196 -264.113954) (xy 46.964346 -264.109971) (xy 47.017496 -264.113954) (xy 47.069458 -264.125814)
			(xy 47.119072 -264.145286) (xy 47.16523 -264.171935) (xy 47.206901 -264.205166) (xy 47.243153 -264.244237)
			(xy 47.273177 -264.288274) (xy 47.296303 -264.336295) (xy 47.312013 -264.387225) (xy 47.319956 -264.439929)
			(xy 47.320454 -264.466578) (xy 47.319956 -264.493227) (xy 47.312013 -264.545931) (xy 47.296303 -264.596861)
			(xy 47.273177 -264.644882) (xy 47.243153 -264.688919) (xy 47.206901 -264.72799) (xy 47.16523 -264.761221)
			(xy 47.119072 -264.78787) (xy 47.069458 -264.807342) (xy 47.017496 -264.819202) (xy 46.964346 -264.823186)
			(xy 46.911196 -264.819202) (xy 46.859234 -264.807342) (xy 46.80962 -264.78787) (xy 46.763462 -264.761221)
			(xy 46.721791 -264.72799) (xy 46.685539 -264.688919) (xy 46.655515 -264.644882) (xy 46.632389 -264.596861)
			(xy 46.616679 -264.545931) (xy 46.608736 -264.493227) (xy 32.232356 -264.493227) (xy 32.224413 -264.545931)
			(xy 32.208703 -264.596861) (xy 32.185577 -264.644882) (xy 32.155553 -264.688919) (xy 32.119301 -264.72799)
			(xy 32.07763 -264.761221) (xy 32.031472 -264.78787) (xy 31.981858 -264.807342) (xy 31.929896 -264.819202)
			(xy 31.876746 -264.823186) (xy 31.823596 -264.819202) (xy 31.771634 -264.807342) (xy 31.72202 -264.78787)
			(xy 31.675862 -264.761221) (xy 31.634191 -264.72799) (xy 31.597939 -264.688919) (xy 31.567915 -264.644882)
			(xy 31.544789 -264.596861) (xy 31.529079 -264.545931) (xy 31.521136 -264.493227) (xy 17.144756 -264.493227)
			(xy 17.136813 -264.545931) (xy 17.121103 -264.596861) (xy 17.097977 -264.644882) (xy 17.067953 -264.688919)
			(xy 17.031701 -264.72799) (xy 16.99003 -264.761221) (xy 16.943872 -264.78787) (xy 16.894258 -264.807342)
			(xy 16.842296 -264.819202) (xy 16.789146 -264.823186) (xy 16.735996 -264.819202) (xy 16.684034 -264.807342)
			(xy 16.63442 -264.78787) (xy 16.588262 -264.761221) (xy 16.546591 -264.72799) (xy 16.510339 -264.688919)
			(xy 16.480315 -264.644882) (xy 16.457189 -264.596861) (xy 16.441479 -264.545931) (xy 16.433536 -264.493227)
			(xy 6.7818 -264.493227) (xy 6.7818 -265.343365) (xy 20.533604 -265.343365) (xy 20.533604 -265.290067)
			(xy 20.541547 -265.237363) (xy 20.557257 -265.186433) (xy 20.580383 -265.138412) (xy 20.610407 -265.094375)
			(xy 20.646659 -265.055304) (xy 20.68833 -265.022073) (xy 20.734488 -264.995424) (xy 20.784102 -264.975952)
			(xy 20.836064 -264.964092) (xy 20.889214 -264.960109) (xy 20.942364 -264.964092) (xy 20.994326 -264.975952)
			(xy 21.04394 -264.995424) (xy 21.090098 -265.022073) (xy 21.131769 -265.055304) (xy 21.168021 -265.094375)
			(xy 21.198045 -265.138412) (xy 21.221171 -265.186433) (xy 21.236881 -265.237363) (xy 21.244824 -265.290067)
			(xy 21.245322 -265.316716) (xy 21.244824 -265.343365) (xy 35.621204 -265.343365) (xy 35.621204 -265.290067)
			(xy 35.629147 -265.237363) (xy 35.644857 -265.186433) (xy 35.667983 -265.138412) (xy 35.698007 -265.094375)
			(xy 35.734259 -265.055304) (xy 35.77593 -265.022073) (xy 35.822088 -264.995424) (xy 35.871702 -264.975952)
			(xy 35.923664 -264.964092) (xy 35.976814 -264.960109) (xy 36.029964 -264.964092) (xy 36.081926 -264.975952)
			(xy 36.13154 -264.995424) (xy 36.177698 -265.022073) (xy 36.219369 -265.055304) (xy 36.255621 -265.094375)
			(xy 36.285645 -265.138412) (xy 36.308771 -265.186433) (xy 36.324481 -265.237363) (xy 36.332424 -265.290067)
			(xy 36.332922 -265.316716) (xy 36.332424 -265.343365) (xy 50.734204 -265.343365) (xy 50.734204 -265.290067)
			(xy 50.742147 -265.237363) (xy 50.757857 -265.186433) (xy 50.780983 -265.138412) (xy 50.811007 -265.094375)
			(xy 50.847259 -265.055304) (xy 50.88893 -265.022073) (xy 50.935088 -264.995424) (xy 50.984702 -264.975952)
			(xy 51.036664 -264.964092) (xy 51.089814 -264.960109) (xy 51.142964 -264.964092) (xy 51.194926 -264.975952)
			(xy 51.24454 -264.995424) (xy 51.290698 -265.022073) (xy 51.332369 -265.055304) (xy 51.368621 -265.094375)
			(xy 51.398645 -265.138412) (xy 51.421771 -265.186433) (xy 51.437481 -265.237363) (xy 51.445424 -265.290067)
			(xy 51.445922 -265.316716) (xy 51.445424 -265.343365) (xy 51.437481 -265.396069) (xy 51.421771 -265.446999)
			(xy 51.398645 -265.49502) (xy 51.368621 -265.539057) (xy 51.332369 -265.578128) (xy 51.290698 -265.611359)
			(xy 51.24454 -265.638008) (xy 51.194926 -265.65748) (xy 51.142964 -265.66934) (xy 51.089814 -265.673324)
			(xy 51.036664 -265.66934) (xy 50.984702 -265.65748) (xy 50.935088 -265.638008) (xy 50.88893 -265.611359)
			(xy 50.847259 -265.578128) (xy 50.811007 -265.539057) (xy 50.780983 -265.49502) (xy 50.757857 -265.446999)
			(xy 50.742147 -265.396069) (xy 50.734204 -265.343365) (xy 36.332424 -265.343365) (xy 36.324481 -265.396069)
			(xy 36.308771 -265.446999) (xy 36.285645 -265.49502) (xy 36.255621 -265.539057) (xy 36.219369 -265.578128)
			(xy 36.177698 -265.611359) (xy 36.13154 -265.638008) (xy 36.081926 -265.65748) (xy 36.029964 -265.66934)
			(xy 35.976814 -265.673324) (xy 35.923664 -265.66934) (xy 35.871702 -265.65748) (xy 35.822088 -265.638008)
			(xy 35.77593 -265.611359) (xy 35.734259 -265.578128) (xy 35.698007 -265.539057) (xy 35.667983 -265.49502)
			(xy 35.644857 -265.446999) (xy 35.629147 -265.396069) (xy 35.621204 -265.343365) (xy 21.244824 -265.343365)
			(xy 21.236881 -265.396069) (xy 21.221171 -265.446999) (xy 21.198045 -265.49502) (xy 21.168021 -265.539057)
			(xy 21.131769 -265.578128) (xy 21.090098 -265.611359) (xy 21.04394 -265.638008) (xy 20.994326 -265.65748)
			(xy 20.942364 -265.66934) (xy 20.889214 -265.673324) (xy 20.836064 -265.66934) (xy 20.784102 -265.65748)
			(xy 20.734488 -265.638008) (xy 20.68833 -265.611359) (xy 20.646659 -265.578128) (xy 20.610407 -265.539057)
			(xy 20.580383 -265.49502) (xy 20.557257 -265.446999) (xy 20.541547 -265.396069) (xy 20.533604 -265.343365)
			(xy 6.7818 -265.343365) (xy 6.7818 -266.193249) (xy 16.433536 -266.193249) (xy 16.433536 -266.139951)
			(xy 16.441479 -266.087247) (xy 16.457189 -266.036317) (xy 16.480315 -265.988296) (xy 16.510339 -265.944259)
			(xy 16.546591 -265.905188) (xy 16.588262 -265.871957) (xy 16.63442 -265.845308) (xy 16.684034 -265.825836)
			(xy 16.735996 -265.813976) (xy 16.789146 -265.809993) (xy 16.842296 -265.813976) (xy 16.894258 -265.825836)
			(xy 16.943872 -265.845308) (xy 16.99003 -265.871957) (xy 17.031701 -265.905188) (xy 17.067953 -265.944259)
			(xy 17.097977 -265.988296) (xy 17.121103 -266.036317) (xy 17.136813 -266.087247) (xy 17.144756 -266.139951)
			(xy 17.145254 -266.1666) (xy 17.144756 -266.193249) (xy 31.521136 -266.193249) (xy 31.521136 -266.139951)
			(xy 31.529079 -266.087247) (xy 31.544789 -266.036317) (xy 31.567915 -265.988296) (xy 31.597939 -265.944259)
			(xy 31.634191 -265.905188) (xy 31.675862 -265.871957) (xy 31.72202 -265.845308) (xy 31.771634 -265.825836)
			(xy 31.823596 -265.813976) (xy 31.876746 -265.809993) (xy 31.929896 -265.813976) (xy 31.981858 -265.825836)
			(xy 32.031472 -265.845308) (xy 32.07763 -265.871957) (xy 32.119301 -265.905188) (xy 32.155553 -265.944259)
			(xy 32.185577 -265.988296) (xy 32.208703 -266.036317) (xy 32.224413 -266.087247) (xy 32.232356 -266.139951)
			(xy 32.232854 -266.1666) (xy 32.232356 -266.193249) (xy 46.608736 -266.193249) (xy 46.608736 -266.139951)
			(xy 46.616679 -266.087247) (xy 46.632389 -266.036317) (xy 46.655515 -265.988296) (xy 46.685539 -265.944259)
			(xy 46.721791 -265.905188) (xy 46.763462 -265.871957) (xy 46.80962 -265.845308) (xy 46.859234 -265.825836)
			(xy 46.911196 -265.813976) (xy 46.964346 -265.809993) (xy 47.017496 -265.813976) (xy 47.069458 -265.825836)
			(xy 47.119072 -265.845308) (xy 47.16523 -265.871957) (xy 47.206901 -265.905188) (xy 47.243153 -265.944259)
			(xy 47.273177 -265.988296) (xy 47.296303 -266.036317) (xy 47.312013 -266.087247) (xy 47.319956 -266.139951)
			(xy 47.320454 -266.1666) (xy 47.319956 -266.193249) (xy 47.312013 -266.245953) (xy 47.296303 -266.296883)
			(xy 47.273177 -266.344904) (xy 47.243153 -266.388941) (xy 47.206901 -266.428012) (xy 47.16523 -266.461243)
			(xy 47.119072 -266.487892) (xy 47.069458 -266.507364) (xy 47.017496 -266.519224) (xy 46.964346 -266.523208)
			(xy 46.911196 -266.519224) (xy 46.859234 -266.507364) (xy 46.80962 -266.487892) (xy 46.763462 -266.461243)
			(xy 46.721791 -266.428012) (xy 46.685539 -266.388941) (xy 46.655515 -266.344904) (xy 46.632389 -266.296883)
			(xy 46.616679 -266.245953) (xy 46.608736 -266.193249) (xy 32.232356 -266.193249) (xy 32.224413 -266.245953)
			(xy 32.208703 -266.296883) (xy 32.185577 -266.344904) (xy 32.155553 -266.388941) (xy 32.119301 -266.428012)
			(xy 32.07763 -266.461243) (xy 32.031472 -266.487892) (xy 31.981858 -266.507364) (xy 31.929896 -266.519224)
			(xy 31.876746 -266.523208) (xy 31.823596 -266.519224) (xy 31.771634 -266.507364) (xy 31.72202 -266.487892)
			(xy 31.675862 -266.461243) (xy 31.634191 -266.428012) (xy 31.597939 -266.388941) (xy 31.567915 -266.344904)
			(xy 31.544789 -266.296883) (xy 31.529079 -266.245953) (xy 31.521136 -266.193249) (xy 17.144756 -266.193249)
			(xy 17.136813 -266.245953) (xy 17.121103 -266.296883) (xy 17.097977 -266.344904) (xy 17.067953 -266.388941)
			(xy 17.031701 -266.428012) (xy 16.99003 -266.461243) (xy 16.943872 -266.487892) (xy 16.894258 -266.507364)
			(xy 16.842296 -266.519224) (xy 16.789146 -266.523208) (xy 16.735996 -266.519224) (xy 16.684034 -266.507364)
			(xy 16.63442 -266.487892) (xy 16.588262 -266.461243) (xy 16.546591 -266.428012) (xy 16.510339 -266.388941)
			(xy 16.480315 -266.344904) (xy 16.457189 -266.296883) (xy 16.441479 -266.245953) (xy 16.433536 -266.193249)
			(xy 6.7818 -266.193249) (xy 6.7818 -267.043387) (xy 12.989804 -267.043387) (xy 12.989804 -266.990089)
			(xy 12.997747 -266.937385) (xy 13.013457 -266.886455) (xy 13.036583 -266.838434) (xy 13.066607 -266.794397)
			(xy 13.102859 -266.755326) (xy 13.14453 -266.722095) (xy 13.190688 -266.695446) (xy 13.240302 -266.675974)
			(xy 13.292264 -266.664114) (xy 13.345414 -266.660131) (xy 13.398564 -266.664114) (xy 13.450526 -266.675974)
			(xy 13.50014 -266.695446) (xy 13.546298 -266.722095) (xy 13.587969 -266.755326) (xy 13.624221 -266.794397)
			(xy 13.654245 -266.838434) (xy 13.677371 -266.886455) (xy 13.693081 -266.937385) (xy 13.701024 -266.990089)
			(xy 13.701522 -267.016738) (xy 13.701024 -267.043387) (xy 20.533604 -267.043387) (xy 20.533604 -266.990089)
			(xy 20.541547 -266.937385) (xy 20.557257 -266.886455) (xy 20.580383 -266.838434) (xy 20.610407 -266.794397)
			(xy 20.646659 -266.755326) (xy 20.68833 -266.722095) (xy 20.734488 -266.695446) (xy 20.784102 -266.675974)
			(xy 20.836064 -266.664114) (xy 20.889214 -266.660131) (xy 20.942364 -266.664114) (xy 20.994326 -266.675974)
			(xy 21.04394 -266.695446) (xy 21.090098 -266.722095) (xy 21.131769 -266.755326) (xy 21.168021 -266.794397)
			(xy 21.198045 -266.838434) (xy 21.221171 -266.886455) (xy 21.236881 -266.937385) (xy 21.244824 -266.990089)
			(xy 21.245322 -267.016738) (xy 21.244824 -267.043387) (xy 28.077404 -267.043387) (xy 28.077404 -266.990089)
			(xy 28.085347 -266.937385) (xy 28.101057 -266.886455) (xy 28.124183 -266.838434) (xy 28.154207 -266.794397)
			(xy 28.190459 -266.755326) (xy 28.23213 -266.722095) (xy 28.278288 -266.695446) (xy 28.327902 -266.675974)
			(xy 28.379864 -266.664114) (xy 28.433014 -266.660131) (xy 28.486164 -266.664114) (xy 28.538126 -266.675974)
			(xy 28.58774 -266.695446) (xy 28.633898 -266.722095) (xy 28.675569 -266.755326) (xy 28.711821 -266.794397)
			(xy 28.741845 -266.838434) (xy 28.764971 -266.886455) (xy 28.780681 -266.937385) (xy 28.788624 -266.990089)
			(xy 28.789122 -267.016738) (xy 28.788624 -267.043387) (xy 35.621204 -267.043387) (xy 35.621204 -266.990089)
			(xy 35.629147 -266.937385) (xy 35.644857 -266.886455) (xy 35.667983 -266.838434) (xy 35.698007 -266.794397)
			(xy 35.734259 -266.755326) (xy 35.77593 -266.722095) (xy 35.822088 -266.695446) (xy 35.871702 -266.675974)
			(xy 35.923664 -266.664114) (xy 35.976814 -266.660131) (xy 36.029964 -266.664114) (xy 36.081926 -266.675974)
			(xy 36.13154 -266.695446) (xy 36.177698 -266.722095) (xy 36.219369 -266.755326) (xy 36.255621 -266.794397)
			(xy 36.285645 -266.838434) (xy 36.308771 -266.886455) (xy 36.324481 -266.937385) (xy 36.332424 -266.990089)
			(xy 36.332922 -267.016738) (xy 36.332424 -267.043387) (xy 43.165004 -267.043387) (xy 43.165004 -266.990089)
			(xy 43.172947 -266.937385) (xy 43.188657 -266.886455) (xy 43.211783 -266.838434) (xy 43.241807 -266.794397)
			(xy 43.278059 -266.755326) (xy 43.31973 -266.722095) (xy 43.365888 -266.695446) (xy 43.415502 -266.675974)
			(xy 43.467464 -266.664114) (xy 43.520614 -266.660131) (xy 43.573764 -266.664114) (xy 43.625726 -266.675974)
			(xy 43.67534 -266.695446) (xy 43.721498 -266.722095) (xy 43.763169 -266.755326) (xy 43.799421 -266.794397)
			(xy 43.829445 -266.838434) (xy 43.852571 -266.886455) (xy 43.868281 -266.937385) (xy 43.876224 -266.990089)
			(xy 43.876722 -267.016738) (xy 43.876224 -267.043387) (xy 50.734204 -267.043387) (xy 50.734204 -266.990089)
			(xy 50.742147 -266.937385) (xy 50.757857 -266.886455) (xy 50.780983 -266.838434) (xy 50.811007 -266.794397)
			(xy 50.847259 -266.755326) (xy 50.88893 -266.722095) (xy 50.935088 -266.695446) (xy 50.984702 -266.675974)
			(xy 51.036664 -266.664114) (xy 51.089814 -266.660131) (xy 51.142964 -266.664114) (xy 51.194926 -266.675974)
			(xy 51.24454 -266.695446) (xy 51.290698 -266.722095) (xy 51.332369 -266.755326) (xy 51.368621 -266.794397)
			(xy 51.398645 -266.838434) (xy 51.421771 -266.886455) (xy 51.437481 -266.937385) (xy 51.445424 -266.990089)
			(xy 51.445922 -267.016738) (xy 51.445424 -267.043387) (xy 51.437481 -267.096091) (xy 51.421771 -267.147021)
			(xy 51.398645 -267.195042) (xy 51.368621 -267.239079) (xy 51.332369 -267.27815) (xy 51.290698 -267.311381)
			(xy 51.24454 -267.33803) (xy 51.194926 -267.357502) (xy 51.142964 -267.369362) (xy 51.089814 -267.373346)
			(xy 51.036664 -267.369362) (xy 50.984702 -267.357502) (xy 50.935088 -267.33803) (xy 50.88893 -267.311381)
			(xy 50.847259 -267.27815) (xy 50.811007 -267.239079) (xy 50.780983 -267.195042) (xy 50.757857 -267.147021)
			(xy 50.742147 -267.096091) (xy 50.734204 -267.043387) (xy 43.876224 -267.043387) (xy 43.868281 -267.096091)
			(xy 43.852571 -267.147021) (xy 43.829445 -267.195042) (xy 43.799421 -267.239079) (xy 43.763169 -267.27815)
			(xy 43.721498 -267.311381) (xy 43.67534 -267.33803) (xy 43.625726 -267.357502) (xy 43.573764 -267.369362)
			(xy 43.520614 -267.373346) (xy 43.467464 -267.369362) (xy 43.415502 -267.357502) (xy 43.365888 -267.33803)
			(xy 43.31973 -267.311381) (xy 43.278059 -267.27815) (xy 43.241807 -267.239079) (xy 43.211783 -267.195042)
			(xy 43.188657 -267.147021) (xy 43.172947 -267.096091) (xy 43.165004 -267.043387) (xy 36.332424 -267.043387)
			(xy 36.324481 -267.096091) (xy 36.308771 -267.147021) (xy 36.285645 -267.195042) (xy 36.255621 -267.239079)
			(xy 36.219369 -267.27815) (xy 36.177698 -267.311381) (xy 36.13154 -267.33803) (xy 36.081926 -267.357502)
			(xy 36.029964 -267.369362) (xy 35.976814 -267.373346) (xy 35.923664 -267.369362) (xy 35.871702 -267.357502)
			(xy 35.822088 -267.33803) (xy 35.77593 -267.311381) (xy 35.734259 -267.27815) (xy 35.698007 -267.239079)
			(xy 35.667983 -267.195042) (xy 35.644857 -267.147021) (xy 35.629147 -267.096091) (xy 35.621204 -267.043387)
			(xy 28.788624 -267.043387) (xy 28.780681 -267.096091) (xy 28.764971 -267.147021) (xy 28.741845 -267.195042)
			(xy 28.711821 -267.239079) (xy 28.675569 -267.27815) (xy 28.633898 -267.311381) (xy 28.58774 -267.33803)
			(xy 28.538126 -267.357502) (xy 28.486164 -267.369362) (xy 28.433014 -267.373346) (xy 28.379864 -267.369362)
			(xy 28.327902 -267.357502) (xy 28.278288 -267.33803) (xy 28.23213 -267.311381) (xy 28.190459 -267.27815)
			(xy 28.154207 -267.239079) (xy 28.124183 -267.195042) (xy 28.101057 -267.147021) (xy 28.085347 -267.096091)
			(xy 28.077404 -267.043387) (xy 21.244824 -267.043387) (xy 21.236881 -267.096091) (xy 21.221171 -267.147021)
			(xy 21.198045 -267.195042) (xy 21.168021 -267.239079) (xy 21.131769 -267.27815) (xy 21.090098 -267.311381)
			(xy 21.04394 -267.33803) (xy 20.994326 -267.357502) (xy 20.942364 -267.369362) (xy 20.889214 -267.373346)
			(xy 20.836064 -267.369362) (xy 20.784102 -267.357502) (xy 20.734488 -267.33803) (xy 20.68833 -267.311381)
			(xy 20.646659 -267.27815) (xy 20.610407 -267.239079) (xy 20.580383 -267.195042) (xy 20.557257 -267.147021)
			(xy 20.541547 -267.096091) (xy 20.533604 -267.043387) (xy 13.701024 -267.043387) (xy 13.693081 -267.096091)
			(xy 13.677371 -267.147021) (xy 13.654245 -267.195042) (xy 13.624221 -267.239079) (xy 13.587969 -267.27815)
			(xy 13.546298 -267.311381) (xy 13.50014 -267.33803) (xy 13.450526 -267.357502) (xy 13.398564 -267.369362)
			(xy 13.345414 -267.373346) (xy 13.292264 -267.369362) (xy 13.240302 -267.357502) (xy 13.190688 -267.33803)
			(xy 13.14453 -267.311381) (xy 13.102859 -267.27815) (xy 13.066607 -267.239079) (xy 13.036583 -267.195042)
			(xy 13.013457 -267.147021) (xy 12.997747 -267.096091) (xy 12.989804 -267.043387) (xy 6.7818 -267.043387)
			(xy 6.7818 -267.893271) (xy 8.889736 -267.893271) (xy 8.889736 -267.839973) (xy 8.897679 -267.787269)
			(xy 8.913389 -267.736339) (xy 8.936515 -267.688318) (xy 8.966539 -267.644281) (xy 9.002791 -267.60521)
			(xy 9.044462 -267.571979) (xy 9.09062 -267.54533) (xy 9.140234 -267.525858) (xy 9.192196 -267.513998)
			(xy 9.245346 -267.510015) (xy 9.298496 -267.513998) (xy 9.350458 -267.525858) (xy 9.400072 -267.54533)
			(xy 9.44623 -267.571979) (xy 9.487901 -267.60521) (xy 9.524153 -267.644281) (xy 9.554177 -267.688318)
			(xy 9.577303 -267.736339) (xy 9.593013 -267.787269) (xy 9.600956 -267.839973) (xy 9.601454 -267.866622)
			(xy 9.600956 -267.893271) (xy 16.433536 -267.893271) (xy 16.433536 -267.839973) (xy 16.441479 -267.787269)
			(xy 16.457189 -267.736339) (xy 16.480315 -267.688318) (xy 16.510339 -267.644281) (xy 16.546591 -267.60521)
			(xy 16.588262 -267.571979) (xy 16.63442 -267.54533) (xy 16.684034 -267.525858) (xy 16.735996 -267.513998)
			(xy 16.789146 -267.510015) (xy 16.842296 -267.513998) (xy 16.894258 -267.525858) (xy 16.943872 -267.54533)
			(xy 16.99003 -267.571979) (xy 17.031701 -267.60521) (xy 17.067953 -267.644281) (xy 17.097977 -267.688318)
			(xy 17.121103 -267.736339) (xy 17.136813 -267.787269) (xy 17.144756 -267.839973) (xy 17.145254 -267.866622)
			(xy 17.144756 -267.893271) (xy 23.977336 -267.893271) (xy 23.977336 -267.839973) (xy 23.985279 -267.787269)
			(xy 24.000989 -267.736339) (xy 24.024115 -267.688318) (xy 24.054139 -267.644281) (xy 24.090391 -267.60521)
			(xy 24.132062 -267.571979) (xy 24.17822 -267.54533) (xy 24.227834 -267.525858) (xy 24.279796 -267.513998)
			(xy 24.332946 -267.510015) (xy 24.386096 -267.513998) (xy 24.438058 -267.525858) (xy 24.487672 -267.54533)
			(xy 24.53383 -267.571979) (xy 24.575501 -267.60521) (xy 24.611753 -267.644281) (xy 24.641777 -267.688318)
			(xy 24.664903 -267.736339) (xy 24.680613 -267.787269) (xy 24.688556 -267.839973) (xy 24.689054 -267.866622)
			(xy 24.688556 -267.893271) (xy 31.521136 -267.893271) (xy 31.521136 -267.839973) (xy 31.529079 -267.787269)
			(xy 31.544789 -267.736339) (xy 31.567915 -267.688318) (xy 31.597939 -267.644281) (xy 31.634191 -267.60521)
			(xy 31.675862 -267.571979) (xy 31.72202 -267.54533) (xy 31.771634 -267.525858) (xy 31.823596 -267.513998)
			(xy 31.876746 -267.510015) (xy 31.929896 -267.513998) (xy 31.981858 -267.525858) (xy 32.031472 -267.54533)
			(xy 32.07763 -267.571979) (xy 32.119301 -267.60521) (xy 32.155553 -267.644281) (xy 32.185577 -267.688318)
			(xy 32.208703 -267.736339) (xy 32.224413 -267.787269) (xy 32.232356 -267.839973) (xy 32.232854 -267.866622)
			(xy 32.232356 -267.893271) (xy 39.064936 -267.893271) (xy 39.064936 -267.839973) (xy 39.072879 -267.787269)
			(xy 39.088589 -267.736339) (xy 39.111715 -267.688318) (xy 39.141739 -267.644281) (xy 39.177991 -267.60521)
			(xy 39.219662 -267.571979) (xy 39.26582 -267.54533) (xy 39.315434 -267.525858) (xy 39.367396 -267.513998)
			(xy 39.420546 -267.510015) (xy 39.473696 -267.513998) (xy 39.525658 -267.525858) (xy 39.575272 -267.54533)
			(xy 39.62143 -267.571979) (xy 39.663101 -267.60521) (xy 39.699353 -267.644281) (xy 39.729377 -267.688318)
			(xy 39.752503 -267.736339) (xy 39.768213 -267.787269) (xy 39.776156 -267.839973) (xy 39.776654 -267.866622)
			(xy 39.776156 -267.893271) (xy 46.608736 -267.893271) (xy 46.608736 -267.839973) (xy 46.616679 -267.787269)
			(xy 46.632389 -267.736339) (xy 46.655515 -267.688318) (xy 46.685539 -267.644281) (xy 46.721791 -267.60521)
			(xy 46.763462 -267.571979) (xy 46.80962 -267.54533) (xy 46.859234 -267.525858) (xy 46.911196 -267.513998)
			(xy 46.964346 -267.510015) (xy 47.017496 -267.513998) (xy 47.069458 -267.525858) (xy 47.119072 -267.54533)
			(xy 47.16523 -267.571979) (xy 47.206901 -267.60521) (xy 47.243153 -267.644281) (xy 47.273177 -267.688318)
			(xy 47.296303 -267.736339) (xy 47.312013 -267.787269) (xy 47.319956 -267.839973) (xy 47.320454 -267.866622)
			(xy 47.319956 -267.893271) (xy 47.312013 -267.945975) (xy 47.296303 -267.996905) (xy 47.273177 -268.044926)
			(xy 47.243153 -268.088963) (xy 47.206901 -268.128034) (xy 47.16523 -268.161265) (xy 47.119072 -268.187914)
			(xy 47.069458 -268.207386) (xy 47.017496 -268.219246) (xy 46.964346 -268.22323) (xy 46.911196 -268.219246)
			(xy 46.859234 -268.207386) (xy 46.80962 -268.187914) (xy 46.763462 -268.161265) (xy 46.721791 -268.128034)
			(xy 46.685539 -268.088963) (xy 46.655515 -268.044926) (xy 46.632389 -267.996905) (xy 46.616679 -267.945975)
			(xy 46.608736 -267.893271) (xy 39.776156 -267.893271) (xy 39.768213 -267.945975) (xy 39.752503 -267.996905)
			(xy 39.729377 -268.044926) (xy 39.699353 -268.088963) (xy 39.663101 -268.128034) (xy 39.62143 -268.161265)
			(xy 39.575272 -268.187914) (xy 39.525658 -268.207386) (xy 39.473696 -268.219246) (xy 39.420546 -268.22323)
			(xy 39.367396 -268.219246) (xy 39.315434 -268.207386) (xy 39.26582 -268.187914) (xy 39.219662 -268.161265)
			(xy 39.177991 -268.128034) (xy 39.141739 -268.088963) (xy 39.111715 -268.044926) (xy 39.088589 -267.996905)
			(xy 39.072879 -267.945975) (xy 39.064936 -267.893271) (xy 32.232356 -267.893271) (xy 32.224413 -267.945975)
			(xy 32.208703 -267.996905) (xy 32.185577 -268.044926) (xy 32.155553 -268.088963) (xy 32.119301 -268.128034)
			(xy 32.07763 -268.161265) (xy 32.031472 -268.187914) (xy 31.981858 -268.207386) (xy 31.929896 -268.219246)
			(xy 31.876746 -268.22323) (xy 31.823596 -268.219246) (xy 31.771634 -268.207386) (xy 31.72202 -268.187914)
			(xy 31.675862 -268.161265) (xy 31.634191 -268.128034) (xy 31.597939 -268.088963) (xy 31.567915 -268.044926)
			(xy 31.544789 -267.996905) (xy 31.529079 -267.945975) (xy 31.521136 -267.893271) (xy 24.688556 -267.893271)
			(xy 24.680613 -267.945975) (xy 24.664903 -267.996905) (xy 24.641777 -268.044926) (xy 24.611753 -268.088963)
			(xy 24.575501 -268.128034) (xy 24.53383 -268.161265) (xy 24.487672 -268.187914) (xy 24.438058 -268.207386)
			(xy 24.386096 -268.219246) (xy 24.332946 -268.22323) (xy 24.279796 -268.219246) (xy 24.227834 -268.207386)
			(xy 24.17822 -268.187914) (xy 24.132062 -268.161265) (xy 24.090391 -268.128034) (xy 24.054139 -268.088963)
			(xy 24.024115 -268.044926) (xy 24.000989 -267.996905) (xy 23.985279 -267.945975) (xy 23.977336 -267.893271)
			(xy 17.144756 -267.893271) (xy 17.136813 -267.945975) (xy 17.121103 -267.996905) (xy 17.097977 -268.044926)
			(xy 17.067953 -268.088963) (xy 17.031701 -268.128034) (xy 16.99003 -268.161265) (xy 16.943872 -268.187914)
			(xy 16.894258 -268.207386) (xy 16.842296 -268.219246) (xy 16.789146 -268.22323) (xy 16.735996 -268.219246)
			(xy 16.684034 -268.207386) (xy 16.63442 -268.187914) (xy 16.588262 -268.161265) (xy 16.546591 -268.128034)
			(xy 16.510339 -268.088963) (xy 16.480315 -268.044926) (xy 16.457189 -267.996905) (xy 16.441479 -267.945975)
			(xy 16.433536 -267.893271) (xy 9.600956 -267.893271) (xy 9.593013 -267.945975) (xy 9.577303 -267.996905)
			(xy 9.554177 -268.044926) (xy 9.524153 -268.088963) (xy 9.487901 -268.128034) (xy 9.44623 -268.161265)
			(xy 9.400072 -268.187914) (xy 9.350458 -268.207386) (xy 9.298496 -268.219246) (xy 9.245346 -268.22323)
			(xy 9.192196 -268.219246) (xy 9.140234 -268.207386) (xy 9.09062 -268.187914) (xy 9.044462 -268.161265)
			(xy 9.002791 -268.128034) (xy 8.966539 -268.088963) (xy 8.936515 -268.044926) (xy 8.913389 -267.996905)
			(xy 8.897679 -267.945975) (xy 8.889736 -267.893271) (xy 6.7818 -267.893271) (xy 6.7818 -268.743409)
			(xy 35.621204 -268.743409) (xy 35.621204 -268.690111) (xy 35.629147 -268.637407) (xy 35.644857 -268.586477)
			(xy 35.667983 -268.538456) (xy 35.698007 -268.494419) (xy 35.734259 -268.455348) (xy 35.77593 -268.422117)
			(xy 35.822088 -268.395468) (xy 35.871702 -268.375996) (xy 35.923664 -268.364136) (xy 35.976814 -268.360153)
			(xy 36.029964 -268.364136) (xy 36.081926 -268.375996) (xy 36.13154 -268.395468) (xy 36.177698 -268.422117)
			(xy 36.219369 -268.455348) (xy 36.255621 -268.494419) (xy 36.285645 -268.538456) (xy 36.308771 -268.586477)
			(xy 36.324481 -268.637407) (xy 36.332424 -268.690111) (xy 36.332922 -268.71676) (xy 36.332424 -268.743409)
			(xy 36.324481 -268.796113) (xy 36.308771 -268.847043) (xy 36.285645 -268.895064) (xy 36.255621 -268.939101)
			(xy 36.219369 -268.978172) (xy 36.177698 -269.011403) (xy 36.13154 -269.038052) (xy 36.081926 -269.057524)
			(xy 36.029964 -269.069384) (xy 35.976814 -269.073368) (xy 35.923664 -269.069384) (xy 35.871702 -269.057524)
			(xy 35.822088 -269.038052) (xy 35.77593 -269.011403) (xy 35.734259 -268.978172) (xy 35.698007 -268.939101)
			(xy 35.667983 -268.895064) (xy 35.644857 -268.847043) (xy 35.629147 -268.796113) (xy 35.621204 -268.743409)
			(xy 6.7818 -268.743409) (xy 6.7818 -269.593293) (xy 16.433536 -269.593293) (xy 16.433536 -269.539995)
			(xy 16.441479 -269.487291) (xy 16.457189 -269.436361) (xy 16.480315 -269.38834) (xy 16.510339 -269.344303)
			(xy 16.546591 -269.305232) (xy 16.588262 -269.272001) (xy 16.63442 -269.245352) (xy 16.684034 -269.22588)
			(xy 16.735996 -269.21402) (xy 16.789146 -269.210037) (xy 16.842296 -269.21402) (xy 16.894258 -269.22588)
			(xy 16.943872 -269.245352) (xy 16.99003 -269.272001) (xy 17.031701 -269.305232) (xy 17.067953 -269.344303)
			(xy 17.097977 -269.38834) (xy 17.121103 -269.436361) (xy 17.136813 -269.487291) (xy 17.144756 -269.539995)
			(xy 17.145254 -269.566644) (xy 17.144756 -269.593293) (xy 31.521136 -269.593293) (xy 31.521136 -269.539995)
			(xy 31.529079 -269.487291) (xy 31.544789 -269.436361) (xy 31.567915 -269.38834) (xy 31.597939 -269.344303)
			(xy 31.634191 -269.305232) (xy 31.675862 -269.272001) (xy 31.72202 -269.245352) (xy 31.771634 -269.22588)
			(xy 31.823596 -269.21402) (xy 31.876746 -269.210037) (xy 31.929896 -269.21402) (xy 31.981858 -269.22588)
			(xy 32.031472 -269.245352) (xy 32.07763 -269.272001) (xy 32.119301 -269.305232) (xy 32.155553 -269.344303)
			(xy 32.185577 -269.38834) (xy 32.208703 -269.436361) (xy 32.224413 -269.487291) (xy 32.232356 -269.539995)
			(xy 32.232854 -269.566644) (xy 32.232356 -269.593293) (xy 46.608736 -269.593293) (xy 46.608736 -269.539995)
			(xy 46.616679 -269.487291) (xy 46.632389 -269.436361) (xy 46.655515 -269.38834) (xy 46.685539 -269.344303)
			(xy 46.721791 -269.305232) (xy 46.763462 -269.272001) (xy 46.80962 -269.245352) (xy 46.859234 -269.22588)
			(xy 46.911196 -269.21402) (xy 46.964346 -269.210037) (xy 47.017496 -269.21402) (xy 47.069458 -269.22588)
			(xy 47.119072 -269.245352) (xy 47.16523 -269.272001) (xy 47.206901 -269.305232) (xy 47.243153 -269.344303)
			(xy 47.273177 -269.38834) (xy 47.296303 -269.436361) (xy 47.312013 -269.487291) (xy 47.319956 -269.539995)
			(xy 47.320454 -269.566644) (xy 47.319956 -269.593293) (xy 61.696336 -269.593293) (xy 61.696336 -269.539995)
			(xy 61.704279 -269.487291) (xy 61.719989 -269.436361) (xy 61.743115 -269.38834) (xy 61.773139 -269.344303)
			(xy 61.809391 -269.305232) (xy 61.851062 -269.272001) (xy 61.89722 -269.245352) (xy 61.946834 -269.22588)
			(xy 61.998796 -269.21402) (xy 62.051946 -269.210037) (xy 62.105096 -269.21402) (xy 62.157058 -269.22588)
			(xy 62.206672 -269.245352) (xy 62.25283 -269.272001) (xy 62.294501 -269.305232) (xy 62.330753 -269.344303)
			(xy 62.360777 -269.38834) (xy 62.383903 -269.436361) (xy 62.399613 -269.487291) (xy 62.407556 -269.539995)
			(xy 62.408054 -269.566644) (xy 62.407556 -269.593293) (xy 62.399613 -269.645997) (xy 62.383903 -269.696927)
			(xy 62.360777 -269.744948) (xy 62.330753 -269.788985) (xy 62.294501 -269.828056) (xy 62.25283 -269.861287)
			(xy 62.206672 -269.887936) (xy 62.157058 -269.907408) (xy 62.105096 -269.919268) (xy 62.051946 -269.923252)
			(xy 61.998796 -269.919268) (xy 61.946834 -269.907408) (xy 61.89722 -269.887936) (xy 61.851062 -269.861287)
			(xy 61.809391 -269.828056) (xy 61.773139 -269.788985) (xy 61.743115 -269.744948) (xy 61.719989 -269.696927)
			(xy 61.704279 -269.645997) (xy 61.696336 -269.593293) (xy 47.319956 -269.593293) (xy 47.312013 -269.645997)
			(xy 47.296303 -269.696927) (xy 47.273177 -269.744948) (xy 47.243153 -269.788985) (xy 47.206901 -269.828056)
			(xy 47.16523 -269.861287) (xy 47.119072 -269.887936) (xy 47.069458 -269.907408) (xy 47.017496 -269.919268)
			(xy 46.964346 -269.923252) (xy 46.911196 -269.919268) (xy 46.859234 -269.907408) (xy 46.80962 -269.887936)
			(xy 46.763462 -269.861287) (xy 46.721791 -269.828056) (xy 46.685539 -269.788985) (xy 46.655515 -269.744948)
			(xy 46.632389 -269.696927) (xy 46.616679 -269.645997) (xy 46.608736 -269.593293) (xy 32.232356 -269.593293)
			(xy 32.224413 -269.645997) (xy 32.208703 -269.696927) (xy 32.185577 -269.744948) (xy 32.155553 -269.788985)
			(xy 32.119301 -269.828056) (xy 32.07763 -269.861287) (xy 32.031472 -269.887936) (xy 31.981858 -269.907408)
			(xy 31.929896 -269.919268) (xy 31.876746 -269.923252) (xy 31.823596 -269.919268) (xy 31.771634 -269.907408)
			(xy 31.72202 -269.887936) (xy 31.675862 -269.861287) (xy 31.634191 -269.828056) (xy 31.597939 -269.788985)
			(xy 31.567915 -269.744948) (xy 31.544789 -269.696927) (xy 31.529079 -269.645997) (xy 31.521136 -269.593293)
			(xy 17.144756 -269.593293) (xy 17.136813 -269.645997) (xy 17.121103 -269.696927) (xy 17.097977 -269.744948)
			(xy 17.067953 -269.788985) (xy 17.031701 -269.828056) (xy 16.99003 -269.861287) (xy 16.943872 -269.887936)
			(xy 16.894258 -269.907408) (xy 16.842296 -269.919268) (xy 16.789146 -269.923252) (xy 16.735996 -269.919268)
			(xy 16.684034 -269.907408) (xy 16.63442 -269.887936) (xy 16.588262 -269.861287) (xy 16.546591 -269.828056)
			(xy 16.510339 -269.788985) (xy 16.480315 -269.744948) (xy 16.457189 -269.696927) (xy 16.441479 -269.645997)
			(xy 16.433536 -269.593293) (xy 6.7818 -269.593293) (xy 6.7818 -270.443431) (xy 20.533604 -270.443431)
			(xy 20.533604 -270.390133) (xy 20.541547 -270.337429) (xy 20.557257 -270.286499) (xy 20.580383 -270.238478)
			(xy 20.610407 -270.194441) (xy 20.646659 -270.15537) (xy 20.68833 -270.122139) (xy 20.734488 -270.09549)
			(xy 20.784102 -270.076018) (xy 20.836064 -270.064158) (xy 20.889214 -270.060175) (xy 20.942364 -270.064158)
			(xy 20.994326 -270.076018) (xy 21.04394 -270.09549) (xy 21.090098 -270.122139) (xy 21.131769 -270.15537)
			(xy 21.168021 -270.194441) (xy 21.198045 -270.238478) (xy 21.221171 -270.286499) (xy 21.236881 -270.337429)
			(xy 21.244824 -270.390133) (xy 21.245322 -270.416782) (xy 21.244824 -270.443431) (xy 35.621204 -270.443431)
			(xy 35.621204 -270.390133) (xy 35.629147 -270.337429) (xy 35.644857 -270.286499) (xy 35.667983 -270.238478)
			(xy 35.698007 -270.194441) (xy 35.734259 -270.15537) (xy 35.77593 -270.122139) (xy 35.822088 -270.09549)
			(xy 35.871702 -270.076018) (xy 35.923664 -270.064158) (xy 35.976814 -270.060175) (xy 36.029964 -270.064158)
			(xy 36.081926 -270.076018) (xy 36.13154 -270.09549) (xy 36.177698 -270.122139) (xy 36.219369 -270.15537)
			(xy 36.255621 -270.194441) (xy 36.285645 -270.238478) (xy 36.308771 -270.286499) (xy 36.324481 -270.337429)
			(xy 36.332424 -270.390133) (xy 36.332922 -270.416782) (xy 36.332424 -270.443431) (xy 50.734204 -270.443431)
			(xy 50.734204 -270.390133) (xy 50.742147 -270.337429) (xy 50.757857 -270.286499) (xy 50.780983 -270.238478)
			(xy 50.811007 -270.194441) (xy 50.847259 -270.15537) (xy 50.88893 -270.122139) (xy 50.935088 -270.09549)
			(xy 50.984702 -270.076018) (xy 51.036664 -270.064158) (xy 51.089814 -270.060175) (xy 51.142964 -270.064158)
			(xy 51.194926 -270.076018) (xy 51.24454 -270.09549) (xy 51.290698 -270.122139) (xy 51.332369 -270.15537)
			(xy 51.368621 -270.194441) (xy 51.398645 -270.238478) (xy 51.421771 -270.286499) (xy 51.437481 -270.337429)
			(xy 51.445424 -270.390133) (xy 51.445922 -270.416782) (xy 51.445424 -270.443431) (xy 51.437481 -270.496135)
			(xy 51.421771 -270.547065) (xy 51.398645 -270.595086) (xy 51.368621 -270.639123) (xy 51.332369 -270.678194)
			(xy 51.290698 -270.711425) (xy 51.24454 -270.738074) (xy 51.194926 -270.757546) (xy 51.142964 -270.769406)
			(xy 51.089814 -270.77339) (xy 51.036664 -270.769406) (xy 50.984702 -270.757546) (xy 50.935088 -270.738074)
			(xy 50.88893 -270.711425) (xy 50.847259 -270.678194) (xy 50.811007 -270.639123) (xy 50.780983 -270.595086)
			(xy 50.757857 -270.547065) (xy 50.742147 -270.496135) (xy 50.734204 -270.443431) (xy 36.332424 -270.443431)
			(xy 36.324481 -270.496135) (xy 36.308771 -270.547065) (xy 36.285645 -270.595086) (xy 36.255621 -270.639123)
			(xy 36.219369 -270.678194) (xy 36.177698 -270.711425) (xy 36.13154 -270.738074) (xy 36.081926 -270.757546)
			(xy 36.029964 -270.769406) (xy 35.976814 -270.77339) (xy 35.923664 -270.769406) (xy 35.871702 -270.757546)
			(xy 35.822088 -270.738074) (xy 35.77593 -270.711425) (xy 35.734259 -270.678194) (xy 35.698007 -270.639123)
			(xy 35.667983 -270.595086) (xy 35.644857 -270.547065) (xy 35.629147 -270.496135) (xy 35.621204 -270.443431)
			(xy 21.244824 -270.443431) (xy 21.236881 -270.496135) (xy 21.221171 -270.547065) (xy 21.198045 -270.595086)
			(xy 21.168021 -270.639123) (xy 21.131769 -270.678194) (xy 21.090098 -270.711425) (xy 21.04394 -270.738074)
			(xy 20.994326 -270.757546) (xy 20.942364 -270.769406) (xy 20.889214 -270.77339) (xy 20.836064 -270.769406)
			(xy 20.784102 -270.757546) (xy 20.734488 -270.738074) (xy 20.68833 -270.711425) (xy 20.646659 -270.678194)
			(xy 20.610407 -270.639123) (xy 20.580383 -270.595086) (xy 20.557257 -270.547065) (xy 20.541547 -270.496135)
			(xy 20.533604 -270.443431) (xy 6.7818 -270.443431) (xy 6.7818 -271.293315) (xy 16.433536 -271.293315)
			(xy 16.433536 -271.240017) (xy 16.441479 -271.187313) (xy 16.457189 -271.136383) (xy 16.480315 -271.088362)
			(xy 16.510339 -271.044325) (xy 16.546591 -271.005254) (xy 16.588262 -270.972023) (xy 16.63442 -270.945374)
			(xy 16.684034 -270.925902) (xy 16.735996 -270.914042) (xy 16.789146 -270.910059) (xy 16.842296 -270.914042)
			(xy 16.894258 -270.925902) (xy 16.943872 -270.945374) (xy 16.99003 -270.972023) (xy 17.031701 -271.005254)
			(xy 17.067953 -271.044325) (xy 17.097977 -271.088362) (xy 17.121103 -271.136383) (xy 17.136813 -271.187313)
			(xy 17.144756 -271.240017) (xy 17.145254 -271.266666) (xy 17.144756 -271.293315) (xy 31.521136 -271.293315)
			(xy 31.521136 -271.240017) (xy 31.529079 -271.187313) (xy 31.544789 -271.136383) (xy 31.567915 -271.088362)
			(xy 31.597939 -271.044325) (xy 31.634191 -271.005254) (xy 31.675862 -270.972023) (xy 31.72202 -270.945374)
			(xy 31.771634 -270.925902) (xy 31.823596 -270.914042) (xy 31.876746 -270.910059) (xy 31.929896 -270.914042)
			(xy 31.981858 -270.925902) (xy 32.031472 -270.945374) (xy 32.07763 -270.972023) (xy 32.119301 -271.005254)
			(xy 32.155553 -271.044325) (xy 32.185577 -271.088362) (xy 32.208703 -271.136383) (xy 32.224413 -271.187313)
			(xy 32.232356 -271.240017) (xy 32.232854 -271.266666) (xy 32.232356 -271.293315) (xy 46.608736 -271.293315)
			(xy 46.608736 -271.240017) (xy 46.616679 -271.187313) (xy 46.632389 -271.136383) (xy 46.655515 -271.088362)
			(xy 46.685539 -271.044325) (xy 46.721791 -271.005254) (xy 46.763462 -270.972023) (xy 46.80962 -270.945374)
			(xy 46.859234 -270.925902) (xy 46.911196 -270.914042) (xy 46.964346 -270.910059) (xy 47.017496 -270.914042)
			(xy 47.069458 -270.925902) (xy 47.119072 -270.945374) (xy 47.16523 -270.972023) (xy 47.206901 -271.005254)
			(xy 47.243153 -271.044325) (xy 47.273177 -271.088362) (xy 47.296303 -271.136383) (xy 47.312013 -271.187313)
			(xy 47.319956 -271.240017) (xy 47.320454 -271.266666) (xy 47.319956 -271.293315) (xy 47.312013 -271.346019)
			(xy 47.296303 -271.396949) (xy 47.273177 -271.44497) (xy 47.243153 -271.489007) (xy 47.206901 -271.528078)
			(xy 47.16523 -271.561309) (xy 47.119072 -271.587958) (xy 47.069458 -271.60743) (xy 47.017496 -271.61929)
			(xy 46.964346 -271.623274) (xy 46.911196 -271.61929) (xy 46.859234 -271.60743) (xy 46.80962 -271.587958)
			(xy 46.763462 -271.561309) (xy 46.721791 -271.528078) (xy 46.685539 -271.489007) (xy 46.655515 -271.44497)
			(xy 46.632389 -271.396949) (xy 46.616679 -271.346019) (xy 46.608736 -271.293315) (xy 32.232356 -271.293315)
			(xy 32.224413 -271.346019) (xy 32.208703 -271.396949) (xy 32.185577 -271.44497) (xy 32.155553 -271.489007)
			(xy 32.119301 -271.528078) (xy 32.07763 -271.561309) (xy 32.031472 -271.587958) (xy 31.981858 -271.60743)
			(xy 31.929896 -271.61929) (xy 31.876746 -271.623274) (xy 31.823596 -271.61929) (xy 31.771634 -271.60743)
			(xy 31.72202 -271.587958) (xy 31.675862 -271.561309) (xy 31.634191 -271.528078) (xy 31.597939 -271.489007)
			(xy 31.567915 -271.44497) (xy 31.544789 -271.396949) (xy 31.529079 -271.346019) (xy 31.521136 -271.293315)
			(xy 17.144756 -271.293315) (xy 17.136813 -271.346019) (xy 17.121103 -271.396949) (xy 17.097977 -271.44497)
			(xy 17.067953 -271.489007) (xy 17.031701 -271.528078) (xy 16.99003 -271.561309) (xy 16.943872 -271.587958)
			(xy 16.894258 -271.60743) (xy 16.842296 -271.61929) (xy 16.789146 -271.623274) (xy 16.735996 -271.61929)
			(xy 16.684034 -271.60743) (xy 16.63442 -271.587958) (xy 16.588262 -271.561309) (xy 16.546591 -271.528078)
			(xy 16.510339 -271.489007) (xy 16.480315 -271.44497) (xy 16.457189 -271.396949) (xy 16.441479 -271.346019)
			(xy 16.433536 -271.293315) (xy 6.7818 -271.293315) (xy 6.7818 -272.143453) (xy 20.533604 -272.143453)
			(xy 20.533604 -272.090155) (xy 20.541547 -272.037451) (xy 20.557257 -271.986521) (xy 20.580383 -271.9385)
			(xy 20.610407 -271.894463) (xy 20.646659 -271.855392) (xy 20.68833 -271.822161) (xy 20.734488 -271.795512)
			(xy 20.784102 -271.77604) (xy 20.836064 -271.76418) (xy 20.889214 -271.760197) (xy 20.942364 -271.76418)
			(xy 20.994326 -271.77604) (xy 21.04394 -271.795512) (xy 21.090098 -271.822161) (xy 21.131769 -271.855392)
			(xy 21.168021 -271.894463) (xy 21.198045 -271.9385) (xy 21.221171 -271.986521) (xy 21.236881 -272.037451)
			(xy 21.244824 -272.090155) (xy 21.245322 -272.116804) (xy 21.244824 -272.143453) (xy 35.621204 -272.143453)
			(xy 35.621204 -272.090155) (xy 35.629147 -272.037451) (xy 35.644857 -271.986521) (xy 35.667983 -271.9385)
			(xy 35.698007 -271.894463) (xy 35.734259 -271.855392) (xy 35.77593 -271.822161) (xy 35.822088 -271.795512)
			(xy 35.871702 -271.77604) (xy 35.923664 -271.76418) (xy 35.976814 -271.760197) (xy 36.029964 -271.76418)
			(xy 36.081926 -271.77604) (xy 36.13154 -271.795512) (xy 36.177698 -271.822161) (xy 36.219369 -271.855392)
			(xy 36.255621 -271.894463) (xy 36.285645 -271.9385) (xy 36.308771 -271.986521) (xy 36.324481 -272.037451)
			(xy 36.332424 -272.090155) (xy 36.332922 -272.116804) (xy 36.332424 -272.143453) (xy 50.734204 -272.143453)
			(xy 50.734204 -272.090155) (xy 50.742147 -272.037451) (xy 50.757857 -271.986521) (xy 50.780983 -271.9385)
			(xy 50.811007 -271.894463) (xy 50.847259 -271.855392) (xy 50.88893 -271.822161) (xy 50.935088 -271.795512)
			(xy 50.984702 -271.77604) (xy 51.036664 -271.76418) (xy 51.089814 -271.760197) (xy 51.142964 -271.76418)
			(xy 51.194926 -271.77604) (xy 51.24454 -271.795512) (xy 51.290698 -271.822161) (xy 51.332369 -271.855392)
			(xy 51.368621 -271.894463) (xy 51.398645 -271.9385) (xy 51.421771 -271.986521) (xy 51.437481 -272.037451)
			(xy 51.445424 -272.090155) (xy 51.445922 -272.116804) (xy 51.445424 -272.143453) (xy 51.437481 -272.196157)
			(xy 51.421771 -272.247087) (xy 51.398645 -272.295108) (xy 51.368621 -272.339145) (xy 51.332369 -272.378216)
			(xy 51.290698 -272.411447) (xy 51.24454 -272.438096) (xy 51.194926 -272.457568) (xy 51.142964 -272.469428)
			(xy 51.089814 -272.473412) (xy 51.036664 -272.469428) (xy 50.984702 -272.457568) (xy 50.935088 -272.438096)
			(xy 50.88893 -272.411447) (xy 50.847259 -272.378216) (xy 50.811007 -272.339145) (xy 50.780983 -272.295108)
			(xy 50.757857 -272.247087) (xy 50.742147 -272.196157) (xy 50.734204 -272.143453) (xy 36.332424 -272.143453)
			(xy 36.324481 -272.196157) (xy 36.308771 -272.247087) (xy 36.285645 -272.295108) (xy 36.255621 -272.339145)
			(xy 36.219369 -272.378216) (xy 36.177698 -272.411447) (xy 36.13154 -272.438096) (xy 36.081926 -272.457568)
			(xy 36.029964 -272.469428) (xy 35.976814 -272.473412) (xy 35.923664 -272.469428) (xy 35.871702 -272.457568)
			(xy 35.822088 -272.438096) (xy 35.77593 -272.411447) (xy 35.734259 -272.378216) (xy 35.698007 -272.339145)
			(xy 35.667983 -272.295108) (xy 35.644857 -272.247087) (xy 35.629147 -272.196157) (xy 35.621204 -272.143453)
			(xy 21.244824 -272.143453) (xy 21.236881 -272.196157) (xy 21.221171 -272.247087) (xy 21.198045 -272.295108)
			(xy 21.168021 -272.339145) (xy 21.131769 -272.378216) (xy 21.090098 -272.411447) (xy 21.04394 -272.438096)
			(xy 20.994326 -272.457568) (xy 20.942364 -272.469428) (xy 20.889214 -272.473412) (xy 20.836064 -272.469428)
			(xy 20.784102 -272.457568) (xy 20.734488 -272.438096) (xy 20.68833 -272.411447) (xy 20.646659 -272.378216)
			(xy 20.610407 -272.339145) (xy 20.580383 -272.295108) (xy 20.557257 -272.247087) (xy 20.541547 -272.196157)
			(xy 20.533604 -272.143453) (xy 6.7818 -272.143453) (xy 6.7818 -272.993337) (xy 16.433536 -272.993337)
			(xy 16.433536 -272.940039) (xy 16.441479 -272.887335) (xy 16.457189 -272.836405) (xy 16.480315 -272.788384)
			(xy 16.510339 -272.744347) (xy 16.546591 -272.705276) (xy 16.588262 -272.672045) (xy 16.63442 -272.645396)
			(xy 16.684034 -272.625924) (xy 16.735996 -272.614064) (xy 16.789146 -272.610081) (xy 16.842296 -272.614064)
			(xy 16.894258 -272.625924) (xy 16.943872 -272.645396) (xy 16.99003 -272.672045) (xy 17.031701 -272.705276)
			(xy 17.067953 -272.744347) (xy 17.097977 -272.788384) (xy 17.121103 -272.836405) (xy 17.136813 -272.887335)
			(xy 17.144756 -272.940039) (xy 17.145254 -272.966688) (xy 17.144756 -272.993337) (xy 31.521136 -272.993337)
			(xy 31.521136 -272.940039) (xy 31.529079 -272.887335) (xy 31.544789 -272.836405) (xy 31.567915 -272.788384)
			(xy 31.597939 -272.744347) (xy 31.634191 -272.705276) (xy 31.675862 -272.672045) (xy 31.72202 -272.645396)
			(xy 31.771634 -272.625924) (xy 31.823596 -272.614064) (xy 31.876746 -272.610081) (xy 31.929896 -272.614064)
			(xy 31.981858 -272.625924) (xy 32.031472 -272.645396) (xy 32.07763 -272.672045) (xy 32.119301 -272.705276)
			(xy 32.155553 -272.744347) (xy 32.185577 -272.788384) (xy 32.208703 -272.836405) (xy 32.224413 -272.887335)
			(xy 32.232356 -272.940039) (xy 32.232854 -272.966688) (xy 32.232356 -272.993337) (xy 46.608736 -272.993337)
			(xy 46.608736 -272.940039) (xy 46.616679 -272.887335) (xy 46.632389 -272.836405) (xy 46.655515 -272.788384)
			(xy 46.685539 -272.744347) (xy 46.721791 -272.705276) (xy 46.763462 -272.672045) (xy 46.80962 -272.645396)
			(xy 46.859234 -272.625924) (xy 46.911196 -272.614064) (xy 46.964346 -272.610081) (xy 47.017496 -272.614064)
			(xy 47.069458 -272.625924) (xy 47.119072 -272.645396) (xy 47.16523 -272.672045) (xy 47.206901 -272.705276)
			(xy 47.243153 -272.744347) (xy 47.273177 -272.788384) (xy 47.296303 -272.836405) (xy 47.312013 -272.887335)
			(xy 47.319956 -272.940039) (xy 47.320454 -272.966688) (xy 47.319956 -272.993337) (xy 47.312013 -273.046041)
			(xy 47.296303 -273.096971) (xy 47.273177 -273.144992) (xy 47.243153 -273.189029) (xy 47.206901 -273.2281)
			(xy 47.16523 -273.261331) (xy 47.119072 -273.28798) (xy 47.069458 -273.307452) (xy 47.017496 -273.319312)
			(xy 46.964346 -273.323296) (xy 46.911196 -273.319312) (xy 46.859234 -273.307452) (xy 46.80962 -273.28798)
			(xy 46.763462 -273.261331) (xy 46.721791 -273.2281) (xy 46.685539 -273.189029) (xy 46.655515 -273.144992)
			(xy 46.632389 -273.096971) (xy 46.616679 -273.046041) (xy 46.608736 -272.993337) (xy 32.232356 -272.993337)
			(xy 32.224413 -273.046041) (xy 32.208703 -273.096971) (xy 32.185577 -273.144992) (xy 32.155553 -273.189029)
			(xy 32.119301 -273.2281) (xy 32.07763 -273.261331) (xy 32.031472 -273.28798) (xy 31.981858 -273.307452)
			(xy 31.929896 -273.319312) (xy 31.876746 -273.323296) (xy 31.823596 -273.319312) (xy 31.771634 -273.307452)
			(xy 31.72202 -273.28798) (xy 31.675862 -273.261331) (xy 31.634191 -273.2281) (xy 31.597939 -273.189029)
			(xy 31.567915 -273.144992) (xy 31.544789 -273.096971) (xy 31.529079 -273.046041) (xy 31.521136 -272.993337)
			(xy 17.144756 -272.993337) (xy 17.136813 -273.046041) (xy 17.121103 -273.096971) (xy 17.097977 -273.144992)
			(xy 17.067953 -273.189029) (xy 17.031701 -273.2281) (xy 16.99003 -273.261331) (xy 16.943872 -273.28798)
			(xy 16.894258 -273.307452) (xy 16.842296 -273.319312) (xy 16.789146 -273.323296) (xy 16.735996 -273.319312)
			(xy 16.684034 -273.307452) (xy 16.63442 -273.28798) (xy 16.588262 -273.261331) (xy 16.546591 -273.2281)
			(xy 16.510339 -273.189029) (xy 16.480315 -273.144992) (xy 16.457189 -273.096971) (xy 16.441479 -273.046041)
			(xy 16.433536 -272.993337) (xy 6.7818 -272.993337) (xy 6.7818 -273.843221) (xy 20.533604 -273.843221)
			(xy 20.533604 -273.789923) (xy 20.541547 -273.737219) (xy 20.557257 -273.686289) (xy 20.580383 -273.638268)
			(xy 20.610407 -273.594231) (xy 20.646659 -273.55516) (xy 20.68833 -273.521929) (xy 20.734488 -273.49528)
			(xy 20.784102 -273.475808) (xy 20.836064 -273.463948) (xy 20.889214 -273.459965) (xy 20.942364 -273.463948)
			(xy 20.994326 -273.475808) (xy 21.04394 -273.49528) (xy 21.090098 -273.521929) (xy 21.131769 -273.55516)
			(xy 21.168021 -273.594231) (xy 21.198045 -273.638268) (xy 21.221171 -273.686289) (xy 21.236881 -273.737219)
			(xy 21.244824 -273.789923) (xy 21.245322 -273.816572) (xy 21.244824 -273.843221) (xy 35.621204 -273.843221)
			(xy 35.621204 -273.789923) (xy 35.629147 -273.737219) (xy 35.644857 -273.686289) (xy 35.667983 -273.638268)
			(xy 35.698007 -273.594231) (xy 35.734259 -273.55516) (xy 35.77593 -273.521929) (xy 35.822088 -273.49528)
			(xy 35.871702 -273.475808) (xy 35.923664 -273.463948) (xy 35.976814 -273.459965) (xy 36.029964 -273.463948)
			(xy 36.081926 -273.475808) (xy 36.13154 -273.49528) (xy 36.177698 -273.521929) (xy 36.219369 -273.55516)
			(xy 36.255621 -273.594231) (xy 36.285645 -273.638268) (xy 36.308771 -273.686289) (xy 36.324481 -273.737219)
			(xy 36.332424 -273.789923) (xy 36.332922 -273.816572) (xy 36.332424 -273.843221) (xy 50.734204 -273.843221)
			(xy 50.734204 -273.789923) (xy 50.742147 -273.737219) (xy 50.757857 -273.686289) (xy 50.780983 -273.638268)
			(xy 50.811007 -273.594231) (xy 50.847259 -273.55516) (xy 50.88893 -273.521929) (xy 50.935088 -273.49528)
			(xy 50.984702 -273.475808) (xy 51.036664 -273.463948) (xy 51.089814 -273.459965) (xy 51.142964 -273.463948)
			(xy 51.194926 -273.475808) (xy 51.24454 -273.49528) (xy 51.290698 -273.521929) (xy 51.332369 -273.55516)
			(xy 51.368621 -273.594231) (xy 51.398645 -273.638268) (xy 51.421771 -273.686289) (xy 51.437481 -273.737219)
			(xy 51.445424 -273.789923) (xy 51.445922 -273.816572) (xy 51.445424 -273.843221) (xy 51.437481 -273.895925)
			(xy 51.421771 -273.946855) (xy 51.398645 -273.994876) (xy 51.368621 -274.038913) (xy 51.332369 -274.077984)
			(xy 51.290698 -274.111215) (xy 51.24454 -274.137864) (xy 51.194926 -274.157336) (xy 51.142964 -274.169196)
			(xy 51.089814 -274.17318) (xy 51.036664 -274.169196) (xy 50.984702 -274.157336) (xy 50.935088 -274.137864)
			(xy 50.88893 -274.111215) (xy 50.847259 -274.077984) (xy 50.811007 -274.038913) (xy 50.780983 -273.994876)
			(xy 50.757857 -273.946855) (xy 50.742147 -273.895925) (xy 50.734204 -273.843221) (xy 36.332424 -273.843221)
			(xy 36.324481 -273.895925) (xy 36.308771 -273.946855) (xy 36.285645 -273.994876) (xy 36.255621 -274.038913)
			(xy 36.219369 -274.077984) (xy 36.177698 -274.111215) (xy 36.13154 -274.137864) (xy 36.081926 -274.157336)
			(xy 36.029964 -274.169196) (xy 35.976814 -274.17318) (xy 35.923664 -274.169196) (xy 35.871702 -274.157336)
			(xy 35.822088 -274.137864) (xy 35.77593 -274.111215) (xy 35.734259 -274.077984) (xy 35.698007 -274.038913)
			(xy 35.667983 -273.994876) (xy 35.644857 -273.946855) (xy 35.629147 -273.895925) (xy 35.621204 -273.843221)
			(xy 21.244824 -273.843221) (xy 21.236881 -273.895925) (xy 21.221171 -273.946855) (xy 21.198045 -273.994876)
			(xy 21.168021 -274.038913) (xy 21.131769 -274.077984) (xy 21.090098 -274.111215) (xy 21.04394 -274.137864)
			(xy 20.994326 -274.157336) (xy 20.942364 -274.169196) (xy 20.889214 -274.17318) (xy 20.836064 -274.169196)
			(xy 20.784102 -274.157336) (xy 20.734488 -274.137864) (xy 20.68833 -274.111215) (xy 20.646659 -274.077984)
			(xy 20.610407 -274.038913) (xy 20.580383 -273.994876) (xy 20.557257 -273.946855) (xy 20.541547 -273.895925)
			(xy 20.533604 -273.843221) (xy 6.7818 -273.843221) (xy 6.7818 -274.693359) (xy 16.433536 -274.693359)
			(xy 16.433536 -274.640061) (xy 16.441479 -274.587357) (xy 16.457189 -274.536427) (xy 16.480315 -274.488406)
			(xy 16.510339 -274.444369) (xy 16.546591 -274.405298) (xy 16.588262 -274.372067) (xy 16.63442 -274.345418)
			(xy 16.684034 -274.325946) (xy 16.735996 -274.314086) (xy 16.789146 -274.310103) (xy 16.842296 -274.314086)
			(xy 16.894258 -274.325946) (xy 16.943872 -274.345418) (xy 16.99003 -274.372067) (xy 17.031701 -274.405298)
			(xy 17.067953 -274.444369) (xy 17.097977 -274.488406) (xy 17.121103 -274.536427) (xy 17.136813 -274.587357)
			(xy 17.144756 -274.640061) (xy 17.145254 -274.66671) (xy 17.144756 -274.693359) (xy 20.533604 -274.693359)
			(xy 20.533604 -274.640061) (xy 20.541547 -274.587357) (xy 20.557257 -274.536427) (xy 20.580383 -274.488406)
			(xy 20.610407 -274.444369) (xy 20.646659 -274.405298) (xy 20.68833 -274.372067) (xy 20.734488 -274.345418)
			(xy 20.784102 -274.325946) (xy 20.836064 -274.314086) (xy 20.889214 -274.310103) (xy 20.942364 -274.314086)
			(xy 20.994326 -274.325946) (xy 21.04394 -274.345418) (xy 21.090098 -274.372067) (xy 21.131769 -274.405298)
			(xy 21.168021 -274.444369) (xy 21.198045 -274.488406) (xy 21.221171 -274.536427) (xy 21.236881 -274.587357)
			(xy 21.244824 -274.640061) (xy 21.245322 -274.66671) (xy 21.244824 -274.693359) (xy 31.521136 -274.693359)
			(xy 31.521136 -274.640061) (xy 31.529079 -274.587357) (xy 31.544789 -274.536427) (xy 31.567915 -274.488406)
			(xy 31.597939 -274.444369) (xy 31.634191 -274.405298) (xy 31.675862 -274.372067) (xy 31.72202 -274.345418)
			(xy 31.771634 -274.325946) (xy 31.823596 -274.314086) (xy 31.876746 -274.310103) (xy 31.929896 -274.314086)
			(xy 31.981858 -274.325946) (xy 32.031472 -274.345418) (xy 32.07763 -274.372067) (xy 32.119301 -274.405298)
			(xy 32.155553 -274.444369) (xy 32.185577 -274.488406) (xy 32.208703 -274.536427) (xy 32.224413 -274.587357)
			(xy 32.232356 -274.640061) (xy 32.232854 -274.66671) (xy 32.232356 -274.693359) (xy 35.621204 -274.693359)
			(xy 35.621204 -274.640061) (xy 35.629147 -274.587357) (xy 35.644857 -274.536427) (xy 35.667983 -274.488406)
			(xy 35.698007 -274.444369) (xy 35.734259 -274.405298) (xy 35.77593 -274.372067) (xy 35.822088 -274.345418)
			(xy 35.871702 -274.325946) (xy 35.923664 -274.314086) (xy 35.976814 -274.310103) (xy 36.029964 -274.314086)
			(xy 36.081926 -274.325946) (xy 36.13154 -274.345418) (xy 36.177698 -274.372067) (xy 36.219369 -274.405298)
			(xy 36.255621 -274.444369) (xy 36.285645 -274.488406) (xy 36.308771 -274.536427) (xy 36.324481 -274.587357)
			(xy 36.332424 -274.640061) (xy 36.332922 -274.66671) (xy 36.332424 -274.693359) (xy 46.608736 -274.693359)
			(xy 46.608736 -274.640061) (xy 46.616679 -274.587357) (xy 46.632389 -274.536427) (xy 46.655515 -274.488406)
			(xy 46.685539 -274.444369) (xy 46.721791 -274.405298) (xy 46.763462 -274.372067) (xy 46.80962 -274.345418)
			(xy 46.859234 -274.325946) (xy 46.911196 -274.314086) (xy 46.964346 -274.310103) (xy 47.017496 -274.314086)
			(xy 47.069458 -274.325946) (xy 47.119072 -274.345418) (xy 47.16523 -274.372067) (xy 47.206901 -274.405298)
			(xy 47.243153 -274.444369) (xy 47.273177 -274.488406) (xy 47.296303 -274.536427) (xy 47.312013 -274.587357)
			(xy 47.319956 -274.640061) (xy 47.320454 -274.66671) (xy 47.319956 -274.693359) (xy 47.319918 -274.693613)
			(xy 50.734204 -274.693613) (xy 50.734204 -274.640315) (xy 50.742147 -274.587611) (xy 50.757857 -274.536681)
			(xy 50.780983 -274.48866) (xy 50.811007 -274.444623) (xy 50.847259 -274.405552) (xy 50.88893 -274.372321)
			(xy 50.935088 -274.345672) (xy 50.984702 -274.3262) (xy 51.036664 -274.31434) (xy 51.089814 -274.310357)
			(xy 51.142964 -274.31434) (xy 51.194926 -274.3262) (xy 51.24454 -274.345672) (xy 51.290698 -274.372321)
			(xy 51.332369 -274.405552) (xy 51.368621 -274.444623) (xy 51.398645 -274.48866) (xy 51.421771 -274.536681)
			(xy 51.437481 -274.587611) (xy 51.445424 -274.640315) (xy 51.445922 -274.666964) (xy 51.445424 -274.693613)
			(xy 51.437481 -274.746317) (xy 51.421771 -274.797247) (xy 51.398645 -274.845268) (xy 51.368621 -274.889305)
			(xy 51.332369 -274.928376) (xy 51.290698 -274.961607) (xy 51.24454 -274.988256) (xy 51.194926 -275.007728)
			(xy 51.142964 -275.019588) (xy 51.089814 -275.023572) (xy 51.036664 -275.019588) (xy 50.984702 -275.007728)
			(xy 50.935088 -274.988256) (xy 50.88893 -274.961607) (xy 50.847259 -274.928376) (xy 50.811007 -274.889305)
			(xy 50.780983 -274.845268) (xy 50.757857 -274.797247) (xy 50.742147 -274.746317) (xy 50.734204 -274.693613)
			(xy 47.319918 -274.693613) (xy 47.312013 -274.746063) (xy 47.296303 -274.796993) (xy 47.273177 -274.845014)
			(xy 47.243153 -274.889051) (xy 47.206901 -274.928122) (xy 47.16523 -274.961353) (xy 47.119072 -274.988002)
			(xy 47.069458 -275.007474) (xy 47.017496 -275.019334) (xy 46.964346 -275.023318) (xy 46.911196 -275.019334)
			(xy 46.859234 -275.007474) (xy 46.80962 -274.988002) (xy 46.763462 -274.961353) (xy 46.721791 -274.928122)
			(xy 46.685539 -274.889051) (xy 46.655515 -274.845014) (xy 46.632389 -274.796993) (xy 46.616679 -274.746063)
			(xy 46.608736 -274.693359) (xy 36.332424 -274.693359) (xy 36.324481 -274.746063) (xy 36.308771 -274.796993)
			(xy 36.285645 -274.845014) (xy 36.255621 -274.889051) (xy 36.219369 -274.928122) (xy 36.177698 -274.961353)
			(xy 36.13154 -274.988002) (xy 36.081926 -275.007474) (xy 36.029964 -275.019334) (xy 35.976814 -275.023318)
			(xy 35.923664 -275.019334) (xy 35.871702 -275.007474) (xy 35.822088 -274.988002) (xy 35.77593 -274.961353)
			(xy 35.734259 -274.928122) (xy 35.698007 -274.889051) (xy 35.667983 -274.845014) (xy 35.644857 -274.796993)
			(xy 35.629147 -274.746063) (xy 35.621204 -274.693359) (xy 32.232356 -274.693359) (xy 32.224413 -274.746063)
			(xy 32.208703 -274.796993) (xy 32.185577 -274.845014) (xy 32.155553 -274.889051) (xy 32.119301 -274.928122)
			(xy 32.07763 -274.961353) (xy 32.031472 -274.988002) (xy 31.981858 -275.007474) (xy 31.929896 -275.019334)
			(xy 31.876746 -275.023318) (xy 31.823596 -275.019334) (xy 31.771634 -275.007474) (xy 31.72202 -274.988002)
			(xy 31.675862 -274.961353) (xy 31.634191 -274.928122) (xy 31.597939 -274.889051) (xy 31.567915 -274.845014)
			(xy 31.544789 -274.796993) (xy 31.529079 -274.746063) (xy 31.521136 -274.693359) (xy 21.244824 -274.693359)
			(xy 21.236881 -274.746063) (xy 21.221171 -274.796993) (xy 21.198045 -274.845014) (xy 21.168021 -274.889051)
			(xy 21.131769 -274.928122) (xy 21.090098 -274.961353) (xy 21.04394 -274.988002) (xy 20.994326 -275.007474)
			(xy 20.942364 -275.019334) (xy 20.889214 -275.023318) (xy 20.836064 -275.019334) (xy 20.784102 -275.007474)
			(xy 20.734488 -274.988002) (xy 20.68833 -274.961353) (xy 20.646659 -274.928122) (xy 20.610407 -274.889051)
			(xy 20.580383 -274.845014) (xy 20.557257 -274.796993) (xy 20.541547 -274.746063) (xy 20.533604 -274.693359)
			(xy 17.144756 -274.693359) (xy 17.136813 -274.746063) (xy 17.121103 -274.796993) (xy 17.097977 -274.845014)
			(xy 17.067953 -274.889051) (xy 17.031701 -274.928122) (xy 16.99003 -274.961353) (xy 16.943872 -274.988002)
			(xy 16.894258 -275.007474) (xy 16.842296 -275.019334) (xy 16.789146 -275.023318) (xy 16.735996 -275.019334)
			(xy 16.684034 -275.007474) (xy 16.63442 -274.988002) (xy 16.588262 -274.961353) (xy 16.546591 -274.928122)
			(xy 16.510339 -274.889051) (xy 16.480315 -274.845014) (xy 16.457189 -274.796993) (xy 16.441479 -274.746063)
			(xy 16.433536 -274.693359) (xy 6.7818 -274.693359) (xy 6.7818 -275.543243) (xy 16.433536 -275.543243)
			(xy 16.433536 -275.489945) (xy 16.441479 -275.437241) (xy 16.457189 -275.386311) (xy 16.480315 -275.33829)
			(xy 16.510339 -275.294253) (xy 16.546591 -275.255182) (xy 16.588262 -275.221951) (xy 16.63442 -275.195302)
			(xy 16.684034 -275.17583) (xy 16.735996 -275.16397) (xy 16.789146 -275.159987) (xy 16.842296 -275.16397)
			(xy 16.894258 -275.17583) (xy 16.943872 -275.195302) (xy 16.99003 -275.221951) (xy 17.031701 -275.255182)
			(xy 17.067953 -275.294253) (xy 17.097977 -275.33829) (xy 17.121103 -275.386311) (xy 17.136813 -275.437241)
			(xy 17.144756 -275.489945) (xy 17.145254 -275.516594) (xy 17.144756 -275.543243) (xy 31.521136 -275.543243)
			(xy 31.521136 -275.489945) (xy 31.529079 -275.437241) (xy 31.544789 -275.386311) (xy 31.567915 -275.33829)
			(xy 31.597939 -275.294253) (xy 31.634191 -275.255182) (xy 31.675862 -275.221951) (xy 31.72202 -275.195302)
			(xy 31.771634 -275.17583) (xy 31.823596 -275.16397) (xy 31.876746 -275.159987) (xy 31.929896 -275.16397)
			(xy 31.981858 -275.17583) (xy 32.031472 -275.195302) (xy 32.07763 -275.221951) (xy 32.119301 -275.255182)
			(xy 32.155553 -275.294253) (xy 32.185577 -275.33829) (xy 32.208703 -275.386311) (xy 32.224413 -275.437241)
			(xy 32.232356 -275.489945) (xy 32.232854 -275.516594) (xy 32.232356 -275.543243) (xy 46.608736 -275.543243)
			(xy 46.608736 -275.489945) (xy 46.616679 -275.437241) (xy 46.632389 -275.386311) (xy 46.655515 -275.33829)
			(xy 46.685539 -275.294253) (xy 46.721791 -275.255182) (xy 46.763462 -275.221951) (xy 46.80962 -275.195302)
			(xy 46.859234 -275.17583) (xy 46.911196 -275.16397) (xy 46.964346 -275.159987) (xy 47.017496 -275.16397)
			(xy 47.069458 -275.17583) (xy 47.119072 -275.195302) (xy 47.16523 -275.221951) (xy 47.206901 -275.255182)
			(xy 47.243153 -275.294253) (xy 47.273177 -275.33829) (xy 47.296303 -275.386311) (xy 47.312013 -275.437241)
			(xy 47.319956 -275.489945) (xy 47.320454 -275.516594) (xy 47.319956 -275.543243) (xy 47.312013 -275.595947)
			(xy 47.296303 -275.646877) (xy 47.273177 -275.694898) (xy 47.243153 -275.738935) (xy 47.206901 -275.778006)
			(xy 47.16523 -275.811237) (xy 47.119072 -275.837886) (xy 47.069458 -275.857358) (xy 47.017496 -275.869218)
			(xy 46.964346 -275.873202) (xy 46.911196 -275.869218) (xy 46.859234 -275.857358) (xy 46.80962 -275.837886)
			(xy 46.763462 -275.811237) (xy 46.721791 -275.778006) (xy 46.685539 -275.738935) (xy 46.655515 -275.694898)
			(xy 46.632389 -275.646877) (xy 46.616679 -275.595947) (xy 46.608736 -275.543243) (xy 32.232356 -275.543243)
			(xy 32.224413 -275.595947) (xy 32.208703 -275.646877) (xy 32.185577 -275.694898) (xy 32.155553 -275.738935)
			(xy 32.119301 -275.778006) (xy 32.07763 -275.811237) (xy 32.031472 -275.837886) (xy 31.981858 -275.857358)
			(xy 31.929896 -275.869218) (xy 31.876746 -275.873202) (xy 31.823596 -275.869218) (xy 31.771634 -275.857358)
			(xy 31.72202 -275.837886) (xy 31.675862 -275.811237) (xy 31.634191 -275.778006) (xy 31.597939 -275.738935)
			(xy 31.567915 -275.694898) (xy 31.544789 -275.646877) (xy 31.529079 -275.595947) (xy 31.521136 -275.543243)
			(xy 17.144756 -275.543243) (xy 17.136813 -275.595947) (xy 17.121103 -275.646877) (xy 17.097977 -275.694898)
			(xy 17.067953 -275.738935) (xy 17.031701 -275.778006) (xy 16.99003 -275.811237) (xy 16.943872 -275.837886)
			(xy 16.894258 -275.857358) (xy 16.842296 -275.869218) (xy 16.789146 -275.873202) (xy 16.735996 -275.869218)
			(xy 16.684034 -275.857358) (xy 16.63442 -275.837886) (xy 16.588262 -275.811237) (xy 16.546591 -275.778006)
			(xy 16.510339 -275.738935) (xy 16.480315 -275.694898) (xy 16.457189 -275.646877) (xy 16.441479 -275.595947)
			(xy 16.433536 -275.543243) (xy 6.7818 -275.543243) (xy 6.7818 -276.393381) (xy 20.533604 -276.393381)
			(xy 20.533604 -276.340083) (xy 20.541547 -276.287379) (xy 20.557257 -276.236449) (xy 20.580383 -276.188428)
			(xy 20.610407 -276.144391) (xy 20.646659 -276.10532) (xy 20.68833 -276.072089) (xy 20.734488 -276.04544)
			(xy 20.784102 -276.025968) (xy 20.836064 -276.014108) (xy 20.889214 -276.010125) (xy 20.942364 -276.014108)
			(xy 20.994326 -276.025968) (xy 21.04394 -276.04544) (xy 21.090098 -276.072089) (xy 21.131769 -276.10532)
			(xy 21.168021 -276.144391) (xy 21.198045 -276.188428) (xy 21.221171 -276.236449) (xy 21.236881 -276.287379)
			(xy 21.244824 -276.340083) (xy 21.245322 -276.366732) (xy 21.244824 -276.393381) (xy 35.621204 -276.393381)
			(xy 35.621204 -276.340083) (xy 35.629147 -276.287379) (xy 35.644857 -276.236449) (xy 35.667983 -276.188428)
			(xy 35.698007 -276.144391) (xy 35.734259 -276.10532) (xy 35.77593 -276.072089) (xy 35.822088 -276.04544)
			(xy 35.871702 -276.025968) (xy 35.923664 -276.014108) (xy 35.976814 -276.010125) (xy 36.029964 -276.014108)
			(xy 36.081926 -276.025968) (xy 36.13154 -276.04544) (xy 36.177698 -276.072089) (xy 36.219369 -276.10532)
			(xy 36.255621 -276.144391) (xy 36.285645 -276.188428) (xy 36.308771 -276.236449) (xy 36.324481 -276.287379)
			(xy 36.332424 -276.340083) (xy 36.332922 -276.366732) (xy 36.332424 -276.393381) (xy 36.332386 -276.393635)
			(xy 50.734204 -276.393635) (xy 50.734204 -276.340337) (xy 50.742147 -276.287633) (xy 50.757857 -276.236703)
			(xy 50.780983 -276.188682) (xy 50.811007 -276.144645) (xy 50.847259 -276.105574) (xy 50.88893 -276.072343)
			(xy 50.935088 -276.045694) (xy 50.984702 -276.026222) (xy 51.036664 -276.014362) (xy 51.089814 -276.010379)
			(xy 51.142964 -276.014362) (xy 51.194926 -276.026222) (xy 51.24454 -276.045694) (xy 51.290698 -276.072343)
			(xy 51.332369 -276.105574) (xy 51.368621 -276.144645) (xy 51.398645 -276.188682) (xy 51.421771 -276.236703)
			(xy 51.437481 -276.287633) (xy 51.445424 -276.340337) (xy 51.445922 -276.366986) (xy 51.445424 -276.393635)
			(xy 51.437481 -276.446339) (xy 51.421771 -276.497269) (xy 51.398645 -276.54529) (xy 51.368621 -276.589327)
			(xy 51.332369 -276.628398) (xy 51.290698 -276.661629) (xy 51.24454 -276.688278) (xy 51.194926 -276.70775)
			(xy 51.142964 -276.71961) (xy 51.089814 -276.723594) (xy 51.036664 -276.71961) (xy 50.984702 -276.70775)
			(xy 50.935088 -276.688278) (xy 50.88893 -276.661629) (xy 50.847259 -276.628398) (xy 50.811007 -276.589327)
			(xy 50.780983 -276.54529) (xy 50.757857 -276.497269) (xy 50.742147 -276.446339) (xy 50.734204 -276.393635)
			(xy 36.332386 -276.393635) (xy 36.324481 -276.446085) (xy 36.308771 -276.497015) (xy 36.285645 -276.545036)
			(xy 36.255621 -276.589073) (xy 36.219369 -276.628144) (xy 36.177698 -276.661375) (xy 36.13154 -276.688024)
			(xy 36.081926 -276.707496) (xy 36.029964 -276.719356) (xy 35.976814 -276.72334) (xy 35.923664 -276.719356)
			(xy 35.871702 -276.707496) (xy 35.822088 -276.688024) (xy 35.77593 -276.661375) (xy 35.734259 -276.628144)
			(xy 35.698007 -276.589073) (xy 35.667983 -276.545036) (xy 35.644857 -276.497015) (xy 35.629147 -276.446085)
			(xy 35.621204 -276.393381) (xy 21.244824 -276.393381) (xy 21.236881 -276.446085) (xy 21.221171 -276.497015)
			(xy 21.198045 -276.545036) (xy 21.168021 -276.589073) (xy 21.131769 -276.628144) (xy 21.090098 -276.661375)
			(xy 21.04394 -276.688024) (xy 20.994326 -276.707496) (xy 20.942364 -276.719356) (xy 20.889214 -276.72334)
			(xy 20.836064 -276.719356) (xy 20.784102 -276.707496) (xy 20.734488 -276.688024) (xy 20.68833 -276.661375)
			(xy 20.646659 -276.628144) (xy 20.610407 -276.589073) (xy 20.580383 -276.545036) (xy 20.557257 -276.497015)
			(xy 20.541547 -276.446085) (xy 20.533604 -276.393381) (xy 6.7818 -276.393381) (xy 6.7818 -277.243265)
			(xy 16.433536 -277.243265) (xy 16.433536 -277.189967) (xy 16.441479 -277.137263) (xy 16.457189 -277.086333)
			(xy 16.480315 -277.038312) (xy 16.510339 -276.994275) (xy 16.546591 -276.955204) (xy 16.588262 -276.921973)
			(xy 16.63442 -276.895324) (xy 16.684034 -276.875852) (xy 16.735996 -276.863992) (xy 16.789146 -276.860009)
			(xy 16.842296 -276.863992) (xy 16.894258 -276.875852) (xy 16.943872 -276.895324) (xy 16.99003 -276.921973)
			(xy 17.031701 -276.955204) (xy 17.067953 -276.994275) (xy 17.097977 -277.038312) (xy 17.121103 -277.086333)
			(xy 17.136813 -277.137263) (xy 17.144756 -277.189967) (xy 17.145254 -277.216616) (xy 17.144756 -277.243265)
			(xy 31.521136 -277.243265) (xy 31.521136 -277.189967) (xy 31.529079 -277.137263) (xy 31.544789 -277.086333)
			(xy 31.567915 -277.038312) (xy 31.597939 -276.994275) (xy 31.634191 -276.955204) (xy 31.675862 -276.921973)
			(xy 31.72202 -276.895324) (xy 31.771634 -276.875852) (xy 31.823596 -276.863992) (xy 31.876746 -276.860009)
			(xy 31.929896 -276.863992) (xy 31.981858 -276.875852) (xy 32.031472 -276.895324) (xy 32.07763 -276.921973)
			(xy 32.119301 -276.955204) (xy 32.155553 -276.994275) (xy 32.185577 -277.038312) (xy 32.208703 -277.086333)
			(xy 32.224413 -277.137263) (xy 32.232356 -277.189967) (xy 32.232854 -277.216616) (xy 32.232356 -277.243265)
			(xy 46.608736 -277.243265) (xy 46.608736 -277.189967) (xy 46.616679 -277.137263) (xy 46.632389 -277.086333)
			(xy 46.655515 -277.038312) (xy 46.685539 -276.994275) (xy 46.721791 -276.955204) (xy 46.763462 -276.921973)
			(xy 46.80962 -276.895324) (xy 46.859234 -276.875852) (xy 46.911196 -276.863992) (xy 46.964346 -276.860009)
			(xy 47.017496 -276.863992) (xy 47.069458 -276.875852) (xy 47.119072 -276.895324) (xy 47.16523 -276.921973)
			(xy 47.206901 -276.955204) (xy 47.243153 -276.994275) (xy 47.273177 -277.038312) (xy 47.296303 -277.086333)
			(xy 47.312013 -277.137263) (xy 47.319956 -277.189967) (xy 47.320454 -277.216616) (xy 47.319956 -277.243265)
			(xy 47.312013 -277.295969) (xy 47.296303 -277.346899) (xy 47.273177 -277.39492) (xy 47.243153 -277.438957)
			(xy 47.206901 -277.478028) (xy 47.16523 -277.511259) (xy 47.119072 -277.537908) (xy 47.069458 -277.55738)
			(xy 47.017496 -277.56924) (xy 46.964346 -277.573224) (xy 46.911196 -277.56924) (xy 46.859234 -277.55738)
			(xy 46.80962 -277.537908) (xy 46.763462 -277.511259) (xy 46.721791 -277.478028) (xy 46.685539 -277.438957)
			(xy 46.655515 -277.39492) (xy 46.632389 -277.346899) (xy 46.616679 -277.295969) (xy 46.608736 -277.243265)
			(xy 32.232356 -277.243265) (xy 32.224413 -277.295969) (xy 32.208703 -277.346899) (xy 32.185577 -277.39492)
			(xy 32.155553 -277.438957) (xy 32.119301 -277.478028) (xy 32.07763 -277.511259) (xy 32.031472 -277.537908)
			(xy 31.981858 -277.55738) (xy 31.929896 -277.56924) (xy 31.876746 -277.573224) (xy 31.823596 -277.56924)
			(xy 31.771634 -277.55738) (xy 31.72202 -277.537908) (xy 31.675862 -277.511259) (xy 31.634191 -277.478028)
			(xy 31.597939 -277.438957) (xy 31.567915 -277.39492) (xy 31.544789 -277.346899) (xy 31.529079 -277.295969)
			(xy 31.521136 -277.243265) (xy 17.144756 -277.243265) (xy 17.136813 -277.295969) (xy 17.121103 -277.346899)
			(xy 17.097977 -277.39492) (xy 17.067953 -277.438957) (xy 17.031701 -277.478028) (xy 16.99003 -277.511259)
			(xy 16.943872 -277.537908) (xy 16.894258 -277.55738) (xy 16.842296 -277.56924) (xy 16.789146 -277.573224)
			(xy 16.735996 -277.56924) (xy 16.684034 -277.55738) (xy 16.63442 -277.537908) (xy 16.588262 -277.511259)
			(xy 16.546591 -277.478028) (xy 16.510339 -277.438957) (xy 16.480315 -277.39492) (xy 16.457189 -277.346899)
			(xy 16.441479 -277.295969) (xy 16.433536 -277.243265) (xy 6.7818 -277.243265) (xy 6.7818 -278.093403)
			(xy 20.533604 -278.093403) (xy 20.533604 -278.040105) (xy 20.541547 -277.987401) (xy 20.557257 -277.936471)
			(xy 20.580383 -277.88845) (xy 20.610407 -277.844413) (xy 20.646659 -277.805342) (xy 20.68833 -277.772111)
			(xy 20.734488 -277.745462) (xy 20.784102 -277.72599) (xy 20.836064 -277.71413) (xy 20.889214 -277.710147)
			(xy 20.942364 -277.71413) (xy 20.994326 -277.72599) (xy 21.04394 -277.745462) (xy 21.090098 -277.772111)
			(xy 21.131769 -277.805342) (xy 21.168021 -277.844413) (xy 21.198045 -277.88845) (xy 21.221171 -277.936471)
			(xy 21.236881 -277.987401) (xy 21.244824 -278.040105) (xy 21.245322 -278.066754) (xy 21.244824 -278.093403)
			(xy 35.621204 -278.093403) (xy 35.621204 -278.040105) (xy 35.629147 -277.987401) (xy 35.644857 -277.936471)
			(xy 35.667983 -277.88845) (xy 35.698007 -277.844413) (xy 35.734259 -277.805342) (xy 35.77593 -277.772111)
			(xy 35.822088 -277.745462) (xy 35.871702 -277.72599) (xy 35.923664 -277.71413) (xy 35.976814 -277.710147)
			(xy 36.029964 -277.71413) (xy 36.081926 -277.72599) (xy 36.13154 -277.745462) (xy 36.177698 -277.772111)
			(xy 36.219369 -277.805342) (xy 36.255621 -277.844413) (xy 36.285645 -277.88845) (xy 36.308771 -277.936471)
			(xy 36.324481 -277.987401) (xy 36.332424 -278.040105) (xy 36.332922 -278.066754) (xy 36.332424 -278.093403)
			(xy 36.332386 -278.093657) (xy 50.734204 -278.093657) (xy 50.734204 -278.040359) (xy 50.742147 -277.987655)
			(xy 50.757857 -277.936725) (xy 50.780983 -277.888704) (xy 50.811007 -277.844667) (xy 50.847259 -277.805596)
			(xy 50.88893 -277.772365) (xy 50.935088 -277.745716) (xy 50.984702 -277.726244) (xy 51.036664 -277.714384)
			(xy 51.089814 -277.710401) (xy 51.142964 -277.714384) (xy 51.194926 -277.726244) (xy 51.24454 -277.745716)
			(xy 51.290698 -277.772365) (xy 51.332369 -277.805596) (xy 51.368621 -277.844667) (xy 51.398645 -277.888704)
			(xy 51.421771 -277.936725) (xy 51.437481 -277.987655) (xy 51.445424 -278.040359) (xy 51.445922 -278.067008)
			(xy 51.445424 -278.093657) (xy 51.437481 -278.146361) (xy 51.421771 -278.197291) (xy 51.398645 -278.245312)
			(xy 51.368621 -278.289349) (xy 51.332369 -278.32842) (xy 51.290698 -278.361651) (xy 51.24454 -278.3883)
			(xy 51.194926 -278.407772) (xy 51.142964 -278.419632) (xy 51.089814 -278.423616) (xy 51.036664 -278.419632)
			(xy 50.984702 -278.407772) (xy 50.935088 -278.3883) (xy 50.88893 -278.361651) (xy 50.847259 -278.32842)
			(xy 50.811007 -278.289349) (xy 50.780983 -278.245312) (xy 50.757857 -278.197291) (xy 50.742147 -278.146361)
			(xy 50.734204 -278.093657) (xy 36.332386 -278.093657) (xy 36.324481 -278.146107) (xy 36.308771 -278.197037)
			(xy 36.285645 -278.245058) (xy 36.255621 -278.289095) (xy 36.219369 -278.328166) (xy 36.177698 -278.361397)
			(xy 36.13154 -278.388046) (xy 36.081926 -278.407518) (xy 36.029964 -278.419378) (xy 35.976814 -278.423362)
			(xy 35.923664 -278.419378) (xy 35.871702 -278.407518) (xy 35.822088 -278.388046) (xy 35.77593 -278.361397)
			(xy 35.734259 -278.328166) (xy 35.698007 -278.289095) (xy 35.667983 -278.245058) (xy 35.644857 -278.197037)
			(xy 35.629147 -278.146107) (xy 35.621204 -278.093403) (xy 21.244824 -278.093403) (xy 21.236881 -278.146107)
			(xy 21.221171 -278.197037) (xy 21.198045 -278.245058) (xy 21.168021 -278.289095) (xy 21.131769 -278.328166)
			(xy 21.090098 -278.361397) (xy 21.04394 -278.388046) (xy 20.994326 -278.407518) (xy 20.942364 -278.419378)
			(xy 20.889214 -278.423362) (xy 20.836064 -278.419378) (xy 20.784102 -278.407518) (xy 20.734488 -278.388046)
			(xy 20.68833 -278.361397) (xy 20.646659 -278.328166) (xy 20.610407 -278.289095) (xy 20.580383 -278.245058)
			(xy 20.557257 -278.197037) (xy 20.541547 -278.146107) (xy 20.533604 -278.093403) (xy 6.7818 -278.093403)
			(xy 6.7818 -278.943287) (xy 16.433536 -278.943287) (xy 16.433536 -278.889989) (xy 16.441479 -278.837285)
			(xy 16.457189 -278.786355) (xy 16.480315 -278.738334) (xy 16.510339 -278.694297) (xy 16.546591 -278.655226)
			(xy 16.588262 -278.621995) (xy 16.63442 -278.595346) (xy 16.684034 -278.575874) (xy 16.735996 -278.564014)
			(xy 16.789146 -278.560031) (xy 16.842296 -278.564014) (xy 16.894258 -278.575874) (xy 16.943872 -278.595346)
			(xy 16.99003 -278.621995) (xy 17.031701 -278.655226) (xy 17.067953 -278.694297) (xy 17.097977 -278.738334)
			(xy 17.121103 -278.786355) (xy 17.136813 -278.837285) (xy 17.144756 -278.889989) (xy 17.145254 -278.916638)
			(xy 17.144756 -278.943287) (xy 31.521136 -278.943287) (xy 31.521136 -278.889989) (xy 31.529079 -278.837285)
			(xy 31.544789 -278.786355) (xy 31.567915 -278.738334) (xy 31.597939 -278.694297) (xy 31.634191 -278.655226)
			(xy 31.675862 -278.621995) (xy 31.72202 -278.595346) (xy 31.771634 -278.575874) (xy 31.823596 -278.564014)
			(xy 31.876746 -278.560031) (xy 31.929896 -278.564014) (xy 31.981858 -278.575874) (xy 32.031472 -278.595346)
			(xy 32.07763 -278.621995) (xy 32.119301 -278.655226) (xy 32.155553 -278.694297) (xy 32.185577 -278.738334)
			(xy 32.208703 -278.786355) (xy 32.224413 -278.837285) (xy 32.232356 -278.889989) (xy 32.232854 -278.916638)
			(xy 32.232356 -278.943287) (xy 46.608736 -278.943287) (xy 46.608736 -278.889989) (xy 46.616679 -278.837285)
			(xy 46.632389 -278.786355) (xy 46.655515 -278.738334) (xy 46.685539 -278.694297) (xy 46.721791 -278.655226)
			(xy 46.763462 -278.621995) (xy 46.80962 -278.595346) (xy 46.859234 -278.575874) (xy 46.911196 -278.564014)
			(xy 46.964346 -278.560031) (xy 47.017496 -278.564014) (xy 47.069458 -278.575874) (xy 47.119072 -278.595346)
			(xy 47.16523 -278.621995) (xy 47.206901 -278.655226) (xy 47.243153 -278.694297) (xy 47.273177 -278.738334)
			(xy 47.296303 -278.786355) (xy 47.312013 -278.837285) (xy 47.319956 -278.889989) (xy 47.320454 -278.916638)
			(xy 47.319956 -278.943287) (xy 47.312013 -278.995991) (xy 47.296303 -279.046921) (xy 47.273177 -279.094942)
			(xy 47.243153 -279.138979) (xy 47.206901 -279.17805) (xy 47.16523 -279.211281) (xy 47.119072 -279.23793)
			(xy 47.069458 -279.257402) (xy 47.017496 -279.269262) (xy 46.964346 -279.273246) (xy 46.911196 -279.269262)
			(xy 46.859234 -279.257402) (xy 46.80962 -279.23793) (xy 46.763462 -279.211281) (xy 46.721791 -279.17805)
			(xy 46.685539 -279.138979) (xy 46.655515 -279.094942) (xy 46.632389 -279.046921) (xy 46.616679 -278.995991)
			(xy 46.608736 -278.943287) (xy 32.232356 -278.943287) (xy 32.224413 -278.995991) (xy 32.208703 -279.046921)
			(xy 32.185577 -279.094942) (xy 32.155553 -279.138979) (xy 32.119301 -279.17805) (xy 32.07763 -279.211281)
			(xy 32.031472 -279.23793) (xy 31.981858 -279.257402) (xy 31.929896 -279.269262) (xy 31.876746 -279.273246)
			(xy 31.823596 -279.269262) (xy 31.771634 -279.257402) (xy 31.72202 -279.23793) (xy 31.675862 -279.211281)
			(xy 31.634191 -279.17805) (xy 31.597939 -279.138979) (xy 31.567915 -279.094942) (xy 31.544789 -279.046921)
			(xy 31.529079 -278.995991) (xy 31.521136 -278.943287) (xy 17.144756 -278.943287) (xy 17.136813 -278.995991)
			(xy 17.121103 -279.046921) (xy 17.097977 -279.094942) (xy 17.067953 -279.138979) (xy 17.031701 -279.17805)
			(xy 16.99003 -279.211281) (xy 16.943872 -279.23793) (xy 16.894258 -279.257402) (xy 16.842296 -279.269262)
			(xy 16.789146 -279.273246) (xy 16.735996 -279.269262) (xy 16.684034 -279.257402) (xy 16.63442 -279.23793)
			(xy 16.588262 -279.211281) (xy 16.546591 -279.17805) (xy 16.510339 -279.138979) (xy 16.480315 -279.094942)
			(xy 16.457189 -279.046921) (xy 16.441479 -278.995991) (xy 16.433536 -278.943287) (xy 6.7818 -278.943287)
			(xy 6.7818 -279.793425) (xy 20.533604 -279.793425) (xy 20.533604 -279.740127) (xy 20.541547 -279.687423)
			(xy 20.557257 -279.636493) (xy 20.580383 -279.588472) (xy 20.610407 -279.544435) (xy 20.646659 -279.505364)
			(xy 20.68833 -279.472133) (xy 20.734488 -279.445484) (xy 20.784102 -279.426012) (xy 20.836064 -279.414152)
			(xy 20.889214 -279.410169) (xy 20.942364 -279.414152) (xy 20.994326 -279.426012) (xy 21.04394 -279.445484)
			(xy 21.090098 -279.472133) (xy 21.131769 -279.505364) (xy 21.168021 -279.544435) (xy 21.198045 -279.588472)
			(xy 21.221171 -279.636493) (xy 21.236881 -279.687423) (xy 21.244824 -279.740127) (xy 21.245322 -279.766776)
			(xy 21.244824 -279.793425) (xy 35.621204 -279.793425) (xy 35.621204 -279.740127) (xy 35.629147 -279.687423)
			(xy 35.644857 -279.636493) (xy 35.667983 -279.588472) (xy 35.698007 -279.544435) (xy 35.734259 -279.505364)
			(xy 35.77593 -279.472133) (xy 35.822088 -279.445484) (xy 35.871702 -279.426012) (xy 35.923664 -279.414152)
			(xy 35.976814 -279.410169) (xy 36.029964 -279.414152) (xy 36.081926 -279.426012) (xy 36.13154 -279.445484)
			(xy 36.177698 -279.472133) (xy 36.219369 -279.505364) (xy 36.255621 -279.544435) (xy 36.285645 -279.588472)
			(xy 36.308771 -279.636493) (xy 36.324481 -279.687423) (xy 36.332424 -279.740127) (xy 36.332922 -279.766776)
			(xy 36.332424 -279.793425) (xy 50.734204 -279.793425) (xy 50.734204 -279.740127) (xy 50.742147 -279.687423)
			(xy 50.757857 -279.636493) (xy 50.780983 -279.588472) (xy 50.811007 -279.544435) (xy 50.847259 -279.505364)
			(xy 50.88893 -279.472133) (xy 50.935088 -279.445484) (xy 50.984702 -279.426012) (xy 51.036664 -279.414152)
			(xy 51.089814 -279.410169) (xy 51.142964 -279.414152) (xy 51.194926 -279.426012) (xy 51.24454 -279.445484)
			(xy 51.290698 -279.472133) (xy 51.332369 -279.505364) (xy 51.368621 -279.544435) (xy 51.398645 -279.588472)
			(xy 51.421771 -279.636493) (xy 51.437481 -279.687423) (xy 51.445424 -279.740127) (xy 51.445922 -279.766776)
			(xy 51.445424 -279.793425) (xy 51.437481 -279.846129) (xy 51.421771 -279.897059) (xy 51.398645 -279.94508)
			(xy 51.368621 -279.989117) (xy 51.332369 -280.028188) (xy 51.290698 -280.061419) (xy 51.24454 -280.088068)
			(xy 51.194926 -280.10754) (xy 51.142964 -280.1194) (xy 51.089814 -280.123384) (xy 51.036664 -280.1194)
			(xy 50.984702 -280.10754) (xy 50.935088 -280.088068) (xy 50.88893 -280.061419) (xy 50.847259 -280.028188)
			(xy 50.811007 -279.989117) (xy 50.780983 -279.94508) (xy 50.757857 -279.897059) (xy 50.742147 -279.846129)
			(xy 50.734204 -279.793425) (xy 36.332424 -279.793425) (xy 36.324481 -279.846129) (xy 36.308771 -279.897059)
			(xy 36.285645 -279.94508) (xy 36.255621 -279.989117) (xy 36.219369 -280.028188) (xy 36.177698 -280.061419)
			(xy 36.13154 -280.088068) (xy 36.081926 -280.10754) (xy 36.029964 -280.1194) (xy 35.976814 -280.123384)
			(xy 35.923664 -280.1194) (xy 35.871702 -280.10754) (xy 35.822088 -280.088068) (xy 35.77593 -280.061419)
			(xy 35.734259 -280.028188) (xy 35.698007 -279.989117) (xy 35.667983 -279.94508) (xy 35.644857 -279.897059)
			(xy 35.629147 -279.846129) (xy 35.621204 -279.793425) (xy 21.244824 -279.793425) (xy 21.236881 -279.846129)
			(xy 21.221171 -279.897059) (xy 21.198045 -279.94508) (xy 21.168021 -279.989117) (xy 21.131769 -280.028188)
			(xy 21.090098 -280.061419) (xy 21.04394 -280.088068) (xy 20.994326 -280.10754) (xy 20.942364 -280.1194)
			(xy 20.889214 -280.123384) (xy 20.836064 -280.1194) (xy 20.784102 -280.10754) (xy 20.734488 -280.088068)
			(xy 20.68833 -280.061419) (xy 20.646659 -280.028188) (xy 20.610407 -279.989117) (xy 20.580383 -279.94508)
			(xy 20.557257 -279.897059) (xy 20.541547 -279.846129) (xy 20.533604 -279.793425) (xy 6.7818 -279.793425)
			(xy 6.7818 -280.643309) (xy 16.433536 -280.643309) (xy 16.433536 -280.590011) (xy 16.441479 -280.537307)
			(xy 16.457189 -280.486377) (xy 16.480315 -280.438356) (xy 16.510339 -280.394319) (xy 16.546591 -280.355248)
			(xy 16.588262 -280.322017) (xy 16.63442 -280.295368) (xy 16.684034 -280.275896) (xy 16.735996 -280.264036)
			(xy 16.789146 -280.260053) (xy 16.842296 -280.264036) (xy 16.894258 -280.275896) (xy 16.943872 -280.295368)
			(xy 16.99003 -280.322017) (xy 17.031701 -280.355248) (xy 17.067953 -280.394319) (xy 17.097977 -280.438356)
			(xy 17.121103 -280.486377) (xy 17.136813 -280.537307) (xy 17.144756 -280.590011) (xy 17.145254 -280.61666)
			(xy 17.144756 -280.643309) (xy 31.521136 -280.643309) (xy 31.521136 -280.590011) (xy 31.529079 -280.537307)
			(xy 31.544789 -280.486377) (xy 31.567915 -280.438356) (xy 31.597939 -280.394319) (xy 31.634191 -280.355248)
			(xy 31.675862 -280.322017) (xy 31.72202 -280.295368) (xy 31.771634 -280.275896) (xy 31.823596 -280.264036)
			(xy 31.876746 -280.260053) (xy 31.929896 -280.264036) (xy 31.981858 -280.275896) (xy 32.031472 -280.295368)
			(xy 32.07763 -280.322017) (xy 32.119301 -280.355248) (xy 32.155553 -280.394319) (xy 32.185577 -280.438356)
			(xy 32.208703 -280.486377) (xy 32.224413 -280.537307) (xy 32.232356 -280.590011) (xy 32.232854 -280.61666)
			(xy 32.232356 -280.643309) (xy 46.608736 -280.643309) (xy 46.608736 -280.590011) (xy 46.616679 -280.537307)
			(xy 46.632389 -280.486377) (xy 46.655515 -280.438356) (xy 46.685539 -280.394319) (xy 46.721791 -280.355248)
			(xy 46.763462 -280.322017) (xy 46.80962 -280.295368) (xy 46.859234 -280.275896) (xy 46.911196 -280.264036)
			(xy 46.964346 -280.260053) (xy 47.017496 -280.264036) (xy 47.069458 -280.275896) (xy 47.119072 -280.295368)
			(xy 47.16523 -280.322017) (xy 47.206901 -280.355248) (xy 47.243153 -280.394319) (xy 47.273177 -280.438356)
			(xy 47.296303 -280.486377) (xy 47.312013 -280.537307) (xy 47.319956 -280.590011) (xy 47.320454 -280.61666)
			(xy 47.319956 -280.643309) (xy 47.312013 -280.696013) (xy 47.296303 -280.746943) (xy 47.273177 -280.794964)
			(xy 47.243153 -280.839001) (xy 47.206901 -280.878072) (xy 47.16523 -280.911303) (xy 47.119072 -280.937952)
			(xy 47.069458 -280.957424) (xy 47.017496 -280.969284) (xy 46.964346 -280.973268) (xy 46.911196 -280.969284)
			(xy 46.859234 -280.957424) (xy 46.80962 -280.937952) (xy 46.763462 -280.911303) (xy 46.721791 -280.878072)
			(xy 46.685539 -280.839001) (xy 46.655515 -280.794964) (xy 46.632389 -280.746943) (xy 46.616679 -280.696013)
			(xy 46.608736 -280.643309) (xy 32.232356 -280.643309) (xy 32.224413 -280.696013) (xy 32.208703 -280.746943)
			(xy 32.185577 -280.794964) (xy 32.155553 -280.839001) (xy 32.119301 -280.878072) (xy 32.07763 -280.911303)
			(xy 32.031472 -280.937952) (xy 31.981858 -280.957424) (xy 31.929896 -280.969284) (xy 31.876746 -280.973268)
			(xy 31.823596 -280.969284) (xy 31.771634 -280.957424) (xy 31.72202 -280.937952) (xy 31.675862 -280.911303)
			(xy 31.634191 -280.878072) (xy 31.597939 -280.839001) (xy 31.567915 -280.794964) (xy 31.544789 -280.746943)
			(xy 31.529079 -280.696013) (xy 31.521136 -280.643309) (xy 17.144756 -280.643309) (xy 17.136813 -280.696013)
			(xy 17.121103 -280.746943) (xy 17.097977 -280.794964) (xy 17.067953 -280.839001) (xy 17.031701 -280.878072)
			(xy 16.99003 -280.911303) (xy 16.943872 -280.937952) (xy 16.894258 -280.957424) (xy 16.842296 -280.969284)
			(xy 16.789146 -280.973268) (xy 16.735996 -280.969284) (xy 16.684034 -280.957424) (xy 16.63442 -280.937952)
			(xy 16.588262 -280.911303) (xy 16.546591 -280.878072) (xy 16.510339 -280.839001) (xy 16.480315 -280.794964)
			(xy 16.457189 -280.746943) (xy 16.441479 -280.696013) (xy 16.433536 -280.643309) (xy 6.7818 -280.643309)
			(xy 6.7818 -281.493447) (xy 20.533604 -281.493447) (xy 20.533604 -281.440149) (xy 20.541547 -281.387445)
			(xy 20.557257 -281.336515) (xy 20.580383 -281.288494) (xy 20.610407 -281.244457) (xy 20.646659 -281.205386)
			(xy 20.68833 -281.172155) (xy 20.734488 -281.145506) (xy 20.784102 -281.126034) (xy 20.836064 -281.114174)
			(xy 20.889214 -281.110191) (xy 20.942364 -281.114174) (xy 20.994326 -281.126034) (xy 21.04394 -281.145506)
			(xy 21.090098 -281.172155) (xy 21.131769 -281.205386) (xy 21.168021 -281.244457) (xy 21.198045 -281.288494)
			(xy 21.221171 -281.336515) (xy 21.236881 -281.387445) (xy 21.244824 -281.440149) (xy 21.245322 -281.466798)
			(xy 21.244824 -281.493447) (xy 35.621204 -281.493447) (xy 35.621204 -281.440149) (xy 35.629147 -281.387445)
			(xy 35.644857 -281.336515) (xy 35.667983 -281.288494) (xy 35.698007 -281.244457) (xy 35.734259 -281.205386)
			(xy 35.77593 -281.172155) (xy 35.822088 -281.145506) (xy 35.871702 -281.126034) (xy 35.923664 -281.114174)
			(xy 35.976814 -281.110191) (xy 36.029964 -281.114174) (xy 36.081926 -281.126034) (xy 36.13154 -281.145506)
			(xy 36.177698 -281.172155) (xy 36.219369 -281.205386) (xy 36.255621 -281.244457) (xy 36.285645 -281.288494)
			(xy 36.308771 -281.336515) (xy 36.324481 -281.387445) (xy 36.332424 -281.440149) (xy 36.332922 -281.466798)
			(xy 36.332424 -281.493447) (xy 50.734204 -281.493447) (xy 50.734204 -281.440149) (xy 50.742147 -281.387445)
			(xy 50.757857 -281.336515) (xy 50.780983 -281.288494) (xy 50.811007 -281.244457) (xy 50.847259 -281.205386)
			(xy 50.88893 -281.172155) (xy 50.935088 -281.145506) (xy 50.984702 -281.126034) (xy 51.036664 -281.114174)
			(xy 51.089814 -281.110191) (xy 51.142964 -281.114174) (xy 51.194926 -281.126034) (xy 51.24454 -281.145506)
			(xy 51.290698 -281.172155) (xy 51.332369 -281.205386) (xy 51.368621 -281.244457) (xy 51.398645 -281.288494)
			(xy 51.421771 -281.336515) (xy 51.437481 -281.387445) (xy 51.445424 -281.440149) (xy 51.445922 -281.466798)
			(xy 51.445424 -281.493447) (xy 51.437481 -281.546151) (xy 51.421771 -281.597081) (xy 51.398645 -281.645102)
			(xy 51.368621 -281.689139) (xy 51.332369 -281.72821) (xy 51.290698 -281.761441) (xy 51.24454 -281.78809)
			(xy 51.194926 -281.807562) (xy 51.142964 -281.819422) (xy 51.089814 -281.823406) (xy 51.036664 -281.819422)
			(xy 50.984702 -281.807562) (xy 50.935088 -281.78809) (xy 50.88893 -281.761441) (xy 50.847259 -281.72821)
			(xy 50.811007 -281.689139) (xy 50.780983 -281.645102) (xy 50.757857 -281.597081) (xy 50.742147 -281.546151)
			(xy 50.734204 -281.493447) (xy 36.332424 -281.493447) (xy 36.324481 -281.546151) (xy 36.308771 -281.597081)
			(xy 36.285645 -281.645102) (xy 36.255621 -281.689139) (xy 36.219369 -281.72821) (xy 36.177698 -281.761441)
			(xy 36.13154 -281.78809) (xy 36.081926 -281.807562) (xy 36.029964 -281.819422) (xy 35.976814 -281.823406)
			(xy 35.923664 -281.819422) (xy 35.871702 -281.807562) (xy 35.822088 -281.78809) (xy 35.77593 -281.761441)
			(xy 35.734259 -281.72821) (xy 35.698007 -281.689139) (xy 35.667983 -281.645102) (xy 35.644857 -281.597081)
			(xy 35.629147 -281.546151) (xy 35.621204 -281.493447) (xy 21.244824 -281.493447) (xy 21.236881 -281.546151)
			(xy 21.221171 -281.597081) (xy 21.198045 -281.645102) (xy 21.168021 -281.689139) (xy 21.131769 -281.72821)
			(xy 21.090098 -281.761441) (xy 21.04394 -281.78809) (xy 20.994326 -281.807562) (xy 20.942364 -281.819422)
			(xy 20.889214 -281.823406) (xy 20.836064 -281.819422) (xy 20.784102 -281.807562) (xy 20.734488 -281.78809)
			(xy 20.68833 -281.761441) (xy 20.646659 -281.72821) (xy 20.610407 -281.689139) (xy 20.580383 -281.645102)
			(xy 20.557257 -281.597081) (xy 20.541547 -281.546151) (xy 20.533604 -281.493447) (xy 6.7818 -281.493447)
			(xy 6.7818 -282.343331) (xy 16.433536 -282.343331) (xy 16.433536 -282.290033) (xy 16.441479 -282.237329)
			(xy 16.457189 -282.186399) (xy 16.480315 -282.138378) (xy 16.510339 -282.094341) (xy 16.546591 -282.05527)
			(xy 16.588262 -282.022039) (xy 16.63442 -281.99539) (xy 16.684034 -281.975918) (xy 16.735996 -281.964058)
			(xy 16.789146 -281.960075) (xy 16.842296 -281.964058) (xy 16.894258 -281.975918) (xy 16.943872 -281.99539)
			(xy 16.99003 -282.022039) (xy 17.031701 -282.05527) (xy 17.067953 -282.094341) (xy 17.097977 -282.138378)
			(xy 17.121103 -282.186399) (xy 17.136813 -282.237329) (xy 17.144756 -282.290033) (xy 17.145254 -282.316682)
			(xy 17.144756 -282.343331) (xy 31.521136 -282.343331) (xy 31.521136 -282.290033) (xy 31.529079 -282.237329)
			(xy 31.544789 -282.186399) (xy 31.567915 -282.138378) (xy 31.597939 -282.094341) (xy 31.634191 -282.05527)
			(xy 31.675862 -282.022039) (xy 31.72202 -281.99539) (xy 31.771634 -281.975918) (xy 31.823596 -281.964058)
			(xy 31.876746 -281.960075) (xy 31.929896 -281.964058) (xy 31.981858 -281.975918) (xy 32.031472 -281.99539)
			(xy 32.07763 -282.022039) (xy 32.119301 -282.05527) (xy 32.155553 -282.094341) (xy 32.185577 -282.138378)
			(xy 32.208703 -282.186399) (xy 32.224413 -282.237329) (xy 32.232356 -282.290033) (xy 32.232854 -282.316682)
			(xy 32.232356 -282.343331) (xy 46.608736 -282.343331) (xy 46.608736 -282.290033) (xy 46.616679 -282.237329)
			(xy 46.632389 -282.186399) (xy 46.655515 -282.138378) (xy 46.685539 -282.094341) (xy 46.721791 -282.05527)
			(xy 46.763462 -282.022039) (xy 46.80962 -281.99539) (xy 46.859234 -281.975918) (xy 46.911196 -281.964058)
			(xy 46.964346 -281.960075) (xy 47.017496 -281.964058) (xy 47.069458 -281.975918) (xy 47.119072 -281.99539)
			(xy 47.16523 -282.022039) (xy 47.206901 -282.05527) (xy 47.243153 -282.094341) (xy 47.273177 -282.138378)
			(xy 47.296303 -282.186399) (xy 47.312013 -282.237329) (xy 47.319956 -282.290033) (xy 47.320454 -282.316682)
			(xy 47.319956 -282.343331) (xy 47.312013 -282.396035) (xy 47.296303 -282.446965) (xy 47.273177 -282.494986)
			(xy 47.243153 -282.539023) (xy 47.206901 -282.578094) (xy 47.16523 -282.611325) (xy 47.119072 -282.637974)
			(xy 47.069458 -282.657446) (xy 47.017496 -282.669306) (xy 46.964346 -282.67329) (xy 46.911196 -282.669306)
			(xy 46.859234 -282.657446) (xy 46.80962 -282.637974) (xy 46.763462 -282.611325) (xy 46.721791 -282.578094)
			(xy 46.685539 -282.539023) (xy 46.655515 -282.494986) (xy 46.632389 -282.446965) (xy 46.616679 -282.396035)
			(xy 46.608736 -282.343331) (xy 32.232356 -282.343331) (xy 32.224413 -282.396035) (xy 32.208703 -282.446965)
			(xy 32.185577 -282.494986) (xy 32.155553 -282.539023) (xy 32.119301 -282.578094) (xy 32.07763 -282.611325)
			(xy 32.031472 -282.637974) (xy 31.981858 -282.657446) (xy 31.929896 -282.669306) (xy 31.876746 -282.67329)
			(xy 31.823596 -282.669306) (xy 31.771634 -282.657446) (xy 31.72202 -282.637974) (xy 31.675862 -282.611325)
			(xy 31.634191 -282.578094) (xy 31.597939 -282.539023) (xy 31.567915 -282.494986) (xy 31.544789 -282.446965)
			(xy 31.529079 -282.396035) (xy 31.521136 -282.343331) (xy 17.144756 -282.343331) (xy 17.136813 -282.396035)
			(xy 17.121103 -282.446965) (xy 17.097977 -282.494986) (xy 17.067953 -282.539023) (xy 17.031701 -282.578094)
			(xy 16.99003 -282.611325) (xy 16.943872 -282.637974) (xy 16.894258 -282.657446) (xy 16.842296 -282.669306)
			(xy 16.789146 -282.67329) (xy 16.735996 -282.669306) (xy 16.684034 -282.657446) (xy 16.63442 -282.637974)
			(xy 16.588262 -282.611325) (xy 16.546591 -282.578094) (xy 16.510339 -282.539023) (xy 16.480315 -282.494986)
			(xy 16.457189 -282.446965) (xy 16.441479 -282.396035) (xy 16.433536 -282.343331) (xy 6.7818 -282.343331)
			(xy 6.7818 -283.193215) (xy 20.533604 -283.193215) (xy 20.533604 -283.139917) (xy 20.541547 -283.087213)
			(xy 20.557257 -283.036283) (xy 20.580383 -282.988262) (xy 20.610407 -282.944225) (xy 20.646659 -282.905154)
			(xy 20.68833 -282.871923) (xy 20.734488 -282.845274) (xy 20.784102 -282.825802) (xy 20.836064 -282.813942)
			(xy 20.889214 -282.809959) (xy 20.942364 -282.813942) (xy 20.994326 -282.825802) (xy 21.04394 -282.845274)
			(xy 21.090098 -282.871923) (xy 21.131769 -282.905154) (xy 21.168021 -282.944225) (xy 21.198045 -282.988262)
			(xy 21.221171 -283.036283) (xy 21.236881 -283.087213) (xy 21.244824 -283.139917) (xy 21.245322 -283.166566)
			(xy 21.244824 -283.193215) (xy 35.621204 -283.193215) (xy 35.621204 -283.139917) (xy 35.629147 -283.087213)
			(xy 35.644857 -283.036283) (xy 35.667983 -282.988262) (xy 35.698007 -282.944225) (xy 35.734259 -282.905154)
			(xy 35.77593 -282.871923) (xy 35.822088 -282.845274) (xy 35.871702 -282.825802) (xy 35.923664 -282.813942)
			(xy 35.976814 -282.809959) (xy 36.029964 -282.813942) (xy 36.081926 -282.825802) (xy 36.13154 -282.845274)
			(xy 36.177698 -282.871923) (xy 36.219369 -282.905154) (xy 36.255621 -282.944225) (xy 36.285645 -282.988262)
			(xy 36.308771 -283.036283) (xy 36.324481 -283.087213) (xy 36.332424 -283.139917) (xy 36.332922 -283.166566)
			(xy 36.332424 -283.193215) (xy 36.332386 -283.193469) (xy 50.734204 -283.193469) (xy 50.734204 -283.140171)
			(xy 50.742147 -283.087467) (xy 50.757857 -283.036537) (xy 50.780983 -282.988516) (xy 50.811007 -282.944479)
			(xy 50.847259 -282.905408) (xy 50.88893 -282.872177) (xy 50.935088 -282.845528) (xy 50.984702 -282.826056)
			(xy 51.036664 -282.814196) (xy 51.089814 -282.810213) (xy 51.142964 -282.814196) (xy 51.194926 -282.826056)
			(xy 51.24454 -282.845528) (xy 51.290698 -282.872177) (xy 51.332369 -282.905408) (xy 51.368621 -282.944479)
			(xy 51.398645 -282.988516) (xy 51.421771 -283.036537) (xy 51.437481 -283.087467) (xy 51.445424 -283.140171)
			(xy 51.445922 -283.16682) (xy 51.445424 -283.193469) (xy 51.437481 -283.246173) (xy 51.421771 -283.297103)
			(xy 51.398645 -283.345124) (xy 51.368621 -283.389161) (xy 51.332369 -283.428232) (xy 51.290698 -283.461463)
			(xy 51.24454 -283.488112) (xy 51.194926 -283.507584) (xy 51.142964 -283.519444) (xy 51.089814 -283.523428)
			(xy 51.036664 -283.519444) (xy 50.984702 -283.507584) (xy 50.935088 -283.488112) (xy 50.88893 -283.461463)
			(xy 50.847259 -283.428232) (xy 50.811007 -283.389161) (xy 50.780983 -283.345124) (xy 50.757857 -283.297103)
			(xy 50.742147 -283.246173) (xy 50.734204 -283.193469) (xy 36.332386 -283.193469) (xy 36.324481 -283.245919)
			(xy 36.308771 -283.296849) (xy 36.285645 -283.34487) (xy 36.255621 -283.388907) (xy 36.219369 -283.427978)
			(xy 36.177698 -283.461209) (xy 36.13154 -283.487858) (xy 36.081926 -283.50733) (xy 36.029964 -283.51919)
			(xy 35.976814 -283.523174) (xy 35.923664 -283.51919) (xy 35.871702 -283.50733) (xy 35.822088 -283.487858)
			(xy 35.77593 -283.461209) (xy 35.734259 -283.427978) (xy 35.698007 -283.388907) (xy 35.667983 -283.34487)
			(xy 35.644857 -283.296849) (xy 35.629147 -283.245919) (xy 35.621204 -283.193215) (xy 21.244824 -283.193215)
			(xy 21.236881 -283.245919) (xy 21.221171 -283.296849) (xy 21.198045 -283.34487) (xy 21.168021 -283.388907)
			(xy 21.131769 -283.427978) (xy 21.090098 -283.461209) (xy 21.04394 -283.487858) (xy 20.994326 -283.50733)
			(xy 20.942364 -283.51919) (xy 20.889214 -283.523174) (xy 20.836064 -283.51919) (xy 20.784102 -283.50733)
			(xy 20.734488 -283.487858) (xy 20.68833 -283.461209) (xy 20.646659 -283.427978) (xy 20.610407 -283.388907)
			(xy 20.580383 -283.34487) (xy 20.557257 -283.296849) (xy 20.541547 -283.245919) (xy 20.533604 -283.193215)
			(xy 6.7818 -283.193215) (xy 6.7818 -284.043353) (xy 16.433536 -284.043353) (xy 16.433536 -283.990055)
			(xy 16.441479 -283.937351) (xy 16.457189 -283.886421) (xy 16.480315 -283.8384) (xy 16.510339 -283.794363)
			(xy 16.546591 -283.755292) (xy 16.588262 -283.722061) (xy 16.63442 -283.695412) (xy 16.684034 -283.67594)
			(xy 16.735996 -283.66408) (xy 16.789146 -283.660097) (xy 16.842296 -283.66408) (xy 16.894258 -283.67594)
			(xy 16.943872 -283.695412) (xy 16.99003 -283.722061) (xy 17.031701 -283.755292) (xy 17.067953 -283.794363)
			(xy 17.097977 -283.8384) (xy 17.121103 -283.886421) (xy 17.136813 -283.937351) (xy 17.144756 -283.990055)
			(xy 17.145254 -284.016704) (xy 17.144756 -284.043353) (xy 20.533604 -284.043353) (xy 20.533604 -283.990055)
			(xy 20.541547 -283.937351) (xy 20.557257 -283.886421) (xy 20.580383 -283.8384) (xy 20.610407 -283.794363)
			(xy 20.646659 -283.755292) (xy 20.68833 -283.722061) (xy 20.734488 -283.695412) (xy 20.784102 -283.67594)
			(xy 20.836064 -283.66408) (xy 20.889214 -283.660097) (xy 20.942364 -283.66408) (xy 20.994326 -283.67594)
			(xy 21.04394 -283.695412) (xy 21.090098 -283.722061) (xy 21.131769 -283.755292) (xy 21.168021 -283.794363)
			(xy 21.198045 -283.8384) (xy 21.221171 -283.886421) (xy 21.236881 -283.937351) (xy 21.244824 -283.990055)
			(xy 21.245322 -284.016704) (xy 21.244824 -284.043353) (xy 31.521136 -284.043353) (xy 31.521136 -283.990055)
			(xy 31.529079 -283.937351) (xy 31.544789 -283.886421) (xy 31.567915 -283.8384) (xy 31.597939 -283.794363)
			(xy 31.634191 -283.755292) (xy 31.675862 -283.722061) (xy 31.72202 -283.695412) (xy 31.771634 -283.67594)
			(xy 31.823596 -283.66408) (xy 31.876746 -283.660097) (xy 31.929896 -283.66408) (xy 31.981858 -283.67594)
			(xy 32.031472 -283.695412) (xy 32.07763 -283.722061) (xy 32.119301 -283.755292) (xy 32.155553 -283.794363)
			(xy 32.185577 -283.8384) (xy 32.208703 -283.886421) (xy 32.224413 -283.937351) (xy 32.232356 -283.990055)
			(xy 32.232854 -284.016704) (xy 32.232356 -284.043353) (xy 35.621204 -284.043353) (xy 35.621204 -283.990055)
			(xy 35.629147 -283.937351) (xy 35.644857 -283.886421) (xy 35.667983 -283.8384) (xy 35.698007 -283.794363)
			(xy 35.734259 -283.755292) (xy 35.77593 -283.722061) (xy 35.822088 -283.695412) (xy 35.871702 -283.67594)
			(xy 35.923664 -283.66408) (xy 35.976814 -283.660097) (xy 36.029964 -283.66408) (xy 36.081926 -283.67594)
			(xy 36.13154 -283.695412) (xy 36.177698 -283.722061) (xy 36.219369 -283.755292) (xy 36.255621 -283.794363)
			(xy 36.285645 -283.8384) (xy 36.308771 -283.886421) (xy 36.324481 -283.937351) (xy 36.332424 -283.990055)
			(xy 36.332922 -284.016704) (xy 36.332424 -284.043353) (xy 46.608736 -284.043353) (xy 46.608736 -283.990055)
			(xy 46.616679 -283.937351) (xy 46.632389 -283.886421) (xy 46.655515 -283.8384) (xy 46.685539 -283.794363)
			(xy 46.721791 -283.755292) (xy 46.763462 -283.722061) (xy 46.80962 -283.695412) (xy 46.859234 -283.67594)
			(xy 46.911196 -283.66408) (xy 46.964346 -283.660097) (xy 47.017496 -283.66408) (xy 47.069458 -283.67594)
			(xy 47.119072 -283.695412) (xy 47.16523 -283.722061) (xy 47.206901 -283.755292) (xy 47.243153 -283.794363)
			(xy 47.273177 -283.8384) (xy 47.296303 -283.886421) (xy 47.312013 -283.937351) (xy 47.319956 -283.990055)
			(xy 47.320454 -284.016704) (xy 47.319956 -284.043353) (xy 47.319918 -284.043607) (xy 50.734204 -284.043607)
			(xy 50.734204 -283.990309) (xy 50.742147 -283.937605) (xy 50.757857 -283.886675) (xy 50.780983 -283.838654)
			(xy 50.811007 -283.794617) (xy 50.847259 -283.755546) (xy 50.88893 -283.722315) (xy 50.935088 -283.695666)
			(xy 50.984702 -283.676194) (xy 51.036664 -283.664334) (xy 51.089814 -283.660351) (xy 51.142964 -283.664334)
			(xy 51.194926 -283.676194) (xy 51.24454 -283.695666) (xy 51.290698 -283.722315) (xy 51.332369 -283.755546)
			(xy 51.368621 -283.794617) (xy 51.398645 -283.838654) (xy 51.421771 -283.886675) (xy 51.437481 -283.937605)
			(xy 51.445424 -283.990309) (xy 51.445922 -284.016958) (xy 51.445424 -284.043607) (xy 51.437481 -284.096311)
			(xy 51.421771 -284.147241) (xy 51.398645 -284.195262) (xy 51.368621 -284.239299) (xy 51.332369 -284.27837)
			(xy 51.290698 -284.311601) (xy 51.24454 -284.33825) (xy 51.194926 -284.357722) (xy 51.142964 -284.369582)
			(xy 51.089814 -284.373566) (xy 51.036664 -284.369582) (xy 50.984702 -284.357722) (xy 50.935088 -284.33825)
			(xy 50.88893 -284.311601) (xy 50.847259 -284.27837) (xy 50.811007 -284.239299) (xy 50.780983 -284.195262)
			(xy 50.757857 -284.147241) (xy 50.742147 -284.096311) (xy 50.734204 -284.043607) (xy 47.319918 -284.043607)
			(xy 47.312013 -284.096057) (xy 47.296303 -284.146987) (xy 47.273177 -284.195008) (xy 47.243153 -284.239045)
			(xy 47.206901 -284.278116) (xy 47.16523 -284.311347) (xy 47.119072 -284.337996) (xy 47.069458 -284.357468)
			(xy 47.017496 -284.369328) (xy 46.964346 -284.373312) (xy 46.911196 -284.369328) (xy 46.859234 -284.357468)
			(xy 46.80962 -284.337996) (xy 46.763462 -284.311347) (xy 46.721791 -284.278116) (xy 46.685539 -284.239045)
			(xy 46.655515 -284.195008) (xy 46.632389 -284.146987) (xy 46.616679 -284.096057) (xy 46.608736 -284.043353)
			(xy 36.332424 -284.043353) (xy 36.324481 -284.096057) (xy 36.308771 -284.146987) (xy 36.285645 -284.195008)
			(xy 36.255621 -284.239045) (xy 36.219369 -284.278116) (xy 36.177698 -284.311347) (xy 36.13154 -284.337996)
			(xy 36.081926 -284.357468) (xy 36.029964 -284.369328) (xy 35.976814 -284.373312) (xy 35.923664 -284.369328)
			(xy 35.871702 -284.357468) (xy 35.822088 -284.337996) (xy 35.77593 -284.311347) (xy 35.734259 -284.278116)
			(xy 35.698007 -284.239045) (xy 35.667983 -284.195008) (xy 35.644857 -284.146987) (xy 35.629147 -284.096057)
			(xy 35.621204 -284.043353) (xy 32.232356 -284.043353) (xy 32.224413 -284.096057) (xy 32.208703 -284.146987)
			(xy 32.185577 -284.195008) (xy 32.155553 -284.239045) (xy 32.119301 -284.278116) (xy 32.07763 -284.311347)
			(xy 32.031472 -284.337996) (xy 31.981858 -284.357468) (xy 31.929896 -284.369328) (xy 31.876746 -284.373312)
			(xy 31.823596 -284.369328) (xy 31.771634 -284.357468) (xy 31.72202 -284.337996) (xy 31.675862 -284.311347)
			(xy 31.634191 -284.278116) (xy 31.597939 -284.239045) (xy 31.567915 -284.195008) (xy 31.544789 -284.146987)
			(xy 31.529079 -284.096057) (xy 31.521136 -284.043353) (xy 21.244824 -284.043353) (xy 21.236881 -284.096057)
			(xy 21.221171 -284.146987) (xy 21.198045 -284.195008) (xy 21.168021 -284.239045) (xy 21.131769 -284.278116)
			(xy 21.090098 -284.311347) (xy 21.04394 -284.337996) (xy 20.994326 -284.357468) (xy 20.942364 -284.369328)
			(xy 20.889214 -284.373312) (xy 20.836064 -284.369328) (xy 20.784102 -284.357468) (xy 20.734488 -284.337996)
			(xy 20.68833 -284.311347) (xy 20.646659 -284.278116) (xy 20.610407 -284.239045) (xy 20.580383 -284.195008)
			(xy 20.557257 -284.146987) (xy 20.541547 -284.096057) (xy 20.533604 -284.043353) (xy 17.144756 -284.043353)
			(xy 17.136813 -284.096057) (xy 17.121103 -284.146987) (xy 17.097977 -284.195008) (xy 17.067953 -284.239045)
			(xy 17.031701 -284.278116) (xy 16.99003 -284.311347) (xy 16.943872 -284.337996) (xy 16.894258 -284.357468)
			(xy 16.842296 -284.369328) (xy 16.789146 -284.373312) (xy 16.735996 -284.369328) (xy 16.684034 -284.357468)
			(xy 16.63442 -284.337996) (xy 16.588262 -284.311347) (xy 16.546591 -284.278116) (xy 16.510339 -284.239045)
			(xy 16.480315 -284.195008) (xy 16.457189 -284.146987) (xy 16.441479 -284.096057) (xy 16.433536 -284.043353)
			(xy 6.7818 -284.043353) (xy 6.7818 -284.893237) (xy 16.433536 -284.893237) (xy 16.433536 -284.839939)
			(xy 16.441479 -284.787235) (xy 16.457189 -284.736305) (xy 16.480315 -284.688284) (xy 16.510339 -284.644247)
			(xy 16.546591 -284.605176) (xy 16.588262 -284.571945) (xy 16.63442 -284.545296) (xy 16.684034 -284.525824)
			(xy 16.735996 -284.513964) (xy 16.789146 -284.509981) (xy 16.842296 -284.513964) (xy 16.894258 -284.525824)
			(xy 16.943872 -284.545296) (xy 16.99003 -284.571945) (xy 17.031701 -284.605176) (xy 17.067953 -284.644247)
			(xy 17.097977 -284.688284) (xy 17.121103 -284.736305) (xy 17.136813 -284.787235) (xy 17.144756 -284.839939)
			(xy 17.145254 -284.866588) (xy 17.144756 -284.893237) (xy 31.521136 -284.893237) (xy 31.521136 -284.839939)
			(xy 31.529079 -284.787235) (xy 31.544789 -284.736305) (xy 31.567915 -284.688284) (xy 31.597939 -284.644247)
			(xy 31.634191 -284.605176) (xy 31.675862 -284.571945) (xy 31.72202 -284.545296) (xy 31.771634 -284.525824)
			(xy 31.823596 -284.513964) (xy 31.876746 -284.509981) (xy 31.929896 -284.513964) (xy 31.981858 -284.525824)
			(xy 32.031472 -284.545296) (xy 32.07763 -284.571945) (xy 32.119301 -284.605176) (xy 32.155553 -284.644247)
			(xy 32.185577 -284.688284) (xy 32.208703 -284.736305) (xy 32.224413 -284.787235) (xy 32.232356 -284.839939)
			(xy 32.232854 -284.866588) (xy 32.232356 -284.893237) (xy 46.608736 -284.893237) (xy 46.608736 -284.839939)
			(xy 46.616679 -284.787235) (xy 46.632389 -284.736305) (xy 46.655515 -284.688284) (xy 46.685539 -284.644247)
			(xy 46.721791 -284.605176) (xy 46.763462 -284.571945) (xy 46.80962 -284.545296) (xy 46.859234 -284.525824)
			(xy 46.911196 -284.513964) (xy 46.964346 -284.509981) (xy 47.017496 -284.513964) (xy 47.069458 -284.525824)
			(xy 47.119072 -284.545296) (xy 47.16523 -284.571945) (xy 47.206901 -284.605176) (xy 47.243153 -284.644247)
			(xy 47.273177 -284.688284) (xy 47.296303 -284.736305) (xy 47.312013 -284.787235) (xy 47.319956 -284.839939)
			(xy 47.320454 -284.866588) (xy 47.319956 -284.893237) (xy 47.312013 -284.945941) (xy 47.296303 -284.996871)
			(xy 47.273177 -285.044892) (xy 47.243153 -285.088929) (xy 47.206901 -285.128) (xy 47.16523 -285.161231)
			(xy 47.119072 -285.18788) (xy 47.069458 -285.207352) (xy 47.017496 -285.219212) (xy 46.964346 -285.223196)
			(xy 46.911196 -285.219212) (xy 46.859234 -285.207352) (xy 46.80962 -285.18788) (xy 46.763462 -285.161231)
			(xy 46.721791 -285.128) (xy 46.685539 -285.088929) (xy 46.655515 -285.044892) (xy 46.632389 -284.996871)
			(xy 46.616679 -284.945941) (xy 46.608736 -284.893237) (xy 32.232356 -284.893237) (xy 32.224413 -284.945941)
			(xy 32.208703 -284.996871) (xy 32.185577 -285.044892) (xy 32.155553 -285.088929) (xy 32.119301 -285.128)
			(xy 32.07763 -285.161231) (xy 32.031472 -285.18788) (xy 31.981858 -285.207352) (xy 31.929896 -285.219212)
			(xy 31.876746 -285.223196) (xy 31.823596 -285.219212) (xy 31.771634 -285.207352) (xy 31.72202 -285.18788)
			(xy 31.675862 -285.161231) (xy 31.634191 -285.128) (xy 31.597939 -285.088929) (xy 31.567915 -285.044892)
			(xy 31.544789 -284.996871) (xy 31.529079 -284.945941) (xy 31.521136 -284.893237) (xy 17.144756 -284.893237)
			(xy 17.136813 -284.945941) (xy 17.121103 -284.996871) (xy 17.097977 -285.044892) (xy 17.067953 -285.088929)
			(xy 17.031701 -285.128) (xy 16.99003 -285.161231) (xy 16.943872 -285.18788) (xy 16.894258 -285.207352)
			(xy 16.842296 -285.219212) (xy 16.789146 -285.223196) (xy 16.735996 -285.219212) (xy 16.684034 -285.207352)
			(xy 16.63442 -285.18788) (xy 16.588262 -285.161231) (xy 16.546591 -285.128) (xy 16.510339 -285.088929)
			(xy 16.480315 -285.044892) (xy 16.457189 -284.996871) (xy 16.441479 -284.945941) (xy 16.433536 -284.893237)
			(xy 6.7818 -284.893237) (xy 6.7818 -285.743375) (xy 20.533604 -285.743375) (xy 20.533604 -285.690077)
			(xy 20.541547 -285.637373) (xy 20.557257 -285.586443) (xy 20.580383 -285.538422) (xy 20.610407 -285.494385)
			(xy 20.646659 -285.455314) (xy 20.68833 -285.422083) (xy 20.734488 -285.395434) (xy 20.784102 -285.375962)
			(xy 20.836064 -285.364102) (xy 20.889214 -285.360119) (xy 20.942364 -285.364102) (xy 20.994326 -285.375962)
			(xy 21.04394 -285.395434) (xy 21.090098 -285.422083) (xy 21.131769 -285.455314) (xy 21.168021 -285.494385)
			(xy 21.198045 -285.538422) (xy 21.221171 -285.586443) (xy 21.236881 -285.637373) (xy 21.244824 -285.690077)
			(xy 21.245322 -285.716726) (xy 21.244824 -285.743375) (xy 35.621204 -285.743375) (xy 35.621204 -285.690077)
			(xy 35.629147 -285.637373) (xy 35.644857 -285.586443) (xy 35.667983 -285.538422) (xy 35.698007 -285.494385)
			(xy 35.734259 -285.455314) (xy 35.77593 -285.422083) (xy 35.822088 -285.395434) (xy 35.871702 -285.375962)
			(xy 35.923664 -285.364102) (xy 35.976814 -285.360119) (xy 36.029964 -285.364102) (xy 36.081926 -285.375962)
			(xy 36.13154 -285.395434) (xy 36.177698 -285.422083) (xy 36.219369 -285.455314) (xy 36.255621 -285.494385)
			(xy 36.285645 -285.538422) (xy 36.308771 -285.586443) (xy 36.324481 -285.637373) (xy 36.332424 -285.690077)
			(xy 36.332922 -285.716726) (xy 36.332424 -285.743375) (xy 50.708804 -285.743375) (xy 50.708804 -285.690077)
			(xy 50.716747 -285.637373) (xy 50.732457 -285.586443) (xy 50.755583 -285.538422) (xy 50.785607 -285.494385)
			(xy 50.821859 -285.455314) (xy 50.86353 -285.422083) (xy 50.909688 -285.395434) (xy 50.959302 -285.375962)
			(xy 51.011264 -285.364102) (xy 51.064414 -285.360119) (xy 51.117564 -285.364102) (xy 51.169526 -285.375962)
			(xy 51.21914 -285.395434) (xy 51.265298 -285.422083) (xy 51.306969 -285.455314) (xy 51.343221 -285.494385)
			(xy 51.373245 -285.538422) (xy 51.396371 -285.586443) (xy 51.412081 -285.637373) (xy 51.420024 -285.690077)
			(xy 51.420522 -285.716726) (xy 51.420024 -285.743375) (xy 51.412081 -285.796079) (xy 51.396371 -285.847009)
			(xy 51.373245 -285.89503) (xy 51.343221 -285.939067) (xy 51.306969 -285.978138) (xy 51.265298 -286.011369)
			(xy 51.21914 -286.038018) (xy 51.169526 -286.05749) (xy 51.117564 -286.06935) (xy 51.064414 -286.073334)
			(xy 51.011264 -286.06935) (xy 50.959302 -286.05749) (xy 50.909688 -286.038018) (xy 50.86353 -286.011369)
			(xy 50.821859 -285.978138) (xy 50.785607 -285.939067) (xy 50.755583 -285.89503) (xy 50.732457 -285.847009)
			(xy 50.716747 -285.796079) (xy 50.708804 -285.743375) (xy 36.332424 -285.743375) (xy 36.324481 -285.796079)
			(xy 36.308771 -285.847009) (xy 36.285645 -285.89503) (xy 36.255621 -285.939067) (xy 36.219369 -285.978138)
			(xy 36.177698 -286.011369) (xy 36.13154 -286.038018) (xy 36.081926 -286.05749) (xy 36.029964 -286.06935)
			(xy 35.976814 -286.073334) (xy 35.923664 -286.06935) (xy 35.871702 -286.05749) (xy 35.822088 -286.038018)
			(xy 35.77593 -286.011369) (xy 35.734259 -285.978138) (xy 35.698007 -285.939067) (xy 35.667983 -285.89503)
			(xy 35.644857 -285.847009) (xy 35.629147 -285.796079) (xy 35.621204 -285.743375) (xy 21.244824 -285.743375)
			(xy 21.236881 -285.796079) (xy 21.221171 -285.847009) (xy 21.198045 -285.89503) (xy 21.168021 -285.939067)
			(xy 21.131769 -285.978138) (xy 21.090098 -286.011369) (xy 21.04394 -286.038018) (xy 20.994326 -286.05749)
			(xy 20.942364 -286.06935) (xy 20.889214 -286.073334) (xy 20.836064 -286.06935) (xy 20.784102 -286.05749)
			(xy 20.734488 -286.038018) (xy 20.68833 -286.011369) (xy 20.646659 -285.978138) (xy 20.610407 -285.939067)
			(xy 20.580383 -285.89503) (xy 20.557257 -285.847009) (xy 20.541547 -285.796079) (xy 20.533604 -285.743375)
			(xy 6.7818 -285.743375) (xy 6.7818 -286.593259) (xy 16.433536 -286.593259) (xy 16.433536 -286.539961)
			(xy 16.441479 -286.487257) (xy 16.457189 -286.436327) (xy 16.480315 -286.388306) (xy 16.510339 -286.344269)
			(xy 16.546591 -286.305198) (xy 16.588262 -286.271967) (xy 16.63442 -286.245318) (xy 16.684034 -286.225846)
			(xy 16.735996 -286.213986) (xy 16.789146 -286.210003) (xy 16.842296 -286.213986) (xy 16.894258 -286.225846)
			(xy 16.943872 -286.245318) (xy 16.99003 -286.271967) (xy 17.031701 -286.305198) (xy 17.067953 -286.344269)
			(xy 17.097977 -286.388306) (xy 17.121103 -286.436327) (xy 17.136813 -286.487257) (xy 17.144756 -286.539961)
			(xy 17.145254 -286.56661) (xy 17.144756 -286.593259) (xy 31.521136 -286.593259) (xy 31.521136 -286.539961)
			(xy 31.529079 -286.487257) (xy 31.544789 -286.436327) (xy 31.567915 -286.388306) (xy 31.597939 -286.344269)
			(xy 31.634191 -286.305198) (xy 31.675862 -286.271967) (xy 31.72202 -286.245318) (xy 31.771634 -286.225846)
			(xy 31.823596 -286.213986) (xy 31.876746 -286.210003) (xy 31.929896 -286.213986) (xy 31.981858 -286.225846)
			(xy 32.031472 -286.245318) (xy 32.07763 -286.271967) (xy 32.119301 -286.305198) (xy 32.155553 -286.344269)
			(xy 32.185577 -286.388306) (xy 32.208703 -286.436327) (xy 32.224413 -286.487257) (xy 32.232356 -286.539961)
			(xy 32.232854 -286.56661) (xy 32.232356 -286.593259) (xy 46.608736 -286.593259) (xy 46.608736 -286.539961)
			(xy 46.616679 -286.487257) (xy 46.632389 -286.436327) (xy 46.655515 -286.388306) (xy 46.685539 -286.344269)
			(xy 46.721791 -286.305198) (xy 46.763462 -286.271967) (xy 46.80962 -286.245318) (xy 46.859234 -286.225846)
			(xy 46.911196 -286.213986) (xy 46.964346 -286.210003) (xy 47.017496 -286.213986) (xy 47.069458 -286.225846)
			(xy 47.119072 -286.245318) (xy 47.16523 -286.271967) (xy 47.206901 -286.305198) (xy 47.243153 -286.344269)
			(xy 47.273177 -286.388306) (xy 47.296303 -286.436327) (xy 47.312013 -286.487257) (xy 47.319956 -286.539961)
			(xy 47.320454 -286.56661) (xy 47.319956 -286.593259) (xy 47.312013 -286.645963) (xy 47.296303 -286.696893)
			(xy 47.273177 -286.744914) (xy 47.243153 -286.788951) (xy 47.206901 -286.828022) (xy 47.16523 -286.861253)
			(xy 47.119072 -286.887902) (xy 47.069458 -286.907374) (xy 47.017496 -286.919234) (xy 46.964346 -286.923218)
			(xy 46.911196 -286.919234) (xy 46.859234 -286.907374) (xy 46.80962 -286.887902) (xy 46.763462 -286.861253)
			(xy 46.721791 -286.828022) (xy 46.685539 -286.788951) (xy 46.655515 -286.744914) (xy 46.632389 -286.696893)
			(xy 46.616679 -286.645963) (xy 46.608736 -286.593259) (xy 32.232356 -286.593259) (xy 32.224413 -286.645963)
			(xy 32.208703 -286.696893) (xy 32.185577 -286.744914) (xy 32.155553 -286.788951) (xy 32.119301 -286.828022)
			(xy 32.07763 -286.861253) (xy 32.031472 -286.887902) (xy 31.981858 -286.907374) (xy 31.929896 -286.919234)
			(xy 31.876746 -286.923218) (xy 31.823596 -286.919234) (xy 31.771634 -286.907374) (xy 31.72202 -286.887902)
			(xy 31.675862 -286.861253) (xy 31.634191 -286.828022) (xy 31.597939 -286.788951) (xy 31.567915 -286.744914)
			(xy 31.544789 -286.696893) (xy 31.529079 -286.645963) (xy 31.521136 -286.593259) (xy 17.144756 -286.593259)
			(xy 17.136813 -286.645963) (xy 17.121103 -286.696893) (xy 17.097977 -286.744914) (xy 17.067953 -286.788951)
			(xy 17.031701 -286.828022) (xy 16.99003 -286.861253) (xy 16.943872 -286.887902) (xy 16.894258 -286.907374)
			(xy 16.842296 -286.919234) (xy 16.789146 -286.923218) (xy 16.735996 -286.919234) (xy 16.684034 -286.907374)
			(xy 16.63442 -286.887902) (xy 16.588262 -286.861253) (xy 16.546591 -286.828022) (xy 16.510339 -286.788951)
			(xy 16.480315 -286.744914) (xy 16.457189 -286.696893) (xy 16.441479 -286.645963) (xy 16.433536 -286.593259)
			(xy 6.7818 -286.593259) (xy 6.7818 -287.443397) (xy 20.533604 -287.443397) (xy 20.533604 -287.390099)
			(xy 20.541547 -287.337395) (xy 20.557257 -287.286465) (xy 20.580383 -287.238444) (xy 20.610407 -287.194407)
			(xy 20.646659 -287.155336) (xy 20.68833 -287.122105) (xy 20.734488 -287.095456) (xy 20.784102 -287.075984)
			(xy 20.836064 -287.064124) (xy 20.889214 -287.060141) (xy 20.942364 -287.064124) (xy 20.994326 -287.075984)
			(xy 21.04394 -287.095456) (xy 21.090098 -287.122105) (xy 21.131769 -287.155336) (xy 21.168021 -287.194407)
			(xy 21.198045 -287.238444) (xy 21.221171 -287.286465) (xy 21.236881 -287.337395) (xy 21.244824 -287.390099)
			(xy 21.245322 -287.416748) (xy 21.244824 -287.443397) (xy 35.621204 -287.443397) (xy 35.621204 -287.390099)
			(xy 35.629147 -287.337395) (xy 35.644857 -287.286465) (xy 35.667983 -287.238444) (xy 35.698007 -287.194407)
			(xy 35.734259 -287.155336) (xy 35.77593 -287.122105) (xy 35.822088 -287.095456) (xy 35.871702 -287.075984)
			(xy 35.923664 -287.064124) (xy 35.976814 -287.060141) (xy 36.029964 -287.064124) (xy 36.081926 -287.075984)
			(xy 36.13154 -287.095456) (xy 36.177698 -287.122105) (xy 36.219369 -287.155336) (xy 36.255621 -287.194407)
			(xy 36.285645 -287.238444) (xy 36.308771 -287.286465) (xy 36.324481 -287.337395) (xy 36.332424 -287.390099)
			(xy 36.332922 -287.416748) (xy 36.332424 -287.443397) (xy 50.708804 -287.443397) (xy 50.708804 -287.390099)
			(xy 50.716747 -287.337395) (xy 50.732457 -287.286465) (xy 50.755583 -287.238444) (xy 50.785607 -287.194407)
			(xy 50.821859 -287.155336) (xy 50.86353 -287.122105) (xy 50.909688 -287.095456) (xy 50.959302 -287.075984)
			(xy 51.011264 -287.064124) (xy 51.064414 -287.060141) (xy 51.117564 -287.064124) (xy 51.169526 -287.075984)
			(xy 51.21914 -287.095456) (xy 51.265298 -287.122105) (xy 51.306969 -287.155336) (xy 51.343221 -287.194407)
			(xy 51.373245 -287.238444) (xy 51.396371 -287.286465) (xy 51.412081 -287.337395) (xy 51.420024 -287.390099)
			(xy 51.420522 -287.416748) (xy 51.420024 -287.443397) (xy 51.412081 -287.496101) (xy 51.396371 -287.547031)
			(xy 51.373245 -287.595052) (xy 51.343221 -287.639089) (xy 51.306969 -287.67816) (xy 51.265298 -287.711391)
			(xy 51.21914 -287.73804) (xy 51.169526 -287.757512) (xy 51.117564 -287.769372) (xy 51.064414 -287.773356)
			(xy 51.011264 -287.769372) (xy 50.959302 -287.757512) (xy 50.909688 -287.73804) (xy 50.86353 -287.711391)
			(xy 50.821859 -287.67816) (xy 50.785607 -287.639089) (xy 50.755583 -287.595052) (xy 50.732457 -287.547031)
			(xy 50.716747 -287.496101) (xy 50.708804 -287.443397) (xy 36.332424 -287.443397) (xy 36.324481 -287.496101)
			(xy 36.308771 -287.547031) (xy 36.285645 -287.595052) (xy 36.255621 -287.639089) (xy 36.219369 -287.67816)
			(xy 36.177698 -287.711391) (xy 36.13154 -287.73804) (xy 36.081926 -287.757512) (xy 36.029964 -287.769372)
			(xy 35.976814 -287.773356) (xy 35.923664 -287.769372) (xy 35.871702 -287.757512) (xy 35.822088 -287.73804)
			(xy 35.77593 -287.711391) (xy 35.734259 -287.67816) (xy 35.698007 -287.639089) (xy 35.667983 -287.595052)
			(xy 35.644857 -287.547031) (xy 35.629147 -287.496101) (xy 35.621204 -287.443397) (xy 21.244824 -287.443397)
			(xy 21.236881 -287.496101) (xy 21.221171 -287.547031) (xy 21.198045 -287.595052) (xy 21.168021 -287.639089)
			(xy 21.131769 -287.67816) (xy 21.090098 -287.711391) (xy 21.04394 -287.73804) (xy 20.994326 -287.757512)
			(xy 20.942364 -287.769372) (xy 20.889214 -287.773356) (xy 20.836064 -287.769372) (xy 20.784102 -287.757512)
			(xy 20.734488 -287.73804) (xy 20.68833 -287.711391) (xy 20.646659 -287.67816) (xy 20.610407 -287.639089)
			(xy 20.580383 -287.595052) (xy 20.557257 -287.547031) (xy 20.541547 -287.496101) (xy 20.533604 -287.443397)
			(xy 6.7818 -287.443397) (xy 6.7818 -288.293281) (xy 16.433536 -288.293281) (xy 16.433536 -288.239983)
			(xy 16.441479 -288.187279) (xy 16.457189 -288.136349) (xy 16.480315 -288.088328) (xy 16.510339 -288.044291)
			(xy 16.546591 -288.00522) (xy 16.588262 -287.971989) (xy 16.63442 -287.94534) (xy 16.684034 -287.925868)
			(xy 16.735996 -287.914008) (xy 16.789146 -287.910025) (xy 16.842296 -287.914008) (xy 16.894258 -287.925868)
			(xy 16.943872 -287.94534) (xy 16.99003 -287.971989) (xy 17.031701 -288.00522) (xy 17.067953 -288.044291)
			(xy 17.097977 -288.088328) (xy 17.121103 -288.136349) (xy 17.136813 -288.187279) (xy 17.144756 -288.239983)
			(xy 17.145254 -288.266632) (xy 17.144756 -288.293281) (xy 31.521136 -288.293281) (xy 31.521136 -288.239983)
			(xy 31.529079 -288.187279) (xy 31.544789 -288.136349) (xy 31.567915 -288.088328) (xy 31.597939 -288.044291)
			(xy 31.634191 -288.00522) (xy 31.675862 -287.971989) (xy 31.72202 -287.94534) (xy 31.771634 -287.925868)
			(xy 31.823596 -287.914008) (xy 31.876746 -287.910025) (xy 31.929896 -287.914008) (xy 31.981858 -287.925868)
			(xy 32.031472 -287.94534) (xy 32.07763 -287.971989) (xy 32.119301 -288.00522) (xy 32.155553 -288.044291)
			(xy 32.185577 -288.088328) (xy 32.208703 -288.136349) (xy 32.224413 -288.187279) (xy 32.232356 -288.239983)
			(xy 32.232854 -288.266632) (xy 32.232356 -288.293281) (xy 46.608736 -288.293281) (xy 46.608736 -288.239983)
			(xy 46.616679 -288.187279) (xy 46.632389 -288.136349) (xy 46.655515 -288.088328) (xy 46.685539 -288.044291)
			(xy 46.721791 -288.00522) (xy 46.763462 -287.971989) (xy 46.80962 -287.94534) (xy 46.859234 -287.925868)
			(xy 46.911196 -287.914008) (xy 46.964346 -287.910025) (xy 47.017496 -287.914008) (xy 47.069458 -287.925868)
			(xy 47.119072 -287.94534) (xy 47.16523 -287.971989) (xy 47.206901 -288.00522) (xy 47.243153 -288.044291)
			(xy 47.273177 -288.088328) (xy 47.296303 -288.136349) (xy 47.312013 -288.187279) (xy 47.319956 -288.239983)
			(xy 47.320454 -288.266632) (xy 47.319956 -288.293281) (xy 47.312013 -288.345985) (xy 47.296303 -288.396915)
			(xy 47.273177 -288.444936) (xy 47.243153 -288.488973) (xy 47.206901 -288.528044) (xy 47.16523 -288.561275)
			(xy 47.119072 -288.587924) (xy 47.069458 -288.607396) (xy 47.017496 -288.619256) (xy 46.964346 -288.62324)
			(xy 46.911196 -288.619256) (xy 46.859234 -288.607396) (xy 46.80962 -288.587924) (xy 46.763462 -288.561275)
			(xy 46.721791 -288.528044) (xy 46.685539 -288.488973) (xy 46.655515 -288.444936) (xy 46.632389 -288.396915)
			(xy 46.616679 -288.345985) (xy 46.608736 -288.293281) (xy 32.232356 -288.293281) (xy 32.224413 -288.345985)
			(xy 32.208703 -288.396915) (xy 32.185577 -288.444936) (xy 32.155553 -288.488973) (xy 32.119301 -288.528044)
			(xy 32.07763 -288.561275) (xy 32.031472 -288.587924) (xy 31.981858 -288.607396) (xy 31.929896 -288.619256)
			(xy 31.876746 -288.62324) (xy 31.823596 -288.619256) (xy 31.771634 -288.607396) (xy 31.72202 -288.587924)
			(xy 31.675862 -288.561275) (xy 31.634191 -288.528044) (xy 31.597939 -288.488973) (xy 31.567915 -288.444936)
			(xy 31.544789 -288.396915) (xy 31.529079 -288.345985) (xy 31.521136 -288.293281) (xy 17.144756 -288.293281)
			(xy 17.136813 -288.345985) (xy 17.121103 -288.396915) (xy 17.097977 -288.444936) (xy 17.067953 -288.488973)
			(xy 17.031701 -288.528044) (xy 16.99003 -288.561275) (xy 16.943872 -288.587924) (xy 16.894258 -288.607396)
			(xy 16.842296 -288.619256) (xy 16.789146 -288.62324) (xy 16.735996 -288.619256) (xy 16.684034 -288.607396)
			(xy 16.63442 -288.587924) (xy 16.588262 -288.561275) (xy 16.546591 -288.528044) (xy 16.510339 -288.488973)
			(xy 16.480315 -288.444936) (xy 16.457189 -288.396915) (xy 16.441479 -288.345985) (xy 16.433536 -288.293281)
			(xy 6.7818 -288.293281) (xy 6.7818 -289.143419) (xy 20.533604 -289.143419) (xy 20.533604 -289.090121)
			(xy 20.541547 -289.037417) (xy 20.557257 -288.986487) (xy 20.580383 -288.938466) (xy 20.610407 -288.894429)
			(xy 20.646659 -288.855358) (xy 20.68833 -288.822127) (xy 20.734488 -288.795478) (xy 20.784102 -288.776006)
			(xy 20.836064 -288.764146) (xy 20.889214 -288.760163) (xy 20.942364 -288.764146) (xy 20.994326 -288.776006)
			(xy 21.04394 -288.795478) (xy 21.090098 -288.822127) (xy 21.131769 -288.855358) (xy 21.168021 -288.894429)
			(xy 21.198045 -288.938466) (xy 21.221171 -288.986487) (xy 21.236881 -289.037417) (xy 21.244824 -289.090121)
			(xy 21.245322 -289.11677) (xy 21.244824 -289.143419) (xy 35.621204 -289.143419) (xy 35.621204 -289.090121)
			(xy 35.629147 -289.037417) (xy 35.644857 -288.986487) (xy 35.667983 -288.938466) (xy 35.698007 -288.894429)
			(xy 35.734259 -288.855358) (xy 35.77593 -288.822127) (xy 35.822088 -288.795478) (xy 35.871702 -288.776006)
			(xy 35.923664 -288.764146) (xy 35.976814 -288.760163) (xy 36.029964 -288.764146) (xy 36.081926 -288.776006)
			(xy 36.13154 -288.795478) (xy 36.177698 -288.822127) (xy 36.219369 -288.855358) (xy 36.255621 -288.894429)
			(xy 36.285645 -288.938466) (xy 36.308771 -288.986487) (xy 36.324481 -289.037417) (xy 36.332424 -289.090121)
			(xy 36.332922 -289.11677) (xy 36.332424 -289.143419) (xy 50.734204 -289.143419) (xy 50.734204 -289.090121)
			(xy 50.742147 -289.037417) (xy 50.757857 -288.986487) (xy 50.780983 -288.938466) (xy 50.811007 -288.894429)
			(xy 50.847259 -288.855358) (xy 50.88893 -288.822127) (xy 50.935088 -288.795478) (xy 50.984702 -288.776006)
			(xy 51.036664 -288.764146) (xy 51.089814 -288.760163) (xy 51.142964 -288.764146) (xy 51.194926 -288.776006)
			(xy 51.24454 -288.795478) (xy 51.290698 -288.822127) (xy 51.332369 -288.855358) (xy 51.368621 -288.894429)
			(xy 51.398645 -288.938466) (xy 51.421771 -288.986487) (xy 51.437481 -289.037417) (xy 51.445424 -289.090121)
			(xy 51.445922 -289.11677) (xy 51.445424 -289.143419) (xy 51.437481 -289.196123) (xy 51.421771 -289.247053)
			(xy 51.398645 -289.295074) (xy 51.368621 -289.339111) (xy 51.332369 -289.378182) (xy 51.290698 -289.411413)
			(xy 51.24454 -289.438062) (xy 51.194926 -289.457534) (xy 51.142964 -289.469394) (xy 51.089814 -289.473378)
			(xy 51.036664 -289.469394) (xy 50.984702 -289.457534) (xy 50.935088 -289.438062) (xy 50.88893 -289.411413)
			(xy 50.847259 -289.378182) (xy 50.811007 -289.339111) (xy 50.780983 -289.295074) (xy 50.757857 -289.247053)
			(xy 50.742147 -289.196123) (xy 50.734204 -289.143419) (xy 36.332424 -289.143419) (xy 36.324481 -289.196123)
			(xy 36.308771 -289.247053) (xy 36.285645 -289.295074) (xy 36.255621 -289.339111) (xy 36.219369 -289.378182)
			(xy 36.177698 -289.411413) (xy 36.13154 -289.438062) (xy 36.081926 -289.457534) (xy 36.029964 -289.469394)
			(xy 35.976814 -289.473378) (xy 35.923664 -289.469394) (xy 35.871702 -289.457534) (xy 35.822088 -289.438062)
			(xy 35.77593 -289.411413) (xy 35.734259 -289.378182) (xy 35.698007 -289.339111) (xy 35.667983 -289.295074)
			(xy 35.644857 -289.247053) (xy 35.629147 -289.196123) (xy 35.621204 -289.143419) (xy 21.244824 -289.143419)
			(xy 21.236881 -289.196123) (xy 21.221171 -289.247053) (xy 21.198045 -289.295074) (xy 21.168021 -289.339111)
			(xy 21.131769 -289.378182) (xy 21.090098 -289.411413) (xy 21.04394 -289.438062) (xy 20.994326 -289.457534)
			(xy 20.942364 -289.469394) (xy 20.889214 -289.473378) (xy 20.836064 -289.469394) (xy 20.784102 -289.457534)
			(xy 20.734488 -289.438062) (xy 20.68833 -289.411413) (xy 20.646659 -289.378182) (xy 20.610407 -289.339111)
			(xy 20.580383 -289.295074) (xy 20.557257 -289.247053) (xy 20.541547 -289.196123) (xy 20.533604 -289.143419)
			(xy 6.7818 -289.143419) (xy 6.7818 -289.993303) (xy 16.433536 -289.993303) (xy 16.433536 -289.940005)
			(xy 16.441479 -289.887301) (xy 16.457189 -289.836371) (xy 16.480315 -289.78835) (xy 16.510339 -289.744313)
			(xy 16.546591 -289.705242) (xy 16.588262 -289.672011) (xy 16.63442 -289.645362) (xy 16.684034 -289.62589)
			(xy 16.735996 -289.61403) (xy 16.789146 -289.610047) (xy 16.842296 -289.61403) (xy 16.894258 -289.62589)
			(xy 16.943872 -289.645362) (xy 16.99003 -289.672011) (xy 17.031701 -289.705242) (xy 17.067953 -289.744313)
			(xy 17.097977 -289.78835) (xy 17.121103 -289.836371) (xy 17.136813 -289.887301) (xy 17.144756 -289.940005)
			(xy 17.145254 -289.966654) (xy 17.144756 -289.993303) (xy 31.521136 -289.993303) (xy 31.521136 -289.940005)
			(xy 31.529079 -289.887301) (xy 31.544789 -289.836371) (xy 31.567915 -289.78835) (xy 31.597939 -289.744313)
			(xy 31.634191 -289.705242) (xy 31.675862 -289.672011) (xy 31.72202 -289.645362) (xy 31.771634 -289.62589)
			(xy 31.823596 -289.61403) (xy 31.876746 -289.610047) (xy 31.929896 -289.61403) (xy 31.981858 -289.62589)
			(xy 32.031472 -289.645362) (xy 32.07763 -289.672011) (xy 32.119301 -289.705242) (xy 32.155553 -289.744313)
			(xy 32.185577 -289.78835) (xy 32.208703 -289.836371) (xy 32.224413 -289.887301) (xy 32.232356 -289.940005)
			(xy 32.232854 -289.966654) (xy 32.232356 -289.993303) (xy 46.608736 -289.993303) (xy 46.608736 -289.940005)
			(xy 46.616679 -289.887301) (xy 46.632389 -289.836371) (xy 46.655515 -289.78835) (xy 46.685539 -289.744313)
			(xy 46.721791 -289.705242) (xy 46.763462 -289.672011) (xy 46.80962 -289.645362) (xy 46.859234 -289.62589)
			(xy 46.911196 -289.61403) (xy 46.964346 -289.610047) (xy 47.017496 -289.61403) (xy 47.069458 -289.62589)
			(xy 47.119072 -289.645362) (xy 47.16523 -289.672011) (xy 47.206901 -289.705242) (xy 47.243153 -289.744313)
			(xy 47.273177 -289.78835) (xy 47.296303 -289.836371) (xy 47.312013 -289.887301) (xy 47.319956 -289.940005)
			(xy 47.320454 -289.966654) (xy 47.319956 -289.993303) (xy 47.312013 -290.046007) (xy 47.296303 -290.096937)
			(xy 47.273177 -290.144958) (xy 47.243153 -290.188995) (xy 47.206901 -290.228066) (xy 47.16523 -290.261297)
			(xy 47.119072 -290.287946) (xy 47.069458 -290.307418) (xy 47.017496 -290.319278) (xy 46.964346 -290.323262)
			(xy 46.911196 -290.319278) (xy 46.859234 -290.307418) (xy 46.80962 -290.287946) (xy 46.763462 -290.261297)
			(xy 46.721791 -290.228066) (xy 46.685539 -290.188995) (xy 46.655515 -290.144958) (xy 46.632389 -290.096937)
			(xy 46.616679 -290.046007) (xy 46.608736 -289.993303) (xy 32.232356 -289.993303) (xy 32.224413 -290.046007)
			(xy 32.208703 -290.096937) (xy 32.185577 -290.144958) (xy 32.155553 -290.188995) (xy 32.119301 -290.228066)
			(xy 32.07763 -290.261297) (xy 32.031472 -290.287946) (xy 31.981858 -290.307418) (xy 31.929896 -290.319278)
			(xy 31.876746 -290.323262) (xy 31.823596 -290.319278) (xy 31.771634 -290.307418) (xy 31.72202 -290.287946)
			(xy 31.675862 -290.261297) (xy 31.634191 -290.228066) (xy 31.597939 -290.188995) (xy 31.567915 -290.144958)
			(xy 31.544789 -290.096937) (xy 31.529079 -290.046007) (xy 31.521136 -289.993303) (xy 17.144756 -289.993303)
			(xy 17.136813 -290.046007) (xy 17.121103 -290.096937) (xy 17.097977 -290.144958) (xy 17.067953 -290.188995)
			(xy 17.031701 -290.228066) (xy 16.99003 -290.261297) (xy 16.943872 -290.287946) (xy 16.894258 -290.307418)
			(xy 16.842296 -290.319278) (xy 16.789146 -290.323262) (xy 16.735996 -290.319278) (xy 16.684034 -290.307418)
			(xy 16.63442 -290.287946) (xy 16.588262 -290.261297) (xy 16.546591 -290.228066) (xy 16.510339 -290.188995)
			(xy 16.480315 -290.144958) (xy 16.457189 -290.096937) (xy 16.441479 -290.046007) (xy 16.433536 -289.993303)
			(xy 6.7818 -289.993303) (xy 6.7818 -290.843441) (xy 20.533604 -290.843441) (xy 20.533604 -290.790143)
			(xy 20.541547 -290.737439) (xy 20.557257 -290.686509) (xy 20.580383 -290.638488) (xy 20.610407 -290.594451)
			(xy 20.646659 -290.55538) (xy 20.68833 -290.522149) (xy 20.734488 -290.4955) (xy 20.784102 -290.476028)
			(xy 20.836064 -290.464168) (xy 20.889214 -290.460185) (xy 20.942364 -290.464168) (xy 20.994326 -290.476028)
			(xy 21.04394 -290.4955) (xy 21.090098 -290.522149) (xy 21.131769 -290.55538) (xy 21.168021 -290.594451)
			(xy 21.198045 -290.638488) (xy 21.221171 -290.686509) (xy 21.236881 -290.737439) (xy 21.244824 -290.790143)
			(xy 21.245322 -290.816792) (xy 21.244824 -290.843441) (xy 35.621204 -290.843441) (xy 35.621204 -290.790143)
			(xy 35.629147 -290.737439) (xy 35.644857 -290.686509) (xy 35.667983 -290.638488) (xy 35.698007 -290.594451)
			(xy 35.734259 -290.55538) (xy 35.77593 -290.522149) (xy 35.822088 -290.4955) (xy 35.871702 -290.476028)
			(xy 35.923664 -290.464168) (xy 35.976814 -290.460185) (xy 36.029964 -290.464168) (xy 36.081926 -290.476028)
			(xy 36.13154 -290.4955) (xy 36.177698 -290.522149) (xy 36.219369 -290.55538) (xy 36.255621 -290.594451)
			(xy 36.285645 -290.638488) (xy 36.308771 -290.686509) (xy 36.324481 -290.737439) (xy 36.332424 -290.790143)
			(xy 36.332922 -290.816792) (xy 36.332424 -290.843441) (xy 50.734204 -290.843441) (xy 50.734204 -290.790143)
			(xy 50.742147 -290.737439) (xy 50.757857 -290.686509) (xy 50.780983 -290.638488) (xy 50.811007 -290.594451)
			(xy 50.847259 -290.55538) (xy 50.88893 -290.522149) (xy 50.935088 -290.4955) (xy 50.984702 -290.476028)
			(xy 51.036664 -290.464168) (xy 51.089814 -290.460185) (xy 51.142964 -290.464168) (xy 51.194926 -290.476028)
			(xy 51.24454 -290.4955) (xy 51.290698 -290.522149) (xy 51.332369 -290.55538) (xy 51.368621 -290.594451)
			(xy 51.398645 -290.638488) (xy 51.421771 -290.686509) (xy 51.437481 -290.737439) (xy 51.445424 -290.790143)
			(xy 51.445922 -290.816792) (xy 51.445424 -290.843441) (xy 51.437481 -290.896145) (xy 51.421771 -290.947075)
			(xy 51.398645 -290.995096) (xy 51.368621 -291.039133) (xy 51.332369 -291.078204) (xy 51.290698 -291.111435)
			(xy 51.24454 -291.138084) (xy 51.194926 -291.157556) (xy 51.142964 -291.169416) (xy 51.089814 -291.1734)
			(xy 51.036664 -291.169416) (xy 50.984702 -291.157556) (xy 50.935088 -291.138084) (xy 50.88893 -291.111435)
			(xy 50.847259 -291.078204) (xy 50.811007 -291.039133) (xy 50.780983 -290.995096) (xy 50.757857 -290.947075)
			(xy 50.742147 -290.896145) (xy 50.734204 -290.843441) (xy 36.332424 -290.843441) (xy 36.324481 -290.896145)
			(xy 36.308771 -290.947075) (xy 36.285645 -290.995096) (xy 36.255621 -291.039133) (xy 36.219369 -291.078204)
			(xy 36.177698 -291.111435) (xy 36.13154 -291.138084) (xy 36.081926 -291.157556) (xy 36.029964 -291.169416)
			(xy 35.976814 -291.1734) (xy 35.923664 -291.169416) (xy 35.871702 -291.157556) (xy 35.822088 -291.138084)
			(xy 35.77593 -291.111435) (xy 35.734259 -291.078204) (xy 35.698007 -291.039133) (xy 35.667983 -290.995096)
			(xy 35.644857 -290.947075) (xy 35.629147 -290.896145) (xy 35.621204 -290.843441) (xy 21.244824 -290.843441)
			(xy 21.236881 -290.896145) (xy 21.221171 -290.947075) (xy 21.198045 -290.995096) (xy 21.168021 -291.039133)
			(xy 21.131769 -291.078204) (xy 21.090098 -291.111435) (xy 21.04394 -291.138084) (xy 20.994326 -291.157556)
			(xy 20.942364 -291.169416) (xy 20.889214 -291.1734) (xy 20.836064 -291.169416) (xy 20.784102 -291.157556)
			(xy 20.734488 -291.138084) (xy 20.68833 -291.111435) (xy 20.646659 -291.078204) (xy 20.610407 -291.039133)
			(xy 20.580383 -290.995096) (xy 20.557257 -290.947075) (xy 20.541547 -290.896145) (xy 20.533604 -290.843441)
			(xy 6.7818 -290.843441) (xy 6.7818 -291.693325) (xy 16.433536 -291.693325) (xy 16.433536 -291.640027)
			(xy 16.441479 -291.587323) (xy 16.457189 -291.536393) (xy 16.480315 -291.488372) (xy 16.510339 -291.444335)
			(xy 16.546591 -291.405264) (xy 16.588262 -291.372033) (xy 16.63442 -291.345384) (xy 16.684034 -291.325912)
			(xy 16.735996 -291.314052) (xy 16.789146 -291.310069) (xy 16.842296 -291.314052) (xy 16.894258 -291.325912)
			(xy 16.943872 -291.345384) (xy 16.99003 -291.372033) (xy 17.031701 -291.405264) (xy 17.067953 -291.444335)
			(xy 17.097977 -291.488372) (xy 17.121103 -291.536393) (xy 17.136813 -291.587323) (xy 17.144756 -291.640027)
			(xy 17.145254 -291.666676) (xy 17.144756 -291.693325) (xy 31.521136 -291.693325) (xy 31.521136 -291.640027)
			(xy 31.529079 -291.587323) (xy 31.544789 -291.536393) (xy 31.567915 -291.488372) (xy 31.597939 -291.444335)
			(xy 31.634191 -291.405264) (xy 31.675862 -291.372033) (xy 31.72202 -291.345384) (xy 31.771634 -291.325912)
			(xy 31.823596 -291.314052) (xy 31.876746 -291.310069) (xy 31.929896 -291.314052) (xy 31.981858 -291.325912)
			(xy 32.031472 -291.345384) (xy 32.07763 -291.372033) (xy 32.119301 -291.405264) (xy 32.155553 -291.444335)
			(xy 32.185577 -291.488372) (xy 32.208703 -291.536393) (xy 32.224413 -291.587323) (xy 32.232356 -291.640027)
			(xy 32.232854 -291.666676) (xy 32.232356 -291.693325) (xy 46.608736 -291.693325) (xy 46.608736 -291.640027)
			(xy 46.616679 -291.587323) (xy 46.632389 -291.536393) (xy 46.655515 -291.488372) (xy 46.685539 -291.444335)
			(xy 46.721791 -291.405264) (xy 46.763462 -291.372033) (xy 46.80962 -291.345384) (xy 46.859234 -291.325912)
			(xy 46.911196 -291.314052) (xy 46.964346 -291.310069) (xy 47.017496 -291.314052) (xy 47.069458 -291.325912)
			(xy 47.119072 -291.345384) (xy 47.16523 -291.372033) (xy 47.206901 -291.405264) (xy 47.243153 -291.444335)
			(xy 47.273177 -291.488372) (xy 47.296303 -291.536393) (xy 47.312013 -291.587323) (xy 47.319956 -291.640027)
			(xy 47.320454 -291.666676) (xy 47.319956 -291.693325) (xy 47.312013 -291.746029) (xy 47.296303 -291.796959)
			(xy 47.273177 -291.84498) (xy 47.243153 -291.889017) (xy 47.206901 -291.928088) (xy 47.16523 -291.961319)
			(xy 47.119072 -291.987968) (xy 47.069458 -292.00744) (xy 47.017496 -292.0193) (xy 46.964346 -292.023284)
			(xy 46.911196 -292.0193) (xy 46.859234 -292.00744) (xy 46.80962 -291.987968) (xy 46.763462 -291.961319)
			(xy 46.721791 -291.928088) (xy 46.685539 -291.889017) (xy 46.655515 -291.84498) (xy 46.632389 -291.796959)
			(xy 46.616679 -291.746029) (xy 46.608736 -291.693325) (xy 32.232356 -291.693325) (xy 32.224413 -291.746029)
			(xy 32.208703 -291.796959) (xy 32.185577 -291.84498) (xy 32.155553 -291.889017) (xy 32.119301 -291.928088)
			(xy 32.07763 -291.961319) (xy 32.031472 -291.987968) (xy 31.981858 -292.00744) (xy 31.929896 -292.0193)
			(xy 31.876746 -292.023284) (xy 31.823596 -292.0193) (xy 31.771634 -292.00744) (xy 31.72202 -291.987968)
			(xy 31.675862 -291.961319) (xy 31.634191 -291.928088) (xy 31.597939 -291.889017) (xy 31.567915 -291.84498)
			(xy 31.544789 -291.796959) (xy 31.529079 -291.746029) (xy 31.521136 -291.693325) (xy 17.144756 -291.693325)
			(xy 17.136813 -291.746029) (xy 17.121103 -291.796959) (xy 17.097977 -291.84498) (xy 17.067953 -291.889017)
			(xy 17.031701 -291.928088) (xy 16.99003 -291.961319) (xy 16.943872 -291.987968) (xy 16.894258 -292.00744)
			(xy 16.842296 -292.0193) (xy 16.789146 -292.023284) (xy 16.735996 -292.0193) (xy 16.684034 -292.00744)
			(xy 16.63442 -291.987968) (xy 16.588262 -291.961319) (xy 16.546591 -291.928088) (xy 16.510339 -291.889017)
			(xy 16.480315 -291.84498) (xy 16.457189 -291.796959) (xy 16.441479 -291.746029) (xy 16.433536 -291.693325)
			(xy 6.7818 -291.693325) (xy 6.7818 -292.543463) (xy 20.533604 -292.543463) (xy 20.533604 -292.490165)
			(xy 20.541547 -292.437461) (xy 20.557257 -292.386531) (xy 20.580383 -292.33851) (xy 20.610407 -292.294473)
			(xy 20.646659 -292.255402) (xy 20.68833 -292.222171) (xy 20.734488 -292.195522) (xy 20.784102 -292.17605)
			(xy 20.836064 -292.16419) (xy 20.889214 -292.160207) (xy 20.942364 -292.16419) (xy 20.994326 -292.17605)
			(xy 21.04394 -292.195522) (xy 21.090098 -292.222171) (xy 21.131769 -292.255402) (xy 21.168021 -292.294473)
			(xy 21.198045 -292.33851) (xy 21.221171 -292.386531) (xy 21.236881 -292.437461) (xy 21.244824 -292.490165)
			(xy 21.245322 -292.516814) (xy 21.244824 -292.543463) (xy 35.621204 -292.543463) (xy 35.621204 -292.490165)
			(xy 35.629147 -292.437461) (xy 35.644857 -292.386531) (xy 35.667983 -292.33851) (xy 35.698007 -292.294473)
			(xy 35.734259 -292.255402) (xy 35.77593 -292.222171) (xy 35.822088 -292.195522) (xy 35.871702 -292.17605)
			(xy 35.923664 -292.16419) (xy 35.976814 -292.160207) (xy 36.029964 -292.16419) (xy 36.081926 -292.17605)
			(xy 36.13154 -292.195522) (xy 36.177698 -292.222171) (xy 36.219369 -292.255402) (xy 36.255621 -292.294473)
			(xy 36.285645 -292.33851) (xy 36.308771 -292.386531) (xy 36.324481 -292.437461) (xy 36.332424 -292.490165)
			(xy 36.332922 -292.516814) (xy 36.332424 -292.543463) (xy 50.734204 -292.543463) (xy 50.734204 -292.490165)
			(xy 50.742147 -292.437461) (xy 50.757857 -292.386531) (xy 50.780983 -292.33851) (xy 50.811007 -292.294473)
			(xy 50.847259 -292.255402) (xy 50.88893 -292.222171) (xy 50.935088 -292.195522) (xy 50.984702 -292.17605)
			(xy 51.036664 -292.16419) (xy 51.089814 -292.160207) (xy 51.142964 -292.16419) (xy 51.194926 -292.17605)
			(xy 51.24454 -292.195522) (xy 51.290698 -292.222171) (xy 51.332369 -292.255402) (xy 51.368621 -292.294473)
			(xy 51.398645 -292.33851) (xy 51.421771 -292.386531) (xy 51.437481 -292.437461) (xy 51.445424 -292.490165)
			(xy 51.445922 -292.516814) (xy 51.445424 -292.543463) (xy 51.437481 -292.596167) (xy 51.421771 -292.647097)
			(xy 51.398645 -292.695118) (xy 51.368621 -292.739155) (xy 51.332369 -292.778226) (xy 51.290698 -292.811457)
			(xy 51.24454 -292.838106) (xy 51.194926 -292.857578) (xy 51.142964 -292.869438) (xy 51.089814 -292.873422)
			(xy 51.036664 -292.869438) (xy 50.984702 -292.857578) (xy 50.935088 -292.838106) (xy 50.88893 -292.811457)
			(xy 50.847259 -292.778226) (xy 50.811007 -292.739155) (xy 50.780983 -292.695118) (xy 50.757857 -292.647097)
			(xy 50.742147 -292.596167) (xy 50.734204 -292.543463) (xy 36.332424 -292.543463) (xy 36.324481 -292.596167)
			(xy 36.308771 -292.647097) (xy 36.285645 -292.695118) (xy 36.255621 -292.739155) (xy 36.219369 -292.778226)
			(xy 36.177698 -292.811457) (xy 36.13154 -292.838106) (xy 36.081926 -292.857578) (xy 36.029964 -292.869438)
			(xy 35.976814 -292.873422) (xy 35.923664 -292.869438) (xy 35.871702 -292.857578) (xy 35.822088 -292.838106)
			(xy 35.77593 -292.811457) (xy 35.734259 -292.778226) (xy 35.698007 -292.739155) (xy 35.667983 -292.695118)
			(xy 35.644857 -292.647097) (xy 35.629147 -292.596167) (xy 35.621204 -292.543463) (xy 21.244824 -292.543463)
			(xy 21.236881 -292.596167) (xy 21.221171 -292.647097) (xy 21.198045 -292.695118) (xy 21.168021 -292.739155)
			(xy 21.131769 -292.778226) (xy 21.090098 -292.811457) (xy 21.04394 -292.838106) (xy 20.994326 -292.857578)
			(xy 20.942364 -292.869438) (xy 20.889214 -292.873422) (xy 20.836064 -292.869438) (xy 20.784102 -292.857578)
			(xy 20.734488 -292.838106) (xy 20.68833 -292.811457) (xy 20.646659 -292.778226) (xy 20.610407 -292.739155)
			(xy 20.580383 -292.695118) (xy 20.557257 -292.647097) (xy 20.541547 -292.596167) (xy 20.533604 -292.543463)
			(xy 6.7818 -292.543463) (xy 6.7818 -293.393347) (xy 16.433536 -293.393347) (xy 16.433536 -293.340049)
			(xy 16.441479 -293.287345) (xy 16.457189 -293.236415) (xy 16.480315 -293.188394) (xy 16.510339 -293.144357)
			(xy 16.546591 -293.105286) (xy 16.588262 -293.072055) (xy 16.63442 -293.045406) (xy 16.684034 -293.025934)
			(xy 16.735996 -293.014074) (xy 16.789146 -293.010091) (xy 16.842296 -293.014074) (xy 16.894258 -293.025934)
			(xy 16.943872 -293.045406) (xy 16.99003 -293.072055) (xy 17.031701 -293.105286) (xy 17.067953 -293.144357)
			(xy 17.097977 -293.188394) (xy 17.121103 -293.236415) (xy 17.136813 -293.287345) (xy 17.144756 -293.340049)
			(xy 17.145254 -293.366698) (xy 17.144756 -293.393347) (xy 20.533604 -293.393347) (xy 20.533604 -293.340049)
			(xy 20.541547 -293.287345) (xy 20.557257 -293.236415) (xy 20.580383 -293.188394) (xy 20.610407 -293.144357)
			(xy 20.646659 -293.105286) (xy 20.68833 -293.072055) (xy 20.734488 -293.045406) (xy 20.784102 -293.025934)
			(xy 20.836064 -293.014074) (xy 20.889214 -293.010091) (xy 20.942364 -293.014074) (xy 20.994326 -293.025934)
			(xy 21.04394 -293.045406) (xy 21.090098 -293.072055) (xy 21.131769 -293.105286) (xy 21.168021 -293.144357)
			(xy 21.198045 -293.188394) (xy 21.221171 -293.236415) (xy 21.236881 -293.287345) (xy 21.244824 -293.340049)
			(xy 21.245322 -293.366698) (xy 21.244824 -293.393347) (xy 31.521136 -293.393347) (xy 31.521136 -293.340049)
			(xy 31.529079 -293.287345) (xy 31.544789 -293.236415) (xy 31.567915 -293.188394) (xy 31.597939 -293.144357)
			(xy 31.634191 -293.105286) (xy 31.675862 -293.072055) (xy 31.72202 -293.045406) (xy 31.771634 -293.025934)
			(xy 31.823596 -293.014074) (xy 31.876746 -293.010091) (xy 31.929896 -293.014074) (xy 31.981858 -293.025934)
			(xy 32.031472 -293.045406) (xy 32.07763 -293.072055) (xy 32.119301 -293.105286) (xy 32.155553 -293.144357)
			(xy 32.185577 -293.188394) (xy 32.208703 -293.236415) (xy 32.224413 -293.287345) (xy 32.232356 -293.340049)
			(xy 32.232854 -293.366698) (xy 32.232356 -293.393347) (xy 35.621204 -293.393347) (xy 35.621204 -293.340049)
			(xy 35.629147 -293.287345) (xy 35.644857 -293.236415) (xy 35.667983 -293.188394) (xy 35.698007 -293.144357)
			(xy 35.734259 -293.105286) (xy 35.77593 -293.072055) (xy 35.822088 -293.045406) (xy 35.871702 -293.025934)
			(xy 35.923664 -293.014074) (xy 35.976814 -293.010091) (xy 36.029964 -293.014074) (xy 36.081926 -293.025934)
			(xy 36.13154 -293.045406) (xy 36.177698 -293.072055) (xy 36.219369 -293.105286) (xy 36.255621 -293.144357)
			(xy 36.285645 -293.188394) (xy 36.308771 -293.236415) (xy 36.324481 -293.287345) (xy 36.332424 -293.340049)
			(xy 36.332922 -293.366698) (xy 36.332424 -293.393347) (xy 46.608736 -293.393347) (xy 46.608736 -293.340049)
			(xy 46.616679 -293.287345) (xy 46.632389 -293.236415) (xy 46.655515 -293.188394) (xy 46.685539 -293.144357)
			(xy 46.721791 -293.105286) (xy 46.763462 -293.072055) (xy 46.80962 -293.045406) (xy 46.859234 -293.025934)
			(xy 46.911196 -293.014074) (xy 46.964346 -293.010091) (xy 47.017496 -293.014074) (xy 47.069458 -293.025934)
			(xy 47.119072 -293.045406) (xy 47.16523 -293.072055) (xy 47.206901 -293.105286) (xy 47.243153 -293.144357)
			(xy 47.273177 -293.188394) (xy 47.296303 -293.236415) (xy 47.312013 -293.287345) (xy 47.319956 -293.340049)
			(xy 47.320454 -293.366698) (xy 47.319956 -293.393347) (xy 47.319918 -293.393601) (xy 50.734204 -293.393601)
			(xy 50.734204 -293.340303) (xy 50.742147 -293.287599) (xy 50.757857 -293.236669) (xy 50.780983 -293.188648)
			(xy 50.811007 -293.144611) (xy 50.847259 -293.10554) (xy 50.88893 -293.072309) (xy 50.935088 -293.04566)
			(xy 50.984702 -293.026188) (xy 51.036664 -293.014328) (xy 51.089814 -293.010345) (xy 51.142964 -293.014328)
			(xy 51.194926 -293.026188) (xy 51.24454 -293.04566) (xy 51.290698 -293.072309) (xy 51.332369 -293.10554)
			(xy 51.368621 -293.144611) (xy 51.398645 -293.188648) (xy 51.421771 -293.236669) (xy 51.437481 -293.287599)
			(xy 51.445424 -293.340303) (xy 51.445922 -293.366952) (xy 51.445424 -293.393601) (xy 51.437481 -293.446305)
			(xy 51.421771 -293.497235) (xy 51.398645 -293.545256) (xy 51.368621 -293.589293) (xy 51.332369 -293.628364)
			(xy 51.290698 -293.661595) (xy 51.24454 -293.688244) (xy 51.194926 -293.707716) (xy 51.142964 -293.719576)
			(xy 51.089814 -293.72356) (xy 51.036664 -293.719576) (xy 50.984702 -293.707716) (xy 50.935088 -293.688244)
			(xy 50.88893 -293.661595) (xy 50.847259 -293.628364) (xy 50.811007 -293.589293) (xy 50.780983 -293.545256)
			(xy 50.757857 -293.497235) (xy 50.742147 -293.446305) (xy 50.734204 -293.393601) (xy 47.319918 -293.393601)
			(xy 47.312013 -293.446051) (xy 47.296303 -293.496981) (xy 47.273177 -293.545002) (xy 47.243153 -293.589039)
			(xy 47.206901 -293.62811) (xy 47.16523 -293.661341) (xy 47.119072 -293.68799) (xy 47.069458 -293.707462)
			(xy 47.017496 -293.719322) (xy 46.964346 -293.723306) (xy 46.911196 -293.719322) (xy 46.859234 -293.707462)
			(xy 46.80962 -293.68799) (xy 46.763462 -293.661341) (xy 46.721791 -293.62811) (xy 46.685539 -293.589039)
			(xy 46.655515 -293.545002) (xy 46.632389 -293.496981) (xy 46.616679 -293.446051) (xy 46.608736 -293.393347)
			(xy 36.332424 -293.393347) (xy 36.324481 -293.446051) (xy 36.308771 -293.496981) (xy 36.285645 -293.545002)
			(xy 36.255621 -293.589039) (xy 36.219369 -293.62811) (xy 36.177698 -293.661341) (xy 36.13154 -293.68799)
			(xy 36.081926 -293.707462) (xy 36.029964 -293.719322) (xy 35.976814 -293.723306) (xy 35.923664 -293.719322)
			(xy 35.871702 -293.707462) (xy 35.822088 -293.68799) (xy 35.77593 -293.661341) (xy 35.734259 -293.62811)
			(xy 35.698007 -293.589039) (xy 35.667983 -293.545002) (xy 35.644857 -293.496981) (xy 35.629147 -293.446051)
			(xy 35.621204 -293.393347) (xy 32.232356 -293.393347) (xy 32.224413 -293.446051) (xy 32.208703 -293.496981)
			(xy 32.185577 -293.545002) (xy 32.155553 -293.589039) (xy 32.119301 -293.62811) (xy 32.07763 -293.661341)
			(xy 32.031472 -293.68799) (xy 31.981858 -293.707462) (xy 31.929896 -293.719322) (xy 31.876746 -293.723306)
			(xy 31.823596 -293.719322) (xy 31.771634 -293.707462) (xy 31.72202 -293.68799) (xy 31.675862 -293.661341)
			(xy 31.634191 -293.62811) (xy 31.597939 -293.589039) (xy 31.567915 -293.545002) (xy 31.544789 -293.496981)
			(xy 31.529079 -293.446051) (xy 31.521136 -293.393347) (xy 21.244824 -293.393347) (xy 21.236881 -293.446051)
			(xy 21.221171 -293.496981) (xy 21.198045 -293.545002) (xy 21.168021 -293.589039) (xy 21.131769 -293.62811)
			(xy 21.090098 -293.661341) (xy 21.04394 -293.68799) (xy 20.994326 -293.707462) (xy 20.942364 -293.719322)
			(xy 20.889214 -293.723306) (xy 20.836064 -293.719322) (xy 20.784102 -293.707462) (xy 20.734488 -293.68799)
			(xy 20.68833 -293.661341) (xy 20.646659 -293.62811) (xy 20.610407 -293.589039) (xy 20.580383 -293.545002)
			(xy 20.557257 -293.496981) (xy 20.541547 -293.446051) (xy 20.533604 -293.393347) (xy 17.144756 -293.393347)
			(xy 17.136813 -293.446051) (xy 17.121103 -293.496981) (xy 17.097977 -293.545002) (xy 17.067953 -293.589039)
			(xy 17.031701 -293.62811) (xy 16.99003 -293.661341) (xy 16.943872 -293.68799) (xy 16.894258 -293.707462)
			(xy 16.842296 -293.719322) (xy 16.789146 -293.723306) (xy 16.735996 -293.719322) (xy 16.684034 -293.707462)
			(xy 16.63442 -293.68799) (xy 16.588262 -293.661341) (xy 16.546591 -293.62811) (xy 16.510339 -293.589039)
			(xy 16.480315 -293.545002) (xy 16.457189 -293.496981) (xy 16.441479 -293.446051) (xy 16.433536 -293.393347)
			(xy 6.7818 -293.393347) (xy 6.7818 -294.243231) (xy 16.433536 -294.243231) (xy 16.433536 -294.189933)
			(xy 16.441479 -294.137229) (xy 16.457189 -294.086299) (xy 16.480315 -294.038278) (xy 16.510339 -293.994241)
			(xy 16.546591 -293.95517) (xy 16.588262 -293.921939) (xy 16.63442 -293.89529) (xy 16.684034 -293.875818)
			(xy 16.735996 -293.863958) (xy 16.789146 -293.859975) (xy 16.842296 -293.863958) (xy 16.894258 -293.875818)
			(xy 16.943872 -293.89529) (xy 16.99003 -293.921939) (xy 17.031701 -293.95517) (xy 17.067953 -293.994241)
			(xy 17.097977 -294.038278) (xy 17.121103 -294.086299) (xy 17.136813 -294.137229) (xy 17.144756 -294.189933)
			(xy 17.145254 -294.216582) (xy 17.144756 -294.243231) (xy 31.521136 -294.243231) (xy 31.521136 -294.189933)
			(xy 31.529079 -294.137229) (xy 31.544789 -294.086299) (xy 31.567915 -294.038278) (xy 31.597939 -293.994241)
			(xy 31.634191 -293.95517) (xy 31.675862 -293.921939) (xy 31.72202 -293.89529) (xy 31.771634 -293.875818)
			(xy 31.823596 -293.863958) (xy 31.876746 -293.859975) (xy 31.929896 -293.863958) (xy 31.981858 -293.875818)
			(xy 32.031472 -293.89529) (xy 32.07763 -293.921939) (xy 32.119301 -293.95517) (xy 32.155553 -293.994241)
			(xy 32.185577 -294.038278) (xy 32.208703 -294.086299) (xy 32.224413 -294.137229) (xy 32.232356 -294.189933)
			(xy 32.232854 -294.216582) (xy 32.232356 -294.243231) (xy 46.608736 -294.243231) (xy 46.608736 -294.189933)
			(xy 46.616679 -294.137229) (xy 46.632389 -294.086299) (xy 46.655515 -294.038278) (xy 46.685539 -293.994241)
			(xy 46.721791 -293.95517) (xy 46.763462 -293.921939) (xy 46.80962 -293.89529) (xy 46.859234 -293.875818)
			(xy 46.911196 -293.863958) (xy 46.964346 -293.859975) (xy 47.017496 -293.863958) (xy 47.069458 -293.875818)
			(xy 47.119072 -293.89529) (xy 47.16523 -293.921939) (xy 47.206901 -293.95517) (xy 47.243153 -293.994241)
			(xy 47.273177 -294.038278) (xy 47.296303 -294.086299) (xy 47.312013 -294.137229) (xy 47.319956 -294.189933)
			(xy 47.320454 -294.216582) (xy 47.319956 -294.243231) (xy 47.312013 -294.295935) (xy 47.296303 -294.346865)
			(xy 47.273177 -294.394886) (xy 47.243153 -294.438923) (xy 47.206901 -294.477994) (xy 47.16523 -294.511225)
			(xy 47.119072 -294.537874) (xy 47.069458 -294.557346) (xy 47.017496 -294.569206) (xy 46.964346 -294.57319)
			(xy 46.911196 -294.569206) (xy 46.859234 -294.557346) (xy 46.80962 -294.537874) (xy 46.763462 -294.511225)
			(xy 46.721791 -294.477994) (xy 46.685539 -294.438923) (xy 46.655515 -294.394886) (xy 46.632389 -294.346865)
			(xy 46.616679 -294.295935) (xy 46.608736 -294.243231) (xy 32.232356 -294.243231) (xy 32.224413 -294.295935)
			(xy 32.208703 -294.346865) (xy 32.185577 -294.394886) (xy 32.155553 -294.438923) (xy 32.119301 -294.477994)
			(xy 32.07763 -294.511225) (xy 32.031472 -294.537874) (xy 31.981858 -294.557346) (xy 31.929896 -294.569206)
			(xy 31.876746 -294.57319) (xy 31.823596 -294.569206) (xy 31.771634 -294.557346) (xy 31.72202 -294.537874)
			(xy 31.675862 -294.511225) (xy 31.634191 -294.477994) (xy 31.597939 -294.438923) (xy 31.567915 -294.394886)
			(xy 31.544789 -294.346865) (xy 31.529079 -294.295935) (xy 31.521136 -294.243231) (xy 17.144756 -294.243231)
			(xy 17.136813 -294.295935) (xy 17.121103 -294.346865) (xy 17.097977 -294.394886) (xy 17.067953 -294.438923)
			(xy 17.031701 -294.477994) (xy 16.99003 -294.511225) (xy 16.943872 -294.537874) (xy 16.894258 -294.557346)
			(xy 16.842296 -294.569206) (xy 16.789146 -294.57319) (xy 16.735996 -294.569206) (xy 16.684034 -294.557346)
			(xy 16.63442 -294.537874) (xy 16.588262 -294.511225) (xy 16.546591 -294.477994) (xy 16.510339 -294.438923)
			(xy 16.480315 -294.394886) (xy 16.457189 -294.346865) (xy 16.441479 -294.295935) (xy 16.433536 -294.243231)
			(xy 6.7818 -294.243231) (xy 6.7818 -295.093369) (xy 20.533604 -295.093369) (xy 20.533604 -295.040071)
			(xy 20.541547 -294.987367) (xy 20.557257 -294.936437) (xy 20.580383 -294.888416) (xy 20.610407 -294.844379)
			(xy 20.646659 -294.805308) (xy 20.68833 -294.772077) (xy 20.734488 -294.745428) (xy 20.784102 -294.725956)
			(xy 20.836064 -294.714096) (xy 20.889214 -294.710113) (xy 20.942364 -294.714096) (xy 20.994326 -294.725956)
			(xy 21.04394 -294.745428) (xy 21.090098 -294.772077) (xy 21.131769 -294.805308) (xy 21.168021 -294.844379)
			(xy 21.198045 -294.888416) (xy 21.221171 -294.936437) (xy 21.236881 -294.987367) (xy 21.244824 -295.040071)
			(xy 21.245322 -295.06672) (xy 21.244824 -295.093369) (xy 35.621204 -295.093369) (xy 35.621204 -295.040071)
			(xy 35.629147 -294.987367) (xy 35.644857 -294.936437) (xy 35.667983 -294.888416) (xy 35.698007 -294.844379)
			(xy 35.734259 -294.805308) (xy 35.77593 -294.772077) (xy 35.822088 -294.745428) (xy 35.871702 -294.725956)
			(xy 35.923664 -294.714096) (xy 35.976814 -294.710113) (xy 36.029964 -294.714096) (xy 36.081926 -294.725956)
			(xy 36.13154 -294.745428) (xy 36.177698 -294.772077) (xy 36.219369 -294.805308) (xy 36.255621 -294.844379)
			(xy 36.285645 -294.888416) (xy 36.308771 -294.936437) (xy 36.324481 -294.987367) (xy 36.332424 -295.040071)
			(xy 36.332922 -295.06672) (xy 36.332424 -295.093369) (xy 50.734204 -295.093369) (xy 50.734204 -295.040071)
			(xy 50.742147 -294.987367) (xy 50.757857 -294.936437) (xy 50.780983 -294.888416) (xy 50.811007 -294.844379)
			(xy 50.847259 -294.805308) (xy 50.88893 -294.772077) (xy 50.935088 -294.745428) (xy 50.984702 -294.725956)
			(xy 51.036664 -294.714096) (xy 51.089814 -294.710113) (xy 51.142964 -294.714096) (xy 51.194926 -294.725956)
			(xy 51.24454 -294.745428) (xy 51.290698 -294.772077) (xy 51.332369 -294.805308) (xy 51.368621 -294.844379)
			(xy 51.398645 -294.888416) (xy 51.421771 -294.936437) (xy 51.437481 -294.987367) (xy 51.445424 -295.040071)
			(xy 51.445922 -295.06672) (xy 51.445424 -295.093369) (xy 51.437481 -295.146073) (xy 51.421771 -295.197003)
			(xy 51.398645 -295.245024) (xy 51.368621 -295.289061) (xy 51.332369 -295.328132) (xy 51.290698 -295.361363)
			(xy 51.24454 -295.388012) (xy 51.194926 -295.407484) (xy 51.142964 -295.419344) (xy 51.089814 -295.423328)
			(xy 51.036664 -295.419344) (xy 50.984702 -295.407484) (xy 50.935088 -295.388012) (xy 50.88893 -295.361363)
			(xy 50.847259 -295.328132) (xy 50.811007 -295.289061) (xy 50.780983 -295.245024) (xy 50.757857 -295.197003)
			(xy 50.742147 -295.146073) (xy 50.734204 -295.093369) (xy 36.332424 -295.093369) (xy 36.324481 -295.146073)
			(xy 36.308771 -295.197003) (xy 36.285645 -295.245024) (xy 36.255621 -295.289061) (xy 36.219369 -295.328132)
			(xy 36.177698 -295.361363) (xy 36.13154 -295.388012) (xy 36.081926 -295.407484) (xy 36.029964 -295.419344)
			(xy 35.976814 -295.423328) (xy 35.923664 -295.419344) (xy 35.871702 -295.407484) (xy 35.822088 -295.388012)
			(xy 35.77593 -295.361363) (xy 35.734259 -295.328132) (xy 35.698007 -295.289061) (xy 35.667983 -295.245024)
			(xy 35.644857 -295.197003) (xy 35.629147 -295.146073) (xy 35.621204 -295.093369) (xy 21.244824 -295.093369)
			(xy 21.236881 -295.146073) (xy 21.221171 -295.197003) (xy 21.198045 -295.245024) (xy 21.168021 -295.289061)
			(xy 21.131769 -295.328132) (xy 21.090098 -295.361363) (xy 21.04394 -295.388012) (xy 20.994326 -295.407484)
			(xy 20.942364 -295.419344) (xy 20.889214 -295.423328) (xy 20.836064 -295.419344) (xy 20.784102 -295.407484)
			(xy 20.734488 -295.388012) (xy 20.68833 -295.361363) (xy 20.646659 -295.328132) (xy 20.610407 -295.289061)
			(xy 20.580383 -295.245024) (xy 20.557257 -295.197003) (xy 20.541547 -295.146073) (xy 20.533604 -295.093369)
			(xy 6.7818 -295.093369) (xy 6.7818 -295.943253) (xy 16.433536 -295.943253) (xy 16.433536 -295.889955)
			(xy 16.441479 -295.837251) (xy 16.457189 -295.786321) (xy 16.480315 -295.7383) (xy 16.510339 -295.694263)
			(xy 16.546591 -295.655192) (xy 16.588262 -295.621961) (xy 16.63442 -295.595312) (xy 16.684034 -295.57584)
			(xy 16.735996 -295.56398) (xy 16.789146 -295.559997) (xy 16.842296 -295.56398) (xy 16.894258 -295.57584)
			(xy 16.943872 -295.595312) (xy 16.99003 -295.621961) (xy 17.031701 -295.655192) (xy 17.067953 -295.694263)
			(xy 17.097977 -295.7383) (xy 17.121103 -295.786321) (xy 17.136813 -295.837251) (xy 17.144756 -295.889955)
			(xy 17.145254 -295.916604) (xy 17.144756 -295.943253) (xy 31.521136 -295.943253) (xy 31.521136 -295.889955)
			(xy 31.529079 -295.837251) (xy 31.544789 -295.786321) (xy 31.567915 -295.7383) (xy 31.597939 -295.694263)
			(xy 31.634191 -295.655192) (xy 31.675862 -295.621961) (xy 31.72202 -295.595312) (xy 31.771634 -295.57584)
			(xy 31.823596 -295.56398) (xy 31.876746 -295.559997) (xy 31.929896 -295.56398) (xy 31.981858 -295.57584)
			(xy 32.031472 -295.595312) (xy 32.07763 -295.621961) (xy 32.119301 -295.655192) (xy 32.155553 -295.694263)
			(xy 32.185577 -295.7383) (xy 32.208703 -295.786321) (xy 32.224413 -295.837251) (xy 32.232356 -295.889955)
			(xy 32.232854 -295.916604) (xy 32.232356 -295.943253) (xy 46.608736 -295.943253) (xy 46.608736 -295.889955)
			(xy 46.616679 -295.837251) (xy 46.632389 -295.786321) (xy 46.655515 -295.7383) (xy 46.685539 -295.694263)
			(xy 46.721791 -295.655192) (xy 46.763462 -295.621961) (xy 46.80962 -295.595312) (xy 46.859234 -295.57584)
			(xy 46.911196 -295.56398) (xy 46.964346 -295.559997) (xy 47.017496 -295.56398) (xy 47.069458 -295.57584)
			(xy 47.119072 -295.595312) (xy 47.16523 -295.621961) (xy 47.206901 -295.655192) (xy 47.243153 -295.694263)
			(xy 47.273177 -295.7383) (xy 47.296303 -295.786321) (xy 47.312013 -295.837251) (xy 47.319956 -295.889955)
			(xy 47.320454 -295.916604) (xy 47.319956 -295.943253) (xy 47.312013 -295.995957) (xy 47.296303 -296.046887)
			(xy 47.273177 -296.094908) (xy 47.243153 -296.138945) (xy 47.206901 -296.178016) (xy 47.16523 -296.211247)
			(xy 47.119072 -296.237896) (xy 47.069458 -296.257368) (xy 47.017496 -296.269228) (xy 46.964346 -296.273212)
			(xy 46.911196 -296.269228) (xy 46.859234 -296.257368) (xy 46.80962 -296.237896) (xy 46.763462 -296.211247)
			(xy 46.721791 -296.178016) (xy 46.685539 -296.138945) (xy 46.655515 -296.094908) (xy 46.632389 -296.046887)
			(xy 46.616679 -295.995957) (xy 46.608736 -295.943253) (xy 32.232356 -295.943253) (xy 32.224413 -295.995957)
			(xy 32.208703 -296.046887) (xy 32.185577 -296.094908) (xy 32.155553 -296.138945) (xy 32.119301 -296.178016)
			(xy 32.07763 -296.211247) (xy 32.031472 -296.237896) (xy 31.981858 -296.257368) (xy 31.929896 -296.269228)
			(xy 31.876746 -296.273212) (xy 31.823596 -296.269228) (xy 31.771634 -296.257368) (xy 31.72202 -296.237896)
			(xy 31.675862 -296.211247) (xy 31.634191 -296.178016) (xy 31.597939 -296.138945) (xy 31.567915 -296.094908)
			(xy 31.544789 -296.046887) (xy 31.529079 -295.995957) (xy 31.521136 -295.943253) (xy 17.144756 -295.943253)
			(xy 17.136813 -295.995957) (xy 17.121103 -296.046887) (xy 17.097977 -296.094908) (xy 17.067953 -296.138945)
			(xy 17.031701 -296.178016) (xy 16.99003 -296.211247) (xy 16.943872 -296.237896) (xy 16.894258 -296.257368)
			(xy 16.842296 -296.269228) (xy 16.789146 -296.273212) (xy 16.735996 -296.269228) (xy 16.684034 -296.257368)
			(xy 16.63442 -296.237896) (xy 16.588262 -296.211247) (xy 16.546591 -296.178016) (xy 16.510339 -296.138945)
			(xy 16.480315 -296.094908) (xy 16.457189 -296.046887) (xy 16.441479 -295.995957) (xy 16.433536 -295.943253)
			(xy 6.7818 -295.943253) (xy 6.7818 -296.793391) (xy 20.533604 -296.793391) (xy 20.533604 -296.740093)
			(xy 20.541547 -296.687389) (xy 20.557257 -296.636459) (xy 20.580383 -296.588438) (xy 20.610407 -296.544401)
			(xy 20.646659 -296.50533) (xy 20.68833 -296.472099) (xy 20.734488 -296.44545) (xy 20.784102 -296.425978)
			(xy 20.836064 -296.414118) (xy 20.889214 -296.410135) (xy 20.942364 -296.414118) (xy 20.994326 -296.425978)
			(xy 21.04394 -296.44545) (xy 21.090098 -296.472099) (xy 21.131769 -296.50533) (xy 21.168021 -296.544401)
			(xy 21.198045 -296.588438) (xy 21.221171 -296.636459) (xy 21.236881 -296.687389) (xy 21.244824 -296.740093)
			(xy 21.245322 -296.766742) (xy 21.244824 -296.793391) (xy 35.621204 -296.793391) (xy 35.621204 -296.740093)
			(xy 35.629147 -296.687389) (xy 35.644857 -296.636459) (xy 35.667983 -296.588438) (xy 35.698007 -296.544401)
			(xy 35.734259 -296.50533) (xy 35.77593 -296.472099) (xy 35.822088 -296.44545) (xy 35.871702 -296.425978)
			(xy 35.923664 -296.414118) (xy 35.976814 -296.410135) (xy 36.029964 -296.414118) (xy 36.081926 -296.425978)
			(xy 36.13154 -296.44545) (xy 36.177698 -296.472099) (xy 36.219369 -296.50533) (xy 36.255621 -296.544401)
			(xy 36.285645 -296.588438) (xy 36.308771 -296.636459) (xy 36.324481 -296.687389) (xy 36.332424 -296.740093)
			(xy 36.332922 -296.766742) (xy 36.332424 -296.793391) (xy 50.734204 -296.793391) (xy 50.734204 -296.740093)
			(xy 50.742147 -296.687389) (xy 50.757857 -296.636459) (xy 50.780983 -296.588438) (xy 50.811007 -296.544401)
			(xy 50.847259 -296.50533) (xy 50.88893 -296.472099) (xy 50.935088 -296.44545) (xy 50.984702 -296.425978)
			(xy 51.036664 -296.414118) (xy 51.089814 -296.410135) (xy 51.142964 -296.414118) (xy 51.194926 -296.425978)
			(xy 51.24454 -296.44545) (xy 51.290698 -296.472099) (xy 51.332369 -296.50533) (xy 51.368621 -296.544401)
			(xy 51.398645 -296.588438) (xy 51.421771 -296.636459) (xy 51.437481 -296.687389) (xy 51.445424 -296.740093)
			(xy 51.445922 -296.766742) (xy 51.445424 -296.793391) (xy 51.437481 -296.846095) (xy 51.421771 -296.897025)
			(xy 51.398645 -296.945046) (xy 51.368621 -296.989083) (xy 51.332369 -297.028154) (xy 51.290698 -297.061385)
			(xy 51.24454 -297.088034) (xy 51.194926 -297.107506) (xy 51.142964 -297.119366) (xy 51.089814 -297.12335)
			(xy 51.036664 -297.119366) (xy 50.984702 -297.107506) (xy 50.935088 -297.088034) (xy 50.88893 -297.061385)
			(xy 50.847259 -297.028154) (xy 50.811007 -296.989083) (xy 50.780983 -296.945046) (xy 50.757857 -296.897025)
			(xy 50.742147 -296.846095) (xy 50.734204 -296.793391) (xy 36.332424 -296.793391) (xy 36.324481 -296.846095)
			(xy 36.308771 -296.897025) (xy 36.285645 -296.945046) (xy 36.255621 -296.989083) (xy 36.219369 -297.028154)
			(xy 36.177698 -297.061385) (xy 36.13154 -297.088034) (xy 36.081926 -297.107506) (xy 36.029964 -297.119366)
			(xy 35.976814 -297.12335) (xy 35.923664 -297.119366) (xy 35.871702 -297.107506) (xy 35.822088 -297.088034)
			(xy 35.77593 -297.061385) (xy 35.734259 -297.028154) (xy 35.698007 -296.989083) (xy 35.667983 -296.945046)
			(xy 35.644857 -296.897025) (xy 35.629147 -296.846095) (xy 35.621204 -296.793391) (xy 21.244824 -296.793391)
			(xy 21.236881 -296.846095) (xy 21.221171 -296.897025) (xy 21.198045 -296.945046) (xy 21.168021 -296.989083)
			(xy 21.131769 -297.028154) (xy 21.090098 -297.061385) (xy 21.04394 -297.088034) (xy 20.994326 -297.107506)
			(xy 20.942364 -297.119366) (xy 20.889214 -297.12335) (xy 20.836064 -297.119366) (xy 20.784102 -297.107506)
			(xy 20.734488 -297.088034) (xy 20.68833 -297.061385) (xy 20.646659 -297.028154) (xy 20.610407 -296.989083)
			(xy 20.580383 -296.945046) (xy 20.557257 -296.897025) (xy 20.541547 -296.846095) (xy 20.533604 -296.793391)
			(xy 6.7818 -296.793391) (xy 6.7818 -297.643275) (xy 16.433536 -297.643275) (xy 16.433536 -297.589977)
			(xy 16.441479 -297.537273) (xy 16.457189 -297.486343) (xy 16.480315 -297.438322) (xy 16.510339 -297.394285)
			(xy 16.546591 -297.355214) (xy 16.588262 -297.321983) (xy 16.63442 -297.295334) (xy 16.684034 -297.275862)
			(xy 16.735996 -297.264002) (xy 16.789146 -297.260019) (xy 16.842296 -297.264002) (xy 16.894258 -297.275862)
			(xy 16.943872 -297.295334) (xy 16.99003 -297.321983) (xy 17.031701 -297.355214) (xy 17.067953 -297.394285)
			(xy 17.097977 -297.438322) (xy 17.121103 -297.486343) (xy 17.136813 -297.537273) (xy 17.144756 -297.589977)
			(xy 17.145254 -297.616626) (xy 17.144756 -297.643275) (xy 31.521136 -297.643275) (xy 31.521136 -297.589977)
			(xy 31.529079 -297.537273) (xy 31.544789 -297.486343) (xy 31.567915 -297.438322) (xy 31.597939 -297.394285)
			(xy 31.634191 -297.355214) (xy 31.675862 -297.321983) (xy 31.72202 -297.295334) (xy 31.771634 -297.275862)
			(xy 31.823596 -297.264002) (xy 31.876746 -297.260019) (xy 31.929896 -297.264002) (xy 31.981858 -297.275862)
			(xy 32.031472 -297.295334) (xy 32.07763 -297.321983) (xy 32.119301 -297.355214) (xy 32.155553 -297.394285)
			(xy 32.185577 -297.438322) (xy 32.208703 -297.486343) (xy 32.224413 -297.537273) (xy 32.232356 -297.589977)
			(xy 32.232854 -297.616626) (xy 32.232356 -297.643275) (xy 46.608736 -297.643275) (xy 46.608736 -297.589977)
			(xy 46.616679 -297.537273) (xy 46.632389 -297.486343) (xy 46.655515 -297.438322) (xy 46.685539 -297.394285)
			(xy 46.721791 -297.355214) (xy 46.763462 -297.321983) (xy 46.80962 -297.295334) (xy 46.859234 -297.275862)
			(xy 46.911196 -297.264002) (xy 46.964346 -297.260019) (xy 47.017496 -297.264002) (xy 47.069458 -297.275862)
			(xy 47.119072 -297.295334) (xy 47.16523 -297.321983) (xy 47.206901 -297.355214) (xy 47.243153 -297.394285)
			(xy 47.273177 -297.438322) (xy 47.296303 -297.486343) (xy 47.312013 -297.537273) (xy 47.319956 -297.589977)
			(xy 47.320454 -297.616626) (xy 47.319956 -297.643275) (xy 47.312013 -297.695979) (xy 47.296303 -297.746909)
			(xy 47.273177 -297.79493) (xy 47.243153 -297.838967) (xy 47.206901 -297.878038) (xy 47.16523 -297.911269)
			(xy 47.119072 -297.937918) (xy 47.069458 -297.95739) (xy 47.017496 -297.96925) (xy 46.964346 -297.973234)
			(xy 46.911196 -297.96925) (xy 46.859234 -297.95739) (xy 46.80962 -297.937918) (xy 46.763462 -297.911269)
			(xy 46.721791 -297.878038) (xy 46.685539 -297.838967) (xy 46.655515 -297.79493) (xy 46.632389 -297.746909)
			(xy 46.616679 -297.695979) (xy 46.608736 -297.643275) (xy 32.232356 -297.643275) (xy 32.224413 -297.695979)
			(xy 32.208703 -297.746909) (xy 32.185577 -297.79493) (xy 32.155553 -297.838967) (xy 32.119301 -297.878038)
			(xy 32.07763 -297.911269) (xy 32.031472 -297.937918) (xy 31.981858 -297.95739) (xy 31.929896 -297.96925)
			(xy 31.876746 -297.973234) (xy 31.823596 -297.96925) (xy 31.771634 -297.95739) (xy 31.72202 -297.937918)
			(xy 31.675862 -297.911269) (xy 31.634191 -297.878038) (xy 31.597939 -297.838967) (xy 31.567915 -297.79493)
			(xy 31.544789 -297.746909) (xy 31.529079 -297.695979) (xy 31.521136 -297.643275) (xy 17.144756 -297.643275)
			(xy 17.136813 -297.695979) (xy 17.121103 -297.746909) (xy 17.097977 -297.79493) (xy 17.067953 -297.838967)
			(xy 17.031701 -297.878038) (xy 16.99003 -297.911269) (xy 16.943872 -297.937918) (xy 16.894258 -297.95739)
			(xy 16.842296 -297.96925) (xy 16.789146 -297.973234) (xy 16.735996 -297.96925) (xy 16.684034 -297.95739)
			(xy 16.63442 -297.937918) (xy 16.588262 -297.911269) (xy 16.546591 -297.878038) (xy 16.510339 -297.838967)
			(xy 16.480315 -297.79493) (xy 16.457189 -297.746909) (xy 16.441479 -297.695979) (xy 16.433536 -297.643275)
			(xy 6.7818 -297.643275) (xy 6.7818 -298.493413) (xy 20.533604 -298.493413) (xy 20.533604 -298.440115)
			(xy 20.541547 -298.387411) (xy 20.557257 -298.336481) (xy 20.580383 -298.28846) (xy 20.610407 -298.244423)
			(xy 20.646659 -298.205352) (xy 20.68833 -298.172121) (xy 20.734488 -298.145472) (xy 20.784102 -298.126)
			(xy 20.836064 -298.11414) (xy 20.889214 -298.110157) (xy 20.942364 -298.11414) (xy 20.994326 -298.126)
			(xy 21.04394 -298.145472) (xy 21.090098 -298.172121) (xy 21.131769 -298.205352) (xy 21.168021 -298.244423)
			(xy 21.198045 -298.28846) (xy 21.221171 -298.336481) (xy 21.236881 -298.387411) (xy 21.244824 -298.440115)
			(xy 21.245322 -298.466764) (xy 21.244824 -298.493413) (xy 35.621204 -298.493413) (xy 35.621204 -298.440115)
			(xy 35.629147 -298.387411) (xy 35.644857 -298.336481) (xy 35.667983 -298.28846) (xy 35.698007 -298.244423)
			(xy 35.734259 -298.205352) (xy 35.77593 -298.172121) (xy 35.822088 -298.145472) (xy 35.871702 -298.126)
			(xy 35.923664 -298.11414) (xy 35.976814 -298.110157) (xy 36.029964 -298.11414) (xy 36.081926 -298.126)
			(xy 36.13154 -298.145472) (xy 36.177698 -298.172121) (xy 36.219369 -298.205352) (xy 36.255621 -298.244423)
			(xy 36.285645 -298.28846) (xy 36.308771 -298.336481) (xy 36.324481 -298.387411) (xy 36.332424 -298.440115)
			(xy 36.332922 -298.466764) (xy 36.332424 -298.493413) (xy 50.734204 -298.493413) (xy 50.734204 -298.440115)
			(xy 50.742147 -298.387411) (xy 50.757857 -298.336481) (xy 50.780983 -298.28846) (xy 50.811007 -298.244423)
			(xy 50.847259 -298.205352) (xy 50.88893 -298.172121) (xy 50.935088 -298.145472) (xy 50.984702 -298.126)
			(xy 51.036664 -298.11414) (xy 51.089814 -298.110157) (xy 51.142964 -298.11414) (xy 51.194926 -298.126)
			(xy 51.24454 -298.145472) (xy 51.290698 -298.172121) (xy 51.332369 -298.205352) (xy 51.368621 -298.244423)
			(xy 51.398645 -298.28846) (xy 51.421771 -298.336481) (xy 51.437481 -298.387411) (xy 51.445424 -298.440115)
			(xy 51.445922 -298.466764) (xy 51.445424 -298.493413) (xy 51.437481 -298.546117) (xy 51.421771 -298.597047)
			(xy 51.398645 -298.645068) (xy 51.368621 -298.689105) (xy 51.332369 -298.728176) (xy 51.290698 -298.761407)
			(xy 51.24454 -298.788056) (xy 51.194926 -298.807528) (xy 51.142964 -298.819388) (xy 51.089814 -298.823372)
			(xy 51.036664 -298.819388) (xy 50.984702 -298.807528) (xy 50.935088 -298.788056) (xy 50.88893 -298.761407)
			(xy 50.847259 -298.728176) (xy 50.811007 -298.689105) (xy 50.780983 -298.645068) (xy 50.757857 -298.597047)
			(xy 50.742147 -298.546117) (xy 50.734204 -298.493413) (xy 36.332424 -298.493413) (xy 36.324481 -298.546117)
			(xy 36.308771 -298.597047) (xy 36.285645 -298.645068) (xy 36.255621 -298.689105) (xy 36.219369 -298.728176)
			(xy 36.177698 -298.761407) (xy 36.13154 -298.788056) (xy 36.081926 -298.807528) (xy 36.029964 -298.819388)
			(xy 35.976814 -298.823372) (xy 35.923664 -298.819388) (xy 35.871702 -298.807528) (xy 35.822088 -298.788056)
			(xy 35.77593 -298.761407) (xy 35.734259 -298.728176) (xy 35.698007 -298.689105) (xy 35.667983 -298.645068)
			(xy 35.644857 -298.597047) (xy 35.629147 -298.546117) (xy 35.621204 -298.493413) (xy 21.244824 -298.493413)
			(xy 21.236881 -298.546117) (xy 21.221171 -298.597047) (xy 21.198045 -298.645068) (xy 21.168021 -298.689105)
			(xy 21.131769 -298.728176) (xy 21.090098 -298.761407) (xy 21.04394 -298.788056) (xy 20.994326 -298.807528)
			(xy 20.942364 -298.819388) (xy 20.889214 -298.823372) (xy 20.836064 -298.819388) (xy 20.784102 -298.807528)
			(xy 20.734488 -298.788056) (xy 20.68833 -298.761407) (xy 20.646659 -298.728176) (xy 20.610407 -298.689105)
			(xy 20.580383 -298.645068) (xy 20.557257 -298.597047) (xy 20.541547 -298.546117) (xy 20.533604 -298.493413)
			(xy 6.7818 -298.493413) (xy 6.7818 -299.343297) (xy 16.433536 -299.343297) (xy 16.433536 -299.289999)
			(xy 16.441479 -299.237295) (xy 16.457189 -299.186365) (xy 16.480315 -299.138344) (xy 16.510339 -299.094307)
			(xy 16.546591 -299.055236) (xy 16.588262 -299.022005) (xy 16.63442 -298.995356) (xy 16.684034 -298.975884)
			(xy 16.735996 -298.964024) (xy 16.789146 -298.960041) (xy 16.842296 -298.964024) (xy 16.894258 -298.975884)
			(xy 16.943872 -298.995356) (xy 16.99003 -299.022005) (xy 17.031701 -299.055236) (xy 17.067953 -299.094307)
			(xy 17.097977 -299.138344) (xy 17.121103 -299.186365) (xy 17.136813 -299.237295) (xy 17.144756 -299.289999)
			(xy 17.145254 -299.316648) (xy 17.144756 -299.343297) (xy 31.521136 -299.343297) (xy 31.521136 -299.289999)
			(xy 31.529079 -299.237295) (xy 31.544789 -299.186365) (xy 31.567915 -299.138344) (xy 31.597939 -299.094307)
			(xy 31.634191 -299.055236) (xy 31.675862 -299.022005) (xy 31.72202 -298.995356) (xy 31.771634 -298.975884)
			(xy 31.823596 -298.964024) (xy 31.876746 -298.960041) (xy 31.929896 -298.964024) (xy 31.981858 -298.975884)
			(xy 32.031472 -298.995356) (xy 32.07763 -299.022005) (xy 32.119301 -299.055236) (xy 32.155553 -299.094307)
			(xy 32.185577 -299.138344) (xy 32.208703 -299.186365) (xy 32.224413 -299.237295) (xy 32.232356 -299.289999)
			(xy 32.232854 -299.316648) (xy 32.232356 -299.343297) (xy 46.608736 -299.343297) (xy 46.608736 -299.289999)
			(xy 46.616679 -299.237295) (xy 46.632389 -299.186365) (xy 46.655515 -299.138344) (xy 46.685539 -299.094307)
			(xy 46.721791 -299.055236) (xy 46.763462 -299.022005) (xy 46.80962 -298.995356) (xy 46.859234 -298.975884)
			(xy 46.911196 -298.964024) (xy 46.964346 -298.960041) (xy 47.017496 -298.964024) (xy 47.069458 -298.975884)
			(xy 47.119072 -298.995356) (xy 47.16523 -299.022005) (xy 47.206901 -299.055236) (xy 47.243153 -299.094307)
			(xy 47.273177 -299.138344) (xy 47.296303 -299.186365) (xy 47.312013 -299.237295) (xy 47.319956 -299.289999)
			(xy 47.320454 -299.316648) (xy 47.319956 -299.343297) (xy 61.696336 -299.343297) (xy 61.696336 -299.289999)
			(xy 61.704279 -299.237295) (xy 61.719989 -299.186365) (xy 61.743115 -299.138344) (xy 61.773139 -299.094307)
			(xy 61.809391 -299.055236) (xy 61.851062 -299.022005) (xy 61.89722 -298.995356) (xy 61.946834 -298.975884)
			(xy 61.998796 -298.964024) (xy 62.051946 -298.960041) (xy 62.105096 -298.964024) (xy 62.157058 -298.975884)
			(xy 62.206672 -298.995356) (xy 62.25283 -299.022005) (xy 62.294501 -299.055236) (xy 62.330753 -299.094307)
			(xy 62.360777 -299.138344) (xy 62.383903 -299.186365) (xy 62.399613 -299.237295) (xy 62.407556 -299.289999)
			(xy 62.408054 -299.316648) (xy 62.407556 -299.343297) (xy 62.399613 -299.396001) (xy 62.383903 -299.446931)
			(xy 62.360777 -299.494952) (xy 62.330753 -299.538989) (xy 62.294501 -299.57806) (xy 62.25283 -299.611291)
			(xy 62.206672 -299.63794) (xy 62.157058 -299.657412) (xy 62.105096 -299.669272) (xy 62.051946 -299.673256)
			(xy 61.998796 -299.669272) (xy 61.946834 -299.657412) (xy 61.89722 -299.63794) (xy 61.851062 -299.611291)
			(xy 61.809391 -299.57806) (xy 61.773139 -299.538989) (xy 61.743115 -299.494952) (xy 61.719989 -299.446931)
			(xy 61.704279 -299.396001) (xy 61.696336 -299.343297) (xy 47.319956 -299.343297) (xy 47.312013 -299.396001)
			(xy 47.296303 -299.446931) (xy 47.273177 -299.494952) (xy 47.243153 -299.538989) (xy 47.206901 -299.57806)
			(xy 47.16523 -299.611291) (xy 47.119072 -299.63794) (xy 47.069458 -299.657412) (xy 47.017496 -299.669272)
			(xy 46.964346 -299.673256) (xy 46.911196 -299.669272) (xy 46.859234 -299.657412) (xy 46.80962 -299.63794)
			(xy 46.763462 -299.611291) (xy 46.721791 -299.57806) (xy 46.685539 -299.538989) (xy 46.655515 -299.494952)
			(xy 46.632389 -299.446931) (xy 46.616679 -299.396001) (xy 46.608736 -299.343297) (xy 32.232356 -299.343297)
			(xy 32.224413 -299.396001) (xy 32.208703 -299.446931) (xy 32.185577 -299.494952) (xy 32.155553 -299.538989)
			(xy 32.119301 -299.57806) (xy 32.07763 -299.611291) (xy 32.031472 -299.63794) (xy 31.981858 -299.657412)
			(xy 31.929896 -299.669272) (xy 31.876746 -299.673256) (xy 31.823596 -299.669272) (xy 31.771634 -299.657412)
			(xy 31.72202 -299.63794) (xy 31.675862 -299.611291) (xy 31.634191 -299.57806) (xy 31.597939 -299.538989)
			(xy 31.567915 -299.494952) (xy 31.544789 -299.446931) (xy 31.529079 -299.396001) (xy 31.521136 -299.343297)
			(xy 17.144756 -299.343297) (xy 17.136813 -299.396001) (xy 17.121103 -299.446931) (xy 17.097977 -299.494952)
			(xy 17.067953 -299.538989) (xy 17.031701 -299.57806) (xy 16.99003 -299.611291) (xy 16.943872 -299.63794)
			(xy 16.894258 -299.657412) (xy 16.842296 -299.669272) (xy 16.789146 -299.673256) (xy 16.735996 -299.669272)
			(xy 16.684034 -299.657412) (xy 16.63442 -299.63794) (xy 16.588262 -299.611291) (xy 16.546591 -299.57806)
			(xy 16.510339 -299.538989) (xy 16.480315 -299.494952) (xy 16.457189 -299.446931) (xy 16.441479 -299.396001)
			(xy 16.433536 -299.343297) (xy 6.7818 -299.343297) (xy 6.7818 -300.193435) (xy 20.533604 -300.193435)
			(xy 20.533604 -300.140137) (xy 20.541547 -300.087433) (xy 20.557257 -300.036503) (xy 20.580383 -299.988482)
			(xy 20.610407 -299.944445) (xy 20.646659 -299.905374) (xy 20.68833 -299.872143) (xy 20.734488 -299.845494)
			(xy 20.784102 -299.826022) (xy 20.836064 -299.814162) (xy 20.889214 -299.810179) (xy 20.942364 -299.814162)
			(xy 20.994326 -299.826022) (xy 21.04394 -299.845494) (xy 21.090098 -299.872143) (xy 21.131769 -299.905374)
			(xy 21.168021 -299.944445) (xy 21.198045 -299.988482) (xy 21.221171 -300.036503) (xy 21.236881 -300.087433)
			(xy 21.244824 -300.140137) (xy 21.245322 -300.166786) (xy 21.244824 -300.193435) (xy 35.621204 -300.193435)
			(xy 35.621204 -300.140137) (xy 35.629147 -300.087433) (xy 35.644857 -300.036503) (xy 35.667983 -299.988482)
			(xy 35.698007 -299.944445) (xy 35.734259 -299.905374) (xy 35.77593 -299.872143) (xy 35.822088 -299.845494)
			(xy 35.871702 -299.826022) (xy 35.923664 -299.814162) (xy 35.976814 -299.810179) (xy 36.029964 -299.814162)
			(xy 36.081926 -299.826022) (xy 36.13154 -299.845494) (xy 36.177698 -299.872143) (xy 36.219369 -299.905374)
			(xy 36.255621 -299.944445) (xy 36.285645 -299.988482) (xy 36.308771 -300.036503) (xy 36.324481 -300.087433)
			(xy 36.332424 -300.140137) (xy 36.332922 -300.166786) (xy 36.332424 -300.193435) (xy 50.734204 -300.193435)
			(xy 50.734204 -300.140137) (xy 50.742147 -300.087433) (xy 50.757857 -300.036503) (xy 50.780983 -299.988482)
			(xy 50.811007 -299.944445) (xy 50.847259 -299.905374) (xy 50.88893 -299.872143) (xy 50.935088 -299.845494)
			(xy 50.984702 -299.826022) (xy 51.036664 -299.814162) (xy 51.089814 -299.810179) (xy 51.142964 -299.814162)
			(xy 51.194926 -299.826022) (xy 51.24454 -299.845494) (xy 51.290698 -299.872143) (xy 51.332369 -299.905374)
			(xy 51.368621 -299.944445) (xy 51.398645 -299.988482) (xy 51.421771 -300.036503) (xy 51.437481 -300.087433)
			(xy 51.445424 -300.140137) (xy 51.445922 -300.166786) (xy 51.445424 -300.193435) (xy 51.437481 -300.246139)
			(xy 51.421771 -300.297069) (xy 51.398645 -300.34509) (xy 51.368621 -300.389127) (xy 51.332369 -300.428198)
			(xy 51.290698 -300.461429) (xy 51.24454 -300.488078) (xy 51.194926 -300.50755) (xy 51.142964 -300.51941)
			(xy 51.089814 -300.523394) (xy 51.036664 -300.51941) (xy 50.984702 -300.50755) (xy 50.935088 -300.488078)
			(xy 50.88893 -300.461429) (xy 50.847259 -300.428198) (xy 50.811007 -300.389127) (xy 50.780983 -300.34509)
			(xy 50.757857 -300.297069) (xy 50.742147 -300.246139) (xy 50.734204 -300.193435) (xy 36.332424 -300.193435)
			(xy 36.324481 -300.246139) (xy 36.308771 -300.297069) (xy 36.285645 -300.34509) (xy 36.255621 -300.389127)
			(xy 36.219369 -300.428198) (xy 36.177698 -300.461429) (xy 36.13154 -300.488078) (xy 36.081926 -300.50755)
			(xy 36.029964 -300.51941) (xy 35.976814 -300.523394) (xy 35.923664 -300.51941) (xy 35.871702 -300.50755)
			(xy 35.822088 -300.488078) (xy 35.77593 -300.461429) (xy 35.734259 -300.428198) (xy 35.698007 -300.389127)
			(xy 35.667983 -300.34509) (xy 35.644857 -300.297069) (xy 35.629147 -300.246139) (xy 35.621204 -300.193435)
			(xy 21.244824 -300.193435) (xy 21.236881 -300.246139) (xy 21.221171 -300.297069) (xy 21.198045 -300.34509)
			(xy 21.168021 -300.389127) (xy 21.131769 -300.428198) (xy 21.090098 -300.461429) (xy 21.04394 -300.488078)
			(xy 20.994326 -300.50755) (xy 20.942364 -300.51941) (xy 20.889214 -300.523394) (xy 20.836064 -300.51941)
			(xy 20.784102 -300.50755) (xy 20.734488 -300.488078) (xy 20.68833 -300.461429) (xy 20.646659 -300.428198)
			(xy 20.610407 -300.389127) (xy 20.580383 -300.34509) (xy 20.557257 -300.297069) (xy 20.541547 -300.246139)
			(xy 20.533604 -300.193435) (xy 6.7818 -300.193435) (xy 6.7818 -301.043319) (xy 16.433536 -301.043319)
			(xy 16.433536 -300.990021) (xy 16.441479 -300.937317) (xy 16.457189 -300.886387) (xy 16.480315 -300.838366)
			(xy 16.510339 -300.794329) (xy 16.546591 -300.755258) (xy 16.588262 -300.722027) (xy 16.63442 -300.695378)
			(xy 16.684034 -300.675906) (xy 16.735996 -300.664046) (xy 16.789146 -300.660063) (xy 16.842296 -300.664046)
			(xy 16.894258 -300.675906) (xy 16.943872 -300.695378) (xy 16.99003 -300.722027) (xy 17.031701 -300.755258)
			(xy 17.067953 -300.794329) (xy 17.097977 -300.838366) (xy 17.121103 -300.886387) (xy 17.136813 -300.937317)
			(xy 17.144756 -300.990021) (xy 17.145254 -301.01667) (xy 17.144756 -301.043319) (xy 31.521136 -301.043319)
			(xy 31.521136 -300.990021) (xy 31.529079 -300.937317) (xy 31.544789 -300.886387) (xy 31.567915 -300.838366)
			(xy 31.597939 -300.794329) (xy 31.634191 -300.755258) (xy 31.675862 -300.722027) (xy 31.72202 -300.695378)
			(xy 31.771634 -300.675906) (xy 31.823596 -300.664046) (xy 31.876746 -300.660063) (xy 31.929896 -300.664046)
			(xy 31.981858 -300.675906) (xy 32.031472 -300.695378) (xy 32.07763 -300.722027) (xy 32.119301 -300.755258)
			(xy 32.155553 -300.794329) (xy 32.185577 -300.838366) (xy 32.208703 -300.886387) (xy 32.224413 -300.937317)
			(xy 32.232356 -300.990021) (xy 32.232854 -301.01667) (xy 32.232356 -301.043319) (xy 46.608736 -301.043319)
			(xy 46.608736 -300.990021) (xy 46.616679 -300.937317) (xy 46.632389 -300.886387) (xy 46.655515 -300.838366)
			(xy 46.685539 -300.794329) (xy 46.721791 -300.755258) (xy 46.763462 -300.722027) (xy 46.80962 -300.695378)
			(xy 46.859234 -300.675906) (xy 46.911196 -300.664046) (xy 46.964346 -300.660063) (xy 47.017496 -300.664046)
			(xy 47.069458 -300.675906) (xy 47.119072 -300.695378) (xy 47.16523 -300.722027) (xy 47.206901 -300.755258)
			(xy 47.243153 -300.794329) (xy 47.273177 -300.838366) (xy 47.296303 -300.886387) (xy 47.312013 -300.937317)
			(xy 47.319956 -300.990021) (xy 47.320454 -301.01667) (xy 47.319956 -301.043319) (xy 61.696336 -301.043319)
			(xy 61.696336 -300.990021) (xy 61.704279 -300.937317) (xy 61.719989 -300.886387) (xy 61.743115 -300.838366)
			(xy 61.773139 -300.794329) (xy 61.809391 -300.755258) (xy 61.851062 -300.722027) (xy 61.89722 -300.695378)
			(xy 61.946834 -300.675906) (xy 61.998796 -300.664046) (xy 62.051946 -300.660063) (xy 62.105096 -300.664046)
			(xy 62.157058 -300.675906) (xy 62.206672 -300.695378) (xy 62.25283 -300.722027) (xy 62.294501 -300.755258)
			(xy 62.330753 -300.794329) (xy 62.360777 -300.838366) (xy 62.383903 -300.886387) (xy 62.399613 -300.937317)
			(xy 62.407556 -300.990021) (xy 62.408054 -301.01667) (xy 62.407556 -301.043319) (xy 62.399613 -301.096023)
			(xy 62.383903 -301.146953) (xy 62.360777 -301.194974) (xy 62.330753 -301.239011) (xy 62.294501 -301.278082)
			(xy 62.25283 -301.311313) (xy 62.206672 -301.337962) (xy 62.157058 -301.357434) (xy 62.105096 -301.369294)
			(xy 62.051946 -301.373278) (xy 61.998796 -301.369294) (xy 61.946834 -301.357434) (xy 61.89722 -301.337962)
			(xy 61.851062 -301.311313) (xy 61.809391 -301.278082) (xy 61.773139 -301.239011) (xy 61.743115 -301.194974)
			(xy 61.719989 -301.146953) (xy 61.704279 -301.096023) (xy 61.696336 -301.043319) (xy 47.319956 -301.043319)
			(xy 47.312013 -301.096023) (xy 47.296303 -301.146953) (xy 47.273177 -301.194974) (xy 47.243153 -301.239011)
			(xy 47.206901 -301.278082) (xy 47.16523 -301.311313) (xy 47.119072 -301.337962) (xy 47.069458 -301.357434)
			(xy 47.017496 -301.369294) (xy 46.964346 -301.373278) (xy 46.911196 -301.369294) (xy 46.859234 -301.357434)
			(xy 46.80962 -301.337962) (xy 46.763462 -301.311313) (xy 46.721791 -301.278082) (xy 46.685539 -301.239011)
			(xy 46.655515 -301.194974) (xy 46.632389 -301.146953) (xy 46.616679 -301.096023) (xy 46.608736 -301.043319)
			(xy 32.232356 -301.043319) (xy 32.224413 -301.096023) (xy 32.208703 -301.146953) (xy 32.185577 -301.194974)
			(xy 32.155553 -301.239011) (xy 32.119301 -301.278082) (xy 32.07763 -301.311313) (xy 32.031472 -301.337962)
			(xy 31.981858 -301.357434) (xy 31.929896 -301.369294) (xy 31.876746 -301.373278) (xy 31.823596 -301.369294)
			(xy 31.771634 -301.357434) (xy 31.72202 -301.337962) (xy 31.675862 -301.311313) (xy 31.634191 -301.278082)
			(xy 31.597939 -301.239011) (xy 31.567915 -301.194974) (xy 31.544789 -301.146953) (xy 31.529079 -301.096023)
			(xy 31.521136 -301.043319) (xy 17.144756 -301.043319) (xy 17.136813 -301.096023) (xy 17.121103 -301.146953)
			(xy 17.097977 -301.194974) (xy 17.067953 -301.239011) (xy 17.031701 -301.278082) (xy 16.99003 -301.311313)
			(xy 16.943872 -301.337962) (xy 16.894258 -301.357434) (xy 16.842296 -301.369294) (xy 16.789146 -301.373278)
			(xy 16.735996 -301.369294) (xy 16.684034 -301.357434) (xy 16.63442 -301.337962) (xy 16.588262 -301.311313)
			(xy 16.546591 -301.278082) (xy 16.510339 -301.239011) (xy 16.480315 -301.194974) (xy 16.457189 -301.146953)
			(xy 16.441479 -301.096023) (xy 16.433536 -301.043319) (xy 6.7818 -301.043319) (xy 6.7818 -301.893457)
			(xy 20.533604 -301.893457) (xy 20.533604 -301.840159) (xy 20.541547 -301.787455) (xy 20.557257 -301.736525)
			(xy 20.580383 -301.688504) (xy 20.610407 -301.644467) (xy 20.646659 -301.605396) (xy 20.68833 -301.572165)
			(xy 20.734488 -301.545516) (xy 20.784102 -301.526044) (xy 20.836064 -301.514184) (xy 20.889214 -301.510201)
			(xy 20.942364 -301.514184) (xy 20.994326 -301.526044) (xy 21.04394 -301.545516) (xy 21.090098 -301.572165)
			(xy 21.131769 -301.605396) (xy 21.168021 -301.644467) (xy 21.198045 -301.688504) (xy 21.221171 -301.736525)
			(xy 21.236881 -301.787455) (xy 21.244824 -301.840159) (xy 21.245322 -301.866808) (xy 21.244824 -301.893457)
			(xy 35.621204 -301.893457) (xy 35.621204 -301.840159) (xy 35.629147 -301.787455) (xy 35.644857 -301.736525)
			(xy 35.667983 -301.688504) (xy 35.698007 -301.644467) (xy 35.734259 -301.605396) (xy 35.77593 -301.572165)
			(xy 35.822088 -301.545516) (xy 35.871702 -301.526044) (xy 35.923664 -301.514184) (xy 35.976814 -301.510201)
			(xy 36.029964 -301.514184) (xy 36.081926 -301.526044) (xy 36.13154 -301.545516) (xy 36.177698 -301.572165)
			(xy 36.219369 -301.605396) (xy 36.255621 -301.644467) (xy 36.285645 -301.688504) (xy 36.308771 -301.736525)
			(xy 36.324481 -301.787455) (xy 36.332424 -301.840159) (xy 36.332922 -301.866808) (xy 36.332424 -301.893457)
			(xy 50.734204 -301.893457) (xy 50.734204 -301.840159) (xy 50.742147 -301.787455) (xy 50.757857 -301.736525)
			(xy 50.780983 -301.688504) (xy 50.811007 -301.644467) (xy 50.847259 -301.605396) (xy 50.88893 -301.572165)
			(xy 50.935088 -301.545516) (xy 50.984702 -301.526044) (xy 51.036664 -301.514184) (xy 51.089814 -301.510201)
			(xy 51.142964 -301.514184) (xy 51.194926 -301.526044) (xy 51.24454 -301.545516) (xy 51.290698 -301.572165)
			(xy 51.332369 -301.605396) (xy 51.368621 -301.644467) (xy 51.398645 -301.688504) (xy 51.421771 -301.736525)
			(xy 51.437481 -301.787455) (xy 51.445424 -301.840159) (xy 51.445922 -301.866808) (xy 51.445424 -301.893457)
			(xy 51.437481 -301.946161) (xy 51.421771 -301.997091) (xy 51.398645 -302.045112) (xy 51.368621 -302.089149)
			(xy 51.332369 -302.12822) (xy 51.290698 -302.161451) (xy 51.24454 -302.1881) (xy 51.194926 -302.207572)
			(xy 51.142964 -302.219432) (xy 51.089814 -302.223416) (xy 51.036664 -302.219432) (xy 50.984702 -302.207572)
			(xy 50.935088 -302.1881) (xy 50.88893 -302.161451) (xy 50.847259 -302.12822) (xy 50.811007 -302.089149)
			(xy 50.780983 -302.045112) (xy 50.757857 -301.997091) (xy 50.742147 -301.946161) (xy 50.734204 -301.893457)
			(xy 36.332424 -301.893457) (xy 36.324481 -301.946161) (xy 36.308771 -301.997091) (xy 36.285645 -302.045112)
			(xy 36.255621 -302.089149) (xy 36.219369 -302.12822) (xy 36.177698 -302.161451) (xy 36.13154 -302.1881)
			(xy 36.081926 -302.207572) (xy 36.029964 -302.219432) (xy 35.976814 -302.223416) (xy 35.923664 -302.219432)
			(xy 35.871702 -302.207572) (xy 35.822088 -302.1881) (xy 35.77593 -302.161451) (xy 35.734259 -302.12822)
			(xy 35.698007 -302.089149) (xy 35.667983 -302.045112) (xy 35.644857 -301.997091) (xy 35.629147 -301.946161)
			(xy 35.621204 -301.893457) (xy 21.244824 -301.893457) (xy 21.236881 -301.946161) (xy 21.221171 -301.997091)
			(xy 21.198045 -302.045112) (xy 21.168021 -302.089149) (xy 21.131769 -302.12822) (xy 21.090098 -302.161451)
			(xy 21.04394 -302.1881) (xy 20.994326 -302.207572) (xy 20.942364 -302.219432) (xy 20.889214 -302.223416)
			(xy 20.836064 -302.219432) (xy 20.784102 -302.207572) (xy 20.734488 -302.1881) (xy 20.68833 -302.161451)
			(xy 20.646659 -302.12822) (xy 20.610407 -302.089149) (xy 20.580383 -302.045112) (xy 20.557257 -301.997091)
			(xy 20.541547 -301.946161) (xy 20.533604 -301.893457) (xy 6.7818 -301.893457) (xy 6.7818 -302.743341)
			(xy 16.433536 -302.743341) (xy 16.433536 -302.690043) (xy 16.441479 -302.637339) (xy 16.457189 -302.586409)
			(xy 16.480315 -302.538388) (xy 16.510339 -302.494351) (xy 16.546591 -302.45528) (xy 16.588262 -302.422049)
			(xy 16.63442 -302.3954) (xy 16.684034 -302.375928) (xy 16.735996 -302.364068) (xy 16.789146 -302.360085)
			(xy 16.842296 -302.364068) (xy 16.894258 -302.375928) (xy 16.943872 -302.3954) (xy 16.99003 -302.422049)
			(xy 17.031701 -302.45528) (xy 17.067953 -302.494351) (xy 17.097977 -302.538388) (xy 17.121103 -302.586409)
			(xy 17.136813 -302.637339) (xy 17.144756 -302.690043) (xy 17.145254 -302.716692) (xy 17.144756 -302.743341)
			(xy 20.533604 -302.743341) (xy 20.533604 -302.690043) (xy 20.541547 -302.637339) (xy 20.557257 -302.586409)
			(xy 20.580383 -302.538388) (xy 20.610407 -302.494351) (xy 20.646659 -302.45528) (xy 20.68833 -302.422049)
			(xy 20.734488 -302.3954) (xy 20.784102 -302.375928) (xy 20.836064 -302.364068) (xy 20.889214 -302.360085)
			(xy 20.942364 -302.364068) (xy 20.994326 -302.375928) (xy 21.04394 -302.3954) (xy 21.090098 -302.422049)
			(xy 21.131769 -302.45528) (xy 21.168021 -302.494351) (xy 21.198045 -302.538388) (xy 21.221171 -302.586409)
			(xy 21.236881 -302.637339) (xy 21.244824 -302.690043) (xy 21.245322 -302.716692) (xy 21.244824 -302.743341)
			(xy 31.521136 -302.743341) (xy 31.521136 -302.690043) (xy 31.529079 -302.637339) (xy 31.544789 -302.586409)
			(xy 31.567915 -302.538388) (xy 31.597939 -302.494351) (xy 31.634191 -302.45528) (xy 31.675862 -302.422049)
			(xy 31.72202 -302.3954) (xy 31.771634 -302.375928) (xy 31.823596 -302.364068) (xy 31.876746 -302.360085)
			(xy 31.929896 -302.364068) (xy 31.981858 -302.375928) (xy 32.031472 -302.3954) (xy 32.07763 -302.422049)
			(xy 32.119301 -302.45528) (xy 32.155553 -302.494351) (xy 32.185577 -302.538388) (xy 32.208703 -302.586409)
			(xy 32.224413 -302.637339) (xy 32.232356 -302.690043) (xy 32.232854 -302.716692) (xy 32.232356 -302.743341)
			(xy 35.621204 -302.743341) (xy 35.621204 -302.690043) (xy 35.629147 -302.637339) (xy 35.644857 -302.586409)
			(xy 35.667983 -302.538388) (xy 35.698007 -302.494351) (xy 35.734259 -302.45528) (xy 35.77593 -302.422049)
			(xy 35.822088 -302.3954) (xy 35.871702 -302.375928) (xy 35.923664 -302.364068) (xy 35.976814 -302.360085)
			(xy 36.029964 -302.364068) (xy 36.081926 -302.375928) (xy 36.13154 -302.3954) (xy 36.177698 -302.422049)
			(xy 36.219369 -302.45528) (xy 36.255621 -302.494351) (xy 36.285645 -302.538388) (xy 36.308771 -302.586409)
			(xy 36.324481 -302.637339) (xy 36.332424 -302.690043) (xy 36.332922 -302.716692) (xy 36.332424 -302.743341)
			(xy 46.608736 -302.743341) (xy 46.608736 -302.690043) (xy 46.616679 -302.637339) (xy 46.632389 -302.586409)
			(xy 46.655515 -302.538388) (xy 46.685539 -302.494351) (xy 46.721791 -302.45528) (xy 46.763462 -302.422049)
			(xy 46.80962 -302.3954) (xy 46.859234 -302.375928) (xy 46.911196 -302.364068) (xy 46.964346 -302.360085)
			(xy 47.017496 -302.364068) (xy 47.069458 -302.375928) (xy 47.119072 -302.3954) (xy 47.16523 -302.422049)
			(xy 47.206901 -302.45528) (xy 47.243153 -302.494351) (xy 47.273177 -302.538388) (xy 47.296303 -302.586409)
			(xy 47.312013 -302.637339) (xy 47.319956 -302.690043) (xy 47.320454 -302.716692) (xy 47.319956 -302.743341)
			(xy 47.319918 -302.743595) (xy 50.734204 -302.743595) (xy 50.734204 -302.690297) (xy 50.742147 -302.637593)
			(xy 50.757857 -302.586663) (xy 50.780983 -302.538642) (xy 50.811007 -302.494605) (xy 50.847259 -302.455534)
			(xy 50.88893 -302.422303) (xy 50.935088 -302.395654) (xy 50.984702 -302.376182) (xy 51.036664 -302.364322)
			(xy 51.089814 -302.360339) (xy 51.142964 -302.364322) (xy 51.194926 -302.376182) (xy 51.24454 -302.395654)
			(xy 51.290698 -302.422303) (xy 51.332369 -302.455534) (xy 51.368621 -302.494605) (xy 51.398645 -302.538642)
			(xy 51.421771 -302.586663) (xy 51.437481 -302.637593) (xy 51.445424 -302.690297) (xy 51.445922 -302.716946)
			(xy 51.445429 -302.743341) (xy 61.696336 -302.743341) (xy 61.696336 -302.690043) (xy 61.704279 -302.637339)
			(xy 61.719989 -302.586409) (xy 61.743115 -302.538388) (xy 61.773139 -302.494351) (xy 61.809391 -302.45528)
			(xy 61.851062 -302.422049) (xy 61.89722 -302.3954) (xy 61.946834 -302.375928) (xy 61.998796 -302.364068)
			(xy 62.051946 -302.360085) (xy 62.105096 -302.364068) (xy 62.157058 -302.375928) (xy 62.206672 -302.3954)
			(xy 62.25283 -302.422049) (xy 62.294501 -302.45528) (xy 62.330753 -302.494351) (xy 62.360777 -302.538388)
			(xy 62.383903 -302.586409) (xy 62.399613 -302.637339) (xy 62.407556 -302.690043) (xy 62.408054 -302.716692)
			(xy 62.407556 -302.743341) (xy 62.399613 -302.796045) (xy 62.383903 -302.846975) (xy 62.360777 -302.894996)
			(xy 62.330753 -302.939033) (xy 62.294501 -302.978104) (xy 62.25283 -303.011335) (xy 62.206672 -303.037984)
			(xy 62.157058 -303.057456) (xy 62.105096 -303.069316) (xy 62.051946 -303.0733) (xy 61.998796 -303.069316)
			(xy 61.946834 -303.057456) (xy 61.89722 -303.037984) (xy 61.851062 -303.011335) (xy 61.809391 -302.978104)
			(xy 61.773139 -302.939033) (xy 61.743115 -302.894996) (xy 61.719989 -302.846975) (xy 61.704279 -302.796045)
			(xy 61.696336 -302.743341) (xy 51.445429 -302.743341) (xy 51.445424 -302.743595) (xy 51.437481 -302.796299)
			(xy 51.421771 -302.847229) (xy 51.398645 -302.89525) (xy 51.368621 -302.939287) (xy 51.332369 -302.978358)
			(xy 51.290698 -303.011589) (xy 51.24454 -303.038238) (xy 51.194926 -303.05771) (xy 51.142964 -303.06957)
			(xy 51.089814 -303.073554) (xy 51.036664 -303.06957) (xy 50.984702 -303.05771) (xy 50.935088 -303.038238)
			(xy 50.88893 -303.011589) (xy 50.847259 -302.978358) (xy 50.811007 -302.939287) (xy 50.780983 -302.89525)
			(xy 50.757857 -302.847229) (xy 50.742147 -302.796299) (xy 50.734204 -302.743595) (xy 47.319918 -302.743595)
			(xy 47.312013 -302.796045) (xy 47.296303 -302.846975) (xy 47.273177 -302.894996) (xy 47.243153 -302.939033)
			(xy 47.206901 -302.978104) (xy 47.16523 -303.011335) (xy 47.119072 -303.037984) (xy 47.069458 -303.057456)
			(xy 47.017496 -303.069316) (xy 46.964346 -303.0733) (xy 46.911196 -303.069316) (xy 46.859234 -303.057456)
			(xy 46.80962 -303.037984) (xy 46.763462 -303.011335) (xy 46.721791 -302.978104) (xy 46.685539 -302.939033)
			(xy 46.655515 -302.894996) (xy 46.632389 -302.846975) (xy 46.616679 -302.796045) (xy 46.608736 -302.743341)
			(xy 36.332424 -302.743341) (xy 36.324481 -302.796045) (xy 36.308771 -302.846975) (xy 36.285645 -302.894996)
			(xy 36.255621 -302.939033) (xy 36.219369 -302.978104) (xy 36.177698 -303.011335) (xy 36.13154 -303.037984)
			(xy 36.081926 -303.057456) (xy 36.029964 -303.069316) (xy 35.976814 -303.0733) (xy 35.923664 -303.069316)
			(xy 35.871702 -303.057456) (xy 35.822088 -303.037984) (xy 35.77593 -303.011335) (xy 35.734259 -302.978104)
			(xy 35.698007 -302.939033) (xy 35.667983 -302.894996) (xy 35.644857 -302.846975) (xy 35.629147 -302.796045)
			(xy 35.621204 -302.743341) (xy 32.232356 -302.743341) (xy 32.224413 -302.796045) (xy 32.208703 -302.846975)
			(xy 32.185577 -302.894996) (xy 32.155553 -302.939033) (xy 32.119301 -302.978104) (xy 32.07763 -303.011335)
			(xy 32.031472 -303.037984) (xy 31.981858 -303.057456) (xy 31.929896 -303.069316) (xy 31.876746 -303.0733)
			(xy 31.823596 -303.069316) (xy 31.771634 -303.057456) (xy 31.72202 -303.037984) (xy 31.675862 -303.011335)
			(xy 31.634191 -302.978104) (xy 31.597939 -302.939033) (xy 31.567915 -302.894996) (xy 31.544789 -302.846975)
			(xy 31.529079 -302.796045) (xy 31.521136 -302.743341) (xy 21.244824 -302.743341) (xy 21.236881 -302.796045)
			(xy 21.221171 -302.846975) (xy 21.198045 -302.894996) (xy 21.168021 -302.939033) (xy 21.131769 -302.978104)
			(xy 21.090098 -303.011335) (xy 21.04394 -303.037984) (xy 20.994326 -303.057456) (xy 20.942364 -303.069316)
			(xy 20.889214 -303.0733) (xy 20.836064 -303.069316) (xy 20.784102 -303.057456) (xy 20.734488 -303.037984)
			(xy 20.68833 -303.011335) (xy 20.646659 -302.978104) (xy 20.610407 -302.939033) (xy 20.580383 -302.894996)
			(xy 20.557257 -302.846975) (xy 20.541547 -302.796045) (xy 20.533604 -302.743341) (xy 17.144756 -302.743341)
			(xy 17.136813 -302.796045) (xy 17.121103 -302.846975) (xy 17.097977 -302.894996) (xy 17.067953 -302.939033)
			(xy 17.031701 -302.978104) (xy 16.99003 -303.011335) (xy 16.943872 -303.037984) (xy 16.894258 -303.057456)
			(xy 16.842296 -303.069316) (xy 16.789146 -303.0733) (xy 16.735996 -303.069316) (xy 16.684034 -303.057456)
			(xy 16.63442 -303.037984) (xy 16.588262 -303.011335) (xy 16.546591 -302.978104) (xy 16.510339 -302.939033)
			(xy 16.480315 -302.894996) (xy 16.457189 -302.846975) (xy 16.441479 -302.796045) (xy 16.433536 -302.743341)
			(xy 6.7818 -302.743341) (xy 6.7818 -303.593225) (xy 16.433536 -303.593225) (xy 16.433536 -303.539927)
			(xy 16.441479 -303.487223) (xy 16.457189 -303.436293) (xy 16.480315 -303.388272) (xy 16.510339 -303.344235)
			(xy 16.546591 -303.305164) (xy 16.588262 -303.271933) (xy 16.63442 -303.245284) (xy 16.684034 -303.225812)
			(xy 16.735996 -303.213952) (xy 16.789146 -303.209969) (xy 16.842296 -303.213952) (xy 16.894258 -303.225812)
			(xy 16.943872 -303.245284) (xy 16.99003 -303.271933) (xy 17.031701 -303.305164) (xy 17.067953 -303.344235)
			(xy 17.097977 -303.388272) (xy 17.121103 -303.436293) (xy 17.136813 -303.487223) (xy 17.144756 -303.539927)
			(xy 17.145254 -303.566576) (xy 17.144756 -303.593225) (xy 31.521136 -303.593225) (xy 31.521136 -303.539927)
			(xy 31.529079 -303.487223) (xy 31.544789 -303.436293) (xy 31.567915 -303.388272) (xy 31.597939 -303.344235)
			(xy 31.634191 -303.305164) (xy 31.675862 -303.271933) (xy 31.72202 -303.245284) (xy 31.771634 -303.225812)
			(xy 31.823596 -303.213952) (xy 31.876746 -303.209969) (xy 31.929896 -303.213952) (xy 31.981858 -303.225812)
			(xy 32.031472 -303.245284) (xy 32.07763 -303.271933) (xy 32.119301 -303.305164) (xy 32.155553 -303.344235)
			(xy 32.185577 -303.388272) (xy 32.208703 -303.436293) (xy 32.224413 -303.487223) (xy 32.232356 -303.539927)
			(xy 32.232854 -303.566576) (xy 32.232356 -303.593225) (xy 46.608736 -303.593225) (xy 46.608736 -303.539927)
			(xy 46.616679 -303.487223) (xy 46.632389 -303.436293) (xy 46.655515 -303.388272) (xy 46.685539 -303.344235)
			(xy 46.721791 -303.305164) (xy 46.763462 -303.271933) (xy 46.80962 -303.245284) (xy 46.859234 -303.225812)
			(xy 46.911196 -303.213952) (xy 46.964346 -303.209969) (xy 47.017496 -303.213952) (xy 47.069458 -303.225812)
			(xy 47.119072 -303.245284) (xy 47.16523 -303.271933) (xy 47.206901 -303.305164) (xy 47.243153 -303.344235)
			(xy 47.273177 -303.388272) (xy 47.296303 -303.436293) (xy 47.312013 -303.487223) (xy 47.319956 -303.539927)
			(xy 47.320454 -303.566576) (xy 47.319956 -303.593225) (xy 61.696336 -303.593225) (xy 61.696336 -303.539927)
			(xy 61.704279 -303.487223) (xy 61.719989 -303.436293) (xy 61.743115 -303.388272) (xy 61.773139 -303.344235)
			(xy 61.809391 -303.305164) (xy 61.851062 -303.271933) (xy 61.89722 -303.245284) (xy 61.946834 -303.225812)
			(xy 61.998796 -303.213952) (xy 62.051946 -303.209969) (xy 62.105096 -303.213952) (xy 62.157058 -303.225812)
			(xy 62.206672 -303.245284) (xy 62.25283 -303.271933) (xy 62.294501 -303.305164) (xy 62.330753 -303.344235)
			(xy 62.360777 -303.388272) (xy 62.383903 -303.436293) (xy 62.399613 -303.487223) (xy 62.407556 -303.539927)
			(xy 62.408054 -303.566576) (xy 62.407556 -303.593225) (xy 62.399613 -303.645929) (xy 62.383903 -303.696859)
			(xy 62.360777 -303.74488) (xy 62.330753 -303.788917) (xy 62.294501 -303.827988) (xy 62.25283 -303.861219)
			(xy 62.206672 -303.887868) (xy 62.157058 -303.90734) (xy 62.105096 -303.9192) (xy 62.051946 -303.923184)
			(xy 61.998796 -303.9192) (xy 61.946834 -303.90734) (xy 61.89722 -303.887868) (xy 61.851062 -303.861219)
			(xy 61.809391 -303.827988) (xy 61.773139 -303.788917) (xy 61.743115 -303.74488) (xy 61.719989 -303.696859)
			(xy 61.704279 -303.645929) (xy 61.696336 -303.593225) (xy 47.319956 -303.593225) (xy 47.312013 -303.645929)
			(xy 47.296303 -303.696859) (xy 47.273177 -303.74488) (xy 47.243153 -303.788917) (xy 47.206901 -303.827988)
			(xy 47.16523 -303.861219) (xy 47.119072 -303.887868) (xy 47.069458 -303.90734) (xy 47.017496 -303.9192)
			(xy 46.964346 -303.923184) (xy 46.911196 -303.9192) (xy 46.859234 -303.90734) (xy 46.80962 -303.887868)
			(xy 46.763462 -303.861219) (xy 46.721791 -303.827988) (xy 46.685539 -303.788917) (xy 46.655515 -303.74488)
			(xy 46.632389 -303.696859) (xy 46.616679 -303.645929) (xy 46.608736 -303.593225) (xy 32.232356 -303.593225)
			(xy 32.224413 -303.645929) (xy 32.208703 -303.696859) (xy 32.185577 -303.74488) (xy 32.155553 -303.788917)
			(xy 32.119301 -303.827988) (xy 32.07763 -303.861219) (xy 32.031472 -303.887868) (xy 31.981858 -303.90734)
			(xy 31.929896 -303.9192) (xy 31.876746 -303.923184) (xy 31.823596 -303.9192) (xy 31.771634 -303.90734)
			(xy 31.72202 -303.887868) (xy 31.675862 -303.861219) (xy 31.634191 -303.827988) (xy 31.597939 -303.788917)
			(xy 31.567915 -303.74488) (xy 31.544789 -303.696859) (xy 31.529079 -303.645929) (xy 31.521136 -303.593225)
			(xy 17.144756 -303.593225) (xy 17.136813 -303.645929) (xy 17.121103 -303.696859) (xy 17.097977 -303.74488)
			(xy 17.067953 -303.788917) (xy 17.031701 -303.827988) (xy 16.99003 -303.861219) (xy 16.943872 -303.887868)
			(xy 16.894258 -303.90734) (xy 16.842296 -303.9192) (xy 16.789146 -303.923184) (xy 16.735996 -303.9192)
			(xy 16.684034 -303.90734) (xy 16.63442 -303.887868) (xy 16.588262 -303.861219) (xy 16.546591 -303.827988)
			(xy 16.510339 -303.788917) (xy 16.480315 -303.74488) (xy 16.457189 -303.696859) (xy 16.441479 -303.645929)
			(xy 16.433536 -303.593225) (xy 6.7818 -303.593225) (xy 6.7818 -304.443363) (xy 20.533604 -304.443363)
			(xy 20.533604 -304.390065) (xy 20.541547 -304.337361) (xy 20.557257 -304.286431) (xy 20.580383 -304.23841)
			(xy 20.610407 -304.194373) (xy 20.646659 -304.155302) (xy 20.68833 -304.122071) (xy 20.734488 -304.095422)
			(xy 20.784102 -304.07595) (xy 20.836064 -304.06409) (xy 20.889214 -304.060107) (xy 20.942364 -304.06409)
			(xy 20.994326 -304.07595) (xy 21.04394 -304.095422) (xy 21.090098 -304.122071) (xy 21.131769 -304.155302)
			(xy 21.168021 -304.194373) (xy 21.198045 -304.23841) (xy 21.221171 -304.286431) (xy 21.236881 -304.337361)
			(xy 21.244824 -304.390065) (xy 21.245322 -304.416714) (xy 21.244824 -304.443363) (xy 35.621204 -304.443363)
			(xy 35.621204 -304.390065) (xy 35.629147 -304.337361) (xy 35.644857 -304.286431) (xy 35.667983 -304.23841)
			(xy 35.698007 -304.194373) (xy 35.734259 -304.155302) (xy 35.77593 -304.122071) (xy 35.822088 -304.095422)
			(xy 35.871702 -304.07595) (xy 35.923664 -304.06409) (xy 35.976814 -304.060107) (xy 36.029964 -304.06409)
			(xy 36.081926 -304.07595) (xy 36.13154 -304.095422) (xy 36.177698 -304.122071) (xy 36.219369 -304.155302)
			(xy 36.255621 -304.194373) (xy 36.285645 -304.23841) (xy 36.308771 -304.286431) (xy 36.324481 -304.337361)
			(xy 36.332424 -304.390065) (xy 36.332922 -304.416714) (xy 36.332424 -304.443363) (xy 50.734204 -304.443363)
			(xy 50.734204 -304.390065) (xy 50.742147 -304.337361) (xy 50.757857 -304.286431) (xy 50.780983 -304.23841)
			(xy 50.811007 -304.194373) (xy 50.847259 -304.155302) (xy 50.88893 -304.122071) (xy 50.935088 -304.095422)
			(xy 50.984702 -304.07595) (xy 51.036664 -304.06409) (xy 51.089814 -304.060107) (xy 51.142964 -304.06409)
			(xy 51.194926 -304.07595) (xy 51.24454 -304.095422) (xy 51.290698 -304.122071) (xy 51.332369 -304.155302)
			(xy 51.368621 -304.194373) (xy 51.398645 -304.23841) (xy 51.421771 -304.286431) (xy 51.437481 -304.337361)
			(xy 51.445424 -304.390065) (xy 51.445922 -304.416714) (xy 51.445424 -304.443363) (xy 51.437481 -304.496067)
			(xy 51.421771 -304.546997) (xy 51.398645 -304.595018) (xy 51.368621 -304.639055) (xy 51.332369 -304.678126)
			(xy 51.290698 -304.711357) (xy 51.24454 -304.738006) (xy 51.194926 -304.757478) (xy 51.142964 -304.769338)
			(xy 51.089814 -304.773322) (xy 51.036664 -304.769338) (xy 50.984702 -304.757478) (xy 50.935088 -304.738006)
			(xy 50.88893 -304.711357) (xy 50.847259 -304.678126) (xy 50.811007 -304.639055) (xy 50.780983 -304.595018)
			(xy 50.757857 -304.546997) (xy 50.742147 -304.496067) (xy 50.734204 -304.443363) (xy 36.332424 -304.443363)
			(xy 36.324481 -304.496067) (xy 36.308771 -304.546997) (xy 36.285645 -304.595018) (xy 36.255621 -304.639055)
			(xy 36.219369 -304.678126) (xy 36.177698 -304.711357) (xy 36.13154 -304.738006) (xy 36.081926 -304.757478)
			(xy 36.029964 -304.769338) (xy 35.976814 -304.773322) (xy 35.923664 -304.769338) (xy 35.871702 -304.757478)
			(xy 35.822088 -304.738006) (xy 35.77593 -304.711357) (xy 35.734259 -304.678126) (xy 35.698007 -304.639055)
			(xy 35.667983 -304.595018) (xy 35.644857 -304.546997) (xy 35.629147 -304.496067) (xy 35.621204 -304.443363)
			(xy 21.244824 -304.443363) (xy 21.236881 -304.496067) (xy 21.221171 -304.546997) (xy 21.198045 -304.595018)
			(xy 21.168021 -304.639055) (xy 21.131769 -304.678126) (xy 21.090098 -304.711357) (xy 21.04394 -304.738006)
			(xy 20.994326 -304.757478) (xy 20.942364 -304.769338) (xy 20.889214 -304.773322) (xy 20.836064 -304.769338)
			(xy 20.784102 -304.757478) (xy 20.734488 -304.738006) (xy 20.68833 -304.711357) (xy 20.646659 -304.678126)
			(xy 20.610407 -304.639055) (xy 20.580383 -304.595018) (xy 20.557257 -304.546997) (xy 20.541547 -304.496067)
			(xy 20.533604 -304.443363) (xy 6.7818 -304.443363) (xy 6.7818 -305.293247) (xy 16.433536 -305.293247)
			(xy 16.433536 -305.239949) (xy 16.441479 -305.187245) (xy 16.457189 -305.136315) (xy 16.480315 -305.088294)
			(xy 16.510339 -305.044257) (xy 16.546591 -305.005186) (xy 16.588262 -304.971955) (xy 16.63442 -304.945306)
			(xy 16.684034 -304.925834) (xy 16.735996 -304.913974) (xy 16.789146 -304.909991) (xy 16.842296 -304.913974)
			(xy 16.894258 -304.925834) (xy 16.943872 -304.945306) (xy 16.99003 -304.971955) (xy 17.031701 -305.005186)
			(xy 17.067953 -305.044257) (xy 17.097977 -305.088294) (xy 17.121103 -305.136315) (xy 17.136813 -305.187245)
			(xy 17.144756 -305.239949) (xy 17.145254 -305.266598) (xy 17.144756 -305.293247) (xy 31.521136 -305.293247)
			(xy 31.521136 -305.239949) (xy 31.529079 -305.187245) (xy 31.544789 -305.136315) (xy 31.567915 -305.088294)
			(xy 31.597939 -305.044257) (xy 31.634191 -305.005186) (xy 31.675862 -304.971955) (xy 31.72202 -304.945306)
			(xy 31.771634 -304.925834) (xy 31.823596 -304.913974) (xy 31.876746 -304.909991) (xy 31.929896 -304.913974)
			(xy 31.981858 -304.925834) (xy 32.031472 -304.945306) (xy 32.07763 -304.971955) (xy 32.119301 -305.005186)
			(xy 32.155553 -305.044257) (xy 32.185577 -305.088294) (xy 32.208703 -305.136315) (xy 32.224413 -305.187245)
			(xy 32.232356 -305.239949) (xy 32.232854 -305.266598) (xy 32.232356 -305.293247) (xy 46.608736 -305.293247)
			(xy 46.608736 -305.239949) (xy 46.616679 -305.187245) (xy 46.632389 -305.136315) (xy 46.655515 -305.088294)
			(xy 46.685539 -305.044257) (xy 46.721791 -305.005186) (xy 46.763462 -304.971955) (xy 46.80962 -304.945306)
			(xy 46.859234 -304.925834) (xy 46.911196 -304.913974) (xy 46.964346 -304.909991) (xy 47.017496 -304.913974)
			(xy 47.069458 -304.925834) (xy 47.119072 -304.945306) (xy 47.16523 -304.971955) (xy 47.206901 -305.005186)
			(xy 47.243153 -305.044257) (xy 47.273177 -305.088294) (xy 47.296303 -305.136315) (xy 47.312013 -305.187245)
			(xy 47.319956 -305.239949) (xy 47.320454 -305.266598) (xy 47.319956 -305.293247) (xy 61.696336 -305.293247)
			(xy 61.696336 -305.239949) (xy 61.704279 -305.187245) (xy 61.719989 -305.136315) (xy 61.743115 -305.088294)
			(xy 61.773139 -305.044257) (xy 61.809391 -305.005186) (xy 61.851062 -304.971955) (xy 61.89722 -304.945306)
			(xy 61.946834 -304.925834) (xy 61.998796 -304.913974) (xy 62.051946 -304.909991) (xy 62.105096 -304.913974)
			(xy 62.157058 -304.925834) (xy 62.206672 -304.945306) (xy 62.25283 -304.971955) (xy 62.294501 -305.005186)
			(xy 62.330753 -305.044257) (xy 62.360777 -305.088294) (xy 62.383903 -305.136315) (xy 62.399613 -305.187245)
			(xy 62.407556 -305.239949) (xy 62.408054 -305.266598) (xy 62.407556 -305.293247) (xy 62.399613 -305.345951)
			(xy 62.383903 -305.396881) (xy 62.360777 -305.444902) (xy 62.330753 -305.488939) (xy 62.294501 -305.52801)
			(xy 62.25283 -305.561241) (xy 62.206672 -305.58789) (xy 62.157058 -305.607362) (xy 62.105096 -305.619222)
			(xy 62.051946 -305.623206) (xy 61.998796 -305.619222) (xy 61.946834 -305.607362) (xy 61.89722 -305.58789)
			(xy 61.851062 -305.561241) (xy 61.809391 -305.52801) (xy 61.773139 -305.488939) (xy 61.743115 -305.444902)
			(xy 61.719989 -305.396881) (xy 61.704279 -305.345951) (xy 61.696336 -305.293247) (xy 47.319956 -305.293247)
			(xy 47.312013 -305.345951) (xy 47.296303 -305.396881) (xy 47.273177 -305.444902) (xy 47.243153 -305.488939)
			(xy 47.206901 -305.52801) (xy 47.16523 -305.561241) (xy 47.119072 -305.58789) (xy 47.069458 -305.607362)
			(xy 47.017496 -305.619222) (xy 46.964346 -305.623206) (xy 46.911196 -305.619222) (xy 46.859234 -305.607362)
			(xy 46.80962 -305.58789) (xy 46.763462 -305.561241) (xy 46.721791 -305.52801) (xy 46.685539 -305.488939)
			(xy 46.655515 -305.444902) (xy 46.632389 -305.396881) (xy 46.616679 -305.345951) (xy 46.608736 -305.293247)
			(xy 32.232356 -305.293247) (xy 32.224413 -305.345951) (xy 32.208703 -305.396881) (xy 32.185577 -305.444902)
			(xy 32.155553 -305.488939) (xy 32.119301 -305.52801) (xy 32.07763 -305.561241) (xy 32.031472 -305.58789)
			(xy 31.981858 -305.607362) (xy 31.929896 -305.619222) (xy 31.876746 -305.623206) (xy 31.823596 -305.619222)
			(xy 31.771634 -305.607362) (xy 31.72202 -305.58789) (xy 31.675862 -305.561241) (xy 31.634191 -305.52801)
			(xy 31.597939 -305.488939) (xy 31.567915 -305.444902) (xy 31.544789 -305.396881) (xy 31.529079 -305.345951)
			(xy 31.521136 -305.293247) (xy 17.144756 -305.293247) (xy 17.136813 -305.345951) (xy 17.121103 -305.396881)
			(xy 17.097977 -305.444902) (xy 17.067953 -305.488939) (xy 17.031701 -305.52801) (xy 16.99003 -305.561241)
			(xy 16.943872 -305.58789) (xy 16.894258 -305.607362) (xy 16.842296 -305.619222) (xy 16.789146 -305.623206)
			(xy 16.735996 -305.619222) (xy 16.684034 -305.607362) (xy 16.63442 -305.58789) (xy 16.588262 -305.561241)
			(xy 16.546591 -305.52801) (xy 16.510339 -305.488939) (xy 16.480315 -305.444902) (xy 16.457189 -305.396881)
			(xy 16.441479 -305.345951) (xy 16.433536 -305.293247) (xy 6.7818 -305.293247) (xy 6.7818 -306.143385)
			(xy 20.533604 -306.143385) (xy 20.533604 -306.090087) (xy 20.541547 -306.037383) (xy 20.557257 -305.986453)
			(xy 20.580383 -305.938432) (xy 20.610407 -305.894395) (xy 20.646659 -305.855324) (xy 20.68833 -305.822093)
			(xy 20.734488 -305.795444) (xy 20.784102 -305.775972) (xy 20.836064 -305.764112) (xy 20.889214 -305.760129)
			(xy 20.942364 -305.764112) (xy 20.994326 -305.775972) (xy 21.04394 -305.795444) (xy 21.090098 -305.822093)
			(xy 21.131769 -305.855324) (xy 21.168021 -305.894395) (xy 21.198045 -305.938432) (xy 21.221171 -305.986453)
			(xy 21.236881 -306.037383) (xy 21.244824 -306.090087) (xy 21.245322 -306.116736) (xy 21.244824 -306.143385)
			(xy 35.621204 -306.143385) (xy 35.621204 -306.090087) (xy 35.629147 -306.037383) (xy 35.644857 -305.986453)
			(xy 35.667983 -305.938432) (xy 35.698007 -305.894395) (xy 35.734259 -305.855324) (xy 35.77593 -305.822093)
			(xy 35.822088 -305.795444) (xy 35.871702 -305.775972) (xy 35.923664 -305.764112) (xy 35.976814 -305.760129)
			(xy 36.029964 -305.764112) (xy 36.081926 -305.775972) (xy 36.13154 -305.795444) (xy 36.177698 -305.822093)
			(xy 36.219369 -305.855324) (xy 36.255621 -305.894395) (xy 36.285645 -305.938432) (xy 36.308771 -305.986453)
			(xy 36.324481 -306.037383) (xy 36.332424 -306.090087) (xy 36.332922 -306.116736) (xy 36.332424 -306.143385)
			(xy 50.734204 -306.143385) (xy 50.734204 -306.090087) (xy 50.742147 -306.037383) (xy 50.757857 -305.986453)
			(xy 50.780983 -305.938432) (xy 50.811007 -305.894395) (xy 50.847259 -305.855324) (xy 50.88893 -305.822093)
			(xy 50.935088 -305.795444) (xy 50.984702 -305.775972) (xy 51.036664 -305.764112) (xy 51.089814 -305.760129)
			(xy 51.142964 -305.764112) (xy 51.194926 -305.775972) (xy 51.24454 -305.795444) (xy 51.290698 -305.822093)
			(xy 51.332369 -305.855324) (xy 51.368621 -305.894395) (xy 51.398645 -305.938432) (xy 51.421771 -305.986453)
			(xy 51.437481 -306.037383) (xy 51.445424 -306.090087) (xy 51.445922 -306.116736) (xy 51.445424 -306.143385)
			(xy 51.437481 -306.196089) (xy 51.421771 -306.247019) (xy 51.398645 -306.29504) (xy 51.368621 -306.339077)
			(xy 51.332369 -306.378148) (xy 51.290698 -306.411379) (xy 51.24454 -306.438028) (xy 51.194926 -306.4575)
			(xy 51.142964 -306.46936) (xy 51.089814 -306.473344) (xy 51.036664 -306.46936) (xy 50.984702 -306.4575)
			(xy 50.935088 -306.438028) (xy 50.88893 -306.411379) (xy 50.847259 -306.378148) (xy 50.811007 -306.339077)
			(xy 50.780983 -306.29504) (xy 50.757857 -306.247019) (xy 50.742147 -306.196089) (xy 50.734204 -306.143385)
			(xy 36.332424 -306.143385) (xy 36.324481 -306.196089) (xy 36.308771 -306.247019) (xy 36.285645 -306.29504)
			(xy 36.255621 -306.339077) (xy 36.219369 -306.378148) (xy 36.177698 -306.411379) (xy 36.13154 -306.438028)
			(xy 36.081926 -306.4575) (xy 36.029964 -306.46936) (xy 35.976814 -306.473344) (xy 35.923664 -306.46936)
			(xy 35.871702 -306.4575) (xy 35.822088 -306.438028) (xy 35.77593 -306.411379) (xy 35.734259 -306.378148)
			(xy 35.698007 -306.339077) (xy 35.667983 -306.29504) (xy 35.644857 -306.247019) (xy 35.629147 -306.196089)
			(xy 35.621204 -306.143385) (xy 21.244824 -306.143385) (xy 21.236881 -306.196089) (xy 21.221171 -306.247019)
			(xy 21.198045 -306.29504) (xy 21.168021 -306.339077) (xy 21.131769 -306.378148) (xy 21.090098 -306.411379)
			(xy 21.04394 -306.438028) (xy 20.994326 -306.4575) (xy 20.942364 -306.46936) (xy 20.889214 -306.473344)
			(xy 20.836064 -306.46936) (xy 20.784102 -306.4575) (xy 20.734488 -306.438028) (xy 20.68833 -306.411379)
			(xy 20.646659 -306.378148) (xy 20.610407 -306.339077) (xy 20.580383 -306.29504) (xy 20.557257 -306.247019)
			(xy 20.541547 -306.196089) (xy 20.533604 -306.143385) (xy 6.7818 -306.143385) (xy 6.7818 -306.993269)
			(xy 16.433536 -306.993269) (xy 16.433536 -306.939971) (xy 16.441479 -306.887267) (xy 16.457189 -306.836337)
			(xy 16.480315 -306.788316) (xy 16.510339 -306.744279) (xy 16.546591 -306.705208) (xy 16.588262 -306.671977)
			(xy 16.63442 -306.645328) (xy 16.684034 -306.625856) (xy 16.735996 -306.613996) (xy 16.789146 -306.610013)
			(xy 16.842296 -306.613996) (xy 16.894258 -306.625856) (xy 16.943872 -306.645328) (xy 16.99003 -306.671977)
			(xy 17.031701 -306.705208) (xy 17.067953 -306.744279) (xy 17.097977 -306.788316) (xy 17.121103 -306.836337)
			(xy 17.136813 -306.887267) (xy 17.144756 -306.939971) (xy 17.145254 -306.96662) (xy 17.144756 -306.993269)
			(xy 31.521136 -306.993269) (xy 31.521136 -306.939971) (xy 31.529079 -306.887267) (xy 31.544789 -306.836337)
			(xy 31.567915 -306.788316) (xy 31.597939 -306.744279) (xy 31.634191 -306.705208) (xy 31.675862 -306.671977)
			(xy 31.72202 -306.645328) (xy 31.771634 -306.625856) (xy 31.823596 -306.613996) (xy 31.876746 -306.610013)
			(xy 31.929896 -306.613996) (xy 31.981858 -306.625856) (xy 32.031472 -306.645328) (xy 32.07763 -306.671977)
			(xy 32.119301 -306.705208) (xy 32.155553 -306.744279) (xy 32.185577 -306.788316) (xy 32.208703 -306.836337)
			(xy 32.224413 -306.887267) (xy 32.232356 -306.939971) (xy 32.232854 -306.96662) (xy 32.232356 -306.993269)
			(xy 46.608736 -306.993269) (xy 46.608736 -306.939971) (xy 46.616679 -306.887267) (xy 46.632389 -306.836337)
			(xy 46.655515 -306.788316) (xy 46.685539 -306.744279) (xy 46.721791 -306.705208) (xy 46.763462 -306.671977)
			(xy 46.80962 -306.645328) (xy 46.859234 -306.625856) (xy 46.911196 -306.613996) (xy 46.964346 -306.610013)
			(xy 47.017496 -306.613996) (xy 47.069458 -306.625856) (xy 47.119072 -306.645328) (xy 47.16523 -306.671977)
			(xy 47.206901 -306.705208) (xy 47.243153 -306.744279) (xy 47.273177 -306.788316) (xy 47.296303 -306.836337)
			(xy 47.312013 -306.887267) (xy 47.319956 -306.939971) (xy 47.320454 -306.96662) (xy 47.319956 -306.993269)
			(xy 61.696336 -306.993269) (xy 61.696336 -306.939971) (xy 61.704279 -306.887267) (xy 61.719989 -306.836337)
			(xy 61.743115 -306.788316) (xy 61.773139 -306.744279) (xy 61.809391 -306.705208) (xy 61.851062 -306.671977)
			(xy 61.89722 -306.645328) (xy 61.946834 -306.625856) (xy 61.998796 -306.613996) (xy 62.051946 -306.610013)
			(xy 62.105096 -306.613996) (xy 62.157058 -306.625856) (xy 62.206672 -306.645328) (xy 62.25283 -306.671977)
			(xy 62.294501 -306.705208) (xy 62.330753 -306.744279) (xy 62.360777 -306.788316) (xy 62.383903 -306.836337)
			(xy 62.399613 -306.887267) (xy 62.407556 -306.939971) (xy 62.408054 -306.96662) (xy 62.407556 -306.993269)
			(xy 62.399613 -307.045973) (xy 62.383903 -307.096903) (xy 62.360777 -307.144924) (xy 62.330753 -307.188961)
			(xy 62.294501 -307.228032) (xy 62.25283 -307.261263) (xy 62.206672 -307.287912) (xy 62.157058 -307.307384)
			(xy 62.105096 -307.319244) (xy 62.051946 -307.323228) (xy 61.998796 -307.319244) (xy 61.946834 -307.307384)
			(xy 61.89722 -307.287912) (xy 61.851062 -307.261263) (xy 61.809391 -307.228032) (xy 61.773139 -307.188961)
			(xy 61.743115 -307.144924) (xy 61.719989 -307.096903) (xy 61.704279 -307.045973) (xy 61.696336 -306.993269)
			(xy 47.319956 -306.993269) (xy 47.312013 -307.045973) (xy 47.296303 -307.096903) (xy 47.273177 -307.144924)
			(xy 47.243153 -307.188961) (xy 47.206901 -307.228032) (xy 47.16523 -307.261263) (xy 47.119072 -307.287912)
			(xy 47.069458 -307.307384) (xy 47.017496 -307.319244) (xy 46.964346 -307.323228) (xy 46.911196 -307.319244)
			(xy 46.859234 -307.307384) (xy 46.80962 -307.287912) (xy 46.763462 -307.261263) (xy 46.721791 -307.228032)
			(xy 46.685539 -307.188961) (xy 46.655515 -307.144924) (xy 46.632389 -307.096903) (xy 46.616679 -307.045973)
			(xy 46.608736 -306.993269) (xy 32.232356 -306.993269) (xy 32.224413 -307.045973) (xy 32.208703 -307.096903)
			(xy 32.185577 -307.144924) (xy 32.155553 -307.188961) (xy 32.119301 -307.228032) (xy 32.07763 -307.261263)
			(xy 32.031472 -307.287912) (xy 31.981858 -307.307384) (xy 31.929896 -307.319244) (xy 31.876746 -307.323228)
			(xy 31.823596 -307.319244) (xy 31.771634 -307.307384) (xy 31.72202 -307.287912) (xy 31.675862 -307.261263)
			(xy 31.634191 -307.228032) (xy 31.597939 -307.188961) (xy 31.567915 -307.144924) (xy 31.544789 -307.096903)
			(xy 31.529079 -307.045973) (xy 31.521136 -306.993269) (xy 17.144756 -306.993269) (xy 17.136813 -307.045973)
			(xy 17.121103 -307.096903) (xy 17.097977 -307.144924) (xy 17.067953 -307.188961) (xy 17.031701 -307.228032)
			(xy 16.99003 -307.261263) (xy 16.943872 -307.287912) (xy 16.894258 -307.307384) (xy 16.842296 -307.319244)
			(xy 16.789146 -307.323228) (xy 16.735996 -307.319244) (xy 16.684034 -307.307384) (xy 16.63442 -307.287912)
			(xy 16.588262 -307.261263) (xy 16.546591 -307.228032) (xy 16.510339 -307.188961) (xy 16.480315 -307.144924)
			(xy 16.457189 -307.096903) (xy 16.441479 -307.045973) (xy 16.433536 -306.993269) (xy 6.7818 -306.993269)
			(xy 6.7818 -307.843407) (xy 20.533604 -307.843407) (xy 20.533604 -307.790109) (xy 20.541547 -307.737405)
			(xy 20.557257 -307.686475) (xy 20.580383 -307.638454) (xy 20.610407 -307.594417) (xy 20.646659 -307.555346)
			(xy 20.68833 -307.522115) (xy 20.734488 -307.495466) (xy 20.784102 -307.475994) (xy 20.836064 -307.464134)
			(xy 20.889214 -307.460151) (xy 20.942364 -307.464134) (xy 20.994326 -307.475994) (xy 21.04394 -307.495466)
			(xy 21.090098 -307.522115) (xy 21.131769 -307.555346) (xy 21.168021 -307.594417) (xy 21.198045 -307.638454)
			(xy 21.221171 -307.686475) (xy 21.236881 -307.737405) (xy 21.244824 -307.790109) (xy 21.245322 -307.816758)
			(xy 21.244824 -307.843407) (xy 35.621204 -307.843407) (xy 35.621204 -307.790109) (xy 35.629147 -307.737405)
			(xy 35.644857 -307.686475) (xy 35.667983 -307.638454) (xy 35.698007 -307.594417) (xy 35.734259 -307.555346)
			(xy 35.77593 -307.522115) (xy 35.822088 -307.495466) (xy 35.871702 -307.475994) (xy 35.923664 -307.464134)
			(xy 35.976814 -307.460151) (xy 36.029964 -307.464134) (xy 36.081926 -307.475994) (xy 36.13154 -307.495466)
			(xy 36.177698 -307.522115) (xy 36.219369 -307.555346) (xy 36.255621 -307.594417) (xy 36.285645 -307.638454)
			(xy 36.308771 -307.686475) (xy 36.324481 -307.737405) (xy 36.332424 -307.790109) (xy 36.332922 -307.816758)
			(xy 36.332424 -307.843407) (xy 50.734204 -307.843407) (xy 50.734204 -307.790109) (xy 50.742147 -307.737405)
			(xy 50.757857 -307.686475) (xy 50.780983 -307.638454) (xy 50.811007 -307.594417) (xy 50.847259 -307.555346)
			(xy 50.88893 -307.522115) (xy 50.935088 -307.495466) (xy 50.984702 -307.475994) (xy 51.036664 -307.464134)
			(xy 51.089814 -307.460151) (xy 51.142964 -307.464134) (xy 51.194926 -307.475994) (xy 51.24454 -307.495466)
			(xy 51.290698 -307.522115) (xy 51.332369 -307.555346) (xy 51.368621 -307.594417) (xy 51.398645 -307.638454)
			(xy 51.421771 -307.686475) (xy 51.437481 -307.737405) (xy 51.445424 -307.790109) (xy 51.445922 -307.816758)
			(xy 51.445424 -307.843407) (xy 51.437481 -307.896111) (xy 51.421771 -307.947041) (xy 51.398645 -307.995062)
			(xy 51.368621 -308.039099) (xy 51.332369 -308.07817) (xy 51.290698 -308.111401) (xy 51.24454 -308.13805)
			(xy 51.194926 -308.157522) (xy 51.142964 -308.169382) (xy 51.089814 -308.173366) (xy 51.036664 -308.169382)
			(xy 50.984702 -308.157522) (xy 50.935088 -308.13805) (xy 50.88893 -308.111401) (xy 50.847259 -308.07817)
			(xy 50.811007 -308.039099) (xy 50.780983 -307.995062) (xy 50.757857 -307.947041) (xy 50.742147 -307.896111)
			(xy 50.734204 -307.843407) (xy 36.332424 -307.843407) (xy 36.324481 -307.896111) (xy 36.308771 -307.947041)
			(xy 36.285645 -307.995062) (xy 36.255621 -308.039099) (xy 36.219369 -308.07817) (xy 36.177698 -308.111401)
			(xy 36.13154 -308.13805) (xy 36.081926 -308.157522) (xy 36.029964 -308.169382) (xy 35.976814 -308.173366)
			(xy 35.923664 -308.169382) (xy 35.871702 -308.157522) (xy 35.822088 -308.13805) (xy 35.77593 -308.111401)
			(xy 35.734259 -308.07817) (xy 35.698007 -308.039099) (xy 35.667983 -307.995062) (xy 35.644857 -307.947041)
			(xy 35.629147 -307.896111) (xy 35.621204 -307.843407) (xy 21.244824 -307.843407) (xy 21.236881 -307.896111)
			(xy 21.221171 -307.947041) (xy 21.198045 -307.995062) (xy 21.168021 -308.039099) (xy 21.131769 -308.07817)
			(xy 21.090098 -308.111401) (xy 21.04394 -308.13805) (xy 20.994326 -308.157522) (xy 20.942364 -308.169382)
			(xy 20.889214 -308.173366) (xy 20.836064 -308.169382) (xy 20.784102 -308.157522) (xy 20.734488 -308.13805)
			(xy 20.68833 -308.111401) (xy 20.646659 -308.07817) (xy 20.610407 -308.039099) (xy 20.580383 -307.995062)
			(xy 20.557257 -307.947041) (xy 20.541547 -307.896111) (xy 20.533604 -307.843407) (xy 6.7818 -307.843407)
			(xy 6.7818 -308.693291) (xy 16.433536 -308.693291) (xy 16.433536 -308.639993) (xy 16.441479 -308.587289)
			(xy 16.457189 -308.536359) (xy 16.480315 -308.488338) (xy 16.510339 -308.444301) (xy 16.546591 -308.40523)
			(xy 16.588262 -308.371999) (xy 16.63442 -308.34535) (xy 16.684034 -308.325878) (xy 16.735996 -308.314018)
			(xy 16.789146 -308.310035) (xy 16.842296 -308.314018) (xy 16.894258 -308.325878) (xy 16.943872 -308.34535)
			(xy 16.99003 -308.371999) (xy 17.031701 -308.40523) (xy 17.067953 -308.444301) (xy 17.097977 -308.488338)
			(xy 17.121103 -308.536359) (xy 17.136813 -308.587289) (xy 17.144756 -308.639993) (xy 17.145254 -308.666642)
			(xy 17.144756 -308.693291) (xy 31.521136 -308.693291) (xy 31.521136 -308.639993) (xy 31.529079 -308.587289)
			(xy 31.544789 -308.536359) (xy 31.567915 -308.488338) (xy 31.597939 -308.444301) (xy 31.634191 -308.40523)
			(xy 31.675862 -308.371999) (xy 31.72202 -308.34535) (xy 31.771634 -308.325878) (xy 31.823596 -308.314018)
			(xy 31.876746 -308.310035) (xy 31.929896 -308.314018) (xy 31.981858 -308.325878) (xy 32.031472 -308.34535)
			(xy 32.07763 -308.371999) (xy 32.119301 -308.40523) (xy 32.155553 -308.444301) (xy 32.185577 -308.488338)
			(xy 32.208703 -308.536359) (xy 32.224413 -308.587289) (xy 32.232356 -308.639993) (xy 32.232854 -308.666642)
			(xy 32.232356 -308.693291) (xy 46.608736 -308.693291) (xy 46.608736 -308.639993) (xy 46.616679 -308.587289)
			(xy 46.632389 -308.536359) (xy 46.655515 -308.488338) (xy 46.685539 -308.444301) (xy 46.721791 -308.40523)
			(xy 46.763462 -308.371999) (xy 46.80962 -308.34535) (xy 46.859234 -308.325878) (xy 46.911196 -308.314018)
			(xy 46.964346 -308.310035) (xy 47.017496 -308.314018) (xy 47.069458 -308.325878) (xy 47.119072 -308.34535)
			(xy 47.16523 -308.371999) (xy 47.206901 -308.40523) (xy 47.243153 -308.444301) (xy 47.273177 -308.488338)
			(xy 47.296303 -308.536359) (xy 47.312013 -308.587289) (xy 47.319956 -308.639993) (xy 47.320454 -308.666642)
			(xy 47.319956 -308.693291) (xy 47.312013 -308.745995) (xy 47.296303 -308.796925) (xy 47.273177 -308.844946)
			(xy 47.243153 -308.888983) (xy 47.206901 -308.928054) (xy 47.16523 -308.961285) (xy 47.119072 -308.987934)
			(xy 47.069458 -309.007406) (xy 47.017496 -309.019266) (xy 46.964346 -309.02325) (xy 46.911196 -309.019266)
			(xy 46.859234 -309.007406) (xy 46.80962 -308.987934) (xy 46.763462 -308.961285) (xy 46.721791 -308.928054)
			(xy 46.685539 -308.888983) (xy 46.655515 -308.844946) (xy 46.632389 -308.796925) (xy 46.616679 -308.745995)
			(xy 46.608736 -308.693291) (xy 32.232356 -308.693291) (xy 32.224413 -308.745995) (xy 32.208703 -308.796925)
			(xy 32.185577 -308.844946) (xy 32.155553 -308.888983) (xy 32.119301 -308.928054) (xy 32.07763 -308.961285)
			(xy 32.031472 -308.987934) (xy 31.981858 -309.007406) (xy 31.929896 -309.019266) (xy 31.876746 -309.02325)
			(xy 31.823596 -309.019266) (xy 31.771634 -309.007406) (xy 31.72202 -308.987934) (xy 31.675862 -308.961285)
			(xy 31.634191 -308.928054) (xy 31.597939 -308.888983) (xy 31.567915 -308.844946) (xy 31.544789 -308.796925)
			(xy 31.529079 -308.745995) (xy 31.521136 -308.693291) (xy 17.144756 -308.693291) (xy 17.136813 -308.745995)
			(xy 17.121103 -308.796925) (xy 17.097977 -308.844946) (xy 17.067953 -308.888983) (xy 17.031701 -308.928054)
			(xy 16.99003 -308.961285) (xy 16.943872 -308.987934) (xy 16.894258 -309.007406) (xy 16.842296 -309.019266)
			(xy 16.789146 -309.02325) (xy 16.735996 -309.019266) (xy 16.684034 -309.007406) (xy 16.63442 -308.987934)
			(xy 16.588262 -308.961285) (xy 16.546591 -308.928054) (xy 16.510339 -308.888983) (xy 16.480315 -308.844946)
			(xy 16.457189 -308.796925) (xy 16.441479 -308.745995) (xy 16.433536 -308.693291) (xy 6.7818 -308.693291)
			(xy 6.7818 -309.543429) (xy 20.533604 -309.543429) (xy 20.533604 -309.490131) (xy 20.541547 -309.437427)
			(xy 20.557257 -309.386497) (xy 20.580383 -309.338476) (xy 20.610407 -309.294439) (xy 20.646659 -309.255368)
			(xy 20.68833 -309.222137) (xy 20.734488 -309.195488) (xy 20.784102 -309.176016) (xy 20.836064 -309.164156)
			(xy 20.889214 -309.160173) (xy 20.942364 -309.164156) (xy 20.994326 -309.176016) (xy 21.04394 -309.195488)
			(xy 21.090098 -309.222137) (xy 21.131769 -309.255368) (xy 21.168021 -309.294439) (xy 21.198045 -309.338476)
			(xy 21.221171 -309.386497) (xy 21.236881 -309.437427) (xy 21.244824 -309.490131) (xy 21.245322 -309.51678)
			(xy 21.244824 -309.543429) (xy 35.621204 -309.543429) (xy 35.621204 -309.490131) (xy 35.629147 -309.437427)
			(xy 35.644857 -309.386497) (xy 35.667983 -309.338476) (xy 35.698007 -309.294439) (xy 35.734259 -309.255368)
			(xy 35.77593 -309.222137) (xy 35.822088 -309.195488) (xy 35.871702 -309.176016) (xy 35.923664 -309.164156)
			(xy 35.976814 -309.160173) (xy 36.029964 -309.164156) (xy 36.081926 -309.176016) (xy 36.13154 -309.195488)
			(xy 36.177698 -309.222137) (xy 36.219369 -309.255368) (xy 36.255621 -309.294439) (xy 36.285645 -309.338476)
			(xy 36.308771 -309.386497) (xy 36.324481 -309.437427) (xy 36.332424 -309.490131) (xy 36.332922 -309.51678)
			(xy 36.332424 -309.543429) (xy 50.734204 -309.543429) (xy 50.734204 -309.490131) (xy 50.742147 -309.437427)
			(xy 50.757857 -309.386497) (xy 50.780983 -309.338476) (xy 50.811007 -309.294439) (xy 50.847259 -309.255368)
			(xy 50.88893 -309.222137) (xy 50.935088 -309.195488) (xy 50.984702 -309.176016) (xy 51.036664 -309.164156)
			(xy 51.089814 -309.160173) (xy 51.142964 -309.164156) (xy 51.194926 -309.176016) (xy 51.24454 -309.195488)
			(xy 51.290698 -309.222137) (xy 51.332369 -309.255368) (xy 51.368621 -309.294439) (xy 51.398645 -309.338476)
			(xy 51.421771 -309.386497) (xy 51.437481 -309.437427) (xy 51.445424 -309.490131) (xy 51.445922 -309.51678)
			(xy 51.445424 -309.543429) (xy 51.437481 -309.596133) (xy 51.421771 -309.647063) (xy 51.398645 -309.695084)
			(xy 51.368621 -309.739121) (xy 51.332369 -309.778192) (xy 51.290698 -309.811423) (xy 51.24454 -309.838072)
			(xy 51.194926 -309.857544) (xy 51.142964 -309.869404) (xy 51.089814 -309.873388) (xy 51.036664 -309.869404)
			(xy 50.984702 -309.857544) (xy 50.935088 -309.838072) (xy 50.88893 -309.811423) (xy 50.847259 -309.778192)
			(xy 50.811007 -309.739121) (xy 50.780983 -309.695084) (xy 50.757857 -309.647063) (xy 50.742147 -309.596133)
			(xy 50.734204 -309.543429) (xy 36.332424 -309.543429) (xy 36.324481 -309.596133) (xy 36.308771 -309.647063)
			(xy 36.285645 -309.695084) (xy 36.255621 -309.739121) (xy 36.219369 -309.778192) (xy 36.177698 -309.811423)
			(xy 36.13154 -309.838072) (xy 36.081926 -309.857544) (xy 36.029964 -309.869404) (xy 35.976814 -309.873388)
			(xy 35.923664 -309.869404) (xy 35.871702 -309.857544) (xy 35.822088 -309.838072) (xy 35.77593 -309.811423)
			(xy 35.734259 -309.778192) (xy 35.698007 -309.739121) (xy 35.667983 -309.695084) (xy 35.644857 -309.647063)
			(xy 35.629147 -309.596133) (xy 35.621204 -309.543429) (xy 21.244824 -309.543429) (xy 21.236881 -309.596133)
			(xy 21.221171 -309.647063) (xy 21.198045 -309.695084) (xy 21.168021 -309.739121) (xy 21.131769 -309.778192)
			(xy 21.090098 -309.811423) (xy 21.04394 -309.838072) (xy 20.994326 -309.857544) (xy 20.942364 -309.869404)
			(xy 20.889214 -309.873388) (xy 20.836064 -309.869404) (xy 20.784102 -309.857544) (xy 20.734488 -309.838072)
			(xy 20.68833 -309.811423) (xy 20.646659 -309.778192) (xy 20.610407 -309.739121) (xy 20.580383 -309.695084)
			(xy 20.557257 -309.647063) (xy 20.541547 -309.596133) (xy 20.533604 -309.543429) (xy 6.7818 -309.543429)
			(xy 6.7818 -310.393313) (xy 16.433536 -310.393313) (xy 16.433536 -310.340015) (xy 16.441479 -310.287311)
			(xy 16.457189 -310.236381) (xy 16.480315 -310.18836) (xy 16.510339 -310.144323) (xy 16.546591 -310.105252)
			(xy 16.588262 -310.072021) (xy 16.63442 -310.045372) (xy 16.684034 -310.0259) (xy 16.735996 -310.01404)
			(xy 16.789146 -310.010057) (xy 16.842296 -310.01404) (xy 16.894258 -310.0259) (xy 16.943872 -310.045372)
			(xy 16.99003 -310.072021) (xy 17.031701 -310.105252) (xy 17.067953 -310.144323) (xy 17.097977 -310.18836)
			(xy 17.121103 -310.236381) (xy 17.136813 -310.287311) (xy 17.144756 -310.340015) (xy 17.145254 -310.366664)
			(xy 17.144756 -310.393313) (xy 31.521136 -310.393313) (xy 31.521136 -310.340015) (xy 31.529079 -310.287311)
			(xy 31.544789 -310.236381) (xy 31.567915 -310.18836) (xy 31.597939 -310.144323) (xy 31.634191 -310.105252)
			(xy 31.675862 -310.072021) (xy 31.72202 -310.045372) (xy 31.771634 -310.0259) (xy 31.823596 -310.01404)
			(xy 31.876746 -310.010057) (xy 31.929896 -310.01404) (xy 31.981858 -310.0259) (xy 32.031472 -310.045372)
			(xy 32.07763 -310.072021) (xy 32.119301 -310.105252) (xy 32.155553 -310.144323) (xy 32.185577 -310.18836)
			(xy 32.208703 -310.236381) (xy 32.224413 -310.287311) (xy 32.232356 -310.340015) (xy 32.232854 -310.366664)
			(xy 32.232356 -310.393313) (xy 46.608736 -310.393313) (xy 46.608736 -310.340015) (xy 46.616679 -310.287311)
			(xy 46.632389 -310.236381) (xy 46.655515 -310.18836) (xy 46.685539 -310.144323) (xy 46.721791 -310.105252)
			(xy 46.763462 -310.072021) (xy 46.80962 -310.045372) (xy 46.859234 -310.0259) (xy 46.911196 -310.01404)
			(xy 46.964346 -310.010057) (xy 47.017496 -310.01404) (xy 47.069458 -310.0259) (xy 47.119072 -310.045372)
			(xy 47.16523 -310.072021) (xy 47.206901 -310.105252) (xy 47.243153 -310.144323) (xy 47.273177 -310.18836)
			(xy 47.296303 -310.236381) (xy 47.312013 -310.287311) (xy 47.319956 -310.340015) (xy 47.320454 -310.366664)
			(xy 47.319956 -310.393313) (xy 47.312013 -310.446017) (xy 47.296303 -310.496947) (xy 47.273177 -310.544968)
			(xy 47.243153 -310.589005) (xy 47.206901 -310.628076) (xy 47.16523 -310.661307) (xy 47.119072 -310.687956)
			(xy 47.069458 -310.707428) (xy 47.017496 -310.719288) (xy 46.964346 -310.723272) (xy 46.911196 -310.719288)
			(xy 46.859234 -310.707428) (xy 46.80962 -310.687956) (xy 46.763462 -310.661307) (xy 46.721791 -310.628076)
			(xy 46.685539 -310.589005) (xy 46.655515 -310.544968) (xy 46.632389 -310.496947) (xy 46.616679 -310.446017)
			(xy 46.608736 -310.393313) (xy 32.232356 -310.393313) (xy 32.224413 -310.446017) (xy 32.208703 -310.496947)
			(xy 32.185577 -310.544968) (xy 32.155553 -310.589005) (xy 32.119301 -310.628076) (xy 32.07763 -310.661307)
			(xy 32.031472 -310.687956) (xy 31.981858 -310.707428) (xy 31.929896 -310.719288) (xy 31.876746 -310.723272)
			(xy 31.823596 -310.719288) (xy 31.771634 -310.707428) (xy 31.72202 -310.687956) (xy 31.675862 -310.661307)
			(xy 31.634191 -310.628076) (xy 31.597939 -310.589005) (xy 31.567915 -310.544968) (xy 31.544789 -310.496947)
			(xy 31.529079 -310.446017) (xy 31.521136 -310.393313) (xy 17.144756 -310.393313) (xy 17.136813 -310.446017)
			(xy 17.121103 -310.496947) (xy 17.097977 -310.544968) (xy 17.067953 -310.589005) (xy 17.031701 -310.628076)
			(xy 16.99003 -310.661307) (xy 16.943872 -310.687956) (xy 16.894258 -310.707428) (xy 16.842296 -310.719288)
			(xy 16.789146 -310.723272) (xy 16.735996 -310.719288) (xy 16.684034 -310.707428) (xy 16.63442 -310.687956)
			(xy 16.588262 -310.661307) (xy 16.546591 -310.628076) (xy 16.510339 -310.589005) (xy 16.480315 -310.544968)
			(xy 16.457189 -310.496947) (xy 16.441479 -310.446017) (xy 16.433536 -310.393313) (xy 6.7818 -310.393313)
			(xy 6.7818 -311.243451) (xy 20.533604 -311.243451) (xy 20.533604 -311.190153) (xy 20.541547 -311.137449)
			(xy 20.557257 -311.086519) (xy 20.580383 -311.038498) (xy 20.610407 -310.994461) (xy 20.646659 -310.95539)
			(xy 20.68833 -310.922159) (xy 20.734488 -310.89551) (xy 20.784102 -310.876038) (xy 20.836064 -310.864178)
			(xy 20.889214 -310.860195) (xy 20.942364 -310.864178) (xy 20.994326 -310.876038) (xy 21.04394 -310.89551)
			(xy 21.090098 -310.922159) (xy 21.131769 -310.95539) (xy 21.168021 -310.994461) (xy 21.198045 -311.038498)
			(xy 21.221171 -311.086519) (xy 21.236881 -311.137449) (xy 21.244824 -311.190153) (xy 21.245322 -311.216802)
			(xy 21.244824 -311.243451) (xy 35.621204 -311.243451) (xy 35.621204 -311.190153) (xy 35.629147 -311.137449)
			(xy 35.644857 -311.086519) (xy 35.667983 -311.038498) (xy 35.698007 -310.994461) (xy 35.734259 -310.95539)
			(xy 35.77593 -310.922159) (xy 35.822088 -310.89551) (xy 35.871702 -310.876038) (xy 35.923664 -310.864178)
			(xy 35.976814 -310.860195) (xy 36.029964 -310.864178) (xy 36.081926 -310.876038) (xy 36.13154 -310.89551)
			(xy 36.177698 -310.922159) (xy 36.219369 -310.95539) (xy 36.255621 -310.994461) (xy 36.285645 -311.038498)
			(xy 36.308771 -311.086519) (xy 36.324481 -311.137449) (xy 36.332424 -311.190153) (xy 36.332922 -311.216802)
			(xy 36.332424 -311.243451) (xy 50.734204 -311.243451) (xy 50.734204 -311.190153) (xy 50.742147 -311.137449)
			(xy 50.757857 -311.086519) (xy 50.780983 -311.038498) (xy 50.811007 -310.994461) (xy 50.847259 -310.95539)
			(xy 50.88893 -310.922159) (xy 50.935088 -310.89551) (xy 50.984702 -310.876038) (xy 51.036664 -310.864178)
			(xy 51.089814 -310.860195) (xy 51.142964 -310.864178) (xy 51.194926 -310.876038) (xy 51.24454 -310.89551)
			(xy 51.290698 -310.922159) (xy 51.332369 -310.95539) (xy 51.368621 -310.994461) (xy 51.398645 -311.038498)
			(xy 51.421771 -311.086519) (xy 51.437481 -311.137449) (xy 51.445424 -311.190153) (xy 51.445922 -311.216802)
			(xy 51.445424 -311.243451) (xy 51.437481 -311.296155) (xy 51.421771 -311.347085) (xy 51.398645 -311.395106)
			(xy 51.368621 -311.439143) (xy 51.332369 -311.478214) (xy 51.290698 -311.511445) (xy 51.24454 -311.538094)
			(xy 51.194926 -311.557566) (xy 51.142964 -311.569426) (xy 51.089814 -311.57341) (xy 51.036664 -311.569426)
			(xy 50.984702 -311.557566) (xy 50.935088 -311.538094) (xy 50.88893 -311.511445) (xy 50.847259 -311.478214)
			(xy 50.811007 -311.439143) (xy 50.780983 -311.395106) (xy 50.757857 -311.347085) (xy 50.742147 -311.296155)
			(xy 50.734204 -311.243451) (xy 36.332424 -311.243451) (xy 36.324481 -311.296155) (xy 36.308771 -311.347085)
			(xy 36.285645 -311.395106) (xy 36.255621 -311.439143) (xy 36.219369 -311.478214) (xy 36.177698 -311.511445)
			(xy 36.13154 -311.538094) (xy 36.081926 -311.557566) (xy 36.029964 -311.569426) (xy 35.976814 -311.57341)
			(xy 35.923664 -311.569426) (xy 35.871702 -311.557566) (xy 35.822088 -311.538094) (xy 35.77593 -311.511445)
			(xy 35.734259 -311.478214) (xy 35.698007 -311.439143) (xy 35.667983 -311.395106) (xy 35.644857 -311.347085)
			(xy 35.629147 -311.296155) (xy 35.621204 -311.243451) (xy 21.244824 -311.243451) (xy 21.236881 -311.296155)
			(xy 21.221171 -311.347085) (xy 21.198045 -311.395106) (xy 21.168021 -311.439143) (xy 21.131769 -311.478214)
			(xy 21.090098 -311.511445) (xy 21.04394 -311.538094) (xy 20.994326 -311.557566) (xy 20.942364 -311.569426)
			(xy 20.889214 -311.57341) (xy 20.836064 -311.569426) (xy 20.784102 -311.557566) (xy 20.734488 -311.538094)
			(xy 20.68833 -311.511445) (xy 20.646659 -311.478214) (xy 20.610407 -311.439143) (xy 20.580383 -311.395106)
			(xy 20.557257 -311.347085) (xy 20.541547 -311.296155) (xy 20.533604 -311.243451) (xy 6.7818 -311.243451)
			(xy 6.7818 -312.093335) (xy 16.433536 -312.093335) (xy 16.433536 -312.040037) (xy 16.441479 -311.987333)
			(xy 16.457189 -311.936403) (xy 16.480315 -311.888382) (xy 16.510339 -311.844345) (xy 16.546591 -311.805274)
			(xy 16.588262 -311.772043) (xy 16.63442 -311.745394) (xy 16.684034 -311.725922) (xy 16.735996 -311.714062)
			(xy 16.789146 -311.710079) (xy 16.842296 -311.714062) (xy 16.894258 -311.725922) (xy 16.943872 -311.745394)
			(xy 16.99003 -311.772043) (xy 17.031701 -311.805274) (xy 17.067953 -311.844345) (xy 17.097977 -311.888382)
			(xy 17.121103 -311.936403) (xy 17.136813 -311.987333) (xy 17.144756 -312.040037) (xy 17.145254 -312.066686)
			(xy 17.144756 -312.093335) (xy 20.533604 -312.093335) (xy 20.533604 -312.040037) (xy 20.541547 -311.987333)
			(xy 20.557257 -311.936403) (xy 20.580383 -311.888382) (xy 20.610407 -311.844345) (xy 20.646659 -311.805274)
			(xy 20.68833 -311.772043) (xy 20.734488 -311.745394) (xy 20.784102 -311.725922) (xy 20.836064 -311.714062)
			(xy 20.889214 -311.710079) (xy 20.942364 -311.714062) (xy 20.994326 -311.725922) (xy 21.04394 -311.745394)
			(xy 21.090098 -311.772043) (xy 21.131769 -311.805274) (xy 21.168021 -311.844345) (xy 21.198045 -311.888382)
			(xy 21.221171 -311.936403) (xy 21.236881 -311.987333) (xy 21.244824 -312.040037) (xy 21.245322 -312.066686)
			(xy 21.244824 -312.093335) (xy 31.521136 -312.093335) (xy 31.521136 -312.040037) (xy 31.529079 -311.987333)
			(xy 31.544789 -311.936403) (xy 31.567915 -311.888382) (xy 31.597939 -311.844345) (xy 31.634191 -311.805274)
			(xy 31.675862 -311.772043) (xy 31.72202 -311.745394) (xy 31.771634 -311.725922) (xy 31.823596 -311.714062)
			(xy 31.876746 -311.710079) (xy 31.929896 -311.714062) (xy 31.981858 -311.725922) (xy 32.031472 -311.745394)
			(xy 32.07763 -311.772043) (xy 32.119301 -311.805274) (xy 32.155553 -311.844345) (xy 32.185577 -311.888382)
			(xy 32.208703 -311.936403) (xy 32.224413 -311.987333) (xy 32.232356 -312.040037) (xy 32.232854 -312.066686)
			(xy 32.232356 -312.093335) (xy 35.621204 -312.093335) (xy 35.621204 -312.040037) (xy 35.629147 -311.987333)
			(xy 35.644857 -311.936403) (xy 35.667983 -311.888382) (xy 35.698007 -311.844345) (xy 35.734259 -311.805274)
			(xy 35.77593 -311.772043) (xy 35.822088 -311.745394) (xy 35.871702 -311.725922) (xy 35.923664 -311.714062)
			(xy 35.976814 -311.710079) (xy 36.029964 -311.714062) (xy 36.081926 -311.725922) (xy 36.13154 -311.745394)
			(xy 36.177698 -311.772043) (xy 36.219369 -311.805274) (xy 36.255621 -311.844345) (xy 36.285645 -311.888382)
			(xy 36.308771 -311.936403) (xy 36.324481 -311.987333) (xy 36.332424 -312.040037) (xy 36.332922 -312.066686)
			(xy 36.332424 -312.093335) (xy 46.608736 -312.093335) (xy 46.608736 -312.040037) (xy 46.616679 -311.987333)
			(xy 46.632389 -311.936403) (xy 46.655515 -311.888382) (xy 46.685539 -311.844345) (xy 46.721791 -311.805274)
			(xy 46.763462 -311.772043) (xy 46.80962 -311.745394) (xy 46.859234 -311.725922) (xy 46.911196 -311.714062)
			(xy 46.964346 -311.710079) (xy 47.017496 -311.714062) (xy 47.069458 -311.725922) (xy 47.119072 -311.745394)
			(xy 47.16523 -311.772043) (xy 47.206901 -311.805274) (xy 47.243153 -311.844345) (xy 47.273177 -311.888382)
			(xy 47.296303 -311.936403) (xy 47.312013 -311.987333) (xy 47.319956 -312.040037) (xy 47.320454 -312.066686)
			(xy 47.319956 -312.093335) (xy 50.734204 -312.093335) (xy 50.734204 -312.040037) (xy 50.742147 -311.987333)
			(xy 50.757857 -311.936403) (xy 50.780983 -311.888382) (xy 50.811007 -311.844345) (xy 50.847259 -311.805274)
			(xy 50.88893 -311.772043) (xy 50.935088 -311.745394) (xy 50.984702 -311.725922) (xy 51.036664 -311.714062)
			(xy 51.089814 -311.710079) (xy 51.142964 -311.714062) (xy 51.194926 -311.725922) (xy 51.24454 -311.745394)
			(xy 51.290698 -311.772043) (xy 51.332369 -311.805274) (xy 51.368621 -311.844345) (xy 51.398645 -311.888382)
			(xy 51.421771 -311.936403) (xy 51.437481 -311.987333) (xy 51.445424 -312.040037) (xy 51.445922 -312.066686)
			(xy 51.445424 -312.093335) (xy 51.437481 -312.146039) (xy 51.421771 -312.196969) (xy 51.398645 -312.24499)
			(xy 51.368621 -312.289027) (xy 51.332369 -312.328098) (xy 51.290698 -312.361329) (xy 51.24454 -312.387978)
			(xy 51.194926 -312.40745) (xy 51.142964 -312.41931) (xy 51.089814 -312.423294) (xy 51.036664 -312.41931)
			(xy 50.984702 -312.40745) (xy 50.935088 -312.387978) (xy 50.88893 -312.361329) (xy 50.847259 -312.328098)
			(xy 50.811007 -312.289027) (xy 50.780983 -312.24499) (xy 50.757857 -312.196969) (xy 50.742147 -312.146039)
			(xy 50.734204 -312.093335) (xy 47.319956 -312.093335) (xy 47.312013 -312.146039) (xy 47.296303 -312.196969)
			(xy 47.273177 -312.24499) (xy 47.243153 -312.289027) (xy 47.206901 -312.328098) (xy 47.16523 -312.361329)
			(xy 47.119072 -312.387978) (xy 47.069458 -312.40745) (xy 47.017496 -312.41931) (xy 46.964346 -312.423294)
			(xy 46.911196 -312.41931) (xy 46.859234 -312.40745) (xy 46.80962 -312.387978) (xy 46.763462 -312.361329)
			(xy 46.721791 -312.328098) (xy 46.685539 -312.289027) (xy 46.655515 -312.24499) (xy 46.632389 -312.196969)
			(xy 46.616679 -312.146039) (xy 46.608736 -312.093335) (xy 36.332424 -312.093335) (xy 36.324481 -312.146039)
			(xy 36.308771 -312.196969) (xy 36.285645 -312.24499) (xy 36.255621 -312.289027) (xy 36.219369 -312.328098)
			(xy 36.177698 -312.361329) (xy 36.13154 -312.387978) (xy 36.081926 -312.40745) (xy 36.029964 -312.41931)
			(xy 35.976814 -312.423294) (xy 35.923664 -312.41931) (xy 35.871702 -312.40745) (xy 35.822088 -312.387978)
			(xy 35.77593 -312.361329) (xy 35.734259 -312.328098) (xy 35.698007 -312.289027) (xy 35.667983 -312.24499)
			(xy 35.644857 -312.196969) (xy 35.629147 -312.146039) (xy 35.621204 -312.093335) (xy 32.232356 -312.093335)
			(xy 32.224413 -312.146039) (xy 32.208703 -312.196969) (xy 32.185577 -312.24499) (xy 32.155553 -312.289027)
			(xy 32.119301 -312.328098) (xy 32.07763 -312.361329) (xy 32.031472 -312.387978) (xy 31.981858 -312.40745)
			(xy 31.929896 -312.41931) (xy 31.876746 -312.423294) (xy 31.823596 -312.41931) (xy 31.771634 -312.40745)
			(xy 31.72202 -312.387978) (xy 31.675862 -312.361329) (xy 31.634191 -312.328098) (xy 31.597939 -312.289027)
			(xy 31.567915 -312.24499) (xy 31.544789 -312.196969) (xy 31.529079 -312.146039) (xy 31.521136 -312.093335)
			(xy 21.244824 -312.093335) (xy 21.236881 -312.146039) (xy 21.221171 -312.196969) (xy 21.198045 -312.24499)
			(xy 21.168021 -312.289027) (xy 21.131769 -312.328098) (xy 21.090098 -312.361329) (xy 21.04394 -312.387978)
			(xy 20.994326 -312.40745) (xy 20.942364 -312.41931) (xy 20.889214 -312.423294) (xy 20.836064 -312.41931)
			(xy 20.784102 -312.40745) (xy 20.734488 -312.387978) (xy 20.68833 -312.361329) (xy 20.646659 -312.328098)
			(xy 20.610407 -312.289027) (xy 20.580383 -312.24499) (xy 20.557257 -312.196969) (xy 20.541547 -312.146039)
			(xy 20.533604 -312.093335) (xy 17.144756 -312.093335) (xy 17.136813 -312.146039) (xy 17.121103 -312.196969)
			(xy 17.097977 -312.24499) (xy 17.067953 -312.289027) (xy 17.031701 -312.328098) (xy 16.99003 -312.361329)
			(xy 16.943872 -312.387978) (xy 16.894258 -312.40745) (xy 16.842296 -312.41931) (xy 16.789146 -312.423294)
			(xy 16.735996 -312.41931) (xy 16.684034 -312.40745) (xy 16.63442 -312.387978) (xy 16.588262 -312.361329)
			(xy 16.546591 -312.328098) (xy 16.510339 -312.289027) (xy 16.480315 -312.24499) (xy 16.457189 -312.196969)
			(xy 16.441479 -312.146039) (xy 16.433536 -312.093335) (xy 6.7818 -312.093335) (xy 6.7818 -312.943219)
			(xy 16.433536 -312.943219) (xy 16.433536 -312.889921) (xy 16.441479 -312.837217) (xy 16.457189 -312.786287)
			(xy 16.480315 -312.738266) (xy 16.510339 -312.694229) (xy 16.546591 -312.655158) (xy 16.588262 -312.621927)
			(xy 16.63442 -312.595278) (xy 16.684034 -312.575806) (xy 16.735996 -312.563946) (xy 16.789146 -312.559963)
			(xy 16.842296 -312.563946) (xy 16.894258 -312.575806) (xy 16.943872 -312.595278) (xy 16.99003 -312.621927)
			(xy 17.031701 -312.655158) (xy 17.067953 -312.694229) (xy 17.097977 -312.738266) (xy 17.121103 -312.786287)
			(xy 17.136813 -312.837217) (xy 17.144756 -312.889921) (xy 17.145254 -312.91657) (xy 17.144756 -312.943219)
			(xy 31.521136 -312.943219) (xy 31.521136 -312.889921) (xy 31.529079 -312.837217) (xy 31.544789 -312.786287)
			(xy 31.567915 -312.738266) (xy 31.597939 -312.694229) (xy 31.634191 -312.655158) (xy 31.675862 -312.621927)
			(xy 31.72202 -312.595278) (xy 31.771634 -312.575806) (xy 31.823596 -312.563946) (xy 31.876746 -312.559963)
			(xy 31.929896 -312.563946) (xy 31.981858 -312.575806) (xy 32.031472 -312.595278) (xy 32.07763 -312.621927)
			(xy 32.119301 -312.655158) (xy 32.155553 -312.694229) (xy 32.185577 -312.738266) (xy 32.208703 -312.786287)
			(xy 32.224413 -312.837217) (xy 32.232356 -312.889921) (xy 32.232854 -312.91657) (xy 32.232356 -312.943219)
			(xy 46.608736 -312.943219) (xy 46.608736 -312.889921) (xy 46.616679 -312.837217) (xy 46.632389 -312.786287)
			(xy 46.655515 -312.738266) (xy 46.685539 -312.694229) (xy 46.721791 -312.655158) (xy 46.763462 -312.621927)
			(xy 46.80962 -312.595278) (xy 46.859234 -312.575806) (xy 46.911196 -312.563946) (xy 46.964346 -312.559963)
			(xy 47.017496 -312.563946) (xy 47.069458 -312.575806) (xy 47.119072 -312.595278) (xy 47.16523 -312.621927)
			(xy 47.206901 -312.655158) (xy 47.243153 -312.694229) (xy 47.273177 -312.738266) (xy 47.296303 -312.786287)
			(xy 47.312013 -312.837217) (xy 47.319956 -312.889921) (xy 47.320454 -312.91657) (xy 47.319956 -312.943219)
			(xy 47.312013 -312.995923) (xy 47.296303 -313.046853) (xy 47.273177 -313.094874) (xy 47.243153 -313.138911)
			(xy 47.206901 -313.177982) (xy 47.16523 -313.211213) (xy 47.119072 -313.237862) (xy 47.069458 -313.257334)
			(xy 47.017496 -313.269194) (xy 46.964346 -313.273178) (xy 46.911196 -313.269194) (xy 46.859234 -313.257334)
			(xy 46.80962 -313.237862) (xy 46.763462 -313.211213) (xy 46.721791 -313.177982) (xy 46.685539 -313.138911)
			(xy 46.655515 -313.094874) (xy 46.632389 -313.046853) (xy 46.616679 -312.995923) (xy 46.608736 -312.943219)
			(xy 32.232356 -312.943219) (xy 32.224413 -312.995923) (xy 32.208703 -313.046853) (xy 32.185577 -313.094874)
			(xy 32.155553 -313.138911) (xy 32.119301 -313.177982) (xy 32.07763 -313.211213) (xy 32.031472 -313.237862)
			(xy 31.981858 -313.257334) (xy 31.929896 -313.269194) (xy 31.876746 -313.273178) (xy 31.823596 -313.269194)
			(xy 31.771634 -313.257334) (xy 31.72202 -313.237862) (xy 31.675862 -313.211213) (xy 31.634191 -313.177982)
			(xy 31.597939 -313.138911) (xy 31.567915 -313.094874) (xy 31.544789 -313.046853) (xy 31.529079 -312.995923)
			(xy 31.521136 -312.943219) (xy 17.144756 -312.943219) (xy 17.136813 -312.995923) (xy 17.121103 -313.046853)
			(xy 17.097977 -313.094874) (xy 17.067953 -313.138911) (xy 17.031701 -313.177982) (xy 16.99003 -313.211213)
			(xy 16.943872 -313.237862) (xy 16.894258 -313.257334) (xy 16.842296 -313.269194) (xy 16.789146 -313.273178)
			(xy 16.735996 -313.269194) (xy 16.684034 -313.257334) (xy 16.63442 -313.237862) (xy 16.588262 -313.211213)
			(xy 16.546591 -313.177982) (xy 16.510339 -313.138911) (xy 16.480315 -313.094874) (xy 16.457189 -313.046853)
			(xy 16.441479 -312.995923) (xy 16.433536 -312.943219) (xy 6.7818 -312.943219) (xy 6.7818 -313.793357)
			(xy 20.533604 -313.793357) (xy 20.533604 -313.740059) (xy 20.541547 -313.687355) (xy 20.557257 -313.636425)
			(xy 20.580383 -313.588404) (xy 20.610407 -313.544367) (xy 20.646659 -313.505296) (xy 20.68833 -313.472065)
			(xy 20.734488 -313.445416) (xy 20.784102 -313.425944) (xy 20.836064 -313.414084) (xy 20.889214 -313.410101)
			(xy 20.942364 -313.414084) (xy 20.994326 -313.425944) (xy 21.04394 -313.445416) (xy 21.090098 -313.472065)
			(xy 21.131769 -313.505296) (xy 21.168021 -313.544367) (xy 21.198045 -313.588404) (xy 21.221171 -313.636425)
			(xy 21.236881 -313.687355) (xy 21.244824 -313.740059) (xy 21.245322 -313.766708) (xy 21.244824 -313.793357)
			(xy 35.621204 -313.793357) (xy 35.621204 -313.740059) (xy 35.629147 -313.687355) (xy 35.644857 -313.636425)
			(xy 35.667983 -313.588404) (xy 35.698007 -313.544367) (xy 35.734259 -313.505296) (xy 35.77593 -313.472065)
			(xy 35.822088 -313.445416) (xy 35.871702 -313.425944) (xy 35.923664 -313.414084) (xy 35.976814 -313.410101)
			(xy 36.029964 -313.414084) (xy 36.081926 -313.425944) (xy 36.13154 -313.445416) (xy 36.177698 -313.472065)
			(xy 36.219369 -313.505296) (xy 36.255621 -313.544367) (xy 36.285645 -313.588404) (xy 36.308771 -313.636425)
			(xy 36.324481 -313.687355) (xy 36.332424 -313.740059) (xy 36.332922 -313.766708) (xy 36.332424 -313.793357)
			(xy 50.734204 -313.793357) (xy 50.734204 -313.740059) (xy 50.742147 -313.687355) (xy 50.757857 -313.636425)
			(xy 50.780983 -313.588404) (xy 50.811007 -313.544367) (xy 50.847259 -313.505296) (xy 50.88893 -313.472065)
			(xy 50.935088 -313.445416) (xy 50.984702 -313.425944) (xy 51.036664 -313.414084) (xy 51.089814 -313.410101)
			(xy 51.142964 -313.414084) (xy 51.194926 -313.425944) (xy 51.24454 -313.445416) (xy 51.290698 -313.472065)
			(xy 51.332369 -313.505296) (xy 51.368621 -313.544367) (xy 51.398645 -313.588404) (xy 51.421771 -313.636425)
			(xy 51.437481 -313.687355) (xy 51.445424 -313.740059) (xy 51.445922 -313.766708) (xy 51.445424 -313.793357)
			(xy 51.437481 -313.846061) (xy 51.421771 -313.896991) (xy 51.398645 -313.945012) (xy 51.368621 -313.989049)
			(xy 51.332369 -314.02812) (xy 51.290698 -314.061351) (xy 51.24454 -314.088) (xy 51.194926 -314.107472)
			(xy 51.142964 -314.119332) (xy 51.089814 -314.123316) (xy 51.036664 -314.119332) (xy 50.984702 -314.107472)
			(xy 50.935088 -314.088) (xy 50.88893 -314.061351) (xy 50.847259 -314.02812) (xy 50.811007 -313.989049)
			(xy 50.780983 -313.945012) (xy 50.757857 -313.896991) (xy 50.742147 -313.846061) (xy 50.734204 -313.793357)
			(xy 36.332424 -313.793357) (xy 36.324481 -313.846061) (xy 36.308771 -313.896991) (xy 36.285645 -313.945012)
			(xy 36.255621 -313.989049) (xy 36.219369 -314.02812) (xy 36.177698 -314.061351) (xy 36.13154 -314.088)
			(xy 36.081926 -314.107472) (xy 36.029964 -314.119332) (xy 35.976814 -314.123316) (xy 35.923664 -314.119332)
			(xy 35.871702 -314.107472) (xy 35.822088 -314.088) (xy 35.77593 -314.061351) (xy 35.734259 -314.02812)
			(xy 35.698007 -313.989049) (xy 35.667983 -313.945012) (xy 35.644857 -313.896991) (xy 35.629147 -313.846061)
			(xy 35.621204 -313.793357) (xy 21.244824 -313.793357) (xy 21.236881 -313.846061) (xy 21.221171 -313.896991)
			(xy 21.198045 -313.945012) (xy 21.168021 -313.989049) (xy 21.131769 -314.02812) (xy 21.090098 -314.061351)
			(xy 21.04394 -314.088) (xy 20.994326 -314.107472) (xy 20.942364 -314.119332) (xy 20.889214 -314.123316)
			(xy 20.836064 -314.119332) (xy 20.784102 -314.107472) (xy 20.734488 -314.088) (xy 20.68833 -314.061351)
			(xy 20.646659 -314.02812) (xy 20.610407 -313.989049) (xy 20.580383 -313.945012) (xy 20.557257 -313.896991)
			(xy 20.541547 -313.846061) (xy 20.533604 -313.793357) (xy 6.7818 -313.793357) (xy 6.7818 -314.643241)
			(xy 16.433536 -314.643241) (xy 16.433536 -314.589943) (xy 16.441479 -314.537239) (xy 16.457189 -314.486309)
			(xy 16.480315 -314.438288) (xy 16.510339 -314.394251) (xy 16.546591 -314.35518) (xy 16.588262 -314.321949)
			(xy 16.63442 -314.2953) (xy 16.684034 -314.275828) (xy 16.735996 -314.263968) (xy 16.789146 -314.259985)
			(xy 16.842296 -314.263968) (xy 16.894258 -314.275828) (xy 16.943872 -314.2953) (xy 16.99003 -314.321949)
			(xy 17.031701 -314.35518) (xy 17.067953 -314.394251) (xy 17.097977 -314.438288) (xy 17.121103 -314.486309)
			(xy 17.136813 -314.537239) (xy 17.144756 -314.589943) (xy 17.145254 -314.616592) (xy 17.144756 -314.643241)
			(xy 31.521136 -314.643241) (xy 31.521136 -314.589943) (xy 31.529079 -314.537239) (xy 31.544789 -314.486309)
			(xy 31.567915 -314.438288) (xy 31.597939 -314.394251) (xy 31.634191 -314.35518) (xy 31.675862 -314.321949)
			(xy 31.72202 -314.2953) (xy 31.771634 -314.275828) (xy 31.823596 -314.263968) (xy 31.876746 -314.259985)
			(xy 31.929896 -314.263968) (xy 31.981858 -314.275828) (xy 32.031472 -314.2953) (xy 32.07763 -314.321949)
			(xy 32.119301 -314.35518) (xy 32.155553 -314.394251) (xy 32.185577 -314.438288) (xy 32.208703 -314.486309)
			(xy 32.224413 -314.537239) (xy 32.232356 -314.589943) (xy 32.232464 -314.595743) (xy 32.647372 -314.595743)
			(xy 32.647372 -314.542445) (xy 32.655315 -314.489741) (xy 32.671025 -314.438811) (xy 32.694151 -314.39079)
			(xy 32.724175 -314.346753) (xy 32.760427 -314.307682) (xy 32.802098 -314.274451) (xy 32.848256 -314.247802)
			(xy 32.89787 -314.22833) (xy 32.949832 -314.21647) (xy 33.002982 -314.212487) (xy 33.056132 -314.21647)
			(xy 33.108094 -314.22833) (xy 33.157708 -314.247802) (xy 33.203866 -314.274451) (xy 33.245537 -314.307682)
			(xy 33.281789 -314.346753) (xy 33.311813 -314.39079) (xy 33.334939 -314.438811) (xy 33.350649 -314.489741)
			(xy 33.358592 -314.542445) (xy 33.35909 -314.569094) (xy 33.358592 -314.595743) (xy 33.351434 -314.643241)
			(xy 46.608736 -314.643241) (xy 46.608736 -314.589943) (xy 46.616679 -314.537239) (xy 46.632389 -314.486309)
			(xy 46.655515 -314.438288) (xy 46.685539 -314.394251) (xy 46.721791 -314.35518) (xy 46.763462 -314.321949)
			(xy 46.80962 -314.2953) (xy 46.859234 -314.275828) (xy 46.911196 -314.263968) (xy 46.964346 -314.259985)
			(xy 47.017496 -314.263968) (xy 47.069458 -314.275828) (xy 47.119072 -314.2953) (xy 47.16523 -314.321949)
			(xy 47.206901 -314.35518) (xy 47.243153 -314.394251) (xy 47.273177 -314.438288) (xy 47.296303 -314.486309)
			(xy 47.312013 -314.537239) (xy 47.319956 -314.589943) (xy 47.320454 -314.616592) (xy 47.319956 -314.643241)
			(xy 47.312013 -314.695945) (xy 47.296303 -314.746875) (xy 47.273177 -314.794896) (xy 47.243153 -314.838933)
			(xy 47.206901 -314.878004) (xy 47.16523 -314.911235) (xy 47.119072 -314.937884) (xy 47.069458 -314.957356)
			(xy 47.017496 -314.969216) (xy 46.964346 -314.9732) (xy 46.911196 -314.969216) (xy 46.859234 -314.957356)
			(xy 46.80962 -314.937884) (xy 46.763462 -314.911235) (xy 46.721791 -314.878004) (xy 46.685539 -314.838933)
			(xy 46.655515 -314.794896) (xy 46.632389 -314.746875) (xy 46.616679 -314.695945) (xy 46.608736 -314.643241)
			(xy 33.351434 -314.643241) (xy 33.350649 -314.648447) (xy 33.334939 -314.699377) (xy 33.311813 -314.747398)
			(xy 33.281789 -314.791435) (xy 33.245537 -314.830506) (xy 33.203866 -314.863737) (xy 33.157708 -314.890386)
			(xy 33.108094 -314.909858) (xy 33.056132 -314.921718) (xy 33.002982 -314.925702) (xy 32.949832 -314.921718)
			(xy 32.89787 -314.909858) (xy 32.848256 -314.890386) (xy 32.802098 -314.863737) (xy 32.760427 -314.830506)
			(xy 32.724175 -314.791435) (xy 32.694151 -314.747398) (xy 32.671025 -314.699377) (xy 32.655315 -314.648447)
			(xy 32.647372 -314.595743) (xy 32.232464 -314.595743) (xy 32.232854 -314.616592) (xy 32.232356 -314.643241)
			(xy 32.224413 -314.695945) (xy 32.208703 -314.746875) (xy 32.185577 -314.794896) (xy 32.155553 -314.838933)
			(xy 32.119301 -314.878004) (xy 32.07763 -314.911235) (xy 32.031472 -314.937884) (xy 31.981858 -314.957356)
			(xy 31.929896 -314.969216) (xy 31.876746 -314.9732) (xy 31.823596 -314.969216) (xy 31.771634 -314.957356)
			(xy 31.72202 -314.937884) (xy 31.675862 -314.911235) (xy 31.634191 -314.878004) (xy 31.597939 -314.838933)
			(xy 31.567915 -314.794896) (xy 31.544789 -314.746875) (xy 31.529079 -314.695945) (xy 31.521136 -314.643241)
			(xy 17.144756 -314.643241) (xy 17.136813 -314.695945) (xy 17.121103 -314.746875) (xy 17.097977 -314.794896)
			(xy 17.067953 -314.838933) (xy 17.031701 -314.878004) (xy 16.99003 -314.911235) (xy 16.943872 -314.937884)
			(xy 16.894258 -314.957356) (xy 16.842296 -314.969216) (xy 16.789146 -314.9732) (xy 16.735996 -314.969216)
			(xy 16.684034 -314.957356) (xy 16.63442 -314.937884) (xy 16.588262 -314.911235) (xy 16.546591 -314.878004)
			(xy 16.510339 -314.838933) (xy 16.480315 -314.794896) (xy 16.457189 -314.746875) (xy 16.441479 -314.695945)
			(xy 16.433536 -314.643241) (xy 6.7818 -314.643241) (xy 6.7818 -315.493379) (xy 20.533604 -315.493379)
			(xy 20.533604 -315.440081) (xy 20.541547 -315.387377) (xy 20.557257 -315.336447) (xy 20.580383 -315.288426)
			(xy 20.610407 -315.244389) (xy 20.646659 -315.205318) (xy 20.68833 -315.172087) (xy 20.734488 -315.145438)
			(xy 20.784102 -315.125966) (xy 20.836064 -315.114106) (xy 20.889214 -315.110123) (xy 20.942364 -315.114106)
			(xy 20.994326 -315.125966) (xy 21.04394 -315.145438) (xy 21.090098 -315.172087) (xy 21.131769 -315.205318)
			(xy 21.168021 -315.244389) (xy 21.198045 -315.288426) (xy 21.221171 -315.336447) (xy 21.236881 -315.387377)
			(xy 21.244824 -315.440081) (xy 21.245322 -315.46673) (xy 21.244824 -315.493379) (xy 35.621204 -315.493379)
			(xy 35.621204 -315.440081) (xy 35.629147 -315.387377) (xy 35.644857 -315.336447) (xy 35.667983 -315.288426)
			(xy 35.698007 -315.244389) (xy 35.734259 -315.205318) (xy 35.77593 -315.172087) (xy 35.822088 -315.145438)
			(xy 35.871702 -315.125966) (xy 35.923664 -315.114106) (xy 35.976814 -315.110123) (xy 36.029964 -315.114106)
			(xy 36.081926 -315.125966) (xy 36.13154 -315.145438) (xy 36.177698 -315.172087) (xy 36.219369 -315.205318)
			(xy 36.255621 -315.244389) (xy 36.285645 -315.288426) (xy 36.308771 -315.336447) (xy 36.324481 -315.387377)
			(xy 36.332424 -315.440081) (xy 36.332922 -315.46673) (xy 36.332424 -315.493379) (xy 50.734204 -315.493379)
			(xy 50.734204 -315.440081) (xy 50.742147 -315.387377) (xy 50.757857 -315.336447) (xy 50.780983 -315.288426)
			(xy 50.811007 -315.244389) (xy 50.847259 -315.205318) (xy 50.88893 -315.172087) (xy 50.935088 -315.145438)
			(xy 50.984702 -315.125966) (xy 51.036664 -315.114106) (xy 51.089814 -315.110123) (xy 51.142964 -315.114106)
			(xy 51.194926 -315.125966) (xy 51.24454 -315.145438) (xy 51.290698 -315.172087) (xy 51.332369 -315.205318)
			(xy 51.368621 -315.244389) (xy 51.398645 -315.288426) (xy 51.421771 -315.336447) (xy 51.437481 -315.387377)
			(xy 51.445424 -315.440081) (xy 51.445922 -315.46673) (xy 51.445424 -315.493379) (xy 51.437481 -315.546083)
			(xy 51.421771 -315.597013) (xy 51.398645 -315.645034) (xy 51.368621 -315.689071) (xy 51.332369 -315.728142)
			(xy 51.290698 -315.761373) (xy 51.24454 -315.788022) (xy 51.194926 -315.807494) (xy 51.142964 -315.819354)
			(xy 51.089814 -315.823338) (xy 51.036664 -315.819354) (xy 50.984702 -315.807494) (xy 50.935088 -315.788022)
			(xy 50.88893 -315.761373) (xy 50.847259 -315.728142) (xy 50.811007 -315.689071) (xy 50.780983 -315.645034)
			(xy 50.757857 -315.597013) (xy 50.742147 -315.546083) (xy 50.734204 -315.493379) (xy 36.332424 -315.493379)
			(xy 36.324481 -315.546083) (xy 36.308771 -315.597013) (xy 36.285645 -315.645034) (xy 36.255621 -315.689071)
			(xy 36.219369 -315.728142) (xy 36.177698 -315.761373) (xy 36.13154 -315.788022) (xy 36.081926 -315.807494)
			(xy 36.029964 -315.819354) (xy 35.976814 -315.823338) (xy 35.923664 -315.819354) (xy 35.871702 -315.807494)
			(xy 35.822088 -315.788022) (xy 35.77593 -315.761373) (xy 35.734259 -315.728142) (xy 35.698007 -315.689071)
			(xy 35.667983 -315.645034) (xy 35.644857 -315.597013) (xy 35.629147 -315.546083) (xy 35.621204 -315.493379)
			(xy 21.244824 -315.493379) (xy 21.236881 -315.546083) (xy 21.221171 -315.597013) (xy 21.198045 -315.645034)
			(xy 21.168021 -315.689071) (xy 21.131769 -315.728142) (xy 21.090098 -315.761373) (xy 21.04394 -315.788022)
			(xy 20.994326 -315.807494) (xy 20.942364 -315.819354) (xy 20.889214 -315.823338) (xy 20.836064 -315.819354)
			(xy 20.784102 -315.807494) (xy 20.734488 -315.788022) (xy 20.68833 -315.761373) (xy 20.646659 -315.728142)
			(xy 20.610407 -315.689071) (xy 20.580383 -315.645034) (xy 20.557257 -315.597013) (xy 20.541547 -315.546083)
			(xy 20.533604 -315.493379) (xy 6.7818 -315.493379) (xy 6.7818 -315.799978) (xy 6.782362 -315.815181)
			(xy 6.791312 -315.844239) (xy 6.808424 -315.869372) (xy 6.83218 -315.888349) (xy 6.860472 -315.899488)
			(xy 6.890789 -315.901798) (xy 6.905752 -315.899038) (xy 6.926556 -315.894637) (xy 6.968818 -315.889925)
			(xy 6.99008 -315.88964) (xy 7.017331 -315.890126) (xy 7.071279 -315.897882) (xy 7.123574 -315.913238)
			(xy 7.173152 -315.935879) (xy 7.219003 -315.965345) (xy 7.260193 -316.001037) (xy 7.295885 -316.042227)
			(xy 7.325351 -316.088078) (xy 7.347992 -316.137656) (xy 7.363348 -316.189951) (xy 7.371104 -316.243899)
			(xy 7.371104 -316.298401) (xy 7.364654 -316.343263) (xy 16.433536 -316.343263) (xy 16.433536 -316.289965)
			(xy 16.441479 -316.237261) (xy 16.457189 -316.186331) (xy 16.480315 -316.13831) (xy 16.510339 -316.094273)
			(xy 16.546591 -316.055202) (xy 16.588262 -316.021971) (xy 16.63442 -315.995322) (xy 16.684034 -315.97585)
			(xy 16.735996 -315.96399) (xy 16.789146 -315.960007) (xy 16.842296 -315.96399) (xy 16.894258 -315.97585)
			(xy 16.943872 -315.995322) (xy 16.99003 -316.021971) (xy 17.031701 -316.055202) (xy 17.067953 -316.094273)
			(xy 17.097977 -316.13831) (xy 17.121103 -316.186331) (xy 17.136813 -316.237261) (xy 17.144756 -316.289965)
			(xy 17.145254 -316.316614) (xy 17.144756 -316.343263) (xy 31.521136 -316.343263) (xy 31.521136 -316.289965)
			(xy 31.529079 -316.237261) (xy 31.544789 -316.186331) (xy 31.567915 -316.13831) (xy 31.597939 -316.094273)
			(xy 31.634191 -316.055202) (xy 31.675862 -316.021971) (xy 31.72202 -315.995322) (xy 31.771634 -315.97585)
			(xy 31.823596 -315.96399) (xy 31.876746 -315.960007) (xy 31.929896 -315.96399) (xy 31.981858 -315.97585)
			(xy 32.031472 -315.995322) (xy 32.07763 -316.021971) (xy 32.119301 -316.055202) (xy 32.155553 -316.094273)
			(xy 32.185577 -316.13831) (xy 32.208703 -316.186331) (xy 32.224413 -316.237261) (xy 32.232356 -316.289965)
			(xy 32.232854 -316.316614) (xy 32.232356 -316.343263) (xy 46.608736 -316.343263) (xy 46.608736 -316.289965)
			(xy 46.616679 -316.237261) (xy 46.632389 -316.186331) (xy 46.655515 -316.13831) (xy 46.685539 -316.094273)
			(xy 46.721791 -316.055202) (xy 46.763462 -316.021971) (xy 46.80962 -315.995322) (xy 46.859234 -315.97585)
			(xy 46.911196 -315.96399) (xy 46.964346 -315.960007) (xy 47.017496 -315.96399) (xy 47.069458 -315.97585)
			(xy 47.119072 -315.995322) (xy 47.16523 -316.021971) (xy 47.206901 -316.055202) (xy 47.243153 -316.094273)
			(xy 47.273177 -316.13831) (xy 47.296303 -316.186331) (xy 47.312013 -316.237261) (xy 47.319956 -316.289965)
			(xy 47.320454 -316.316614) (xy 47.319956 -316.343263) (xy 47.312013 -316.395967) (xy 47.296303 -316.446897)
			(xy 47.273177 -316.494918) (xy 47.243153 -316.538955) (xy 47.206901 -316.578026) (xy 47.16523 -316.611257)
			(xy 47.119072 -316.637906) (xy 47.069458 -316.657378) (xy 47.017496 -316.669238) (xy 46.964346 -316.673222)
			(xy 46.911196 -316.669238) (xy 46.859234 -316.657378) (xy 46.80962 -316.637906) (xy 46.763462 -316.611257)
			(xy 46.721791 -316.578026) (xy 46.685539 -316.538955) (xy 46.655515 -316.494918) (xy 46.632389 -316.446897)
			(xy 46.616679 -316.395967) (xy 46.608736 -316.343263) (xy 32.232356 -316.343263) (xy 32.224413 -316.395967)
			(xy 32.208703 -316.446897) (xy 32.185577 -316.494918) (xy 32.155553 -316.538955) (xy 32.119301 -316.578026)
			(xy 32.07763 -316.611257) (xy 32.031472 -316.637906) (xy 31.981858 -316.657378) (xy 31.929896 -316.669238)
			(xy 31.876746 -316.673222) (xy 31.823596 -316.669238) (xy 31.771634 -316.657378) (xy 31.72202 -316.637906)
			(xy 31.675862 -316.611257) (xy 31.634191 -316.578026) (xy 31.597939 -316.538955) (xy 31.567915 -316.494918)
			(xy 31.544789 -316.446897) (xy 31.529079 -316.395967) (xy 31.521136 -316.343263) (xy 17.144756 -316.343263)
			(xy 17.136813 -316.395967) (xy 17.121103 -316.446897) (xy 17.097977 -316.494918) (xy 17.067953 -316.538955)
			(xy 17.031701 -316.578026) (xy 16.99003 -316.611257) (xy 16.943872 -316.637906) (xy 16.894258 -316.657378)
			(xy 16.842296 -316.669238) (xy 16.789146 -316.673222) (xy 16.735996 -316.669238) (xy 16.684034 -316.657378)
			(xy 16.63442 -316.637906) (xy 16.588262 -316.611257) (xy 16.546591 -316.578026) (xy 16.510339 -316.538955)
			(xy 16.480315 -316.494918) (xy 16.457189 -316.446897) (xy 16.441479 -316.395967) (xy 16.433536 -316.343263)
			(xy 7.364654 -316.343263) (xy 7.363348 -316.352349) (xy 7.347992 -316.404644) (xy 7.325351 -316.454222)
			(xy 7.295885 -316.500073) (xy 7.260193 -316.541263) (xy 7.219003 -316.576955) (xy 7.173152 -316.606421)
			(xy 7.123574 -316.629062) (xy 7.071279 -316.644418) (xy 7.017331 -316.652174) (xy 6.99008 -316.652656)
			(xy 6.968817 -316.652382) (xy 6.926553 -316.647676) (xy 6.905752 -316.643258) (xy 6.890797 -316.640464)
			(xy 6.860479 -316.642799) (xy 6.832191 -316.65395) (xy 6.808435 -316.672931) (xy 6.791314 -316.69806)
			(xy 6.782345 -316.727115) (xy 6.7818 -316.742318) (xy 6.7818 -317.166752) (xy 10.753596 -317.166752)
			(xy 10.757667 -317.11113) (xy 10.769793 -317.056693) (xy 10.789716 -317.004602) (xy 10.817012 -316.955967)
			(xy 10.851098 -316.911824) (xy 10.891247 -316.873115) (xy 10.936605 -316.840664) (xy 10.986205 -316.815163)
			(xy 11.038989 -316.797156) (xy 11.093832 -316.787026) (xy 11.149566 -316.784989) (xy 11.205003 -316.791089)
			(xy 11.25896 -316.805195) (xy 11.310289 -316.827007) (xy 11.357895 -316.856061) (xy 11.400763 -316.891736)
			(xy 11.43798 -316.933273) (xy 11.468753 -316.979786) (xy 11.492425 -317.030283) (xy 11.508493 -317.08369)
			(xy 11.516613 -317.138866) (xy 11.517122 -317.166752) (xy 11.516636 -317.193401) (xy 20.533604 -317.193401)
			(xy 20.533604 -317.140103) (xy 20.541547 -317.087399) (xy 20.557257 -317.036469) (xy 20.580383 -316.988448)
			(xy 20.610407 -316.944411) (xy 20.646659 -316.90534) (xy 20.68833 -316.872109) (xy 20.734488 -316.84546)
			(xy 20.784102 -316.825988) (xy 20.836064 -316.814128) (xy 20.889214 -316.810145) (xy 20.942364 -316.814128)
			(xy 20.994326 -316.825988) (xy 21.04394 -316.84546) (xy 21.090098 -316.872109) (xy 21.131769 -316.90534)
			(xy 21.168021 -316.944411) (xy 21.198045 -316.988448) (xy 21.221171 -317.036469) (xy 21.236881 -317.087399)
			(xy 21.244824 -317.140103) (xy 21.245322 -317.166752) (xy 21.244824 -317.193401) (xy 28.077404 -317.193401)
			(xy 28.077404 -317.140103) (xy 28.085347 -317.087399) (xy 28.101057 -317.036469) (xy 28.124183 -316.988448)
			(xy 28.154207 -316.944411) (xy 28.190459 -316.90534) (xy 28.23213 -316.872109) (xy 28.278288 -316.84546)
			(xy 28.327902 -316.825988) (xy 28.379864 -316.814128) (xy 28.433014 -316.810145) (xy 28.486164 -316.814128)
			(xy 28.538126 -316.825988) (xy 28.58774 -316.84546) (xy 28.633898 -316.872109) (xy 28.675569 -316.90534)
			(xy 28.711821 -316.944411) (xy 28.741845 -316.988448) (xy 28.764971 -317.036469) (xy 28.780681 -317.087399)
			(xy 28.788624 -317.140103) (xy 28.789122 -317.166752) (xy 28.788624 -317.193401) (xy 35.621204 -317.193401)
			(xy 35.621204 -317.140103) (xy 35.629147 -317.087399) (xy 35.644857 -317.036469) (xy 35.667983 -316.988448)
			(xy 35.698007 -316.944411) (xy 35.734259 -316.90534) (xy 35.77593 -316.872109) (xy 35.822088 -316.84546)
			(xy 35.871702 -316.825988) (xy 35.923664 -316.814128) (xy 35.976814 -316.810145) (xy 36.029964 -316.814128)
			(xy 36.081926 -316.825988) (xy 36.13154 -316.84546) (xy 36.177698 -316.872109) (xy 36.219369 -316.90534)
			(xy 36.255621 -316.944411) (xy 36.285645 -316.988448) (xy 36.308771 -317.036469) (xy 36.324481 -317.087399)
			(xy 36.332424 -317.140103) (xy 36.332922 -317.166752) (xy 36.332424 -317.193401) (xy 43.165004 -317.193401)
			(xy 43.165004 -317.140103) (xy 43.172947 -317.087399) (xy 43.188657 -317.036469) (xy 43.211783 -316.988448)
			(xy 43.241807 -316.944411) (xy 43.278059 -316.90534) (xy 43.31973 -316.872109) (xy 43.365888 -316.84546)
			(xy 43.415502 -316.825988) (xy 43.467464 -316.814128) (xy 43.520614 -316.810145) (xy 43.573764 -316.814128)
			(xy 43.625726 -316.825988) (xy 43.67534 -316.84546) (xy 43.721498 -316.872109) (xy 43.763169 -316.90534)
			(xy 43.799421 -316.944411) (xy 43.829445 -316.988448) (xy 43.852571 -317.036469) (xy 43.868281 -317.087399)
			(xy 43.876224 -317.140103) (xy 43.876722 -317.166752) (xy 43.876224 -317.193401) (xy 50.708804 -317.193401)
			(xy 50.708804 -317.140103) (xy 50.716747 -317.087399) (xy 50.732457 -317.036469) (xy 50.755583 -316.988448)
			(xy 50.785607 -316.944411) (xy 50.821859 -316.90534) (xy 50.86353 -316.872109) (xy 50.909688 -316.84546)
			(xy 50.959302 -316.825988) (xy 51.011264 -316.814128) (xy 51.064414 -316.810145) (xy 51.117564 -316.814128)
			(xy 51.169526 -316.825988) (xy 51.21914 -316.84546) (xy 51.265298 -316.872109) (xy 51.306969 -316.90534)
			(xy 51.343221 -316.944411) (xy 51.373245 -316.988448) (xy 51.396371 -317.036469) (xy 51.412081 -317.087399)
			(xy 51.420024 -317.140103) (xy 51.420522 -317.166752) (xy 51.420024 -317.193401) (xy 58.252604 -317.193401)
			(xy 58.252604 -317.140103) (xy 58.260547 -317.087399) (xy 58.276257 -317.036469) (xy 58.299383 -316.988448)
			(xy 58.329407 -316.944411) (xy 58.365659 -316.90534) (xy 58.40733 -316.872109) (xy 58.453488 -316.84546)
			(xy 58.503102 -316.825988) (xy 58.555064 -316.814128) (xy 58.608214 -316.810145) (xy 58.661364 -316.814128)
			(xy 58.713326 -316.825988) (xy 58.76294 -316.84546) (xy 58.809098 -316.872109) (xy 58.850769 -316.90534)
			(xy 58.887021 -316.944411) (xy 58.917045 -316.988448) (xy 58.940171 -317.036469) (xy 58.955881 -317.087399)
			(xy 58.963824 -317.140103) (xy 58.964322 -317.166752) (xy 58.963824 -317.193401) (xy 58.955881 -317.246105)
			(xy 58.940171 -317.297035) (xy 58.917045 -317.345056) (xy 58.887021 -317.389093) (xy 58.850769 -317.428164)
			(xy 58.809098 -317.461395) (xy 58.76294 -317.488044) (xy 58.713326 -317.507516) (xy 58.661364 -317.519376)
			(xy 58.608214 -317.52336) (xy 58.555064 -317.519376) (xy 58.503102 -317.507516) (xy 58.453488 -317.488044)
			(xy 58.40733 -317.461395) (xy 58.365659 -317.428164) (xy 58.329407 -317.389093) (xy 58.299383 -317.345056)
			(xy 58.276257 -317.297035) (xy 58.260547 -317.246105) (xy 58.252604 -317.193401) (xy 51.420024 -317.193401)
			(xy 51.412081 -317.246105) (xy 51.396371 -317.297035) (xy 51.373245 -317.345056) (xy 51.343221 -317.389093)
			(xy 51.306969 -317.428164) (xy 51.265298 -317.461395) (xy 51.21914 -317.488044) (xy 51.169526 -317.507516)
			(xy 51.117564 -317.519376) (xy 51.064414 -317.52336) (xy 51.011264 -317.519376) (xy 50.959302 -317.507516)
			(xy 50.909688 -317.488044) (xy 50.86353 -317.461395) (xy 50.821859 -317.428164) (xy 50.785607 -317.389093)
			(xy 50.755583 -317.345056) (xy 50.732457 -317.297035) (xy 50.716747 -317.246105) (xy 50.708804 -317.193401)
			(xy 43.876224 -317.193401) (xy 43.868281 -317.246105) (xy 43.852571 -317.297035) (xy 43.829445 -317.345056)
			(xy 43.799421 -317.389093) (xy 43.763169 -317.428164) (xy 43.721498 -317.461395) (xy 43.67534 -317.488044)
			(xy 43.625726 -317.507516) (xy 43.573764 -317.519376) (xy 43.520614 -317.52336) (xy 43.467464 -317.519376)
			(xy 43.415502 -317.507516) (xy 43.365888 -317.488044) (xy 43.31973 -317.461395) (xy 43.278059 -317.428164)
			(xy 43.241807 -317.389093) (xy 43.211783 -317.345056) (xy 43.188657 -317.297035) (xy 43.172947 -317.246105)
			(xy 43.165004 -317.193401) (xy 36.332424 -317.193401) (xy 36.324481 -317.246105) (xy 36.308771 -317.297035)
			(xy 36.285645 -317.345056) (xy 36.255621 -317.389093) (xy 36.219369 -317.428164) (xy 36.177698 -317.461395)
			(xy 36.13154 -317.488044) (xy 36.081926 -317.507516) (xy 36.029964 -317.519376) (xy 35.976814 -317.52336)
			(xy 35.923664 -317.519376) (xy 35.871702 -317.507516) (xy 35.822088 -317.488044) (xy 35.77593 -317.461395)
			(xy 35.734259 -317.428164) (xy 35.698007 -317.389093) (xy 35.667983 -317.345056) (xy 35.644857 -317.297035)
			(xy 35.629147 -317.246105) (xy 35.621204 -317.193401) (xy 28.788624 -317.193401) (xy 28.780681 -317.246105)
			(xy 28.764971 -317.297035) (xy 28.741845 -317.345056) (xy 28.711821 -317.389093) (xy 28.675569 -317.428164)
			(xy 28.633898 -317.461395) (xy 28.58774 -317.488044) (xy 28.538126 -317.507516) (xy 28.486164 -317.519376)
			(xy 28.433014 -317.52336) (xy 28.379864 -317.519376) (xy 28.327902 -317.507516) (xy 28.278288 -317.488044)
			(xy 28.23213 -317.461395) (xy 28.190459 -317.428164) (xy 28.154207 -317.389093) (xy 28.124183 -317.345056)
			(xy 28.101057 -317.297035) (xy 28.085347 -317.246105) (xy 28.077404 -317.193401) (xy 21.244824 -317.193401)
			(xy 21.236881 -317.246105) (xy 21.221171 -317.297035) (xy 21.198045 -317.345056) (xy 21.168021 -317.389093)
			(xy 21.131769 -317.428164) (xy 21.090098 -317.461395) (xy 21.04394 -317.488044) (xy 20.994326 -317.507516)
			(xy 20.942364 -317.519376) (xy 20.889214 -317.52336) (xy 20.836064 -317.519376) (xy 20.784102 -317.507516)
			(xy 20.734488 -317.488044) (xy 20.68833 -317.461395) (xy 20.646659 -317.428164) (xy 20.610407 -317.389093)
			(xy 20.580383 -317.345056) (xy 20.557257 -317.297035) (xy 20.541547 -317.246105) (xy 20.533604 -317.193401)
			(xy 11.516636 -317.193401) (xy 11.516613 -317.194638) (xy 11.508493 -317.249814) (xy 11.492425 -317.303221)
			(xy 11.468753 -317.353718) (xy 11.43798 -317.400231) (xy 11.400763 -317.441768) (xy 11.357895 -317.477443)
			(xy 11.310289 -317.506497) (xy 11.25896 -317.528309) (xy 11.205003 -317.542415) (xy 11.149566 -317.548515)
			(xy 11.093832 -317.546478) (xy 11.038989 -317.536348) (xy 10.986205 -317.518341) (xy 10.936605 -317.49284)
			(xy 10.891247 -317.460389) (xy 10.851098 -317.42168) (xy 10.817012 -317.377537) (xy 10.789716 -317.328902)
			(xy 10.769793 -317.276811) (xy 10.757667 -317.222374) (xy 10.753596 -317.166752) (xy 6.7818 -317.166752)
			(xy 6.7818 -318.043285) (xy 10.780004 -318.043285) (xy 10.780004 -317.989987) (xy 10.787947 -317.937283)
			(xy 10.803657 -317.886353) (xy 10.826783 -317.838332) (xy 10.856807 -317.794295) (xy 10.893059 -317.755224)
			(xy 10.93473 -317.721993) (xy 10.980888 -317.695344) (xy 11.030502 -317.675872) (xy 11.082464 -317.664012)
			(xy 11.135614 -317.660029) (xy 11.188764 -317.664012) (xy 11.240726 -317.675872) (xy 11.29034 -317.695344)
			(xy 11.336498 -317.721993) (xy 11.378169 -317.755224) (xy 11.414421 -317.794295) (xy 11.444445 -317.838332)
			(xy 11.467571 -317.886353) (xy 11.483281 -317.937283) (xy 11.491224 -317.989987) (xy 11.491722 -318.016636)
			(xy 11.491224 -318.043285) (xy 18.323804 -318.043285) (xy 18.323804 -317.989987) (xy 18.331747 -317.937283)
			(xy 18.347457 -317.886353) (xy 18.370583 -317.838332) (xy 18.400607 -317.794295) (xy 18.436859 -317.755224)
			(xy 18.47853 -317.721993) (xy 18.524688 -317.695344) (xy 18.574302 -317.675872) (xy 18.626264 -317.664012)
			(xy 18.679414 -317.660029) (xy 18.732564 -317.664012) (xy 18.784526 -317.675872) (xy 18.83414 -317.695344)
			(xy 18.880298 -317.721993) (xy 18.921969 -317.755224) (xy 18.958221 -317.794295) (xy 18.988245 -317.838332)
			(xy 19.011371 -317.886353) (xy 19.027081 -317.937283) (xy 19.035024 -317.989987) (xy 19.035522 -318.016636)
			(xy 19.035024 -318.043285) (xy 25.867604 -318.043285) (xy 25.867604 -317.989987) (xy 25.875547 -317.937283)
			(xy 25.891257 -317.886353) (xy 25.914383 -317.838332) (xy 25.944407 -317.794295) (xy 25.980659 -317.755224)
			(xy 26.02233 -317.721993) (xy 26.068488 -317.695344) (xy 26.118102 -317.675872) (xy 26.170064 -317.664012)
			(xy 26.223214 -317.660029) (xy 26.276364 -317.664012) (xy 26.328326 -317.675872) (xy 26.37794 -317.695344)
			(xy 26.424098 -317.721993) (xy 26.465769 -317.755224) (xy 26.502021 -317.794295) (xy 26.532045 -317.838332)
			(xy 26.555171 -317.886353) (xy 26.570881 -317.937283) (xy 26.578824 -317.989987) (xy 26.579322 -318.016636)
			(xy 26.578824 -318.043285) (xy 33.411404 -318.043285) (xy 33.411404 -317.989987) (xy 33.419347 -317.937283)
			(xy 33.435057 -317.886353) (xy 33.458183 -317.838332) (xy 33.488207 -317.794295) (xy 33.524459 -317.755224)
			(xy 33.56613 -317.721993) (xy 33.612288 -317.695344) (xy 33.661902 -317.675872) (xy 33.713864 -317.664012)
			(xy 33.767014 -317.660029) (xy 33.820164 -317.664012) (xy 33.872126 -317.675872) (xy 33.92174 -317.695344)
			(xy 33.967898 -317.721993) (xy 34.009569 -317.755224) (xy 34.045821 -317.794295) (xy 34.075845 -317.838332)
			(xy 34.098971 -317.886353) (xy 34.114681 -317.937283) (xy 34.119476 -317.9691) (xy 40.316406 -317.9691)
			(xy 40.320389 -317.915951) (xy 40.33225 -317.863988) (xy 40.351722 -317.814375) (xy 40.378373 -317.768217)
			(xy 40.411605 -317.726547) (xy 40.450676 -317.690296) (xy 40.494715 -317.660274) (xy 40.542736 -317.63715)
			(xy 40.593667 -317.621443) (xy 40.646371 -317.613502) (xy 40.67302 -317.61303) (xy 40.69818 -317.61349)
			(xy 40.748001 -317.620564) (xy 40.796329 -317.634582) (xy 40.842202 -317.655265) (xy 40.884706 -317.682202)
			(xy 40.922994 -317.714854) (xy 40.939974 -317.733426) (xy 40.948975 -317.743014) (xy 40.970766 -317.757712)
			(xy 40.995595 -317.766339) (xy 41.021805 -317.768318) (xy 41.047648 -317.763518) (xy 41.0714 -317.75226)
			(xy 41.081706 -317.744094) (xy 41.101022 -317.72837) (xy 41.143233 -317.701932) (xy 41.188719 -317.681639)
			(xy 41.23659 -317.667887) (xy 41.28591 -317.660944) (xy 41.310814 -317.660528) (xy 41.337465 -317.660955)
			(xy 41.390172 -317.668901) (xy 41.441106 -317.684614) (xy 41.48913 -317.707742) (xy 41.53317 -317.73777)
			(xy 41.572243 -317.774026) (xy 41.605476 -317.8157) (xy 41.632126 -317.861862) (xy 41.6516 -317.91148)
			(xy 41.66346 -317.963446) (xy 41.667444 -318.0166) (xy 41.665444 -318.043285) (xy 48.499004 -318.043285)
			(xy 48.499004 -317.989987) (xy 48.506947 -317.937283) (xy 48.522657 -317.886353) (xy 48.545783 -317.838332)
			(xy 48.575807 -317.794295) (xy 48.612059 -317.755224) (xy 48.65373 -317.721993) (xy 48.699888 -317.695344)
			(xy 48.749502 -317.675872) (xy 48.801464 -317.664012) (xy 48.854614 -317.660029) (xy 48.907764 -317.664012)
			(xy 48.959726 -317.675872) (xy 49.00934 -317.695344) (xy 49.055498 -317.721993) (xy 49.097169 -317.755224)
			(xy 49.133421 -317.794295) (xy 49.163445 -317.838332) (xy 49.186571 -317.886353) (xy 49.202281 -317.937283)
			(xy 49.210224 -317.989987) (xy 49.210722 -318.016636) (xy 49.210224 -318.043285) (xy 56.042804 -318.043285)
			(xy 56.042804 -317.989987) (xy 56.050747 -317.937283) (xy 56.066457 -317.886353) (xy 56.089583 -317.838332)
			(xy 56.119607 -317.794295) (xy 56.155859 -317.755224) (xy 56.19753 -317.721993) (xy 56.243688 -317.695344)
			(xy 56.293302 -317.675872) (xy 56.345264 -317.664012) (xy 56.398414 -317.660029) (xy 56.451564 -317.664012)
			(xy 56.503526 -317.675872) (xy 56.55314 -317.695344) (xy 56.599298 -317.721993) (xy 56.640969 -317.755224)
			(xy 56.677221 -317.794295) (xy 56.707245 -317.838332) (xy 56.730371 -317.886353) (xy 56.746081 -317.937283)
			(xy 56.754024 -317.989987) (xy 56.754522 -318.016636) (xy 56.754024 -318.043285) (xy 56.746081 -318.095989)
			(xy 56.730371 -318.146919) (xy 56.707245 -318.19494) (xy 56.677221 -318.238977) (xy 56.640969 -318.278048)
			(xy 56.599298 -318.311279) (xy 56.55314 -318.337928) (xy 56.503526 -318.3574) (xy 56.451564 -318.36926)
			(xy 56.398414 -318.373244) (xy 56.345264 -318.36926) (xy 56.293302 -318.3574) (xy 56.243688 -318.337928)
			(xy 56.19753 -318.311279) (xy 56.155859 -318.278048) (xy 56.119607 -318.238977) (xy 56.089583 -318.19494)
			(xy 56.066457 -318.146919) (xy 56.050747 -318.095989) (xy 56.042804 -318.043285) (xy 49.210224 -318.043285)
			(xy 49.202281 -318.095989) (xy 49.186571 -318.146919) (xy 49.163445 -318.19494) (xy 49.133421 -318.238977)
			(xy 49.097169 -318.278048) (xy 49.055498 -318.311279) (xy 49.00934 -318.337928) (xy 48.959726 -318.3574)
			(xy 48.907764 -318.36926) (xy 48.854614 -318.373244) (xy 48.801464 -318.36926) (xy 48.749502 -318.3574)
			(xy 48.699888 -318.337928) (xy 48.65373 -318.311279) (xy 48.612059 -318.278048) (xy 48.575807 -318.238977)
			(xy 48.545783 -318.19494) (xy 48.522657 -318.146919) (xy 48.506947 -318.095989) (xy 48.499004 -318.043285)
			(xy 41.665444 -318.043285) (xy 41.66346 -318.069754) (xy 41.6516 -318.12172) (xy 41.632126 -318.171338)
			(xy 41.605476 -318.2175) (xy 41.572243 -318.259174) (xy 41.53317 -318.29543) (xy 41.48913 -318.325458)
			(xy 41.441106 -318.348586) (xy 41.390172 -318.364299) (xy 41.337465 -318.372245) (xy 41.310814 -318.372744)
			(xy 41.285652 -318.372338) (xy 41.235828 -318.365255) (xy 41.187498 -318.351226) (xy 41.141625 -318.330533)
			(xy 41.099123 -318.303587) (xy 41.060838 -318.270924) (xy 41.04386 -318.252348) (xy 41.034921 -318.242699)
			(xy 41.013112 -318.228007) (xy 40.988268 -318.219389) (xy 40.962045 -318.217422) (xy 40.936193 -318.222234)
			(xy 40.912435 -318.233507) (xy 40.902128 -318.24168) (xy 40.882797 -318.257385) (xy 40.84059 -318.283826)
			(xy 40.795108 -318.304123) (xy 40.747241 -318.31788) (xy 40.697923 -318.324828) (xy 40.67302 -318.325246)
			(xy 40.646371 -318.324698) (xy 40.593667 -318.316757) (xy 40.542736 -318.30105) (xy 40.494715 -318.277926)
			(xy 40.450676 -318.247904) (xy 40.411605 -318.211653) (xy 40.378373 -318.169983) (xy 40.351722 -318.123825)
			(xy 40.33225 -318.074212) (xy 40.320389 -318.022249) (xy 40.316406 -317.9691) (xy 34.119476 -317.9691)
			(xy 34.122624 -317.989987) (xy 34.123122 -318.016636) (xy 34.122624 -318.043285) (xy 34.114681 -318.095989)
			(xy 34.098971 -318.146919) (xy 34.075845 -318.19494) (xy 34.045821 -318.238977) (xy 34.009569 -318.278048)
			(xy 33.967898 -318.311279) (xy 33.92174 -318.337928) (xy 33.872126 -318.3574) (xy 33.820164 -318.36926)
			(xy 33.767014 -318.373244) (xy 33.713864 -318.36926) (xy 33.661902 -318.3574) (xy 33.612288 -318.337928)
			(xy 33.56613 -318.311279) (xy 33.524459 -318.278048) (xy 33.488207 -318.238977) (xy 33.458183 -318.19494)
			(xy 33.435057 -318.146919) (xy 33.419347 -318.095989) (xy 33.411404 -318.043285) (xy 26.578824 -318.043285)
			(xy 26.570881 -318.095989) (xy 26.555171 -318.146919) (xy 26.532045 -318.19494) (xy 26.502021 -318.238977)
			(xy 26.465769 -318.278048) (xy 26.424098 -318.311279) (xy 26.37794 -318.337928) (xy 26.328326 -318.3574)
			(xy 26.276364 -318.36926) (xy 26.223214 -318.373244) (xy 26.170064 -318.36926) (xy 26.118102 -318.3574)
			(xy 26.068488 -318.337928) (xy 26.02233 -318.311279) (xy 25.980659 -318.278048) (xy 25.944407 -318.238977)
			(xy 25.914383 -318.19494) (xy 25.891257 -318.146919) (xy 25.875547 -318.095989) (xy 25.867604 -318.043285)
			(xy 19.035024 -318.043285) (xy 19.027081 -318.095989) (xy 19.011371 -318.146919) (xy 18.988245 -318.19494)
			(xy 18.958221 -318.238977) (xy 18.921969 -318.278048) (xy 18.880298 -318.311279) (xy 18.83414 -318.337928)
			(xy 18.784526 -318.3574) (xy 18.732564 -318.36926) (xy 18.679414 -318.373244) (xy 18.626264 -318.36926)
			(xy 18.574302 -318.3574) (xy 18.524688 -318.337928) (xy 18.47853 -318.311279) (xy 18.436859 -318.278048)
			(xy 18.400607 -318.238977) (xy 18.370583 -318.19494) (xy 18.347457 -318.146919) (xy 18.331747 -318.095989)
			(xy 18.323804 -318.043285) (xy 11.491224 -318.043285) (xy 11.483281 -318.095989) (xy 11.467571 -318.146919)
			(xy 11.444445 -318.19494) (xy 11.414421 -318.238977) (xy 11.378169 -318.278048) (xy 11.336498 -318.311279)
			(xy 11.29034 -318.337928) (xy 11.240726 -318.3574) (xy 11.188764 -318.36926) (xy 11.135614 -318.373244)
			(xy 11.082464 -318.36926) (xy 11.030502 -318.3574) (xy 10.980888 -318.337928) (xy 10.93473 -318.311279)
			(xy 10.893059 -318.278048) (xy 10.856807 -318.238977) (xy 10.826783 -318.19494) (xy 10.803657 -318.146919)
			(xy 10.787947 -318.095989) (xy 10.780004 -318.043285) (xy 6.7818 -318.043285) (xy 6.7818 -318.435228)
			(xy 6.782263 -318.449111) (xy 6.789733 -318.475852) (xy 6.804139 -318.499588) (xy 6.812699 -318.507597)
			(xy 13.06067 -318.507597) (xy 13.06067 -318.454299) (xy 13.068613 -318.401595) (xy 13.084323 -318.350665)
			(xy 13.107449 -318.302644) (xy 13.137473 -318.258607) (xy 13.173725 -318.219536) (xy 13.215396 -318.186305)
			(xy 13.261554 -318.159656) (xy 13.311168 -318.140184) (xy 13.36313 -318.128324) (xy 13.41628 -318.124341)
			(xy 13.46943 -318.128324) (xy 13.521392 -318.140184) (xy 13.571006 -318.159656) (xy 13.617164 -318.186305)
			(xy 13.658835 -318.219536) (xy 13.695087 -318.258607) (xy 13.725111 -318.302644) (xy 13.748237 -318.350665)
			(xy 13.763947 -318.401595) (xy 13.77189 -318.454299) (xy 13.772388 -318.480948) (xy 13.77189 -318.507597)
			(xy 13.763947 -318.560301) (xy 13.748237 -318.611231) (xy 13.725111 -318.659252) (xy 13.695087 -318.703289)
			(xy 13.658835 -318.74236) (xy 13.617164 -318.775591) (xy 13.571006 -318.80224) (xy 13.521392 -318.821712)
			(xy 13.46943 -318.833572) (xy 13.41628 -318.837556) (xy 13.36313 -318.833572) (xy 13.311168 -318.821712)
			(xy 13.261554 -318.80224) (xy 13.215396 -318.775591) (xy 13.173725 -318.74236) (xy 13.137473 -318.703289)
			(xy 13.107449 -318.659252) (xy 13.084323 -318.611231) (xy 13.068613 -318.560301) (xy 13.06067 -318.507597)
			(xy 6.812699 -318.507597) (xy 6.824414 -318.518557) (xy 6.849054 -318.531355) (xy 6.876233 -318.537032)
			(xy 6.903935 -318.535167) (xy 6.917182 -318.530986) (xy 6.945856 -318.521528) (xy 7.005359 -318.511308)
			(xy 7.035546 -318.510666) (xy 7.063325 -318.511202) (xy 7.118207 -318.519837) (xy 7.171083 -318.536889)
			(xy 7.220669 -318.561945) (xy 7.265763 -318.594398) (xy 7.30527 -318.633459) (xy 7.338233 -318.678182)
			(xy 7.36385 -318.72748) (xy 7.381502 -318.780159) (xy 7.390759 -318.83494) (xy 7.391654 -318.86271)
			(xy 7.392245 -318.875912) (xy 7.399359 -318.901353) (xy 7.412767 -318.924114) (xy 7.431572 -318.942668)
			(xy 7.454511 -318.95577) (xy 7.480045 -318.962541) (xy 7.493254 -318.96304) (xy 10.677906 -318.96304)
			(xy 10.691121 -318.962619) (xy 10.716664 -318.955832) (xy 10.739608 -318.942715) (xy 10.758416 -318.924147)
			(xy 10.771827 -318.901372) (xy 10.778941 -318.875918) (xy 10.779506 -318.86271) (xy 10.780291 -318.836259)
			(xy 10.788718 -318.784019) (xy 10.804781 -318.733601) (xy 10.828128 -318.686114) (xy 10.858245 -318.642605)
			(xy 10.894468 -318.604031) (xy 10.936 -318.571241) (xy 10.981926 -318.544958) (xy 11.031236 -318.52576)
			(xy 11.082844 -318.514069) (xy 11.135614 -318.510143) (xy 11.188384 -318.514069) (xy 11.239992 -318.52576)
			(xy 11.289302 -318.544958) (xy 11.335228 -318.571241) (xy 11.37676 -318.604031) (xy 11.412983 -318.642605)
			(xy 11.4431 -318.686114) (xy 11.466447 -318.733601) (xy 11.48251 -318.784019) (xy 11.490937 -318.836259)
			(xy 11.491722 -318.86271) (xy 11.492313 -318.875914) (xy 11.497207 -318.893423) (xy 18.323804 -318.893423)
			(xy 18.323804 -318.840125) (xy 18.331747 -318.787421) (xy 18.347457 -318.736491) (xy 18.370583 -318.68847)
			(xy 18.400607 -318.644433) (xy 18.436859 -318.605362) (xy 18.47853 -318.572131) (xy 18.524688 -318.545482)
			(xy 18.574302 -318.52601) (xy 18.626264 -318.51415) (xy 18.679414 -318.510167) (xy 18.732564 -318.51415)
			(xy 18.784526 -318.52601) (xy 18.83414 -318.545482) (xy 18.880298 -318.572131) (xy 18.921969 -318.605362)
			(xy 18.925763 -318.609451) (xy 21.065226 -318.609451) (xy 21.065226 -318.556153) (xy 21.073169 -318.503449)
			(xy 21.088879 -318.452519) (xy 21.112005 -318.404498) (xy 21.142029 -318.360461) (xy 21.178281 -318.32139)
			(xy 21.219952 -318.288159) (xy 21.26611 -318.26151) (xy 21.315724 -318.242038) (xy 21.367686 -318.230178)
			(xy 21.420836 -318.226195) (xy 21.473986 -318.230178) (xy 21.525948 -318.242038) (xy 21.575562 -318.26151)
			(xy 21.62172 -318.288159) (xy 21.663391 -318.32139) (xy 21.699643 -318.360461) (xy 21.729667 -318.404498)
			(xy 21.752793 -318.452519) (xy 21.768503 -318.503449) (xy 21.776446 -318.556153) (xy 21.776944 -318.582802)
			(xy 21.776446 -318.609451) (xy 21.768503 -318.662155) (xy 21.752793 -318.713085) (xy 21.729667 -318.761106)
			(xy 21.699643 -318.805143) (xy 21.663391 -318.844214) (xy 21.62172 -318.877445) (xy 21.594045 -318.893423)
			(xy 25.867604 -318.893423) (xy 25.867604 -318.840125) (xy 25.875547 -318.787421) (xy 25.891257 -318.736491)
			(xy 25.914383 -318.68847) (xy 25.944407 -318.644433) (xy 25.980659 -318.605362) (xy 26.02233 -318.572131)
			(xy 26.068488 -318.545482) (xy 26.118102 -318.52601) (xy 26.170064 -318.51415) (xy 26.223214 -318.510167)
			(xy 26.276364 -318.51415) (xy 26.328326 -318.52601) (xy 26.37794 -318.545482) (xy 26.424098 -318.572131)
			(xy 26.465769 -318.605362) (xy 26.502021 -318.644433) (xy 26.532045 -318.68847) (xy 26.535703 -318.696065)
			(xy 28.648904 -318.696065) (xy 28.648904 -318.642767) (xy 28.656847 -318.590063) (xy 28.672557 -318.539133)
			(xy 28.695683 -318.491112) (xy 28.725707 -318.447075) (xy 28.761959 -318.408004) (xy 28.80363 -318.374773)
			(xy 28.849788 -318.348124) (xy 28.899402 -318.328652) (xy 28.951364 -318.316792) (xy 29.004514 -318.312809)
			(xy 29.057664 -318.316792) (xy 29.109626 -318.328652) (xy 29.15924 -318.348124) (xy 29.205398 -318.374773)
			(xy 29.247069 -318.408004) (xy 29.283321 -318.447075) (xy 29.313345 -318.491112) (xy 29.336471 -318.539133)
			(xy 29.352181 -318.590063) (xy 29.360124 -318.642767) (xy 29.360622 -318.669416) (xy 29.360124 -318.696065)
			(xy 29.352181 -318.748769) (xy 29.336471 -318.799699) (xy 29.313345 -318.84772) (xy 29.283321 -318.891757)
			(xy 29.281775 -318.893423) (xy 33.411404 -318.893423) (xy 33.411404 -318.840125) (xy 33.419347 -318.787421)
			(xy 33.435057 -318.736491) (xy 33.458183 -318.68847) (xy 33.488207 -318.644433) (xy 33.524459 -318.605362)
			(xy 33.56613 -318.572131) (xy 33.612288 -318.545482) (xy 33.661902 -318.52601) (xy 33.713864 -318.51415)
			(xy 33.767014 -318.510167) (xy 33.820164 -318.51415) (xy 33.872126 -318.52601) (xy 33.92174 -318.545482)
			(xy 33.967898 -318.572131) (xy 34.009569 -318.605362) (xy 34.045821 -318.644433) (xy 34.075845 -318.68847)
			(xy 34.098971 -318.736491) (xy 34.114681 -318.787421) (xy 34.122624 -318.840125) (xy 34.123122 -318.866774)
			(xy 34.122624 -318.893423) (xy 34.115504 -318.940667) (xy 36.13784 -318.940667) (xy 36.13784 -318.887369)
			(xy 36.145783 -318.834665) (xy 36.161493 -318.783735) (xy 36.184619 -318.735714) (xy 36.214643 -318.691677)
			(xy 36.250895 -318.652606) (xy 36.292566 -318.619375) (xy 36.338724 -318.592726) (xy 36.388338 -318.573254)
			(xy 36.4403 -318.561394) (xy 36.49345 -318.557411) (xy 36.5466 -318.561394) (xy 36.598562 -318.573254)
			(xy 36.648176 -318.592726) (xy 36.694334 -318.619375) (xy 36.736005 -318.652606) (xy 36.772257 -318.691677)
			(xy 36.802281 -318.735714) (xy 36.825407 -318.783735) (xy 36.841117 -318.834665) (xy 36.84906 -318.887369)
			(xy 36.849173 -318.893423) (xy 40.955204 -318.893423) (xy 40.955204 -318.840125) (xy 40.963147 -318.787421)
			(xy 40.978857 -318.736491) (xy 41.001983 -318.68847) (xy 41.032007 -318.644433) (xy 41.068259 -318.605362)
			(xy 41.10993 -318.572131) (xy 41.156088 -318.545482) (xy 41.205702 -318.52601) (xy 41.257664 -318.51415)
			(xy 41.310814 -318.510167) (xy 41.363964 -318.51415) (xy 41.415926 -318.52601) (xy 41.46554 -318.545482)
			(xy 41.511698 -318.572131) (xy 41.553369 -318.605362) (xy 41.589621 -318.644433) (xy 41.619645 -318.68847)
			(xy 41.642771 -318.736491) (xy 41.658481 -318.787421) (xy 41.666424 -318.840125) (xy 41.666922 -318.866774)
			(xy 41.666424 -318.893423) (xy 41.658481 -318.946127) (xy 41.642771 -318.997057) (xy 41.636901 -319.009247)
			(xy 43.318928 -319.009247) (xy 43.318928 -318.955949) (xy 43.326871 -318.903245) (xy 43.342581 -318.852315)
			(xy 43.365707 -318.804294) (xy 43.395731 -318.760257) (xy 43.431983 -318.721186) (xy 43.473654 -318.687955)
			(xy 43.519812 -318.661306) (xy 43.569426 -318.641834) (xy 43.621388 -318.629974) (xy 43.674538 -318.625991)
			(xy 43.727688 -318.629974) (xy 43.77965 -318.641834) (xy 43.829264 -318.661306) (xy 43.875422 -318.687955)
			(xy 43.917093 -318.721186) (xy 43.953345 -318.760257) (xy 43.983369 -318.804294) (xy 44.006495 -318.852315)
			(xy 44.019175 -318.893423) (xy 48.499004 -318.893423) (xy 48.499004 -318.840125) (xy 48.506947 -318.787421)
			(xy 48.522657 -318.736491) (xy 48.545783 -318.68847) (xy 48.575807 -318.644433) (xy 48.612059 -318.605362)
			(xy 48.65373 -318.572131) (xy 48.699888 -318.545482) (xy 48.749502 -318.52601) (xy 48.801464 -318.51415)
			(xy 48.854614 -318.510167) (xy 48.907764 -318.51415) (xy 48.959726 -318.52601) (xy 49.00934 -318.545482)
			(xy 49.055498 -318.572131) (xy 49.097169 -318.605362) (xy 49.133421 -318.644433) (xy 49.163445 -318.68847)
			(xy 49.186571 -318.736491) (xy 49.202281 -318.787421) (xy 49.210224 -318.840125) (xy 49.210722 -318.866774)
			(xy 49.210224 -318.893423) (xy 56.042804 -318.893423) (xy 56.042804 -318.840125) (xy 56.050747 -318.787421)
			(xy 56.066457 -318.736491) (xy 56.089583 -318.68847) (xy 56.119607 -318.644433) (xy 56.155859 -318.605362)
			(xy 56.19753 -318.572131) (xy 56.243688 -318.545482) (xy 56.293302 -318.52601) (xy 56.345264 -318.51415)
			(xy 56.398414 -318.510167) (xy 56.451564 -318.51415) (xy 56.503526 -318.52601) (xy 56.55314 -318.545482)
			(xy 56.599298 -318.572131) (xy 56.640969 -318.605362) (xy 56.677221 -318.644433) (xy 56.707245 -318.68847)
			(xy 56.730371 -318.736491) (xy 56.746081 -318.787421) (xy 56.754024 -318.840125) (xy 56.754522 -318.866774)
			(xy 56.754024 -318.893423) (xy 56.746081 -318.946127) (xy 56.730371 -318.997057) (xy 56.707245 -319.045078)
			(xy 56.677221 -319.089115) (xy 56.640969 -319.128186) (xy 56.599298 -319.161417) (xy 56.55314 -319.188066)
			(xy 56.503526 -319.207538) (xy 56.451564 -319.219398) (xy 56.398414 -319.223382) (xy 56.345264 -319.219398)
			(xy 56.293302 -319.207538) (xy 56.243688 -319.188066) (xy 56.19753 -319.161417) (xy 56.155859 -319.128186)
			(xy 56.119607 -319.089115) (xy 56.089583 -319.045078) (xy 56.066457 -318.997057) (xy 56.050747 -318.946127)
			(xy 56.042804 -318.893423) (xy 49.210224 -318.893423) (xy 49.202281 -318.946127) (xy 49.186571 -318.997057)
			(xy 49.163445 -319.045078) (xy 49.133421 -319.089115) (xy 49.097169 -319.128186) (xy 49.055498 -319.161417)
			(xy 49.00934 -319.188066) (xy 48.959726 -319.207538) (xy 48.907764 -319.219398) (xy 48.854614 -319.223382)
			(xy 48.801464 -319.219398) (xy 48.749502 -319.207538) (xy 48.699888 -319.188066) (xy 48.65373 -319.161417)
			(xy 48.612059 -319.128186) (xy 48.575807 -319.089115) (xy 48.545783 -319.045078) (xy 48.522657 -318.997057)
			(xy 48.506947 -318.946127) (xy 48.499004 -318.893423) (xy 44.019175 -318.893423) (xy 44.022205 -318.903245)
			(xy 44.030148 -318.955949) (xy 44.030646 -318.982598) (xy 44.030148 -319.009247) (xy 44.022205 -319.061951)
			(xy 44.006495 -319.112881) (xy 43.983369 -319.160902) (xy 43.953345 -319.204939) (xy 43.917093 -319.24401)
			(xy 43.875422 -319.277241) (xy 43.829264 -319.30389) (xy 43.77965 -319.323362) (xy 43.727688 -319.335222)
			(xy 43.674538 -319.339206) (xy 43.621388 -319.335222) (xy 43.569426 -319.323362) (xy 43.519812 -319.30389)
			(xy 43.473654 -319.277241) (xy 43.431983 -319.24401) (xy 43.395731 -319.204939) (xy 43.365707 -319.160902)
			(xy 43.342581 -319.112881) (xy 43.326871 -319.061951) (xy 43.318928 -319.009247) (xy 41.636901 -319.009247)
			(xy 41.619645 -319.045078) (xy 41.589621 -319.089115) (xy 41.553369 -319.128186) (xy 41.511698 -319.161417)
			(xy 41.46554 -319.188066) (xy 41.415926 -319.207538) (xy 41.363964 -319.219398) (xy 41.310814 -319.223382)
			(xy 41.257664 -319.219398) (xy 41.205702 -319.207538) (xy 41.156088 -319.188066) (xy 41.10993 -319.161417)
			(xy 41.068259 -319.128186) (xy 41.032007 -319.089115) (xy 41.001983 -319.045078) (xy 40.978857 -318.997057)
			(xy 40.963147 -318.946127) (xy 40.955204 -318.893423) (xy 36.849173 -318.893423) (xy 36.849558 -318.914018)
			(xy 36.84906 -318.940667) (xy 36.841117 -318.993371) (xy 36.825407 -319.044301) (xy 36.802281 -319.092322)
			(xy 36.772257 -319.136359) (xy 36.736005 -319.17543) (xy 36.694334 -319.208661) (xy 36.648176 -319.23531)
			(xy 36.598562 -319.254782) (xy 36.5466 -319.266642) (xy 36.49345 -319.270626) (xy 36.4403 -319.266642)
			(xy 36.388338 -319.254782) (xy 36.338724 -319.23531) (xy 36.292566 -319.208661) (xy 36.250895 -319.17543)
			(xy 36.214643 -319.136359) (xy 36.184619 -319.092322) (xy 36.161493 -319.044301) (xy 36.145783 -318.993371)
			(xy 36.13784 -318.940667) (xy 34.115504 -318.940667) (xy 34.114681 -318.946127) (xy 34.098971 -318.997057)
			(xy 34.075845 -319.045078) (xy 34.045821 -319.089115) (xy 34.009569 -319.128186) (xy 33.967898 -319.161417)
			(xy 33.92174 -319.188066) (xy 33.872126 -319.207538) (xy 33.820164 -319.219398) (xy 33.767014 -319.223382)
			(xy 33.713864 -319.219398) (xy 33.661902 -319.207538) (xy 33.612288 -319.188066) (xy 33.56613 -319.161417)
			(xy 33.524459 -319.128186) (xy 33.488207 -319.089115) (xy 33.458183 -319.045078) (xy 33.435057 -318.997057)
			(xy 33.419347 -318.946127) (xy 33.411404 -318.893423) (xy 29.281775 -318.893423) (xy 29.247069 -318.930828)
			(xy 29.205398 -318.964059) (xy 29.15924 -318.990708) (xy 29.109626 -319.01018) (xy 29.057664 -319.02204)
			(xy 29.004514 -319.026024) (xy 28.951364 -319.02204) (xy 28.899402 -319.01018) (xy 28.849788 -318.990708)
			(xy 28.80363 -318.964059) (xy 28.761959 -318.930828) (xy 28.725707 -318.891757) (xy 28.695683 -318.84772)
			(xy 28.672557 -318.799699) (xy 28.656847 -318.748769) (xy 28.648904 -318.696065) (xy 26.535703 -318.696065)
			(xy 26.555171 -318.736491) (xy 26.570881 -318.787421) (xy 26.578824 -318.840125) (xy 26.579322 -318.866774)
			(xy 26.578824 -318.893423) (xy 26.570881 -318.946127) (xy 26.555171 -318.997057) (xy 26.532045 -319.045078)
			(xy 26.502021 -319.089115) (xy 26.465769 -319.128186) (xy 26.424098 -319.161417) (xy 26.37794 -319.188066)
			(xy 26.328326 -319.207538) (xy 26.276364 -319.219398) (xy 26.223214 -319.223382) (xy 26.170064 -319.219398)
			(xy 26.118102 -319.207538) (xy 26.068488 -319.188066) (xy 26.02233 -319.161417) (xy 25.980659 -319.128186)
			(xy 25.944407 -319.089115) (xy 25.914383 -319.045078) (xy 25.891257 -318.997057) (xy 25.875547 -318.946127)
			(xy 25.867604 -318.893423) (xy 21.594045 -318.893423) (xy 21.575562 -318.904094) (xy 21.525948 -318.923566)
			(xy 21.473986 -318.935426) (xy 21.420836 -318.93941) (xy 21.367686 -318.935426) (xy 21.315724 -318.923566)
			(xy 21.26611 -318.904094) (xy 21.219952 -318.877445) (xy 21.178281 -318.844214) (xy 21.142029 -318.805143)
			(xy 21.112005 -318.761106) (xy 21.088879 -318.713085) (xy 21.073169 -318.662155) (xy 21.065226 -318.609451)
			(xy 18.925763 -318.609451) (xy 18.958221 -318.644433) (xy 18.988245 -318.68847) (xy 19.011371 -318.736491)
			(xy 19.027081 -318.787421) (xy 19.035024 -318.840125) (xy 19.035522 -318.866774) (xy 19.035024 -318.893423)
			(xy 19.027081 -318.946127) (xy 19.011371 -318.997057) (xy 18.988245 -319.045078) (xy 18.958221 -319.089115)
			(xy 18.921969 -319.128186) (xy 18.880298 -319.161417) (xy 18.83414 -319.188066) (xy 18.784526 -319.207538)
			(xy 18.732564 -319.219398) (xy 18.679414 -319.223382) (xy 18.626264 -319.219398) (xy 18.574302 -319.207538)
			(xy 18.524688 -319.188066) (xy 18.47853 -319.161417) (xy 18.436859 -319.128186) (xy 18.400607 -319.089115)
			(xy 18.370583 -319.045078) (xy 18.347457 -318.997057) (xy 18.331747 -318.946127) (xy 18.323804 -318.893423)
			(xy 11.497207 -318.893423) (xy 11.499425 -318.901358) (xy 11.512833 -318.924123) (xy 11.531637 -318.942682)
			(xy 11.554576 -318.95579) (xy 11.580112 -318.962569) (xy 11.593322 -318.96304) (xy 15.19301 -318.96304)
			(xy 15.697708 -319.467738) (xy 15.697708 -319.743307) (xy 18.323804 -319.743307) (xy 18.323804 -319.690009)
			(xy 18.331747 -319.637305) (xy 18.347457 -319.586375) (xy 18.370583 -319.538354) (xy 18.400607 -319.494317)
			(xy 18.436859 -319.455246) (xy 18.47853 -319.422015) (xy 18.524688 -319.395366) (xy 18.574302 -319.375894)
			(xy 18.626264 -319.364034) (xy 18.679414 -319.360051) (xy 18.732564 -319.364034) (xy 18.784526 -319.375894)
			(xy 18.83414 -319.395366) (xy 18.880298 -319.422015) (xy 18.921969 -319.455246) (xy 18.958221 -319.494317)
			(xy 18.988245 -319.538354) (xy 19.011371 -319.586375) (xy 19.027081 -319.637305) (xy 19.035024 -319.690009)
			(xy 19.035522 -319.716658) (xy 19.035024 -319.743307) (xy 21.767536 -319.743307) (xy 21.767536 -319.690009)
			(xy 21.775479 -319.637305) (xy 21.791189 -319.586375) (xy 21.814315 -319.538354) (xy 21.844339 -319.494317)
			(xy 21.880591 -319.455246) (xy 21.922262 -319.422015) (xy 21.96842 -319.395366) (xy 22.018034 -319.375894)
			(xy 22.069996 -319.364034) (xy 22.123146 -319.360051) (xy 22.176296 -319.364034) (xy 22.228258 -319.375894)
			(xy 22.277872 -319.395366) (xy 22.32403 -319.422015) (xy 22.365701 -319.455246) (xy 22.401953 -319.494317)
			(xy 22.431977 -319.538354) (xy 22.455103 -319.586375) (xy 22.470813 -319.637305) (xy 22.478756 -319.690009)
			(xy 22.479254 -319.716658) (xy 22.478756 -319.743307) (xy 25.867604 -319.743307) (xy 25.867604 -319.690009)
			(xy 25.875547 -319.637305) (xy 25.891257 -319.586375) (xy 25.914383 -319.538354) (xy 25.944407 -319.494317)
			(xy 25.980659 -319.455246) (xy 26.02233 -319.422015) (xy 26.068488 -319.395366) (xy 26.118102 -319.375894)
			(xy 26.170064 -319.364034) (xy 26.223214 -319.360051) (xy 26.276364 -319.364034) (xy 26.328326 -319.375894)
			(xy 26.37794 -319.395366) (xy 26.424098 -319.422015) (xy 26.465769 -319.455246) (xy 26.502021 -319.494317)
			(xy 26.532045 -319.538354) (xy 26.555171 -319.586375) (xy 26.570881 -319.637305) (xy 26.578824 -319.690009)
			(xy 26.579322 -319.716658) (xy 26.578824 -319.743307) (xy 29.311336 -319.743307) (xy 29.311336 -319.690009)
			(xy 29.319279 -319.637305) (xy 29.334989 -319.586375) (xy 29.358115 -319.538354) (xy 29.388139 -319.494317)
			(xy 29.424391 -319.455246) (xy 29.466062 -319.422015) (xy 29.51222 -319.395366) (xy 29.561834 -319.375894)
			(xy 29.613796 -319.364034) (xy 29.666946 -319.360051) (xy 29.720096 -319.364034) (xy 29.772058 -319.375894)
			(xy 29.821672 -319.395366) (xy 29.86783 -319.422015) (xy 29.909501 -319.455246) (xy 29.945753 -319.494317)
			(xy 29.975777 -319.538354) (xy 29.998903 -319.586375) (xy 30.014613 -319.637305) (xy 30.022556 -319.690009)
			(xy 30.023054 -319.716658) (xy 30.022556 -319.743307) (xy 33.411404 -319.743307) (xy 33.411404 -319.690009)
			(xy 33.419347 -319.637305) (xy 33.435057 -319.586375) (xy 33.458183 -319.538354) (xy 33.488207 -319.494317)
			(xy 33.524459 -319.455246) (xy 33.56613 -319.422015) (xy 33.612288 -319.395366) (xy 33.661902 -319.375894)
			(xy 33.713864 -319.364034) (xy 33.767014 -319.360051) (xy 33.820164 -319.364034) (xy 33.872126 -319.375894)
			(xy 33.92174 -319.395366) (xy 33.967898 -319.422015) (xy 34.009569 -319.455246) (xy 34.045821 -319.494317)
			(xy 34.075845 -319.538354) (xy 34.098971 -319.586375) (xy 34.114681 -319.637305) (xy 34.122624 -319.690009)
			(xy 34.123122 -319.716658) (xy 34.122624 -319.743307) (xy 36.855136 -319.743307) (xy 36.855136 -319.690009)
			(xy 36.863079 -319.637305) (xy 36.878789 -319.586375) (xy 36.901915 -319.538354) (xy 36.931939 -319.494317)
			(xy 36.968191 -319.455246) (xy 37.009862 -319.422015) (xy 37.05602 -319.395366) (xy 37.105634 -319.375894)
			(xy 37.157596 -319.364034) (xy 37.210746 -319.360051) (xy 37.263896 -319.364034) (xy 37.315858 -319.375894)
			(xy 37.365472 -319.395366) (xy 37.41163 -319.422015) (xy 37.453301 -319.455246) (xy 37.489553 -319.494317)
			(xy 37.519577 -319.538354) (xy 37.542703 -319.586375) (xy 37.558413 -319.637305) (xy 37.566356 -319.690009)
			(xy 37.566854 -319.716658) (xy 37.566356 -319.743307) (xy 40.955204 -319.743307) (xy 40.955204 -319.690009)
			(xy 40.963147 -319.637305) (xy 40.978857 -319.586375) (xy 41.001983 -319.538354) (xy 41.032007 -319.494317)
			(xy 41.068259 -319.455246) (xy 41.10993 -319.422015) (xy 41.156088 -319.395366) (xy 41.205702 -319.375894)
			(xy 41.257664 -319.364034) (xy 41.310814 -319.360051) (xy 41.363964 -319.364034) (xy 41.415926 -319.375894)
			(xy 41.46554 -319.395366) (xy 41.511698 -319.422015) (xy 41.553369 -319.455246) (xy 41.589621 -319.494317)
			(xy 41.619645 -319.538354) (xy 41.642771 -319.586375) (xy 41.658481 -319.637305) (xy 41.666424 -319.690009)
			(xy 41.666922 -319.716658) (xy 41.666424 -319.743307) (xy 44.398936 -319.743307) (xy 44.398936 -319.690009)
			(xy 44.406879 -319.637305) (xy 44.422589 -319.586375) (xy 44.445715 -319.538354) (xy 44.475739 -319.494317)
			(xy 44.511991 -319.455246) (xy 44.553662 -319.422015) (xy 44.59982 -319.395366) (xy 44.649434 -319.375894)
			(xy 44.701396 -319.364034) (xy 44.754546 -319.360051) (xy 44.807696 -319.364034) (xy 44.859658 -319.375894)
			(xy 44.909272 -319.395366) (xy 44.95543 -319.422015) (xy 44.997101 -319.455246) (xy 45.033353 -319.494317)
			(xy 45.063377 -319.538354) (xy 45.086503 -319.586375) (xy 45.102213 -319.637305) (xy 45.110156 -319.690009)
			(xy 45.110654 -319.716658) (xy 45.110156 -319.743307) (xy 48.499004 -319.743307) (xy 48.499004 -319.690009)
			(xy 48.506947 -319.637305) (xy 48.522657 -319.586375) (xy 48.545783 -319.538354) (xy 48.575807 -319.494317)
			(xy 48.612059 -319.455246) (xy 48.65373 -319.422015) (xy 48.699888 -319.395366) (xy 48.749502 -319.375894)
			(xy 48.801464 -319.364034) (xy 48.854614 -319.360051) (xy 48.907764 -319.364034) (xy 48.959726 -319.375894)
			(xy 49.00934 -319.395366) (xy 49.055498 -319.422015) (xy 49.097169 -319.455246) (xy 49.133421 -319.494317)
			(xy 49.159964 -319.533249) (xy 50.747412 -319.533249) (xy 50.747412 -319.479951) (xy 50.755355 -319.427247)
			(xy 50.771065 -319.376317) (xy 50.794191 -319.328296) (xy 50.824215 -319.284259) (xy 50.860467 -319.245188)
			(xy 50.902138 -319.211957) (xy 50.948296 -319.185308) (xy 50.99791 -319.165836) (xy 51.049872 -319.153976)
			(xy 51.103022 -319.149993) (xy 51.156172 -319.153976) (xy 51.208134 -319.165836) (xy 51.257748 -319.185308)
			(xy 51.303906 -319.211957) (xy 51.345577 -319.245188) (xy 51.381829 -319.284259) (xy 51.411853 -319.328296)
			(xy 51.434979 -319.376317) (xy 51.450689 -319.427247) (xy 51.458632 -319.479951) (xy 51.45913 -319.5066)
			(xy 51.458632 -319.533249) (xy 51.450689 -319.585953) (xy 51.434979 -319.636883) (xy 51.411853 -319.684904)
			(xy 51.381829 -319.728941) (xy 51.3685 -319.743307) (xy 51.942736 -319.743307) (xy 51.942736 -319.690009)
			(xy 51.950679 -319.637305) (xy 51.966389 -319.586375) (xy 51.989515 -319.538354) (xy 52.019539 -319.494317)
			(xy 52.055791 -319.455246) (xy 52.097462 -319.422015) (xy 52.14362 -319.395366) (xy 52.193234 -319.375894)
			(xy 52.245196 -319.364034) (xy 52.298346 -319.360051) (xy 52.351496 -319.364034) (xy 52.403458 -319.375894)
			(xy 52.453072 -319.395366) (xy 52.49923 -319.422015) (xy 52.540901 -319.455246) (xy 52.577153 -319.494317)
			(xy 52.607177 -319.538354) (xy 52.630303 -319.586375) (xy 52.646013 -319.637305) (xy 52.653956 -319.690009)
			(xy 52.654454 -319.716658) (xy 52.653956 -319.743307) (xy 52.646013 -319.796011) (xy 52.630303 -319.846941)
			(xy 52.607177 -319.894962) (xy 52.577153 -319.938999) (xy 52.540901 -319.97807) (xy 52.49923 -320.011301)
			(xy 52.453072 -320.03795) (xy 52.403458 -320.057422) (xy 52.351496 -320.069282) (xy 52.298346 -320.073266)
			(xy 52.245196 -320.069282) (xy 52.193234 -320.057422) (xy 52.14362 -320.03795) (xy 52.097462 -320.011301)
			(xy 52.055791 -319.97807) (xy 52.019539 -319.938999) (xy 51.989515 -319.894962) (xy 51.966389 -319.846941)
			(xy 51.950679 -319.796011) (xy 51.942736 -319.743307) (xy 51.3685 -319.743307) (xy 51.345577 -319.768012)
			(xy 51.303906 -319.801243) (xy 51.257748 -319.827892) (xy 51.208134 -319.847364) (xy 51.156172 -319.859224)
			(xy 51.103022 -319.863208) (xy 51.049872 -319.859224) (xy 50.99791 -319.847364) (xy 50.948296 -319.827892)
			(xy 50.902138 -319.801243) (xy 50.860467 -319.768012) (xy 50.824215 -319.728941) (xy 50.794191 -319.684904)
			(xy 50.771065 -319.636883) (xy 50.755355 -319.585953) (xy 50.747412 -319.533249) (xy 49.159964 -319.533249)
			(xy 49.163445 -319.538354) (xy 49.186571 -319.586375) (xy 49.202281 -319.637305) (xy 49.210224 -319.690009)
			(xy 49.210722 -319.716658) (xy 49.210224 -319.743307) (xy 49.202281 -319.796011) (xy 49.186571 -319.846941)
			(xy 49.163445 -319.894962) (xy 49.133421 -319.938999) (xy 49.097169 -319.97807) (xy 49.055498 -320.011301)
			(xy 49.00934 -320.03795) (xy 48.959726 -320.057422) (xy 48.907764 -320.069282) (xy 48.854614 -320.073266)
			(xy 48.801464 -320.069282) (xy 48.749502 -320.057422) (xy 48.699888 -320.03795) (xy 48.65373 -320.011301)
			(xy 48.612059 -319.97807) (xy 48.575807 -319.938999) (xy 48.545783 -319.894962) (xy 48.522657 -319.846941)
			(xy 48.506947 -319.796011) (xy 48.499004 -319.743307) (xy 45.110156 -319.743307) (xy 45.102213 -319.796011)
			(xy 45.086503 -319.846941) (xy 45.063377 -319.894962) (xy 45.033353 -319.938999) (xy 44.997101 -319.97807)
			(xy 44.95543 -320.011301) (xy 44.909272 -320.03795) (xy 44.859658 -320.057422) (xy 44.807696 -320.069282)
			(xy 44.754546 -320.073266) (xy 44.701396 -320.069282) (xy 44.649434 -320.057422) (xy 44.59982 -320.03795)
			(xy 44.553662 -320.011301) (xy 44.511991 -319.97807) (xy 44.475739 -319.938999) (xy 44.445715 -319.894962)
			(xy 44.422589 -319.846941) (xy 44.406879 -319.796011) (xy 44.398936 -319.743307) (xy 41.666424 -319.743307)
			(xy 41.658481 -319.796011) (xy 41.642771 -319.846941) (xy 41.619645 -319.894962) (xy 41.589621 -319.938999)
			(xy 41.553369 -319.97807) (xy 41.511698 -320.011301) (xy 41.46554 -320.03795) (xy 41.415926 -320.057422)
			(xy 41.363964 -320.069282) (xy 41.310814 -320.073266) (xy 41.257664 -320.069282) (xy 41.205702 -320.057422)
			(xy 41.156088 -320.03795) (xy 41.10993 -320.011301) (xy 41.068259 -319.97807) (xy 41.032007 -319.938999)
			(xy 41.001983 -319.894962) (xy 40.978857 -319.846941) (xy 40.963147 -319.796011) (xy 40.955204 -319.743307)
			(xy 37.566356 -319.743307) (xy 37.558413 -319.796011) (xy 37.542703 -319.846941) (xy 37.519577 -319.894962)
			(xy 37.489553 -319.938999) (xy 37.453301 -319.97807) (xy 37.41163 -320.011301) (xy 37.365472 -320.03795)
			(xy 37.315858 -320.057422) (xy 37.263896 -320.069282) (xy 37.210746 -320.073266) (xy 37.157596 -320.069282)
			(xy 37.105634 -320.057422) (xy 37.05602 -320.03795) (xy 37.009862 -320.011301) (xy 36.968191 -319.97807)
			(xy 36.931939 -319.938999) (xy 36.901915 -319.894962) (xy 36.878789 -319.846941) (xy 36.863079 -319.796011)
			(xy 36.855136 -319.743307) (xy 34.122624 -319.743307) (xy 34.114681 -319.796011) (xy 34.098971 -319.846941)
			(xy 34.075845 -319.894962) (xy 34.045821 -319.938999) (xy 34.009569 -319.97807) (xy 33.967898 -320.011301)
			(xy 33.92174 -320.03795) (xy 33.872126 -320.057422) (xy 33.820164 -320.069282) (xy 33.767014 -320.073266)
			(xy 33.713864 -320.069282) (xy 33.661902 -320.057422) (xy 33.612288 -320.03795) (xy 33.56613 -320.011301)
			(xy 33.524459 -319.97807) (xy 33.488207 -319.938999) (xy 33.458183 -319.894962) (xy 33.435057 -319.846941)
			(xy 33.419347 -319.796011) (xy 33.411404 -319.743307) (xy 30.022556 -319.743307) (xy 30.014613 -319.796011)
			(xy 29.998903 -319.846941) (xy 29.975777 -319.894962) (xy 29.945753 -319.938999) (xy 29.909501 -319.97807)
			(xy 29.86783 -320.011301) (xy 29.821672 -320.03795) (xy 29.772058 -320.057422) (xy 29.720096 -320.069282)
			(xy 29.666946 -320.073266) (xy 29.613796 -320.069282) (xy 29.561834 -320.057422) (xy 29.51222 -320.03795)
			(xy 29.466062 -320.011301) (xy 29.424391 -319.97807) (xy 29.388139 -319.938999) (xy 29.358115 -319.894962)
			(xy 29.334989 -319.846941) (xy 29.319279 -319.796011) (xy 29.311336 -319.743307) (xy 26.578824 -319.743307)
			(xy 26.570881 -319.796011) (xy 26.555171 -319.846941) (xy 26.532045 -319.894962) (xy 26.502021 -319.938999)
			(xy 26.465769 -319.97807) (xy 26.424098 -320.011301) (xy 26.37794 -320.03795) (xy 26.328326 -320.057422)
			(xy 26.276364 -320.069282) (xy 26.223214 -320.073266) (xy 26.170064 -320.069282) (xy 26.118102 -320.057422)
			(xy 26.068488 -320.03795) (xy 26.02233 -320.011301) (xy 25.980659 -319.97807) (xy 25.944407 -319.938999)
			(xy 25.914383 -319.894962) (xy 25.891257 -319.846941) (xy 25.875547 -319.796011) (xy 25.867604 -319.743307)
			(xy 22.478756 -319.743307) (xy 22.470813 -319.796011) (xy 22.455103 -319.846941) (xy 22.431977 -319.894962)
			(xy 22.401953 -319.938999) (xy 22.365701 -319.97807) (xy 22.32403 -320.011301) (xy 22.277872 -320.03795)
			(xy 22.228258 -320.057422) (xy 22.176296 -320.069282) (xy 22.123146 -320.073266) (xy 22.069996 -320.069282)
			(xy 22.018034 -320.057422) (xy 21.96842 -320.03795) (xy 21.922262 -320.011301) (xy 21.880591 -319.97807)
			(xy 21.844339 -319.938999) (xy 21.814315 -319.894962) (xy 21.791189 -319.846941) (xy 21.775479 -319.796011)
			(xy 21.767536 -319.743307) (xy 19.035024 -319.743307) (xy 19.027081 -319.796011) (xy 19.011371 -319.846941)
			(xy 18.988245 -319.894962) (xy 18.958221 -319.938999) (xy 18.921969 -319.97807) (xy 18.880298 -320.011301)
			(xy 18.83414 -320.03795) (xy 18.784526 -320.057422) (xy 18.732564 -320.069282) (xy 18.679414 -320.073266)
			(xy 18.626264 -320.069282) (xy 18.574302 -320.057422) (xy 18.524688 -320.03795) (xy 18.47853 -320.011301)
			(xy 18.436859 -319.97807) (xy 18.400607 -319.938999) (xy 18.370583 -319.894962) (xy 18.347457 -319.846941)
			(xy 18.331747 -319.796011) (xy 18.323804 -319.743307) (xy 15.697708 -319.743307) (xy 15.697708 -320.165)
			(xy 55.436936 -320.165) (xy 55.44092 -320.111838) (xy 55.452784 -320.059864) (xy 55.472262 -320.010239)
			(xy 55.498919 -319.964071) (xy 55.53216 -319.922393) (xy 55.571242 -319.886135) (xy 55.615291 -319.856107)
			(xy 55.663324 -319.83298) (xy 55.714268 -319.817271) (xy 55.766985 -319.80933) (xy 55.79364 -319.80886)
			(xy 55.820407 -319.809353) (xy 55.873341 -319.817344) (xy 55.924482 -319.833171) (xy 55.972677 -319.856477)
			(xy 56.016839 -319.886736) (xy 56.055973 -319.923265) (xy 56.089196 -319.965243) (xy 56.11576 -320.011721)
			(xy 56.135065 -320.061653) (xy 56.146677 -320.113912) (xy 56.148986 -320.140584) (xy 56.150362 -320.153815)
			(xy 56.159003 -320.178962) (xy 56.173845 -320.201025) (xy 56.193881 -320.218505) (xy 56.217753 -320.230218)
			(xy 56.243839 -320.235369) (xy 56.270371 -320.233607) (xy 56.283098 -320.229738) (xy 56.311079 -320.220784)
			(xy 56.36904 -320.211211) (xy 56.398414 -320.210688) (xy 56.425062 -320.211195) (xy 56.477763 -320.21914)
			(xy 56.528692 -320.234851) (xy 56.57671 -320.257977) (xy 56.620745 -320.288001) (xy 56.659813 -320.324253)
			(xy 56.693043 -320.365923) (xy 56.71969 -320.412079) (xy 56.739161 -320.461692) (xy 56.751021 -320.513652)
			(xy 56.755004 -320.5668) (xy 56.751021 -320.619948) (xy 56.739161 -320.671908) (xy 56.71969 -320.721521)
			(xy 56.693043 -320.767677) (xy 56.659813 -320.809347) (xy 56.620745 -320.845599) (xy 56.57671 -320.875623)
			(xy 56.528692 -320.898749) (xy 56.477763 -320.91446) (xy 56.425062 -320.922405) (xy 56.398414 -320.922904)
			(xy 56.371644 -320.922487) (xy 56.318705 -320.914488) (xy 56.267561 -320.898653) (xy 56.219364 -320.875339)
			(xy 56.1752 -320.845071) (xy 56.136067 -320.808533) (xy 56.102845 -320.766547) (xy 56.076284 -320.720061)
			(xy 56.056982 -320.670121) (xy 56.045375 -320.617855) (xy 56.043068 -320.59118) (xy 56.041703 -320.577945)
			(xy 56.033071 -320.552789) (xy 56.018231 -320.530718) (xy 55.998192 -320.513232) (xy 55.974314 -320.501519)
			(xy 55.94822 -320.496375) (xy 55.921684 -320.498149) (xy 55.908956 -320.502026) (xy 55.880971 -320.510966)
			(xy 55.823013 -320.520548) (xy 55.79364 -320.521076) (xy 55.766985 -320.52067) (xy 55.714268 -320.512729)
			(xy 55.663324 -320.49702) (xy 55.615291 -320.473893) (xy 55.571242 -320.443865) (xy 55.53216 -320.407607)
			(xy 55.498919 -320.365929) (xy 55.472262 -320.319761) (xy 55.452784 -320.270136) (xy 55.44092 -320.218162)
			(xy 55.436936 -320.165) (xy 15.697708 -320.165) (xy 15.697708 -320.593445) (xy 18.323804 -320.593445)
			(xy 18.323804 -320.540147) (xy 18.331747 -320.487443) (xy 18.347457 -320.436513) (xy 18.370583 -320.388492)
			(xy 18.400607 -320.344455) (xy 18.436859 -320.305384) (xy 18.47853 -320.272153) (xy 18.524688 -320.245504)
			(xy 18.574302 -320.226032) (xy 18.626264 -320.214172) (xy 18.679414 -320.210189) (xy 18.732564 -320.214172)
			(xy 18.784526 -320.226032) (xy 18.83414 -320.245504) (xy 18.880298 -320.272153) (xy 18.921969 -320.305384)
			(xy 18.958221 -320.344455) (xy 18.988245 -320.388492) (xy 19.011371 -320.436513) (xy 19.027081 -320.487443)
			(xy 19.035024 -320.540147) (xy 19.035522 -320.566796) (xy 19.035024 -320.593445) (xy 21.767536 -320.593445)
			(xy 21.767536 -320.540147) (xy 21.775479 -320.487443) (xy 21.791189 -320.436513) (xy 21.814315 -320.388492)
			(xy 21.844339 -320.344455) (xy 21.880591 -320.305384) (xy 21.922262 -320.272153) (xy 21.96842 -320.245504)
			(xy 22.018034 -320.226032) (xy 22.069996 -320.214172) (xy 22.123146 -320.210189) (xy 22.176296 -320.214172)
			(xy 22.228258 -320.226032) (xy 22.277872 -320.245504) (xy 22.32403 -320.272153) (xy 22.365701 -320.305384)
			(xy 22.401953 -320.344455) (xy 22.431977 -320.388492) (xy 22.455103 -320.436513) (xy 22.470813 -320.487443)
			(xy 22.478756 -320.540147) (xy 22.479254 -320.566796) (xy 22.478756 -320.593445) (xy 25.867604 -320.593445)
			(xy 25.867604 -320.540147) (xy 25.875547 -320.487443) (xy 25.891257 -320.436513) (xy 25.914383 -320.388492)
			(xy 25.944407 -320.344455) (xy 25.980659 -320.305384) (xy 26.02233 -320.272153) (xy 26.068488 -320.245504)
			(xy 26.118102 -320.226032) (xy 26.170064 -320.214172) (xy 26.223214 -320.210189) (xy 26.276364 -320.214172)
			(xy 26.328326 -320.226032) (xy 26.37794 -320.245504) (xy 26.424098 -320.272153) (xy 26.465769 -320.305384)
			(xy 26.502021 -320.344455) (xy 26.532045 -320.388492) (xy 26.555171 -320.436513) (xy 26.570881 -320.487443)
			(xy 26.578824 -320.540147) (xy 26.579322 -320.566796) (xy 26.578824 -320.593445) (xy 29.311336 -320.593445)
			(xy 29.311336 -320.540147) (xy 29.319279 -320.487443) (xy 29.334989 -320.436513) (xy 29.358115 -320.388492)
			(xy 29.388139 -320.344455) (xy 29.424391 -320.305384) (xy 29.466062 -320.272153) (xy 29.51222 -320.245504)
			(xy 29.561834 -320.226032) (xy 29.613796 -320.214172) (xy 29.666946 -320.210189) (xy 29.720096 -320.214172)
			(xy 29.772058 -320.226032) (xy 29.821672 -320.245504) (xy 29.86783 -320.272153) (xy 29.909501 -320.305384)
			(xy 29.945753 -320.344455) (xy 29.975777 -320.388492) (xy 29.998903 -320.436513) (xy 30.014613 -320.487443)
			(xy 30.022556 -320.540147) (xy 30.023054 -320.566796) (xy 30.022556 -320.593445) (xy 33.411404 -320.593445)
			(xy 33.411404 -320.540147) (xy 33.419347 -320.487443) (xy 33.435057 -320.436513) (xy 33.458183 -320.388492)
			(xy 33.488207 -320.344455) (xy 33.524459 -320.305384) (xy 33.56613 -320.272153) (xy 33.612288 -320.245504)
			(xy 33.661902 -320.226032) (xy 33.713864 -320.214172) (xy 33.767014 -320.210189) (xy 33.820164 -320.214172)
			(xy 33.872126 -320.226032) (xy 33.92174 -320.245504) (xy 33.967898 -320.272153) (xy 34.009569 -320.305384)
			(xy 34.045821 -320.344455) (xy 34.075845 -320.388492) (xy 34.098971 -320.436513) (xy 34.114681 -320.487443)
			(xy 34.122624 -320.540147) (xy 34.123122 -320.566796) (xy 34.122624 -320.593445) (xy 36.855136 -320.593445)
			(xy 36.855136 -320.540147) (xy 36.863079 -320.487443) (xy 36.878789 -320.436513) (xy 36.901915 -320.388492)
			(xy 36.931939 -320.344455) (xy 36.968191 -320.305384) (xy 37.009862 -320.272153) (xy 37.05602 -320.245504)
			(xy 37.105634 -320.226032) (xy 37.157596 -320.214172) (xy 37.210746 -320.210189) (xy 37.263896 -320.214172)
			(xy 37.315858 -320.226032) (xy 37.365472 -320.245504) (xy 37.41163 -320.272153) (xy 37.453301 -320.305384)
			(xy 37.489553 -320.344455) (xy 37.519577 -320.388492) (xy 37.542703 -320.436513) (xy 37.558413 -320.487443)
			(xy 37.566356 -320.540147) (xy 37.566854 -320.566796) (xy 37.566356 -320.593445) (xy 40.955204 -320.593445)
			(xy 40.955204 -320.540147) (xy 40.963147 -320.487443) (xy 40.978857 -320.436513) (xy 41.001983 -320.388492)
			(xy 41.032007 -320.344455) (xy 41.068259 -320.305384) (xy 41.10993 -320.272153) (xy 41.156088 -320.245504)
			(xy 41.205702 -320.226032) (xy 41.257664 -320.214172) (xy 41.310814 -320.210189) (xy 41.363964 -320.214172)
			(xy 41.415926 -320.226032) (xy 41.46554 -320.245504) (xy 41.511698 -320.272153) (xy 41.553369 -320.305384)
			(xy 41.589621 -320.344455) (xy 41.619645 -320.388492) (xy 41.642771 -320.436513) (xy 41.658481 -320.487443)
			(xy 41.666424 -320.540147) (xy 41.666922 -320.566796) (xy 41.666424 -320.593445) (xy 44.398936 -320.593445)
			(xy 44.398936 -320.540147) (xy 44.406879 -320.487443) (xy 44.422589 -320.436513) (xy 44.445715 -320.388492)
			(xy 44.475739 -320.344455) (xy 44.511991 -320.305384) (xy 44.553662 -320.272153) (xy 44.59982 -320.245504)
			(xy 44.649434 -320.226032) (xy 44.701396 -320.214172) (xy 44.754546 -320.210189) (xy 44.807696 -320.214172)
			(xy 44.859658 -320.226032) (xy 44.909272 -320.245504) (xy 44.95543 -320.272153) (xy 44.997101 -320.305384)
			(xy 45.033353 -320.344455) (xy 45.063377 -320.388492) (xy 45.086503 -320.436513) (xy 45.102213 -320.487443)
			(xy 45.110156 -320.540147) (xy 45.110654 -320.566796) (xy 45.110156 -320.593445) (xy 48.499004 -320.593445)
			(xy 48.499004 -320.540147) (xy 48.506947 -320.487443) (xy 48.522657 -320.436513) (xy 48.545783 -320.388492)
			(xy 48.575807 -320.344455) (xy 48.612059 -320.305384) (xy 48.65373 -320.272153) (xy 48.699888 -320.245504)
			(xy 48.749502 -320.226032) (xy 48.801464 -320.214172) (xy 48.854614 -320.210189) (xy 48.907764 -320.214172)
			(xy 48.959726 -320.226032) (xy 49.00934 -320.245504) (xy 49.055498 -320.272153) (xy 49.097169 -320.305384)
			(xy 49.133421 -320.344455) (xy 49.163445 -320.388492) (xy 49.186571 -320.436513) (xy 49.202281 -320.487443)
			(xy 49.210224 -320.540147) (xy 49.210722 -320.566796) (xy 49.210224 -320.593445) (xy 51.942736 -320.593445)
			(xy 51.942736 -320.540147) (xy 51.950679 -320.487443) (xy 51.966389 -320.436513) (xy 51.989515 -320.388492)
			(xy 52.019539 -320.344455) (xy 52.055791 -320.305384) (xy 52.097462 -320.272153) (xy 52.14362 -320.245504)
			(xy 52.193234 -320.226032) (xy 52.245196 -320.214172) (xy 52.298346 -320.210189) (xy 52.351496 -320.214172)
			(xy 52.403458 -320.226032) (xy 52.453072 -320.245504) (xy 52.49923 -320.272153) (xy 52.540901 -320.305384)
			(xy 52.577153 -320.344455) (xy 52.607177 -320.388492) (xy 52.630303 -320.436513) (xy 52.646013 -320.487443)
			(xy 52.653956 -320.540147) (xy 52.654454 -320.566796) (xy 52.653956 -320.593445) (xy 52.646013 -320.646149)
			(xy 52.630303 -320.697079) (xy 52.607177 -320.7451) (xy 52.577153 -320.789137) (xy 52.540901 -320.828208)
			(xy 52.49923 -320.861439) (xy 52.453072 -320.888088) (xy 52.403458 -320.90756) (xy 52.351496 -320.91942)
			(xy 52.298346 -320.923404) (xy 52.245196 -320.91942) (xy 52.193234 -320.90756) (xy 52.14362 -320.888088)
			(xy 52.097462 -320.861439) (xy 52.055791 -320.828208) (xy 52.019539 -320.789137) (xy 51.989515 -320.7451)
			(xy 51.966389 -320.697079) (xy 51.950679 -320.646149) (xy 51.942736 -320.593445) (xy 49.210224 -320.593445)
			(xy 49.202281 -320.646149) (xy 49.186571 -320.697079) (xy 49.163445 -320.7451) (xy 49.133421 -320.789137)
			(xy 49.097169 -320.828208) (xy 49.055498 -320.861439) (xy 49.00934 -320.888088) (xy 48.959726 -320.90756)
			(xy 48.907764 -320.91942) (xy 48.854614 -320.923404) (xy 48.801464 -320.91942) (xy 48.749502 -320.90756)
			(xy 48.699888 -320.888088) (xy 48.65373 -320.861439) (xy 48.612059 -320.828208) (xy 48.575807 -320.789137)
			(xy 48.545783 -320.7451) (xy 48.522657 -320.697079) (xy 48.506947 -320.646149) (xy 48.499004 -320.593445)
			(xy 45.110156 -320.593445) (xy 45.102213 -320.646149) (xy 45.086503 -320.697079) (xy 45.063377 -320.7451)
			(xy 45.033353 -320.789137) (xy 44.997101 -320.828208) (xy 44.95543 -320.861439) (xy 44.909272 -320.888088)
			(xy 44.859658 -320.90756) (xy 44.807696 -320.91942) (xy 44.754546 -320.923404) (xy 44.701396 -320.91942)
			(xy 44.649434 -320.90756) (xy 44.59982 -320.888088) (xy 44.553662 -320.861439) (xy 44.511991 -320.828208)
			(xy 44.475739 -320.789137) (xy 44.445715 -320.7451) (xy 44.422589 -320.697079) (xy 44.406879 -320.646149)
			(xy 44.398936 -320.593445) (xy 41.666424 -320.593445) (xy 41.658481 -320.646149) (xy 41.642771 -320.697079)
			(xy 41.619645 -320.7451) (xy 41.589621 -320.789137) (xy 41.553369 -320.828208) (xy 41.511698 -320.861439)
			(xy 41.46554 -320.888088) (xy 41.415926 -320.90756) (xy 41.363964 -320.91942) (xy 41.310814 -320.923404)
			(xy 41.257664 -320.91942) (xy 41.205702 -320.90756) (xy 41.156088 -320.888088) (xy 41.10993 -320.861439)
			(xy 41.068259 -320.828208) (xy 41.032007 -320.789137) (xy 41.001983 -320.7451) (xy 40.978857 -320.697079)
			(xy 40.963147 -320.646149) (xy 40.955204 -320.593445) (xy 37.566356 -320.593445) (xy 37.558413 -320.646149)
			(xy 37.542703 -320.697079) (xy 37.519577 -320.7451) (xy 37.489553 -320.789137) (xy 37.453301 -320.828208)
			(xy 37.41163 -320.861439) (xy 37.365472 -320.888088) (xy 37.315858 -320.90756) (xy 37.263896 -320.91942)
			(xy 37.210746 -320.923404) (xy 37.157596 -320.91942) (xy 37.105634 -320.90756) (xy 37.05602 -320.888088)
			(xy 37.009862 -320.861439) (xy 36.968191 -320.828208) (xy 36.931939 -320.789137) (xy 36.901915 -320.7451)
			(xy 36.878789 -320.697079) (xy 36.863079 -320.646149) (xy 36.855136 -320.593445) (xy 34.122624 -320.593445)
			(xy 34.114681 -320.646149) (xy 34.098971 -320.697079) (xy 34.075845 -320.7451) (xy 34.045821 -320.789137)
			(xy 34.009569 -320.828208) (xy 33.967898 -320.861439) (xy 33.92174 -320.888088) (xy 33.872126 -320.90756)
			(xy 33.820164 -320.91942) (xy 33.767014 -320.923404) (xy 33.713864 -320.91942) (xy 33.661902 -320.90756)
			(xy 33.612288 -320.888088) (xy 33.56613 -320.861439) (xy 33.524459 -320.828208) (xy 33.488207 -320.789137)
			(xy 33.458183 -320.7451) (xy 33.435057 -320.697079) (xy 33.419347 -320.646149) (xy 33.411404 -320.593445)
			(xy 30.022556 -320.593445) (xy 30.014613 -320.646149) (xy 29.998903 -320.697079) (xy 29.975777 -320.7451)
			(xy 29.945753 -320.789137) (xy 29.909501 -320.828208) (xy 29.86783 -320.861439) (xy 29.821672 -320.888088)
			(xy 29.772058 -320.90756) (xy 29.720096 -320.91942) (xy 29.666946 -320.923404) (xy 29.613796 -320.91942)
			(xy 29.561834 -320.90756) (xy 29.51222 -320.888088) (xy 29.466062 -320.861439) (xy 29.424391 -320.828208)
			(xy 29.388139 -320.789137) (xy 29.358115 -320.7451) (xy 29.334989 -320.697079) (xy 29.319279 -320.646149)
			(xy 29.311336 -320.593445) (xy 26.578824 -320.593445) (xy 26.570881 -320.646149) (xy 26.555171 -320.697079)
			(xy 26.532045 -320.7451) (xy 26.502021 -320.789137) (xy 26.465769 -320.828208) (xy 26.424098 -320.861439)
			(xy 26.37794 -320.888088) (xy 26.328326 -320.90756) (xy 26.276364 -320.91942) (xy 26.223214 -320.923404)
			(xy 26.170064 -320.91942) (xy 26.118102 -320.90756) (xy 26.068488 -320.888088) (xy 26.02233 -320.861439)
			(xy 25.980659 -320.828208) (xy 25.944407 -320.789137) (xy 25.914383 -320.7451) (xy 25.891257 -320.697079)
			(xy 25.875547 -320.646149) (xy 25.867604 -320.593445) (xy 22.478756 -320.593445) (xy 22.470813 -320.646149)
			(xy 22.455103 -320.697079) (xy 22.431977 -320.7451) (xy 22.401953 -320.789137) (xy 22.365701 -320.828208)
			(xy 22.32403 -320.861439) (xy 22.277872 -320.888088) (xy 22.228258 -320.90756) (xy 22.176296 -320.91942)
			(xy 22.123146 -320.923404) (xy 22.069996 -320.91942) (xy 22.018034 -320.90756) (xy 21.96842 -320.888088)
			(xy 21.922262 -320.861439) (xy 21.880591 -320.828208) (xy 21.844339 -320.789137) (xy 21.814315 -320.7451)
			(xy 21.791189 -320.697079) (xy 21.775479 -320.646149) (xy 21.767536 -320.593445) (xy 19.035024 -320.593445)
			(xy 19.027081 -320.646149) (xy 19.011371 -320.697079) (xy 18.988245 -320.7451) (xy 18.958221 -320.789137)
			(xy 18.921969 -320.828208) (xy 18.880298 -320.861439) (xy 18.83414 -320.888088) (xy 18.784526 -320.90756)
			(xy 18.732564 -320.91942) (xy 18.679414 -320.923404) (xy 18.626264 -320.91942) (xy 18.574302 -320.90756)
			(xy 18.524688 -320.888088) (xy 18.47853 -320.861439) (xy 18.436859 -320.828208) (xy 18.400607 -320.789137)
			(xy 18.370583 -320.7451) (xy 18.347457 -320.697079) (xy 18.331747 -320.646149) (xy 18.323804 -320.593445)
			(xy 15.697708 -320.593445) (xy 15.697708 -321.443329) (xy 18.323804 -321.443329) (xy 18.323804 -321.390031)
			(xy 18.331747 -321.337327) (xy 18.347457 -321.286397) (xy 18.370583 -321.238376) (xy 18.400607 -321.194339)
			(xy 18.436859 -321.155268) (xy 18.47853 -321.122037) (xy 18.524688 -321.095388) (xy 18.574302 -321.075916)
			(xy 18.626264 -321.064056) (xy 18.679414 -321.060073) (xy 18.732564 -321.064056) (xy 18.784526 -321.075916)
			(xy 18.83414 -321.095388) (xy 18.880298 -321.122037) (xy 18.921969 -321.155268) (xy 18.958221 -321.194339)
			(xy 18.988245 -321.238376) (xy 19.011371 -321.286397) (xy 19.027081 -321.337327) (xy 19.035024 -321.390031)
			(xy 19.035522 -321.41668) (xy 19.035024 -321.443329) (xy 21.767536 -321.443329) (xy 21.767536 -321.390031)
			(xy 21.775479 -321.337327) (xy 21.791189 -321.286397) (xy 21.814315 -321.238376) (xy 21.844339 -321.194339)
			(xy 21.880591 -321.155268) (xy 21.922262 -321.122037) (xy 21.96842 -321.095388) (xy 22.018034 -321.075916)
			(xy 22.069996 -321.064056) (xy 22.123146 -321.060073) (xy 22.176296 -321.064056) (xy 22.228258 -321.075916)
			(xy 22.277872 -321.095388) (xy 22.32403 -321.122037) (xy 22.365701 -321.155268) (xy 22.401953 -321.194339)
			(xy 22.431977 -321.238376) (xy 22.455103 -321.286397) (xy 22.470813 -321.337327) (xy 22.478756 -321.390031)
			(xy 22.479254 -321.41668) (xy 22.478756 -321.443329) (xy 25.867604 -321.443329) (xy 25.867604 -321.390031)
			(xy 25.875547 -321.337327) (xy 25.891257 -321.286397) (xy 25.914383 -321.238376) (xy 25.944407 -321.194339)
			(xy 25.980659 -321.155268) (xy 26.02233 -321.122037) (xy 26.068488 -321.095388) (xy 26.118102 -321.075916)
			(xy 26.170064 -321.064056) (xy 26.223214 -321.060073) (xy 26.276364 -321.064056) (xy 26.328326 -321.075916)
			(xy 26.37794 -321.095388) (xy 26.424098 -321.122037) (xy 26.465769 -321.155268) (xy 26.502021 -321.194339)
			(xy 26.532045 -321.238376) (xy 26.555171 -321.286397) (xy 26.570881 -321.337327) (xy 26.578824 -321.390031)
			(xy 26.579322 -321.41668) (xy 26.578824 -321.443329) (xy 29.311336 -321.443329) (xy 29.311336 -321.390031)
			(xy 29.319279 -321.337327) (xy 29.334989 -321.286397) (xy 29.358115 -321.238376) (xy 29.388139 -321.194339)
			(xy 29.424391 -321.155268) (xy 29.466062 -321.122037) (xy 29.51222 -321.095388) (xy 29.561834 -321.075916)
			(xy 29.613796 -321.064056) (xy 29.666946 -321.060073) (xy 29.720096 -321.064056) (xy 29.772058 -321.075916)
			(xy 29.821672 -321.095388) (xy 29.86783 -321.122037) (xy 29.909501 -321.155268) (xy 29.945753 -321.194339)
			(xy 29.975777 -321.238376) (xy 29.998903 -321.286397) (xy 30.014613 -321.337327) (xy 30.022556 -321.390031)
			(xy 30.023054 -321.41668) (xy 30.022556 -321.443329) (xy 33.411404 -321.443329) (xy 33.411404 -321.390031)
			(xy 33.419347 -321.337327) (xy 33.435057 -321.286397) (xy 33.458183 -321.238376) (xy 33.488207 -321.194339)
			(xy 33.524459 -321.155268) (xy 33.56613 -321.122037) (xy 33.612288 -321.095388) (xy 33.661902 -321.075916)
			(xy 33.713864 -321.064056) (xy 33.767014 -321.060073) (xy 33.820164 -321.064056) (xy 33.872126 -321.075916)
			(xy 33.92174 -321.095388) (xy 33.967898 -321.122037) (xy 34.009569 -321.155268) (xy 34.045821 -321.194339)
			(xy 34.075845 -321.238376) (xy 34.098971 -321.286397) (xy 34.114681 -321.337327) (xy 34.122624 -321.390031)
			(xy 34.123122 -321.41668) (xy 34.122624 -321.443329) (xy 36.855136 -321.443329) (xy 36.855136 -321.390031)
			(xy 36.863079 -321.337327) (xy 36.878789 -321.286397) (xy 36.901915 -321.238376) (xy 36.931939 -321.194339)
			(xy 36.968191 -321.155268) (xy 37.009862 -321.122037) (xy 37.05602 -321.095388) (xy 37.105634 -321.075916)
			(xy 37.157596 -321.064056) (xy 37.210746 -321.060073) (xy 37.263896 -321.064056) (xy 37.315858 -321.075916)
			(xy 37.365472 -321.095388) (xy 37.41163 -321.122037) (xy 37.453301 -321.155268) (xy 37.489553 -321.194339)
			(xy 37.519577 -321.238376) (xy 37.542703 -321.286397) (xy 37.558413 -321.337327) (xy 37.566356 -321.390031)
			(xy 37.566854 -321.41668) (xy 37.566356 -321.443329) (xy 40.955204 -321.443329) (xy 40.955204 -321.390031)
			(xy 40.963147 -321.337327) (xy 40.978857 -321.286397) (xy 41.001983 -321.238376) (xy 41.032007 -321.194339)
			(xy 41.068259 -321.155268) (xy 41.10993 -321.122037) (xy 41.156088 -321.095388) (xy 41.205702 -321.075916)
			(xy 41.257664 -321.064056) (xy 41.310814 -321.060073) (xy 41.363964 -321.064056) (xy 41.415926 -321.075916)
			(xy 41.46554 -321.095388) (xy 41.511698 -321.122037) (xy 41.553369 -321.155268) (xy 41.589621 -321.194339)
			(xy 41.619645 -321.238376) (xy 41.642771 -321.286397) (xy 41.658481 -321.337327) (xy 41.666424 -321.390031)
			(xy 41.666922 -321.41668) (xy 41.666424 -321.443329) (xy 44.398936 -321.443329) (xy 44.398936 -321.390031)
			(xy 44.406879 -321.337327) (xy 44.422589 -321.286397) (xy 44.445715 -321.238376) (xy 44.475739 -321.194339)
			(xy 44.511991 -321.155268) (xy 44.553662 -321.122037) (xy 44.59982 -321.095388) (xy 44.649434 -321.075916)
			(xy 44.701396 -321.064056) (xy 44.754546 -321.060073) (xy 44.807696 -321.064056) (xy 44.859658 -321.075916)
			(xy 44.909272 -321.095388) (xy 44.95543 -321.122037) (xy 44.997101 -321.155268) (xy 45.033353 -321.194339)
			(xy 45.063377 -321.238376) (xy 45.086503 -321.286397) (xy 45.102213 -321.337327) (xy 45.110156 -321.390031)
			(xy 45.110654 -321.41668) (xy 45.110156 -321.443329) (xy 48.499004 -321.443329) (xy 48.499004 -321.390031)
			(xy 48.506947 -321.337327) (xy 48.522657 -321.286397) (xy 48.545783 -321.238376) (xy 48.575807 -321.194339)
			(xy 48.612059 -321.155268) (xy 48.65373 -321.122037) (xy 48.699888 -321.095388) (xy 48.749502 -321.075916)
			(xy 48.801464 -321.064056) (xy 48.854614 -321.060073) (xy 48.907764 -321.064056) (xy 48.959726 -321.075916)
			(xy 49.00934 -321.095388) (xy 49.055498 -321.122037) (xy 49.097169 -321.155268) (xy 49.133421 -321.194339)
			(xy 49.163445 -321.238376) (xy 49.186571 -321.286397) (xy 49.202281 -321.337327) (xy 49.210224 -321.390031)
			(xy 49.210722 -321.41668) (xy 49.210224 -321.443329) (xy 51.942736 -321.443329) (xy 51.942736 -321.390031)
			(xy 51.950679 -321.337327) (xy 51.966389 -321.286397) (xy 51.989515 -321.238376) (xy 52.019539 -321.194339)
			(xy 52.055791 -321.155268) (xy 52.097462 -321.122037) (xy 52.14362 -321.095388) (xy 52.193234 -321.075916)
			(xy 52.245196 -321.064056) (xy 52.298346 -321.060073) (xy 52.351496 -321.064056) (xy 52.403458 -321.075916)
			(xy 52.453072 -321.095388) (xy 52.49923 -321.122037) (xy 52.540901 -321.155268) (xy 52.577153 -321.194339)
			(xy 52.607177 -321.238376) (xy 52.630303 -321.286397) (xy 52.646013 -321.337327) (xy 52.653956 -321.390031)
			(xy 52.654454 -321.41668) (xy 52.653956 -321.443329) (xy 52.646013 -321.496033) (xy 52.630303 -321.546963)
			(xy 52.607177 -321.594984) (xy 52.577153 -321.639021) (xy 52.540901 -321.678092) (xy 52.49923 -321.711323)
			(xy 52.453072 -321.737972) (xy 52.403458 -321.757444) (xy 52.351496 -321.769304) (xy 52.298346 -321.773288)
			(xy 52.245196 -321.769304) (xy 52.193234 -321.757444) (xy 52.14362 -321.737972) (xy 52.097462 -321.711323)
			(xy 52.055791 -321.678092) (xy 52.019539 -321.639021) (xy 51.989515 -321.594984) (xy 51.966389 -321.546963)
			(xy 51.950679 -321.496033) (xy 51.942736 -321.443329) (xy 49.210224 -321.443329) (xy 49.202281 -321.496033)
			(xy 49.186571 -321.546963) (xy 49.163445 -321.594984) (xy 49.133421 -321.639021) (xy 49.097169 -321.678092)
			(xy 49.055498 -321.711323) (xy 49.00934 -321.737972) (xy 48.959726 -321.757444) (xy 48.907764 -321.769304)
			(xy 48.854614 -321.773288) (xy 48.801464 -321.769304) (xy 48.749502 -321.757444) (xy 48.699888 -321.737972)
			(xy 48.65373 -321.711323) (xy 48.612059 -321.678092) (xy 48.575807 -321.639021) (xy 48.545783 -321.594984)
			(xy 48.522657 -321.546963) (xy 48.506947 -321.496033) (xy 48.499004 -321.443329) (xy 45.110156 -321.443329)
			(xy 45.102213 -321.496033) (xy 45.086503 -321.546963) (xy 45.063377 -321.594984) (xy 45.033353 -321.639021)
			(xy 44.997101 -321.678092) (xy 44.95543 -321.711323) (xy 44.909272 -321.737972) (xy 44.859658 -321.757444)
			(xy 44.807696 -321.769304) (xy 44.754546 -321.773288) (xy 44.701396 -321.769304) (xy 44.649434 -321.757444)
			(xy 44.59982 -321.737972) (xy 44.553662 -321.711323) (xy 44.511991 -321.678092) (xy 44.475739 -321.639021)
			(xy 44.445715 -321.594984) (xy 44.422589 -321.546963) (xy 44.406879 -321.496033) (xy 44.398936 -321.443329)
			(xy 41.666424 -321.443329) (xy 41.658481 -321.496033) (xy 41.642771 -321.546963) (xy 41.619645 -321.594984)
			(xy 41.589621 -321.639021) (xy 41.553369 -321.678092) (xy 41.511698 -321.711323) (xy 41.46554 -321.737972)
			(xy 41.415926 -321.757444) (xy 41.363964 -321.769304) (xy 41.310814 -321.773288) (xy 41.257664 -321.769304)
			(xy 41.205702 -321.757444) (xy 41.156088 -321.737972) (xy 41.10993 -321.711323) (xy 41.068259 -321.678092)
			(xy 41.032007 -321.639021) (xy 41.001983 -321.594984) (xy 40.978857 -321.546963) (xy 40.963147 -321.496033)
			(xy 40.955204 -321.443329) (xy 37.566356 -321.443329) (xy 37.558413 -321.496033) (xy 37.542703 -321.546963)
			(xy 37.519577 -321.594984) (xy 37.489553 -321.639021) (xy 37.453301 -321.678092) (xy 37.41163 -321.711323)
			(xy 37.365472 -321.737972) (xy 37.315858 -321.757444) (xy 37.263896 -321.769304) (xy 37.210746 -321.773288)
			(xy 37.157596 -321.769304) (xy 37.105634 -321.757444) (xy 37.05602 -321.737972) (xy 37.009862 -321.711323)
			(xy 36.968191 -321.678092) (xy 36.931939 -321.639021) (xy 36.901915 -321.594984) (xy 36.878789 -321.546963)
			(xy 36.863079 -321.496033) (xy 36.855136 -321.443329) (xy 34.122624 -321.443329) (xy 34.114681 -321.496033)
			(xy 34.098971 -321.546963) (xy 34.075845 -321.594984) (xy 34.045821 -321.639021) (xy 34.009569 -321.678092)
			(xy 33.967898 -321.711323) (xy 33.92174 -321.737972) (xy 33.872126 -321.757444) (xy 33.820164 -321.769304)
			(xy 33.767014 -321.773288) (xy 33.713864 -321.769304) (xy 33.661902 -321.757444) (xy 33.612288 -321.737972)
			(xy 33.56613 -321.711323) (xy 33.524459 -321.678092) (xy 33.488207 -321.639021) (xy 33.458183 -321.594984)
			(xy 33.435057 -321.546963) (xy 33.419347 -321.496033) (xy 33.411404 -321.443329) (xy 30.022556 -321.443329)
			(xy 30.014613 -321.496033) (xy 29.998903 -321.546963) (xy 29.975777 -321.594984) (xy 29.945753 -321.639021)
			(xy 29.909501 -321.678092) (xy 29.86783 -321.711323) (xy 29.821672 -321.737972) (xy 29.772058 -321.757444)
			(xy 29.720096 -321.769304) (xy 29.666946 -321.773288) (xy 29.613796 -321.769304) (xy 29.561834 -321.757444)
			(xy 29.51222 -321.737972) (xy 29.466062 -321.711323) (xy 29.424391 -321.678092) (xy 29.388139 -321.639021)
			(xy 29.358115 -321.594984) (xy 29.334989 -321.546963) (xy 29.319279 -321.496033) (xy 29.311336 -321.443329)
			(xy 26.578824 -321.443329) (xy 26.570881 -321.496033) (xy 26.555171 -321.546963) (xy 26.532045 -321.594984)
			(xy 26.502021 -321.639021) (xy 26.465769 -321.678092) (xy 26.424098 -321.711323) (xy 26.37794 -321.737972)
			(xy 26.328326 -321.757444) (xy 26.276364 -321.769304) (xy 26.223214 -321.773288) (xy 26.170064 -321.769304)
			(xy 26.118102 -321.757444) (xy 26.068488 -321.737972) (xy 26.02233 -321.711323) (xy 25.980659 -321.678092)
			(xy 25.944407 -321.639021) (xy 25.914383 -321.594984) (xy 25.891257 -321.546963) (xy 25.875547 -321.496033)
			(xy 25.867604 -321.443329) (xy 22.478756 -321.443329) (xy 22.470813 -321.496033) (xy 22.455103 -321.546963)
			(xy 22.431977 -321.594984) (xy 22.401953 -321.639021) (xy 22.365701 -321.678092) (xy 22.32403 -321.711323)
			(xy 22.277872 -321.737972) (xy 22.228258 -321.757444) (xy 22.176296 -321.769304) (xy 22.123146 -321.773288)
			(xy 22.069996 -321.769304) (xy 22.018034 -321.757444) (xy 21.96842 -321.737972) (xy 21.922262 -321.711323)
			(xy 21.880591 -321.678092) (xy 21.844339 -321.639021) (xy 21.814315 -321.594984) (xy 21.791189 -321.546963)
			(xy 21.775479 -321.496033) (xy 21.767536 -321.443329) (xy 19.035024 -321.443329) (xy 19.027081 -321.496033)
			(xy 19.011371 -321.546963) (xy 18.988245 -321.594984) (xy 18.958221 -321.639021) (xy 18.921969 -321.678092)
			(xy 18.880298 -321.711323) (xy 18.83414 -321.737972) (xy 18.784526 -321.757444) (xy 18.732564 -321.769304)
			(xy 18.679414 -321.773288) (xy 18.626264 -321.769304) (xy 18.574302 -321.757444) (xy 18.524688 -321.737972)
			(xy 18.47853 -321.711323) (xy 18.436859 -321.678092) (xy 18.400607 -321.639021) (xy 18.370583 -321.594984)
			(xy 18.347457 -321.546963) (xy 18.331747 -321.496033) (xy 18.323804 -321.443329) (xy 15.697708 -321.443329)
			(xy 15.697708 -321.812158) (xy 15.26921 -322.240656) (xy 7.03199 -322.240656) (xy 6.955282 -322.163694)
			(xy 6.944303 -322.153458) (xy 6.91785 -322.139306) (xy 6.888427 -322.133447) (xy 6.85857 -322.136386)
			(xy 6.830854 -322.14787) (xy 6.807668 -322.166909) (xy 6.791011 -322.191861) (xy 6.782319 -322.220575)
			(xy 6.7818 -322.235576) (xy 6.7818 -325.643748) (xy 9.1694 -328.031348) (xy 49.6824 -328.031348)
		)
		(stroke
			(width 0)
			(type solid)
		)
		(fill yes)
		(layer "In15.Cu")
		(net "GND")
	)
	(gr_poly
		(pts
			(xy 434.098446 -382.197102) (xy 434.098446 -378.412248) (xy 436.238142 -376.272552) (xy 436.238142 -322.99529)
			(xy 439.227722 -320.00571) (xy 439.506106 -320.00571) (xy 439.520596 -320.005199) (xy 439.548408 -319.997058)
			(xy 439.572814 -319.981433) (xy 439.591849 -319.959582) (xy 439.60398 -319.933264) (xy 439.608231 -319.904599)
			(xy 439.60426 -319.875893) (xy 439.598816 -319.862454) (xy 439.588941 -319.83943) (xy 439.575024 -319.791306)
			(xy 439.567991 -319.741706) (xy 439.567574 -319.716658) (xy 439.568072 -319.690009) (xy 439.576015 -319.637305)
			(xy 439.591725 -319.586375) (xy 439.614851 -319.538354) (xy 439.644875 -319.494317) (xy 439.681127 -319.455246)
			(xy 439.722798 -319.422015) (xy 439.768956 -319.395366) (xy 439.81857 -319.375894) (xy 439.870532 -319.364034)
			(xy 439.923682 -319.360051) (xy 439.976832 -319.364034) (xy 440.010441 -319.371705) (xy 445.284342 -319.371705)
			(xy 445.284342 -319.318407) (xy 445.292285 -319.265703) (xy 445.307995 -319.214773) (xy 445.331121 -319.166752)
			(xy 445.361145 -319.122715) (xy 445.397397 -319.083644) (xy 445.439068 -319.050413) (xy 445.485226 -319.023764)
			(xy 445.53484 -319.004292) (xy 445.586802 -318.992432) (xy 445.639952 -318.988449) (xy 445.693102 -318.992432)
			(xy 445.745064 -319.004292) (xy 445.794678 -319.023764) (xy 445.840836 -319.050413) (xy 445.882507 -319.083644)
			(xy 445.918759 -319.122715) (xy 445.948783 -319.166752) (xy 445.971909 -319.214773) (xy 445.987619 -319.265703)
			(xy 445.995562 -319.318407) (xy 445.99606 -319.345056) (xy 445.995562 -319.371705) (xy 445.987619 -319.424409)
			(xy 445.971909 -319.475339) (xy 445.948783 -319.52336) (xy 445.918759 -319.567397) (xy 445.882507 -319.606468)
			(xy 445.840836 -319.639699) (xy 445.794678 -319.666348) (xy 445.745064 -319.68582) (xy 445.693102 -319.69768)
			(xy 445.639952 -319.701664) (xy 445.586802 -319.69768) (xy 445.53484 -319.68582) (xy 445.485226 -319.666348)
			(xy 445.439068 -319.639699) (xy 445.397397 -319.606468) (xy 445.361145 -319.567397) (xy 445.331121 -319.52336)
			(xy 445.307995 -319.475339) (xy 445.292285 -319.424409) (xy 445.284342 -319.371705) (xy 440.010441 -319.371705)
			(xy 440.028794 -319.375894) (xy 440.078408 -319.395366) (xy 440.124566 -319.422015) (xy 440.166237 -319.455246)
			(xy 440.202489 -319.494317) (xy 440.232513 -319.538354) (xy 440.255639 -319.586375) (xy 440.271349 -319.637305)
			(xy 440.279292 -319.690009) (xy 440.27979 -319.716658) (xy 440.279366 -319.741706) (xy 440.272344 -319.791309)
			(xy 440.258434 -319.839435) (xy 440.248548 -319.862454) (xy 440.243073 -319.875882) (xy 440.239097 -319.904591)
			(xy 440.243349 -319.933262) (xy 440.255486 -319.959582) (xy 440.274529 -319.981432) (xy 440.298945 -319.99705)
			(xy 440.326766 -320.005178) (xy 440.341258 -320.00571) (xy 447.049906 -320.00571) (xy 447.064396 -320.005199)
			(xy 447.092208 -319.997058) (xy 447.116614 -319.981433) (xy 447.135649 -319.959582) (xy 447.14778 -319.933264)
			(xy 447.152031 -319.904599) (xy 447.14806 -319.875893) (xy 447.142616 -319.862454) (xy 447.132741 -319.83943)
			(xy 447.118824 -319.791306) (xy 447.111791 -319.741706) (xy 447.111374 -319.716658) (xy 447.111872 -319.690009)
			(xy 447.119815 -319.637305) (xy 447.135525 -319.586375) (xy 447.158651 -319.538354) (xy 447.188675 -319.494317)
			(xy 447.224927 -319.455246) (xy 447.266598 -319.422015) (xy 447.312756 -319.395366) (xy 447.36237 -319.375894)
			(xy 447.414332 -319.364034) (xy 447.467482 -319.360051) (xy 447.520632 -319.364034) (xy 447.572594 -319.375894)
			(xy 447.622208 -319.395366) (xy 447.668366 -319.422015) (xy 447.710037 -319.455246) (xy 447.726793 -319.473305)
			(xy 452.828142 -319.473305) (xy 452.828142 -319.420007) (xy 452.836085 -319.367303) (xy 452.851795 -319.316373)
			(xy 452.874921 -319.268352) (xy 452.904945 -319.224315) (xy 452.941197 -319.185244) (xy 452.982868 -319.152013)
			(xy 453.029026 -319.125364) (xy 453.07864 -319.105892) (xy 453.130602 -319.094032) (xy 453.183752 -319.090049)
			(xy 453.236902 -319.094032) (xy 453.288864 -319.105892) (xy 453.338478 -319.125364) (xy 453.350325 -319.132204)
			(xy 456.84516 -319.132204) (xy 456.849231 -319.076582) (xy 456.861357 -319.022145) (xy 456.88128 -318.970054)
			(xy 456.908576 -318.921419) (xy 456.942662 -318.877276) (xy 456.982811 -318.838567) (xy 457.028169 -318.806116)
			(xy 457.077769 -318.780615) (xy 457.130553 -318.762608) (xy 457.185396 -318.752478) (xy 457.24113 -318.750441)
			(xy 457.296567 -318.756541) (xy 457.350524 -318.770647) (xy 457.401853 -318.792459) (xy 457.449459 -318.821513)
			(xy 457.492327 -318.857188) (xy 457.529544 -318.898725) (xy 457.560317 -318.945238) (xy 457.583989 -318.995735)
			(xy 457.600057 -319.049142) (xy 457.608177 -319.104318) (xy 457.608686 -319.132204) (xy 457.608177 -319.16009)
			(xy 457.600057 -319.215266) (xy 457.583989 -319.268673) (xy 457.560317 -319.31917) (xy 457.529544 -319.365683)
			(xy 457.492327 -319.40722) (xy 457.449459 -319.442895) (xy 457.401853 -319.471949) (xy 457.350524 -319.493761)
			(xy 457.296567 -319.507867) (xy 457.24113 -319.513967) (xy 457.185396 -319.51193) (xy 457.130553 -319.5018)
			(xy 457.077769 -319.483793) (xy 457.028169 -319.458292) (xy 456.982811 -319.425841) (xy 456.942662 -319.387132)
			(xy 456.908576 -319.342989) (xy 456.88128 -319.294354) (xy 456.861357 -319.242263) (xy 456.849231 -319.187826)
			(xy 456.84516 -319.132204) (xy 453.350325 -319.132204) (xy 453.384636 -319.152013) (xy 453.426307 -319.185244)
			(xy 453.462559 -319.224315) (xy 453.492583 -319.268352) (xy 453.515709 -319.316373) (xy 453.531419 -319.367303)
			(xy 453.539362 -319.420007) (xy 453.53986 -319.446656) (xy 453.539362 -319.473305) (xy 453.531419 -319.526009)
			(xy 453.515709 -319.576939) (xy 453.492583 -319.62496) (xy 453.462559 -319.668997) (xy 453.426307 -319.708068)
			(xy 453.384636 -319.741299) (xy 453.338478 -319.767948) (xy 453.288864 -319.78742) (xy 453.236902 -319.79928)
			(xy 453.183752 -319.803264) (xy 453.130602 -319.79928) (xy 453.07864 -319.78742) (xy 453.029026 -319.767948)
			(xy 452.982868 -319.741299) (xy 452.941197 -319.708068) (xy 452.904945 -319.668997) (xy 452.874921 -319.62496)
			(xy 452.851795 -319.576939) (xy 452.836085 -319.526009) (xy 452.828142 -319.473305) (xy 447.726793 -319.473305)
			(xy 447.746289 -319.494317) (xy 447.776313 -319.538354) (xy 447.799439 -319.586375) (xy 447.815149 -319.637305)
			(xy 447.823092 -319.690009) (xy 447.82359 -319.716658) (xy 447.823166 -319.741706) (xy 447.816144 -319.791309)
			(xy 447.802234 -319.839435) (xy 447.792348 -319.862454) (xy 447.786873 -319.875882) (xy 447.782897 -319.904591)
			(xy 447.787149 -319.933262) (xy 447.799286 -319.959582) (xy 447.818329 -319.981432) (xy 447.842745 -319.99705)
			(xy 447.870566 -320.005178) (xy 447.885058 -320.00571) (xy 453.751696 -320.00571) (xy 453.765744 -320.005273)
			(xy 453.792779 -319.997632) (xy 453.816701 -319.9829) (xy 453.835693 -319.962197) (xy 453.848311 -319.937096)
			(xy 453.853599 -319.909504) (xy 453.852788 -319.895474) (xy 453.851518 -319.865248) (xy 453.852016 -319.838599)
			(xy 453.859959 -319.785895) (xy 453.875669 -319.734965) (xy 453.898795 -319.686944) (xy 453.928819 -319.642907)
			(xy 453.965071 -319.603836) (xy 454.006742 -319.570605) (xy 454.0529 -319.543956) (xy 454.102514 -319.524484)
			(xy 454.154476 -319.512624) (xy 454.207626 -319.508641) (xy 454.260776 -319.512624) (xy 454.312738 -319.524484)
			(xy 454.362352 -319.543956) (xy 454.40851 -319.570605) (xy 454.450181 -319.603836) (xy 454.486433 -319.642907)
			(xy 454.516457 -319.686944) (xy 454.539583 -319.734965) (xy 454.555293 -319.785895) (xy 454.563236 -319.838599)
			(xy 454.563734 -319.865248) (xy 454.562464 -319.895474) (xy 454.561731 -319.909492) (xy 454.56707 -319.93704)
			(xy 454.579699 -319.962098) (xy 454.598666 -319.982778) (xy 454.622542 -319.997521) (xy 454.649527 -320.005216)
			(xy 454.663556 -320.00571) (xy 455.054208 -320.00571) (xy 460.183484 -319.957958) (xy 460.871316 -319.270126)
			(xy 460.871316 -319.145666) (xy 460.870818 -319.131219) (xy 460.862729 -319.103481) (xy 460.847183 -319.079127)
			(xy 460.825428 -319.060114) (xy 460.799212 -319.047968) (xy 460.770641 -319.043665) (xy 460.756254 -319.045082)
			(xy 460.744434 -319.046538) (xy 460.720665 -319.048064) (xy 460.708756 -319.04813) (xy 460.682107 -319.047629)
			(xy 460.629406 -319.03968) (xy 460.578477 -319.023965) (xy 460.53046 -319.000836) (xy 460.486425 -318.970808)
			(xy 460.447358 -318.934554) (xy 460.414129 -318.892883) (xy 460.387482 -318.846724) (xy 460.368012 -318.79711)
			(xy 460.356153 -318.745149) (xy 460.35217 -318.692) (xy 460.356153 -318.638851) (xy 460.368012 -318.58689)
			(xy 460.387482 -318.537276) (xy 460.414129 -318.491117) (xy 460.447358 -318.449446) (xy 460.486425 -318.413192)
			(xy 460.53046 -318.383164) (xy 460.578477 -318.360035) (xy 460.629406 -318.34432) (xy 460.682107 -318.336371)
			(xy 460.708756 -318.335914) (xy 460.720665 -318.335977) (xy 460.744434 -318.337502) (xy 460.756254 -318.338962)
			(xy 460.770635 -318.340373) (xy 460.799189 -318.33603) (xy 460.825386 -318.32387) (xy 460.847135 -318.304864)
			(xy 460.862696 -318.280533) (xy 460.870827 -318.252818) (xy 460.871316 -318.238378) (xy 460.871316 -317.612268)
			(xy 460.870806 -317.596964) (xy 460.861757 -317.567723) (xy 460.844452 -317.542477) (xy 460.820444 -317.52349)
			(xy 460.791889 -317.512468) (xy 460.761351 -317.510402) (xy 460.746348 -317.513462) (xy 460.726254 -317.517872)
			(xy 460.685384 -317.522582) (xy 460.664814 -317.52286) (xy 460.638166 -317.522388) (xy 460.585464 -317.514446)
			(xy 460.534535 -317.498739) (xy 460.486516 -317.475615) (xy 460.44248 -317.445594) (xy 460.40341 -317.409344)
			(xy 460.370179 -317.367675) (xy 460.343531 -317.32152) (xy 460.324059 -317.271908) (xy 460.312199 -317.219947)
			(xy 460.308216 -317.1668) (xy 460.312199 -317.113653) (xy 460.324059 -317.061692) (xy 460.343531 -317.01208)
			(xy 460.370179 -316.965925) (xy 460.40341 -316.924256) (xy 460.44248 -316.888006) (xy 460.486516 -316.857985)
			(xy 460.534535 -316.834861) (xy 460.585464 -316.819154) (xy 460.638166 -316.811212) (xy 460.664814 -316.810644)
			(xy 460.685385 -316.810919) (xy 460.726255 -316.815626) (xy 460.746348 -316.820042) (xy 460.761355 -316.823053)
			(xy 460.791877 -316.820961) (xy 460.820416 -316.809937) (xy 460.844418 -316.790966) (xy 460.861737 -316.765746)
			(xy 460.870823 -316.736532) (xy 460.871316 -316.721236) (xy 460.871316 -315.912246) (xy 460.870803 -315.896944)
			(xy 460.861751 -315.86771) (xy 460.844445 -315.842469) (xy 460.820439 -315.823487) (xy 460.791888 -315.812468)
			(xy 460.761354 -315.810401) (xy 460.746348 -315.81344) (xy 460.726254 -315.81785) (xy 460.685384 -315.822561)
			(xy 460.664814 -315.822838) (xy 460.63816 -315.822366) (xy 460.585447 -315.814422) (xy 460.534507 -315.798711)
			(xy 460.486477 -315.775583) (xy 460.442431 -315.745555) (xy 460.403353 -315.709297) (xy 460.370115 -315.667619)
			(xy 460.34346 -315.621453) (xy 460.323984 -315.571831) (xy 460.312122 -315.519859) (xy 460.308138 -315.4667)
			(xy 460.312122 -315.413541) (xy 460.323984 -315.361569) (xy 460.34346 -315.311947) (xy 460.370115 -315.265781)
			(xy 460.403353 -315.224103) (xy 460.442431 -315.187845) (xy 460.486477 -315.157817) (xy 460.534507 -315.134689)
			(xy 460.585447 -315.118978) (xy 460.63816 -315.111034) (xy 460.664814 -315.110622) (xy 460.685385 -315.110897)
			(xy 460.726255 -315.115603) (xy 460.746348 -315.12002) (xy 460.761354 -315.123031) (xy 460.791874 -315.12094)
			(xy 460.820411 -315.109915) (xy 460.84441 -315.090943) (xy 460.861724 -315.065723) (xy 460.870805 -315.036509)
			(xy 460.871316 -315.021214) (xy 460.871316 -314.212224) (xy 460.8708 -314.196924) (xy 460.861744 -314.167696)
			(xy 460.844438 -314.142461) (xy 460.820434 -314.123484) (xy 460.791886 -314.112468) (xy 460.761357 -314.110401)
			(xy 460.746348 -314.113418) (xy 460.726254 -314.117829) (xy 460.685384 -314.122539) (xy 460.664814 -314.122816)
			(xy 460.636828 -314.122297) (xy 460.581544 -314.113543) (xy 460.52831 -314.096248) (xy 460.478437 -314.070839)
			(xy 460.433153 -314.037941) (xy 460.393574 -313.998363) (xy 460.360672 -313.953082) (xy 460.33526 -313.90321)
			(xy 460.317962 -313.849978) (xy 460.309205 -313.794694) (xy 460.308706 -313.766708) (xy 460.309221 -313.739255)
			(xy 460.317663 -313.685002) (xy 460.334332 -313.632687) (xy 460.358834 -313.583551) (xy 460.390588 -313.538758)
			(xy 460.428841 -313.499371) (xy 460.472686 -313.466321) (xy 460.521085 -313.440393) (xy 460.57289 -313.422202)
			(xy 460.59979 -313.416696) (xy 460.613297 -313.413729) (xy 460.638137 -313.4016) (xy 460.658817 -313.383256)
			(xy 460.673821 -313.36004) (xy 460.682053 -313.333651) (xy 460.682909 -313.306021) (xy 460.680054 -313.29249)
			(xy 460.675317 -313.27173) (xy 460.670225 -313.229453) (xy 460.669894 -313.208162) (xy 460.670461 -313.179619)
			(xy 460.679571 -313.123266) (xy 460.697553 -313.069086) (xy 460.723945 -313.018468) (xy 460.758072 -312.972707)
			(xy 460.799061 -312.932974) (xy 460.845862 -312.900287) (xy 460.871316 -312.88736) (xy 460.871316 -311.662318)
			(xy 460.870799 -311.647019) (xy 460.861742 -311.617792) (xy 460.844436 -311.592559) (xy 460.820432 -311.573583)
			(xy 460.791886 -311.562568) (xy 460.761357 -311.560501) (xy 460.746348 -311.563512) (xy 460.726254 -311.567923)
			(xy 460.685384 -311.572633) (xy 460.664814 -311.57291) (xy 460.638162 -311.572438) (xy 460.585453 -311.564495)
			(xy 460.534517 -311.548785) (xy 460.486491 -311.525659) (xy 460.442449 -311.495633) (xy 460.403373 -311.459378)
			(xy 460.370138 -311.417703) (xy 460.343486 -311.371541) (xy 460.324011 -311.321922) (xy 460.31215 -311.269955)
			(xy 460.308166 -311.2168) (xy 460.31215 -311.163645) (xy 460.324011 -311.111678) (xy 460.343486 -311.062059)
			(xy 460.370138 -311.015897) (xy 460.403373 -310.974222) (xy 460.442449 -310.937967) (xy 460.486491 -310.907941)
			(xy 460.534517 -310.884815) (xy 460.585453 -310.869105) (xy 460.638162 -310.861162) (xy 460.664814 -310.860694)
			(xy 460.685385 -310.860969) (xy 460.726255 -310.865676) (xy 460.746348 -310.870092) (xy 460.761352 -310.873104)
			(xy 460.79187 -310.871013) (xy 460.820404 -310.859987) (xy 460.844399 -310.841015) (xy 460.861708 -310.815793)
			(xy 460.870782 -310.78658) (xy 460.871316 -310.771286) (xy 460.871316 -309.962296) (xy 460.870796 -309.946999)
			(xy 460.861735 -309.917778) (xy 460.844428 -309.892551) (xy 460.820427 -309.87358) (xy 460.791884 -309.862567)
			(xy 460.76136 -309.860501) (xy 460.746348 -309.86349) (xy 460.726254 -309.867901) (xy 460.685384 -309.872612)
			(xy 460.664814 -309.872888) (xy 460.638164 -309.872416) (xy 460.585458 -309.864474) (xy 460.534525 -309.848765)
			(xy 460.486502 -309.82564) (xy 460.442462 -309.795615) (xy 460.403389 -309.759363) (xy 460.370156 -309.717691)
			(xy 460.343505 -309.671532) (xy 460.324032 -309.621916) (xy 460.312171 -309.569952) (xy 460.308188 -309.5168)
			(xy 460.312171 -309.463648) (xy 460.324032 -309.411684) (xy 460.343505 -309.362068) (xy 460.370156 -309.315909)
			(xy 460.403389 -309.274237) (xy 460.442462 -309.237985) (xy 460.486502 -309.20796) (xy 460.534525 -309.184835)
			(xy 460.585458 -309.169126) (xy 460.638164 -309.161184) (xy 460.664814 -309.160672) (xy 460.685385 -309.160947)
			(xy 460.726255 -309.165654) (xy 460.746348 -309.17007) (xy 460.761351 -309.173082) (xy 460.791867 -309.170991)
			(xy 460.820399 -309.159965) (xy 460.844391 -309.140992) (xy 460.861695 -309.11577) (xy 460.870763 -309.086557)
			(xy 460.871316 -309.071264) (xy 460.871316 -308.262274) (xy 460.870807 -308.246969) (xy 460.861759 -308.217727)
			(xy 460.844454 -308.192479) (xy 460.820446 -308.173491) (xy 460.79189 -308.162469) (xy 460.76135 -308.160402)
			(xy 460.746348 -308.163468) (xy 460.726254 -308.167878) (xy 460.685384 -308.172588) (xy 460.664814 -308.172866)
			(xy 460.638165 -308.172394) (xy 460.585463 -308.164452) (xy 460.534533 -308.148744) (xy 460.486513 -308.125621)
			(xy 460.442476 -308.095598) (xy 460.403406 -308.059348) (xy 460.370175 -308.017679) (xy 460.343525 -307.971522)
			(xy 460.324053 -307.921909) (xy 460.312193 -307.869948) (xy 460.30821 -307.8168) (xy 460.312193 -307.763652)
			(xy 460.324053 -307.711691) (xy 460.343525 -307.662078) (xy 460.370175 -307.615921) (xy 460.403406 -307.574252)
			(xy 460.442476 -307.538002) (xy 460.486513 -307.507979) (xy 460.534533 -307.484856) (xy 460.585463 -307.469148)
			(xy 460.638165 -307.461206) (xy 460.664814 -307.46065) (xy 460.685385 -307.460925) (xy 460.726255 -307.465632)
			(xy 460.746348 -307.470048) (xy 460.761355 -307.473059) (xy 460.791878 -307.470967) (xy 460.820417 -307.459943)
			(xy 460.84442 -307.440972) (xy 460.86174 -307.415752) (xy 460.870828 -307.386539) (xy 460.871316 -307.371242)
			(xy 460.871316 -306.562252) (xy 460.870804 -306.546949) (xy 460.861752 -306.517713) (xy 460.844447 -306.492471)
			(xy 460.82044 -306.473488) (xy 460.791888 -306.462468) (xy 460.761353 -306.460401) (xy 460.746348 -306.463446)
			(xy 460.726254 -306.467856) (xy 460.685384 -306.472566) (xy 460.664814 -306.472844) (xy 460.638159 -306.472372)
			(xy 460.585446 -306.464428) (xy 460.534504 -306.448717) (xy 460.486474 -306.425588) (xy 460.442427 -306.395559)
			(xy 460.403348 -306.359301) (xy 460.37011 -306.317623) (xy 460.343455 -306.271456) (xy 460.323979 -306.221832)
			(xy 460.312116 -306.16986) (xy 460.308132 -306.1167) (xy 460.312116 -306.06354) (xy 460.323979 -306.011568)
			(xy 460.343455 -305.961944) (xy 460.37011 -305.915777) (xy 460.403348 -305.874099) (xy 460.442427 -305.837841)
			(xy 460.486474 -305.807812) (xy 460.534504 -305.784683) (xy 460.585446 -305.768972) (xy 460.638159 -305.761028)
			(xy 460.664814 -305.760628) (xy 460.685385 -305.760903) (xy 460.726255 -305.765609) (xy 460.746348 -305.770026)
			(xy 460.761354 -305.773037) (xy 460.791875 -305.770946) (xy 460.820412 -305.759921) (xy 460.844412 -305.74095)
			(xy 460.861728 -305.715729) (xy 460.87081 -305.686516) (xy 460.871316 -305.67122) (xy 460.871316 -304.86223)
			(xy 460.870801 -304.84693) (xy 460.861746 -304.817699) (xy 460.84444 -304.792463) (xy 460.820435 -304.773485)
			(xy 460.791886 -304.762468) (xy 460.761356 -304.760401) (xy 460.746348 -304.763424) (xy 460.726254 -304.767834)
			(xy 460.685384 -304.772545) (xy 460.664814 -304.772822) (xy 460.638161 -304.77235) (xy 460.585451 -304.764407)
			(xy 460.534513 -304.748696) (xy 460.486485 -304.725569) (xy 460.442441 -304.695542) (xy 460.403365 -304.659286)
			(xy 460.370128 -304.61761) (xy 460.343475 -304.571447) (xy 460.324 -304.521826) (xy 460.312138 -304.469857)
			(xy 460.308154 -304.4167) (xy 460.312138 -304.363543) (xy 460.324 -304.311574) (xy 460.343475 -304.261953)
			(xy 460.370128 -304.21579) (xy 460.403365 -304.174114) (xy 460.442441 -304.137858) (xy 460.486485 -304.107831)
			(xy 460.534513 -304.084704) (xy 460.585451 -304.068993) (xy 460.638161 -304.06105) (xy 460.664814 -304.060606)
			(xy 460.685385 -304.060881) (xy 460.726255 -304.065588) (xy 460.746348 -304.070004) (xy 460.761353 -304.073016)
			(xy 460.791872 -304.070924) (xy 460.820407 -304.059899) (xy 460.844404 -304.040927) (xy 460.861715 -304.015706)
			(xy 460.870792 -303.986493) (xy 460.871316 -303.971198) (xy 460.871316 -302.312324) (xy 460.8708 -302.297024)
			(xy 460.861744 -302.267796) (xy 460.844438 -302.242561) (xy 460.820434 -302.223584) (xy 460.791886 -302.212568)
			(xy 460.761357 -302.210501) (xy 460.746348 -302.213518) (xy 460.726254 -302.217929) (xy 460.685384 -302.222639)
			(xy 460.664814 -302.222916) (xy 460.638162 -302.222444) (xy 460.585452 -302.214501) (xy 460.534515 -302.198791)
			(xy 460.486488 -302.175664) (xy 460.442445 -302.145637) (xy 460.403369 -302.109382) (xy 460.370133 -302.067707)
			(xy 460.34348 -302.021544) (xy 460.324005 -301.971924) (xy 460.312144 -301.919956) (xy 460.30816 -301.8668)
			(xy 460.312144 -301.813644) (xy 460.324005 -301.761676) (xy 460.34348 -301.712056) (xy 460.370133 -301.665893)
			(xy 460.403369 -301.624218) (xy 460.442445 -301.587963) (xy 460.486488 -301.557936) (xy 460.534515 -301.534809)
			(xy 460.585452 -301.519099) (xy 460.638162 -301.511156) (xy 460.664814 -301.5107) (xy 460.685385 -301.510975)
			(xy 460.726255 -301.515682) (xy 460.746348 -301.520098) (xy 460.761353 -301.52311) (xy 460.791871 -301.521018)
			(xy 460.820405 -301.509993) (xy 460.844401 -301.491021) (xy 460.861712 -301.4658) (xy 460.870787 -301.436587)
			(xy 460.871316 -301.421292) (xy 460.871316 -300.612302) (xy 460.870797 -300.597005) (xy 460.861737 -300.567782)
			(xy 460.84443 -300.542553) (xy 460.820428 -300.523581) (xy 460.791884 -300.512567) (xy 460.761359 -300.510501)
			(xy 460.746348 -300.513496) (xy 460.726254 -300.517907) (xy 460.685384 -300.522618) (xy 460.664814 -300.522894)
			(xy 460.638163 -300.522422) (xy 460.585457 -300.51448) (xy 460.534523 -300.49877) (xy 460.486499 -300.475645)
			(xy 460.442459 -300.44562) (xy 460.403385 -300.409367) (xy 460.370151 -300.367694) (xy 460.3435 -300.321534)
			(xy 460.324026 -300.271918) (xy 460.312165 -300.219952) (xy 460.308182 -300.1668) (xy 460.312165 -300.113648)
			(xy 460.324026 -300.061682) (xy 460.3435 -300.012066) (xy 460.370151 -299.965906) (xy 460.403385 -299.924233)
			(xy 460.442459 -299.88798) (xy 460.486499 -299.857955) (xy 460.534523 -299.83483) (xy 460.585457 -299.81912)
			(xy 460.638163 -299.811178) (xy 460.664814 -299.810678) (xy 460.685385 -299.810953) (xy 460.726255 -299.81566)
			(xy 460.746348 -299.820076) (xy 460.761352 -299.823088) (xy 460.791868 -299.820997) (xy 460.8204 -299.809971)
			(xy 460.844393 -299.790998) (xy 460.861699 -299.765776) (xy 460.870768 -299.736564) (xy 460.871316 -299.72127)
			(xy 460.871316 -298.91228) (xy 460.870807 -298.896974) (xy 460.861761 -298.867731) (xy 460.844456 -298.842481)
			(xy 460.820447 -298.823492) (xy 460.79189 -298.812469) (xy 460.761349 -298.810402) (xy 460.746348 -298.813474)
			(xy 460.726254 -298.817884) (xy 460.685384 -298.822594) (xy 460.664814 -298.822872) (xy 460.638165 -298.8224)
			(xy 460.585462 -298.814458) (xy 460.534531 -298.79875) (xy 460.48651 -298.775626) (xy 460.442472 -298.745603)
			(xy 460.403401 -298.709352) (xy 460.37017 -298.667682) (xy 460.34352 -298.621525) (xy 460.324047 -298.571911)
			(xy 460.312187 -298.519949) (xy 460.308204 -298.4668) (xy 460.312187 -298.413651) (xy 460.324047 -298.361689)
			(xy 460.34352 -298.312075) (xy 460.37017 -298.265918) (xy 460.403401 -298.224248) (xy 460.442472 -298.187997)
			(xy 460.48651 -298.157974) (xy 460.534531 -298.13485) (xy 460.585462 -298.119142) (xy 460.638165 -298.1112)
			(xy 460.664814 -298.110656) (xy 460.685385 -298.110931) (xy 460.726255 -298.115638) (xy 460.746348 -298.120054)
			(xy 460.761355 -298.123065) (xy 460.791879 -298.120973) (xy 460.820419 -298.109948) (xy 460.844423 -298.090978)
			(xy 460.861744 -298.065759) (xy 460.870833 -298.036545) (xy 460.871316 -298.021248) (xy 460.871316 -297.212258)
			(xy 460.870804 -297.196955) (xy 460.861754 -297.167717) (xy 460.844449 -297.142473) (xy 460.820442 -297.123489)
			(xy 460.791889 -297.112468) (xy 460.761352 -297.110401) (xy 460.746348 -297.113452) (xy 460.726254 -297.117862)
			(xy 460.685384 -297.122572) (xy 460.664814 -297.12285) (xy 460.638159 -297.122378) (xy 460.585444 -297.114434)
			(xy 460.534502 -297.098722) (xy 460.486471 -297.075593) (xy 460.442424 -297.045564) (xy 460.403344 -297.009305)
			(xy 460.370105 -296.967626) (xy 460.34345 -296.921459) (xy 460.323973 -296.871834) (xy 460.31211 -296.819861)
			(xy 460.308126 -296.7667) (xy 460.31211 -296.713539) (xy 460.323973 -296.661566) (xy 460.34345 -296.611941)
			(xy 460.370105 -296.565774) (xy 460.403344 -296.524095) (xy 460.442424 -296.487836) (xy 460.486471 -296.457807)
			(xy 460.534502 -296.434678) (xy 460.585444 -296.418966) (xy 460.638159 -296.411022) (xy 460.664814 -296.410634)
			(xy 460.685385 -296.410909) (xy 460.726255 -296.415615) (xy 460.746348 -296.420032) (xy 460.761354 -296.423043)
			(xy 460.791876 -296.420951) (xy 460.820413 -296.409927) (xy 460.844414 -296.390956) (xy 460.861731 -296.365735)
			(xy 460.870815 -296.336522) (xy 460.871316 -296.321226) (xy 460.871316 -295.512236) (xy 460.870801 -295.496935)
			(xy 460.861748 -295.467703) (xy 460.844442 -295.442465) (xy 460.820437 -295.423486) (xy 460.791887 -295.412468)
			(xy 460.761355 -295.410401) (xy 460.746348 -295.41343) (xy 460.726254 -295.41784) (xy 460.685384 -295.422551)
			(xy 460.664814 -295.422828) (xy 460.638161 -295.422356) (xy 460.585449 -295.414413) (xy 460.53451 -295.398702)
			(xy 460.486482 -295.375574) (xy 460.442437 -295.345547) (xy 460.40336 -295.30929) (xy 460.370123 -295.267614)
			(xy 460.343469 -295.221449) (xy 460.323994 -295.171828) (xy 460.312132 -295.119858) (xy 460.308148 -295.0667)
			(xy 460.312132 -295.013542) (xy 460.323994 -294.961572) (xy 460.343469 -294.911951) (xy 460.370123 -294.865786)
			(xy 460.40336 -294.82411) (xy 460.442437 -294.787853) (xy 460.486482 -294.757826) (xy 460.53451 -294.734698)
			(xy 460.585449 -294.718987) (xy 460.638161 -294.711044) (xy 460.664814 -294.710612) (xy 460.685385 -294.710887)
			(xy 460.726255 -294.715595) (xy 460.746348 -294.72001) (xy 460.761353 -294.723022) (xy 460.791873 -294.72093)
			(xy 460.820408 -294.709905) (xy 460.844406 -294.690933) (xy 460.861719 -294.665712) (xy 460.870797 -294.636499)
			(xy 460.871316 -294.621204) (xy 460.871316 -292.96233) (xy 460.870801 -292.94703) (xy 460.861746 -292.917799)
			(xy 460.84444 -292.892563) (xy 460.820435 -292.873585) (xy 460.791886 -292.862568) (xy 460.761356 -292.860501)
			(xy 460.746348 -292.863524) (xy 460.726254 -292.867934) (xy 460.685384 -292.872645) (xy 460.664814 -292.872922)
			(xy 460.638161 -292.87245) (xy 460.585451 -292.864507) (xy 460.534513 -292.848796) (xy 460.486485 -292.825669)
			(xy 460.442441 -292.795642) (xy 460.403365 -292.759386) (xy 460.370128 -292.71771) (xy 460.343475 -292.671547)
			(xy 460.324 -292.621926) (xy 460.312138 -292.569957) (xy 460.308154 -292.5168) (xy 460.312138 -292.463643)
			(xy 460.324 -292.411674) (xy 460.343475 -292.362053) (xy 460.370128 -292.31589) (xy 460.403365 -292.274214)
			(xy 460.442441 -292.237958) (xy 460.486485 -292.207931) (xy 460.534513 -292.184804) (xy 460.585451 -292.169093)
			(xy 460.638161 -292.16115) (xy 460.664814 -292.160706) (xy 460.685385 -292.160981) (xy 460.726255 -292.165688)
			(xy 460.746348 -292.170104) (xy 460.761353 -292.173116) (xy 460.791872 -292.171024) (xy 460.820407 -292.159999)
			(xy 460.844404 -292.141027) (xy 460.861715 -292.115806) (xy 460.870792 -292.086593) (xy 460.871316 -292.071298)
			(xy 460.871316 -291.262308) (xy 460.870798 -291.24701) (xy 460.861739 -291.217786) (xy 460.844432 -291.192555)
			(xy 460.82043 -291.173582) (xy 460.791885 -291.162567) (xy 460.761359 -291.160501) (xy 460.746348 -291.163502)
			(xy 460.726254 -291.167913) (xy 460.685384 -291.172624) (xy 460.664814 -291.1729) (xy 460.638163 -291.172428)
			(xy 460.585455 -291.164485) (xy 460.534521 -291.148776) (xy 460.486496 -291.12565) (xy 460.442455 -291.095625)
			(xy 460.403381 -291.059371) (xy 460.370146 -291.017698) (xy 460.343495 -290.971537) (xy 460.324021 -290.921919)
			(xy 460.312159 -290.869953) (xy 460.308176 -290.8168) (xy 460.312159 -290.763647) (xy 460.324021 -290.711681)
			(xy 460.343495 -290.662063) (xy 460.370146 -290.615902) (xy 460.403381 -290.574229) (xy 460.442455 -290.537975)
			(xy 460.486496 -290.50795) (xy 460.534521 -290.484824) (xy 460.585455 -290.469115) (xy 460.638163 -290.461172)
			(xy 460.664814 -290.460684) (xy 460.685385 -290.460959) (xy 460.726255 -290.465666) (xy 460.746348 -290.470082)
			(xy 460.761352 -290.473094) (xy 460.791869 -290.471002) (xy 460.820401 -290.459977) (xy 460.844395 -290.441004)
			(xy 460.861702 -290.415783) (xy 460.870773 -290.38657) (xy 460.871316 -290.371276) (xy 460.871316 -289.562286)
			(xy 460.870808 -289.54698) (xy 460.861763 -289.517735) (xy 460.844458 -289.492483) (xy 460.820449 -289.473493)
			(xy 460.791891 -289.462469) (xy 460.761349 -289.460402) (xy 460.746348 -289.46348) (xy 460.726254 -289.467891)
			(xy 460.685384 -289.472602) (xy 460.664814 -289.472878) (xy 460.638164 -289.472406) (xy 460.58546 -289.464464)
			(xy 460.534529 -289.448755) (xy 460.486507 -289.425631) (xy 460.442469 -289.395608) (xy 460.403397 -289.359356)
			(xy 460.370165 -289.317685) (xy 460.343514 -289.271527) (xy 460.324042 -289.221913) (xy 460.312181 -289.16995)
			(xy 460.308198 -289.1168) (xy 460.312181 -289.06365) (xy 460.324042 -289.011687) (xy 460.343514 -288.962073)
			(xy 460.370165 -288.915915) (xy 460.403397 -288.874244) (xy 460.442469 -288.837992) (xy 460.486507 -288.807969)
			(xy 460.534529 -288.784845) (xy 460.58546 -288.769136) (xy 460.638164 -288.761194) (xy 460.664814 -288.760662)
			(xy 460.685385 -288.760937) (xy 460.726255 -288.765644) (xy 460.746348 -288.77006) (xy 460.761351 -288.773072)
			(xy 460.791866 -288.770981) (xy 460.820396 -288.759955) (xy 460.844387 -288.740982) (xy 460.86169 -288.715759)
			(xy 460.870755 -288.686547) (xy 460.871316 -288.671254) (xy 460.871316 -287.862264) (xy 460.870805 -287.84696)
			(xy 460.861756 -287.817721) (xy 460.844451 -287.792475) (xy 460.820443 -287.773489) (xy 460.791889 -287.762468)
			(xy 460.761351 -287.760401) (xy 460.746348 -287.763458) (xy 460.726254 -287.767868) (xy 460.685384 -287.772578)
			(xy 460.664814 -287.772856) (xy 460.638159 -287.772384) (xy 460.585443 -287.76444) (xy 460.5345 -287.748728)
			(xy 460.486468 -287.725599) (xy 460.44242 -287.695569) (xy 460.40334 -287.659309) (xy 460.3701 -287.617629)
			(xy 460.343444 -287.571461) (xy 460.323967 -287.521836) (xy 460.312104 -287.469862) (xy 460.30812 -287.4167)
			(xy 460.312104 -287.363538) (xy 460.323967 -287.311564) (xy 460.343444 -287.261939) (xy 460.3701 -287.215771)
			(xy 460.40334 -287.174091) (xy 460.44242 -287.137831) (xy 460.486468 -287.107801) (xy 460.5345 -287.084672)
			(xy 460.585443 -287.06896) (xy 460.638159 -287.061016) (xy 460.664814 -287.06064) (xy 460.685385 -287.060915)
			(xy 460.726255 -287.065622) (xy 460.746348 -287.070038) (xy 460.761354 -287.073049) (xy 460.791877 -287.070957)
			(xy 460.820415 -287.059933) (xy 460.844417 -287.040962) (xy 460.861735 -287.015742) (xy 460.87082 -286.986528)
			(xy 460.871316 -286.971232) (xy 460.871316 -286.162242) (xy 460.870802 -286.14694) (xy 460.861749 -286.117707)
			(xy 460.844444 -286.092467) (xy 460.820438 -286.073486) (xy 460.791887 -286.062468) (xy 460.761354 -286.060401)
			(xy 460.746348 -286.063436) (xy 460.726254 -286.067846) (xy 460.685384 -286.072557) (xy 460.664814 -286.072834)
			(xy 460.63816 -286.072362) (xy 460.585448 -286.064419) (xy 460.534508 -286.048707) (xy 460.486479 -286.02558)
			(xy 460.442434 -285.995551) (xy 460.403356 -285.959294) (xy 460.370118 -285.917617) (xy 460.343464 -285.871452)
			(xy 460.323988 -285.821829) (xy 460.312126 -285.769858) (xy 460.308142 -285.7167) (xy 460.312126 -285.663542)
			(xy 460.323988 -285.611571) (xy 460.343464 -285.561948) (xy 460.370118 -285.515783) (xy 460.403356 -285.474106)
			(xy 460.442434 -285.437849) (xy 460.486479 -285.40782) (xy 460.534508 -285.384693) (xy 460.585448 -285.368981)
			(xy 460.63816 -285.361038) (xy 460.664814 -285.360618) (xy 460.685385 -285.360893) (xy 460.726255 -285.365599)
			(xy 460.746348 -285.370016) (xy 460.761353 -285.373027) (xy 460.791874 -285.370936) (xy 460.82041 -285.359911)
			(xy 460.844408 -285.340939) (xy 460.861722 -285.315719) (xy 460.870802 -285.286505) (xy 460.871316 -285.27121)
			(xy 460.871316 -283.612082) (xy 460.870808 -283.596776) (xy 460.861762 -283.567532) (xy 460.844457 -283.542282)
			(xy 460.820448 -283.523292) (xy 460.79189 -283.512269) (xy 460.761349 -283.510202) (xy 460.746348 -283.513276)
			(xy 460.726254 -283.517687) (xy 460.685384 -283.522398) (xy 460.664814 -283.522674) (xy 460.638165 -283.522202)
			(xy 460.585461 -283.51426) (xy 460.53453 -283.498552) (xy 460.486509 -283.475428) (xy 460.442471 -283.445405)
			(xy 460.4034 -283.409153) (xy 460.370168 -283.367483) (xy 460.343518 -283.321326) (xy 460.324045 -283.271712)
			(xy 460.312185 -283.219749) (xy 460.308202 -283.1666) (xy 460.312185 -283.113451) (xy 460.324045 -283.061488)
			(xy 460.343518 -283.011874) (xy 460.370168 -282.965717) (xy 460.4034 -282.924047) (xy 460.442471 -282.887795)
			(xy 460.486509 -282.857772) (xy 460.53453 -282.834648) (xy 460.585461 -282.81894) (xy 460.638165 -282.810998)
			(xy 460.664814 -282.810458) (xy 460.685385 -282.810733) (xy 460.726255 -282.81544) (xy 460.746348 -282.819856)
			(xy 460.761351 -282.822868) (xy 460.791865 -282.820777) (xy 460.820395 -282.809751) (xy 460.844385 -282.790778)
			(xy 460.861687 -282.765555) (xy 460.870752 -282.736343) (xy 460.871316 -282.72105) (xy 460.871316 -281.912314)
			(xy 460.870798 -281.897015) (xy 460.861741 -281.867789) (xy 460.844434 -281.842557) (xy 460.820431 -281.823582)
			(xy 460.791885 -281.812568) (xy 460.761358 -281.810501) (xy 460.746348 -281.813508) (xy 460.726254 -281.817919)
			(xy 460.685384 -281.822629) (xy 460.664814 -281.822906) (xy 460.638162 -281.822434) (xy 460.585454 -281.814491)
			(xy 460.534518 -281.798781) (xy 460.486493 -281.775655) (xy 460.442451 -281.74563) (xy 460.403376 -281.709375)
			(xy 460.370141 -281.667701) (xy 460.343489 -281.62154) (xy 460.324015 -281.571921) (xy 460.312153 -281.519954)
			(xy 460.30817 -281.4668) (xy 460.312153 -281.413646) (xy 460.324015 -281.361679) (xy 460.343489 -281.31206)
			(xy 460.370141 -281.265899) (xy 460.403376 -281.224225) (xy 460.442451 -281.18797) (xy 460.486493 -281.157945)
			(xy 460.534518 -281.134819) (xy 460.585454 -281.119109) (xy 460.638162 -281.111166) (xy 460.664814 -281.11069)
			(xy 460.685385 -281.110965) (xy 460.726255 -281.115672) (xy 460.746348 -281.120088) (xy 460.761352 -281.1231)
			(xy 460.79187 -281.121009) (xy 460.820403 -281.109983) (xy 460.844398 -281.091011) (xy 460.861706 -281.065789)
			(xy 460.870778 -281.036576) (xy 460.871316 -281.021282) (xy 460.871316 -280.212292) (xy 460.870809 -280.196985)
			(xy 460.861765 -280.167738) (xy 460.84446 -280.142485) (xy 460.82045 -280.123493) (xy 460.791891 -280.112469)
			(xy 460.761348 -280.110402) (xy 460.746348 -280.113486) (xy 460.726254 -280.117897) (xy 460.685384 -280.122608)
			(xy 460.664814 -280.122884) (xy 460.638164 -280.122412) (xy 460.585459 -280.11447) (xy 460.534526 -280.098761)
			(xy 460.486504 -280.075636) (xy 460.442465 -280.045612) (xy 460.403392 -280.00936) (xy 460.37016 -279.967689)
			(xy 460.343509 -279.92153) (xy 460.324036 -279.871915) (xy 460.312175 -279.819951) (xy 460.308192 -279.7668)
			(xy 460.312175 -279.713649) (xy 460.324036 -279.661685) (xy 460.343509 -279.61207) (xy 460.37016 -279.565911)
			(xy 460.403392 -279.52424) (xy 460.442465 -279.487988) (xy 460.486504 -279.457964) (xy 460.534526 -279.434839)
			(xy 460.585459 -279.41913) (xy 460.638164 -279.411188) (xy 460.664814 -279.410668) (xy 460.685385 -279.410943)
			(xy 460.726255 -279.41565) (xy 460.746348 -279.420066) (xy 460.761351 -279.423078) (xy 460.791867 -279.420987)
			(xy 460.820398 -279.409961) (xy 460.844389 -279.390988) (xy 460.861693 -279.365766) (xy 460.87076 -279.336553)
			(xy 460.871316 -279.32126) (xy 460.871316 -278.51227) (xy 460.870806 -278.496965) (xy 460.861758 -278.467725)
			(xy 460.844453 -278.442477) (xy 460.820445 -278.42349) (xy 460.79189 -278.412468) (xy 460.761351 -278.410402)
			(xy 460.746348 -278.413464) (xy 460.726254 -278.417874) (xy 460.685384 -278.422584) (xy 460.664814 -278.422862)
			(xy 460.638166 -278.42239) (xy 460.585464 -278.414448) (xy 460.534534 -278.39874) (xy 460.486515 -278.375617)
			(xy 460.442479 -278.345595) (xy 460.403409 -278.309345) (xy 460.370178 -278.267676) (xy 460.343529 -278.22152)
			(xy 460.324057 -278.171908) (xy 460.312197 -278.119948) (xy 460.308214 -278.0668) (xy 460.312197 -278.013652)
			(xy 460.324057 -277.961692) (xy 460.343529 -277.91208) (xy 460.370178 -277.865924) (xy 460.403409 -277.824255)
			(xy 460.442479 -277.788005) (xy 460.486515 -277.757983) (xy 460.534534 -277.73486) (xy 460.585464 -277.719152)
			(xy 460.638166 -277.71121) (xy 460.664814 -277.710646) (xy 460.685385 -277.710921) (xy 460.726255 -277.715628)
			(xy 460.746348 -277.720044) (xy 460.761355 -277.723055) (xy 460.791877 -277.720963) (xy 460.820416 -277.709939)
			(xy 460.844419 -277.690968) (xy 460.861738 -277.665748) (xy 460.870825 -277.636534) (xy 460.871316 -277.621238)
			(xy 460.871316 -276.812248) (xy 460.870803 -276.796946) (xy 460.861751 -276.767711) (xy 460.844446 -276.742469)
			(xy 460.820439 -276.723487) (xy 460.791888 -276.712468) (xy 460.761354 -276.710401) (xy 460.746348 -276.713442)
			(xy 460.726254 -276.717852) (xy 460.685384 -276.722563) (xy 460.664814 -276.72284) (xy 460.63816 -276.722368)
			(xy 460.585447 -276.714424) (xy 460.534506 -276.698713) (xy 460.486476 -276.675585) (xy 460.44243 -276.645556)
			(xy 460.403351 -276.609298) (xy 460.370113 -276.56762) (xy 460.343459 -276.521454) (xy 460.323982 -276.471831)
			(xy 460.31212 -276.419859) (xy 460.308136 -276.3667) (xy 460.31212 -276.313541) (xy 460.323982 -276.261569)
			(xy 460.343459 -276.211946) (xy 460.370113 -276.16578) (xy 460.403351 -276.124102) (xy 460.44243 -276.087844)
			(xy 460.486476 -276.057815) (xy 460.534506 -276.034687) (xy 460.585447 -276.018976) (xy 460.63816 -276.011032)
			(xy 460.664814 -276.010624) (xy 460.685385 -276.010899) (xy 460.726255 -276.015605) (xy 460.746348 -276.020022)
			(xy 460.761354 -276.023033) (xy 460.791874 -276.020942) (xy 460.820411 -276.009917) (xy 460.844411 -275.990946)
			(xy 460.861725 -275.965725) (xy 460.870807 -275.936512) (xy 460.871316 -275.921216) (xy 460.871316 -274.262088)
			(xy 460.870809 -274.246781) (xy 460.861763 -274.217536) (xy 460.844459 -274.192284) (xy 460.820449 -274.173293)
			(xy 460.791891 -274.162269) (xy 460.761348 -274.160202) (xy 460.746348 -274.163282) (xy 460.726254 -274.167693)
			(xy 460.685384 -274.172404) (xy 460.664814 -274.17268) (xy 460.638164 -274.172208) (xy 460.58546 -274.164266)
			(xy 460.534528 -274.148557) (xy 460.486506 -274.125433) (xy 460.442467 -274.095409) (xy 460.403395 -274.059157)
			(xy 460.370163 -274.017487) (xy 460.343513 -273.971328) (xy 460.32404 -273.921713) (xy 460.312179 -273.86975)
			(xy 460.308196 -273.8166) (xy 460.312179 -273.76345) (xy 460.32404 -273.711487) (xy 460.343513 -273.661872)
			(xy 460.370163 -273.615713) (xy 460.403395 -273.574043) (xy 460.442467 -273.537791) (xy 460.486506 -273.507767)
			(xy 460.534528 -273.484643) (xy 460.58546 -273.468934) (xy 460.638164 -273.460992) (xy 460.664814 -273.460464)
			(xy 460.685385 -273.460739) (xy 460.726255 -273.465446) (xy 460.746348 -273.469862) (xy 460.761351 -273.472874)
			(xy 460.791866 -273.470783) (xy 460.820397 -273.459757) (xy 460.844388 -273.440784) (xy 460.861691 -273.415562)
			(xy 460.870757 -273.386349) (xy 460.871316 -273.371056) (xy 460.871316 -272.56232) (xy 460.870799 -272.547021)
			(xy 460.861743 -272.517793) (xy 460.844436 -272.492559) (xy 460.820433 -272.473583) (xy 460.791886 -272.462568)
			(xy 460.761357 -272.460501) (xy 460.746348 -272.463514) (xy 460.726254 -272.467925) (xy 460.685384 -272.472635)
			(xy 460.664814 -272.472912) (xy 460.638162 -272.47244) (xy 460.585453 -272.464497) (xy 460.534516 -272.448787)
			(xy 460.48649 -272.425661) (xy 460.442447 -272.395634) (xy 460.403372 -272.359379) (xy 460.370137 -272.317705)
			(xy 460.343484 -272.271542) (xy 460.324009 -272.221923) (xy 460.312148 -272.169955) (xy 460.308164 -272.1168)
			(xy 460.312148 -272.063645) (xy 460.324009 -272.011677) (xy 460.343484 -271.962058) (xy 460.370137 -271.915895)
			(xy 460.403372 -271.874221) (xy 460.442447 -271.837966) (xy 460.48649 -271.807939) (xy 460.534516 -271.784813)
			(xy 460.585453 -271.769103) (xy 460.638162 -271.76116) (xy 460.664814 -271.760696) (xy 460.685385 -271.760971)
			(xy 460.726255 -271.765678) (xy 460.746348 -271.770094) (xy 460.761352 -271.773106) (xy 460.791871 -271.771015)
			(xy 460.820404 -271.759989) (xy 460.8444 -271.741017) (xy 460.861709 -271.715795) (xy 460.870783 -271.686582)
			(xy 460.871316 -271.671288) (xy 460.871316 -270.862298) (xy 460.870796 -270.847001) (xy 460.861736 -270.817779)
			(xy 460.844429 -270.792551) (xy 460.820427 -270.77358) (xy 460.791884 -270.762567) (xy 460.76136 -270.760501)
			(xy 460.746348 -270.763492) (xy 460.726254 -270.767903) (xy 460.685384 -270.772614) (xy 460.664814 -270.77289)
			(xy 460.638164 -270.772418) (xy 460.585458 -270.764476) (xy 460.534524 -270.748767) (xy 460.486501 -270.725641)
			(xy 460.442461 -270.695617) (xy 460.403388 -270.659364) (xy 460.370155 -270.617692) (xy 460.343504 -270.571533)
			(xy 460.32403 -270.521916) (xy 460.312169 -270.469952) (xy 460.308186 -270.4168) (xy 460.312169 -270.363648)
			(xy 460.32403 -270.311684) (xy 460.343504 -270.262067) (xy 460.370155 -270.215908) (xy 460.403388 -270.174236)
			(xy 460.442461 -270.137983) (xy 460.486501 -270.107959) (xy 460.534524 -270.084833) (xy 460.585458 -270.069124)
			(xy 460.638164 -270.061182) (xy 460.664814 -270.060674) (xy 460.685385 -270.060949) (xy 460.726255 -270.065656)
			(xy 460.746348 -270.070072) (xy 460.761351 -270.073084) (xy 460.791868 -270.070993) (xy 460.820399 -270.059967)
			(xy 460.844391 -270.040994) (xy 460.861696 -270.015772) (xy 460.870765 -269.98656) (xy 460.871316 -269.971266)
			(xy 460.871316 -269.162276) (xy 460.870807 -269.146971) (xy 460.86176 -269.117728) (xy 460.844455 -269.092479)
			(xy 460.820446 -269.073491) (xy 460.79189 -269.062469) (xy 460.76135 -269.060402) (xy 460.746348 -269.06347)
			(xy 460.726254 -269.06788) (xy 460.685384 -269.07259) (xy 460.664814 -269.072868) (xy 460.638165 -269.072396)
			(xy 460.585463 -269.064454) (xy 460.534532 -269.048746) (xy 460.486512 -269.025622) (xy 460.442475 -268.9956)
			(xy 460.403404 -268.959349) (xy 460.370173 -268.91768) (xy 460.343523 -268.871523) (xy 460.324051 -268.82191)
			(xy 460.312191 -268.769949) (xy 460.308208 -268.7168) (xy 460.312191 -268.663651) (xy 460.324051 -268.61169)
			(xy 460.343523 -268.562077) (xy 460.370173 -268.51592) (xy 460.403404 -268.474251) (xy 460.442475 -268.438)
			(xy 460.486512 -268.407978) (xy 460.534532 -268.384854) (xy 460.585463 -268.369146) (xy 460.638165 -268.361204)
			(xy 460.664814 -268.360652) (xy 460.685385 -268.360927) (xy 460.726255 -268.365634) (xy 460.746348 -268.37005)
			(xy 460.761355 -268.373061) (xy 460.791878 -268.370969) (xy 460.820418 -268.359945) (xy 460.844421 -268.340974)
			(xy 460.861741 -268.315754) (xy 460.87083 -268.286541) (xy 460.871316 -268.271244) (xy 460.871316 -267.462254)
			(xy 460.870804 -267.446951) (xy 460.861753 -267.417715) (xy 460.844448 -267.392472) (xy 460.820441 -267.373488)
			(xy 460.791888 -267.362468) (xy 460.761353 -267.360401) (xy 460.746348 -267.363448) (xy 460.726254 -267.367858)
			(xy 460.685384 -267.372568) (xy 460.664814 -267.372846) (xy 460.638159 -267.372374) (xy 460.585445 -267.36443)
			(xy 460.534504 -267.348719) (xy 460.486473 -267.32559) (xy 460.442426 -267.295561) (xy 460.403347 -267.259302)
			(xy 460.370108 -267.217624) (xy 460.343453 -267.171457) (xy 460.323977 -267.121833) (xy 460.312114 -267.06986)
			(xy 460.30813 -267.0167) (xy 460.312114 -266.96354) (xy 460.323977 -266.911567) (xy 460.343453 -266.861943)
			(xy 460.370108 -266.815776) (xy 460.403347 -266.774098) (xy 460.442426 -266.737839) (xy 460.486473 -266.70781)
			(xy 460.534504 -266.684681) (xy 460.585445 -266.66897) (xy 460.638159 -266.661026) (xy 460.664814 -266.66063)
			(xy 460.685385 -266.660905) (xy 460.726255 -266.665611) (xy 460.746348 -266.670028) (xy 460.761354 -266.673039)
			(xy 460.791875 -266.670947) (xy 460.820412 -266.659923) (xy 460.844413 -266.640952) (xy 460.861729 -266.615731)
			(xy 460.870812 -266.586518) (xy 460.871316 -266.571222) (xy 460.871316 -265.762232) (xy 460.870801 -265.746931)
			(xy 460.861746 -265.717701) (xy 460.84444 -265.692464) (xy 460.820436 -265.673485) (xy 460.791887 -265.662468)
			(xy 460.761356 -265.660401) (xy 460.746348 -265.663426) (xy 460.726254 -265.667836) (xy 460.685384 -265.672547)
			(xy 460.664814 -265.672824) (xy 460.638161 -265.672352) (xy 460.58545 -265.664409) (xy 460.534512 -265.648698)
			(xy 460.486484 -265.625571) (xy 460.44244 -265.595544) (xy 460.403363 -265.559287) (xy 460.370127 -265.517611)
			(xy 460.343473 -265.471447) (xy 460.323998 -265.421826) (xy 460.312136 -265.369857) (xy 460.308152 -265.3167)
			(xy 460.312136 -265.263543) (xy 460.323998 -265.211574) (xy 460.343473 -265.161953) (xy 460.370127 -265.115789)
			(xy 460.403363 -265.074113) (xy 460.44244 -265.037856) (xy 460.486484 -265.007829) (xy 460.534512 -264.984702)
			(xy 460.58545 -264.968991) (xy 460.638161 -264.961048) (xy 460.664814 -264.960608) (xy 460.685385 -264.960883)
			(xy 460.726255 -264.965591) (xy 460.746348 -264.970006) (xy 460.761353 -264.973018) (xy 460.791872 -264.970926)
			(xy 460.820407 -264.959901) (xy 460.844404 -264.940929) (xy 460.861716 -264.915708) (xy 460.870793 -264.886495)
			(xy 460.871316 -264.8712) (xy 460.871316 -264.06221) (xy 460.870798 -264.046912) (xy 460.86174 -264.017687)
			(xy 460.844433 -263.992456) (xy 460.82043 -263.973482) (xy 460.791885 -263.962468) (xy 460.761358 -263.960401)
			(xy 460.746348 -263.963404) (xy 460.726254 -263.967815) (xy 460.685384 -263.972526) (xy 460.664814 -263.972802)
			(xy 460.638163 -263.97233) (xy 460.585455 -263.964387) (xy 460.53452 -263.948678) (xy 460.486495 -263.925552)
			(xy 460.442454 -263.895526) (xy 460.403379 -263.859272) (xy 460.370145 -263.817599) (xy 460.343493 -263.771438)
			(xy 460.324019 -263.72182) (xy 460.312157 -263.669854) (xy 460.308174 -263.6167) (xy 460.312157 -263.563546)
			(xy 460.324019 -263.51158) (xy 460.343493 -263.461962) (xy 460.370145 -263.415801) (xy 460.403379 -263.374128)
			(xy 460.442454 -263.337874) (xy 460.486495 -263.307848) (xy 460.53452 -263.284722) (xy 460.585455 -263.269013)
			(xy 460.638163 -263.26107) (xy 460.664814 -263.260586) (xy 460.685385 -263.260861) (xy 460.726255 -263.265568)
			(xy 460.746348 -263.269984) (xy 460.761352 -263.272996) (xy 460.791869 -263.270904) (xy 460.820402 -263.259879)
			(xy 460.844396 -263.240906) (xy 460.861703 -263.215685) (xy 460.870775 -263.186472) (xy 460.871316 -263.171178)
			(xy 460.871316 -262.362188) (xy 460.870809 -262.346881) (xy 460.861763 -262.317636) (xy 460.844459 -262.292384)
			(xy 460.820449 -262.273393) (xy 460.791891 -262.262369) (xy 460.761348 -262.260302) (xy 460.746348 -262.263382)
			(xy 460.726254 -262.267793) (xy 460.685384 -262.272504) (xy 460.664814 -262.27278) (xy 460.638164 -262.272308)
			(xy 460.58546 -262.264366) (xy 460.534528 -262.248657) (xy 460.486506 -262.225533) (xy 460.442467 -262.195509)
			(xy 460.403395 -262.159257) (xy 460.370163 -262.117587) (xy 460.343513 -262.071428) (xy 460.32404 -262.021813)
			(xy 460.312179 -261.96985) (xy 460.308196 -261.9167) (xy 460.312179 -261.86355) (xy 460.32404 -261.811587)
			(xy 460.343513 -261.761972) (xy 460.370163 -261.715813) (xy 460.403395 -261.674143) (xy 460.442467 -261.637891)
			(xy 460.486506 -261.607867) (xy 460.534528 -261.584743) (xy 460.58546 -261.569034) (xy 460.638164 -261.561092)
			(xy 460.664814 -261.560564) (xy 460.685385 -261.560839) (xy 460.726255 -261.565546) (xy 460.746348 -261.569962)
			(xy 460.761351 -261.572974) (xy 460.791866 -261.570883) (xy 460.820397 -261.559857) (xy 460.844388 -261.540884)
			(xy 460.861691 -261.515662) (xy 460.870757 -261.486449) (xy 460.871316 -261.471156) (xy 460.871316 -260.662166)
			(xy 460.870806 -260.646862) (xy 460.861757 -260.617622) (xy 460.844452 -260.592376) (xy 460.820444 -260.57339)
			(xy 460.791889 -260.562368) (xy 460.761351 -260.560301) (xy 460.746348 -260.56336) (xy 460.726254 -260.56777)
			(xy 460.685384 -260.57248) (xy 460.664814 -260.572758) (xy 460.638158 -260.572286) (xy 460.585443 -260.564342)
			(xy 460.534499 -260.54863) (xy 460.486467 -260.5255) (xy 460.442419 -260.49547) (xy 460.403338 -260.45921)
			(xy 460.370099 -260.417531) (xy 460.343442 -260.371362) (xy 460.323965 -260.321736) (xy 460.312102 -260.269762)
			(xy 460.308118 -260.2166) (xy 460.312102 -260.163438) (xy 460.323965 -260.111464) (xy 460.343442 -260.061838)
			(xy 460.370099 -260.015669) (xy 460.403338 -259.97399) (xy 460.442419 -259.93773) (xy 460.486467 -259.9077)
			(xy 460.534499 -259.88457) (xy 460.585443 -259.868858) (xy 460.638158 -259.860914) (xy 460.664814 -259.860542)
			(xy 460.685385 -259.860817) (xy 460.726255 -259.865524) (xy 460.746348 -259.86994) (xy 460.761355 -259.872951)
			(xy 460.791877 -259.870859) (xy 460.820415 -259.859835) (xy 460.844417 -259.840864) (xy 460.861736 -259.815644)
			(xy 460.870821 -259.78643) (xy 460.871316 -259.771134) (xy 460.871316 -258.962144) (xy 460.870803 -258.946842)
			(xy 460.86175 -258.917608) (xy 460.844444 -258.892368) (xy 460.820438 -258.873387) (xy 460.791888 -258.862368)
			(xy 460.761354 -258.860301) (xy 460.746348 -258.863338) (xy 460.726254 -258.867748) (xy 460.685384 -258.872459)
			(xy 460.664814 -258.872736) (xy 460.63816 -258.872264) (xy 460.585447 -258.86432) (xy 460.534507 -258.848609)
			(xy 460.486478 -258.825481) (xy 460.442432 -258.795453) (xy 460.403354 -258.759195) (xy 460.370117 -258.717518)
			(xy 460.343462 -258.671353) (xy 460.323986 -258.62173) (xy 460.312124 -258.569759) (xy 460.30814 -258.5166)
			(xy 460.312124 -258.463441) (xy 460.323986 -258.41147) (xy 460.343462 -258.361847) (xy 460.370117 -258.315682)
			(xy 460.403354 -258.274005) (xy 460.442432 -258.237747) (xy 460.486478 -258.207719) (xy 460.534507 -258.184591)
			(xy 460.585447 -258.16888) (xy 460.63816 -258.160936) (xy 460.664814 -258.16052) (xy 460.685385 -258.160795)
			(xy 460.726255 -258.165501) (xy 460.746348 -258.169918) (xy 460.761354 -258.172929) (xy 460.791874 -258.170838)
			(xy 460.82041 -258.159813) (xy 460.844409 -258.140841) (xy 460.861723 -258.115621) (xy 460.870803 -258.086407)
			(xy 460.871316 -258.071112) (xy 460.871316 -255.124966) (xy 460.829406 -255.1176) (xy 460.787525 -255.109758)
			(xy 460.705326 -255.087296) (xy 460.625574 -255.057286) (xy 460.548958 -255.019988) (xy 460.476143 -254.975725)
			(xy 460.407761 -254.924882) (xy 460.344405 -254.867899) (xy 460.286623 -254.80527) (xy 460.234917 -254.737538)
			(xy 460.189735 -254.66529) (xy 460.151468 -254.589154) (xy 460.12045 -254.509788) (xy 460.096947 -254.427881)
			(xy 460.081165 -254.344143) (xy 460.07324 -254.2593) (xy 460.073241 -254.174087) (xy 460.081167 -254.089244)
			(xy 460.09695 -254.005507) (xy 460.120454 -253.9236) (xy 460.151474 -253.844234) (xy 460.189741 -253.768098)
			(xy 460.234924 -253.695851) (xy 460.286631 -253.62812) (xy 460.344414 -253.565492) (xy 460.407771 -253.508509)
			(xy 460.476154 -253.457667) (xy 460.548969 -253.413406) (xy 460.625586 -253.376109) (xy 460.705339 -253.3461)
			(xy 460.787538 -253.323639) (xy 460.829406 -253.315724) (xy 460.871316 -253.308358) (xy 460.871316 -252.16231)
			(xy 460.870798 -252.147012) (xy 460.86174 -252.117787) (xy 460.844433 -252.092556) (xy 460.82043 -252.073582)
			(xy 460.791885 -252.062568) (xy 460.761358 -252.060501) (xy 460.746348 -252.063504) (xy 460.726254 -252.067915)
			(xy 460.685384 -252.072626) (xy 460.664814 -252.072902) (xy 460.638163 -252.07243) (xy 460.585455 -252.064487)
			(xy 460.53452 -252.048778) (xy 460.486495 -252.025652) (xy 460.442454 -251.995626) (xy 460.403379 -251.959372)
			(xy 460.370145 -251.917699) (xy 460.343493 -251.871538) (xy 460.324019 -251.82192) (xy 460.312157 -251.769954)
			(xy 460.308174 -251.7168) (xy 460.312157 -251.663646) (xy 460.324019 -251.61168) (xy 460.343493 -251.562062)
			(xy 460.370145 -251.515901) (xy 460.403379 -251.474228) (xy 460.442454 -251.437974) (xy 460.486495 -251.407948)
			(xy 460.53452 -251.384822) (xy 460.585455 -251.369113) (xy 460.638163 -251.36117) (xy 460.664814 -251.360686)
			(xy 460.685385 -251.360961) (xy 460.726255 -251.365668) (xy 460.746348 -251.370084) (xy 460.761352 -251.373096)
			(xy 460.791869 -251.371004) (xy 460.820402 -251.359979) (xy 460.844396 -251.341006) (xy 460.861703 -251.315785)
			(xy 460.870775 -251.286572) (xy 460.871316 -251.271278) (xy 460.871316 -250.462288) (xy 460.870809 -250.446981)
			(xy 460.861763 -250.417736) (xy 460.844459 -250.392484) (xy 460.820449 -250.373493) (xy 460.791891 -250.362469)
			(xy 460.761348 -250.360402) (xy 460.746348 -250.363482) (xy 460.726254 -250.367893) (xy 460.685384 -250.372604)
			(xy 460.664814 -250.37288) (xy 460.638164 -250.372408) (xy 460.58546 -250.364466) (xy 460.534528 -250.348757)
			(xy 460.486506 -250.325633) (xy 460.442467 -250.295609) (xy 460.403395 -250.259357) (xy 460.370163 -250.217687)
			(xy 460.343513 -250.171528) (xy 460.32404 -250.121913) (xy 460.312179 -250.06995) (xy 460.308196 -250.0168)
			(xy 460.312179 -249.96365) (xy 460.32404 -249.911687) (xy 460.343513 -249.862072) (xy 460.370163 -249.815913)
			(xy 460.403395 -249.774243) (xy 460.442467 -249.737991) (xy 460.486506 -249.707967) (xy 460.534528 -249.684843)
			(xy 460.58546 -249.669134) (xy 460.638164 -249.661192) (xy 460.664814 -249.660664) (xy 460.685385 -249.660939)
			(xy 460.726255 -249.665646) (xy 460.746348 -249.670062) (xy 460.761351 -249.673074) (xy 460.791866 -249.670983)
			(xy 460.820397 -249.659957) (xy 460.844388 -249.640984) (xy 460.861691 -249.615762) (xy 460.870757 -249.586549)
			(xy 460.871316 -249.571256) (xy 460.871316 -248.762266) (xy 460.870806 -248.746962) (xy 460.861757 -248.717722)
			(xy 460.844452 -248.692476) (xy 460.820444 -248.67349) (xy 460.791889 -248.662468) (xy 460.761351 -248.660401)
			(xy 460.746348 -248.66346) (xy 460.726254 -248.66787) (xy 460.685384 -248.67258) (xy 460.664814 -248.672858)
			(xy 460.638158 -248.672386) (xy 460.585443 -248.664442) (xy 460.534499 -248.64873) (xy 460.486467 -248.6256)
			(xy 460.442419 -248.59557) (xy 460.403338 -248.55931) (xy 460.370099 -248.517631) (xy 460.343442 -248.471462)
			(xy 460.323965 -248.421836) (xy 460.312102 -248.369862) (xy 460.308118 -248.3167) (xy 460.312102 -248.263538)
			(xy 460.323965 -248.211564) (xy 460.343442 -248.161938) (xy 460.370099 -248.115769) (xy 460.403338 -248.07409)
			(xy 460.442419 -248.03783) (xy 460.486467 -248.0078) (xy 460.534499 -247.98467) (xy 460.585443 -247.968958)
			(xy 460.638158 -247.961014) (xy 460.664814 -247.960642) (xy 460.685385 -247.960917) (xy 460.726255 -247.965624)
			(xy 460.746348 -247.97004) (xy 460.761355 -247.973051) (xy 460.791877 -247.970959) (xy 460.820415 -247.959935)
			(xy 460.844417 -247.940964) (xy 460.861736 -247.915744) (xy 460.870821 -247.88653) (xy 460.871316 -247.871234)
			(xy 460.871316 -247.062244) (xy 460.870803 -247.046942) (xy 460.86175 -247.017708) (xy 460.844444 -246.992468)
			(xy 460.820438 -246.973487) (xy 460.791888 -246.962468) (xy 460.761354 -246.960401) (xy 460.746348 -246.963438)
			(xy 460.726254 -246.967848) (xy 460.685384 -246.972559) (xy 460.664814 -246.972836) (xy 460.63816 -246.972364)
			(xy 460.585447 -246.96442) (xy 460.534507 -246.948709) (xy 460.486478 -246.925581) (xy 460.442432 -246.895553)
			(xy 460.403354 -246.859295) (xy 460.370117 -246.817618) (xy 460.343462 -246.771453) (xy 460.323986 -246.72183)
			(xy 460.312124 -246.669859) (xy 460.30814 -246.6167) (xy 460.312124 -246.563541) (xy 460.323986 -246.51157)
			(xy 460.343462 -246.461947) (xy 460.370117 -246.415782) (xy 460.403354 -246.374105) (xy 460.442432 -246.337847)
			(xy 460.486478 -246.307819) (xy 460.534507 -246.284691) (xy 460.585447 -246.26898) (xy 460.63816 -246.261036)
			(xy 460.664814 -246.26062) (xy 460.685385 -246.260895) (xy 460.726255 -246.265601) (xy 460.746348 -246.270018)
			(xy 460.761354 -246.273029) (xy 460.791874 -246.270938) (xy 460.82041 -246.259913) (xy 460.844409 -246.240941)
			(xy 460.861723 -246.215721) (xy 460.870803 -246.186507) (xy 460.871316 -246.171212) (xy 460.871316 -245.362222)
			(xy 460.8708 -245.346922) (xy 460.861743 -245.317694) (xy 460.844437 -245.29246) (xy 460.820433 -245.273484)
			(xy 460.791886 -245.262468) (xy 460.761357 -245.260401) (xy 460.746348 -245.263416) (xy 460.726254 -245.267827)
			(xy 460.685384 -245.272537) (xy 460.664814 -245.272814) (xy 460.638162 -245.272342) (xy 460.585452 -245.264399)
			(xy 460.534515 -245.248689) (xy 460.486489 -245.225562) (xy 460.442446 -245.195536) (xy 460.40337 -245.15928)
			(xy 460.370135 -245.117606) (xy 460.343482 -245.071443) (xy 460.324007 -245.021823) (xy 460.312146 -244.969855)
			(xy 460.308162 -244.9167) (xy 460.312146 -244.863545) (xy 460.324007 -244.811577) (xy 460.343482 -244.761957)
			(xy 460.370135 -244.715794) (xy 460.40337 -244.67412) (xy 460.442446 -244.637864) (xy 460.486489 -244.607838)
			(xy 460.534515 -244.584711) (xy 460.585452 -244.569001) (xy 460.638162 -244.561058) (xy 460.664814 -244.560598)
			(xy 460.685385 -244.560873) (xy 460.726255 -244.56558) (xy 460.746348 -244.569996) (xy 460.761352 -244.573008)
			(xy 460.791871 -244.570917) (xy 460.820405 -244.559891) (xy 460.844401 -244.540919) (xy 460.861711 -244.515698)
			(xy 460.870785 -244.486485) (xy 460.871316 -244.47119) (xy 460.871316 -242.812316) (xy 460.870799 -242.797017)
			(xy 460.861742 -242.767791) (xy 460.844435 -242.742558) (xy 460.820432 -242.723583) (xy 460.791885 -242.712568)
			(xy 460.761358 -242.710501) (xy 460.746348 -242.71351) (xy 460.726254 -242.717921) (xy 460.685384 -242.722631)
			(xy 460.664814 -242.722908) (xy 460.638162 -242.722436) (xy 460.585454 -242.714493) (xy 460.534518 -242.698783)
			(xy 460.486492 -242.675657) (xy 460.44245 -242.645631) (xy 460.403375 -242.609376) (xy 460.37014 -242.567702)
			(xy 460.343487 -242.52154) (xy 460.324013 -242.471922) (xy 460.312151 -242.419955) (xy 460.308168 -242.3668)
			(xy 460.312151 -242.313645) (xy 460.324013 -242.261678) (xy 460.343487 -242.21206) (xy 460.37014 -242.165898)
			(xy 460.403375 -242.124224) (xy 460.44245 -242.087969) (xy 460.486492 -242.057943) (xy 460.534518 -242.034817)
			(xy 460.585454 -242.019107) (xy 460.638162 -242.011164) (xy 460.664814 -242.010692) (xy 460.685385 -242.010967)
			(xy 460.726255 -242.015674) (xy 460.746348 -242.02009) (xy 460.761352 -242.023102) (xy 460.79187 -242.021011)
			(xy 460.820404 -242.009985) (xy 460.844398 -241.991013) (xy 460.861707 -241.965791) (xy 460.87078 -241.936578)
			(xy 460.871316 -241.921284) (xy 460.871316 -241.112294) (xy 460.870809 -241.096987) (xy 460.861765 -241.06774)
			(xy 460.844461 -241.042486) (xy 460.820451 -241.023494) (xy 460.791891 -241.012469) (xy 460.761348 -241.010402)
			(xy 460.746348 -241.013488) (xy 460.726254 -241.017899) (xy 460.685384 -241.02261) (xy 460.664814 -241.022886)
			(xy 460.638164 -241.022414) (xy 460.585459 -241.014472) (xy 460.534526 -240.998763) (xy 460.486503 -240.975638)
			(xy 460.442464 -240.945614) (xy 460.403391 -240.909361) (xy 460.370158 -240.86769) (xy 460.343507 -240.821531)
			(xy 460.324034 -240.771915) (xy 460.312173 -240.719951) (xy 460.30819 -240.6668) (xy 460.312173 -240.613649)
			(xy 460.324034 -240.561685) (xy 460.343507 -240.512069) (xy 460.370158 -240.46591) (xy 460.403391 -240.424239)
			(xy 460.442464 -240.387986) (xy 460.486503 -240.357962) (xy 460.534526 -240.334837) (xy 460.585459 -240.319128)
			(xy 460.638164 -240.311186) (xy 460.664814 -240.31067) (xy 460.685385 -240.310945) (xy 460.726255 -240.315652)
			(xy 460.746348 -240.320068) (xy 460.761351 -240.32308) (xy 460.791867 -240.320989) (xy 460.820398 -240.309963)
			(xy 460.84439 -240.29099) (xy 460.861694 -240.265768) (xy 460.870761 -240.236555) (xy 460.871316 -240.221262)
			(xy 460.871316 -239.412272) (xy 460.870806 -239.396967) (xy 460.861759 -239.367726) (xy 460.844454 -239.342478)
			(xy 460.820445 -239.323491) (xy 460.79189 -239.312469) (xy 460.76135 -239.310402) (xy 460.746348 -239.313466)
			(xy 460.726254 -239.317876) (xy 460.685384 -239.322586) (xy 460.664814 -239.322864) (xy 460.638165 -239.322392)
			(xy 460.585463 -239.31445) (xy 460.534534 -239.298742) (xy 460.486514 -239.275619) (xy 460.442477 -239.245597)
			(xy 460.403407 -239.209346) (xy 460.370176 -239.167678) (xy 460.343527 -239.121521) (xy 460.324055 -239.071909)
			(xy 460.312195 -239.019948) (xy 460.308212 -238.9668) (xy 460.312195 -238.913652) (xy 460.324055 -238.861691)
			(xy 460.343527 -238.812079) (xy 460.370176 -238.765922) (xy 460.403407 -238.724254) (xy 460.442477 -238.688003)
			(xy 460.486514 -238.657981) (xy 460.534534 -238.634858) (xy 460.585463 -238.61915) (xy 460.638165 -238.611208)
			(xy 460.664814 -238.610648) (xy 460.685385 -238.610923) (xy 460.726255 -238.61563) (xy 460.746348 -238.620046)
			(xy 460.761355 -238.623057) (xy 460.791878 -238.620965) (xy 460.820417 -238.609941) (xy 460.84442 -238.59097)
			(xy 460.861739 -238.56575) (xy 460.870826 -238.536537) (xy 460.871316 -238.52124) (xy 460.871316 -236.862112)
			(xy 460.870798 -236.846814) (xy 460.86174 -236.817588) (xy 460.844433 -236.792356) (xy 460.820431 -236.773382)
			(xy 460.791885 -236.762368) (xy 460.761358 -236.760301) (xy 460.746348 -236.763306) (xy 460.726254 -236.767717)
			(xy 460.685384 -236.772427) (xy 460.664814 -236.772704) (xy 460.638162 -236.772232) (xy 460.585455 -236.764289)
			(xy 460.534519 -236.74858) (xy 460.486494 -236.725454) (xy 460.442452 -236.695428) (xy 460.403378 -236.659174)
			(xy 460.370143 -236.6175) (xy 460.343491 -236.571339) (xy 460.324017 -236.521721) (xy 460.312155 -236.469754)
			(xy 460.308172 -236.4166) (xy 460.312155 -236.363446) (xy 460.324017 -236.311479) (xy 460.343491 -236.261861)
			(xy 460.370143 -236.2157) (xy 460.403378 -236.174026) (xy 460.442452 -236.137772) (xy 460.486494 -236.107746)
			(xy 460.534519 -236.08462) (xy 460.585455 -236.068911) (xy 460.638162 -236.060968) (xy 460.664814 -236.060488)
			(xy 460.685385 -236.060763) (xy 460.726255 -236.06547) (xy 460.746348 -236.069886) (xy 460.761352 -236.072898)
			(xy 460.79187 -236.070807) (xy 460.820403 -236.059781) (xy 460.844397 -236.040809) (xy 460.861705 -236.015587)
			(xy 460.870777 -235.986374) (xy 460.871316 -235.97108) (xy 460.871316 -235.16209) (xy 460.870809 -235.146783)
			(xy 460.861764 -235.117537) (xy 460.84446 -235.092284) (xy 460.82045 -235.073293) (xy 460.791891 -235.062269)
			(xy 460.761348 -235.060202) (xy 460.746348 -235.063284) (xy 460.726254 -235.067695) (xy 460.685384 -235.072406)
			(xy 460.664814 -235.072682) (xy 460.638164 -235.07221) (xy 460.585459 -235.064268) (xy 460.534527 -235.048559)
			(xy 460.486505 -235.025435) (xy 460.442466 -234.995411) (xy 460.403394 -234.959159) (xy 460.370161 -234.917488)
			(xy 460.343511 -234.871329) (xy 460.324038 -234.821714) (xy 460.312177 -234.769751) (xy 460.308194 -234.7166)
			(xy 460.312177 -234.663449) (xy 460.324038 -234.611486) (xy 460.343511 -234.561871) (xy 460.370161 -234.515712)
			(xy 460.403394 -234.474041) (xy 460.442466 -234.437789) (xy 460.486505 -234.407765) (xy 460.534527 -234.384641)
			(xy 460.585459 -234.368932) (xy 460.638164 -234.36099) (xy 460.664814 -234.360466) (xy 460.685385 -234.360741)
			(xy 460.726255 -234.365448) (xy 460.746348 -234.369864) (xy 460.761351 -234.372876) (xy 460.791866 -234.370785)
			(xy 460.820397 -234.359759) (xy 460.844388 -234.340786) (xy 460.861692 -234.315564) (xy 460.870758 -234.286351)
			(xy 460.871316 -234.271058) (xy 460.871316 -233.462322) (xy 460.8708 -233.447022) (xy 460.861743 -233.417794)
			(xy 460.844437 -233.39256) (xy 460.820433 -233.373584) (xy 460.791886 -233.362568) (xy 460.761357 -233.360501)
			(xy 460.746348 -233.363516) (xy 460.726254 -233.367927) (xy 460.685384 -233.372637) (xy 460.664814 -233.372914)
			(xy 460.638162 -233.372442) (xy 460.585452 -233.364499) (xy 460.534515 -233.348789) (xy 460.486489 -233.325662)
			(xy 460.442446 -233.295636) (xy 460.40337 -233.25938) (xy 460.370135 -233.217706) (xy 460.343482 -233.171543)
			(xy 460.324007 -233.121923) (xy 460.312146 -233.069955) (xy 460.308162 -233.0168) (xy 460.312146 -232.963645)
			(xy 460.324007 -232.911677) (xy 460.343482 -232.862057) (xy 460.370135 -232.815894) (xy 460.40337 -232.77422)
			(xy 460.442446 -232.737964) (xy 460.486489 -232.707938) (xy 460.534515 -232.684811) (xy 460.585452 -232.669101)
			(xy 460.638162 -232.661158) (xy 460.664814 -232.660698) (xy 460.685385 -232.660973) (xy 460.726255 -232.66568)
			(xy 460.746348 -232.670096) (xy 460.761352 -232.673108) (xy 460.791871 -232.671017) (xy 460.820405 -232.659991)
			(xy 460.844401 -232.641019) (xy 460.861711 -232.615798) (xy 460.870785 -232.586585) (xy 460.871316 -232.57129)
			(xy 460.871316 -231.7623) (xy 460.870797 -231.747003) (xy 460.861737 -231.717781) (xy 460.844429 -231.692552)
			(xy 460.820428 -231.67358) (xy 460.791884 -231.662567) (xy 460.76136 -231.660501) (xy 460.746348 -231.663494)
			(xy 460.726254 -231.667905) (xy 460.685384 -231.672616) (xy 460.664814 -231.672892) (xy 460.638163 -231.67242)
			(xy 460.585457 -231.664478) (xy 460.534523 -231.648768) (xy 460.4865 -231.625643) (xy 460.44246 -231.595619)
			(xy 460.403387 -231.559365) (xy 460.370153 -231.517693) (xy 460.343502 -231.471533) (xy 460.324028 -231.421917)
			(xy 460.312167 -231.369952) (xy 460.308184 -231.3168) (xy 460.312167 -231.263648) (xy 460.324028 -231.211683)
			(xy 460.343502 -231.162067) (xy 460.370153 -231.115907) (xy 460.403387 -231.074235) (xy 460.44246 -231.037981)
			(xy 460.4865 -231.007957) (xy 460.534523 -230.984832) (xy 460.585457 -230.969122) (xy 460.638163 -230.96118)
			(xy 460.664814 -230.960676) (xy 460.685385 -230.960951) (xy 460.726255 -230.965658) (xy 460.746348 -230.970074)
			(xy 460.761351 -230.973086) (xy 460.791868 -230.970995) (xy 460.820399 -230.959969) (xy 460.844392 -230.940996)
			(xy 460.861698 -230.915774) (xy 460.870766 -230.886562) (xy 460.871316 -230.871268) (xy 460.871316 -230.062278)
			(xy 460.870807 -230.046972) (xy 460.86176 -230.01773) (xy 460.844456 -229.99248) (xy 460.820447 -229.973491)
			(xy 460.79189 -229.962469) (xy 460.76135 -229.960402) (xy 460.746348 -229.963472) (xy 460.726254 -229.967882)
			(xy 460.685384 -229.972592) (xy 460.664814 -229.97287) (xy 460.638165 -229.972398) (xy 460.585462 -229.964456)
			(xy 460.534532 -229.948748) (xy 460.486511 -229.925624) (xy 460.442474 -229.895601) (xy 460.403403 -229.85935)
			(xy 460.370171 -229.817681) (xy 460.343522 -229.771524) (xy 460.324049 -229.72191) (xy 460.312189 -229.669949)
			(xy 460.308206 -229.6168) (xy 460.312189 -229.563651) (xy 460.324049 -229.51169) (xy 460.343522 -229.462076)
			(xy 460.370171 -229.415919) (xy 460.403403 -229.37425) (xy 460.442474 -229.337999) (xy 460.486511 -229.307976)
			(xy 460.534532 -229.284852) (xy 460.585462 -229.269144) (xy 460.638165 -229.261202) (xy 460.664814 -229.260654)
			(xy 460.685385 -229.260929) (xy 460.726255 -229.265636) (xy 460.746348 -229.270052) (xy 460.761355 -229.273063)
			(xy 460.791878 -229.270971) (xy 460.820418 -229.259947) (xy 460.844422 -229.240976) (xy 460.861743 -229.215756)
			(xy 460.870831 -229.186543) (xy 460.871316 -229.171246) (xy 460.871316 -227.512118) (xy 460.870799 -227.496819)
			(xy 460.861742 -227.467592) (xy 460.844436 -227.442359) (xy 460.820432 -227.423383) (xy 460.791886 -227.412368)
			(xy 460.761357 -227.410301) (xy 460.746348 -227.413312) (xy 460.726254 -227.417723) (xy 460.685384 -227.422433)
			(xy 460.664814 -227.42271) (xy 460.638162 -227.422238) (xy 460.585453 -227.414295) (xy 460.534517 -227.398585)
			(xy 460.486491 -227.375459) (xy 460.442449 -227.345433) (xy 460.403373 -227.309178) (xy 460.370138 -227.267503)
			(xy 460.343486 -227.221341) (xy 460.324011 -227.171722) (xy 460.31215 -227.119755) (xy 460.308166 -227.0666)
			(xy 460.31215 -227.013445) (xy 460.324011 -226.961478) (xy 460.343486 -226.911859) (xy 460.370138 -226.865697)
			(xy 460.403373 -226.824022) (xy 460.442449 -226.787767) (xy 460.486491 -226.757741) (xy 460.534517 -226.734615)
			(xy 460.585453 -226.718905) (xy 460.638162 -226.710962) (xy 460.664814 -226.710494) (xy 460.685385 -226.710769)
			(xy 460.726255 -226.715476) (xy 460.746348 -226.719892) (xy 460.761352 -226.722904) (xy 460.79187 -226.720813)
			(xy 460.820404 -226.709787) (xy 460.844399 -226.690815) (xy 460.861708 -226.665593) (xy 460.870782 -226.63638)
			(xy 460.871316 -226.621086) (xy 460.871316 -225.812096) (xy 460.870796 -225.796799) (xy 460.861735 -225.767578)
			(xy 460.844428 -225.742351) (xy 460.820427 -225.72338) (xy 460.791884 -225.712367) (xy 460.76136 -225.710301)
			(xy 460.746348 -225.71329) (xy 460.726254 -225.717701) (xy 460.685384 -225.722412) (xy 460.664814 -225.722688)
			(xy 460.638164 -225.722216) (xy 460.585458 -225.714274) (xy 460.534525 -225.698565) (xy 460.486502 -225.67544)
			(xy 460.442462 -225.645415) (xy 460.403389 -225.609163) (xy 460.370156 -225.567491) (xy 460.343505 -225.521332)
			(xy 460.324032 -225.471716) (xy 460.312171 -225.419752) (xy 460.308188 -225.3666) (xy 460.312171 -225.313448)
			(xy 460.324032 -225.261484) (xy 460.343505 -225.211868) (xy 460.370156 -225.165709) (xy 460.403389 -225.124037)
			(xy 460.442462 -225.087785) (xy 460.486502 -225.05776) (xy 460.534525 -225.034635) (xy 460.585458 -225.018926)
			(xy 460.638164 -225.010984) (xy 460.664814 -225.010472) (xy 460.685385 -225.010747) (xy 460.726255 -225.015454)
			(xy 460.746348 -225.01987) (xy 460.761351 -225.022882) (xy 460.791867 -225.020791) (xy 460.820399 -225.009765)
			(xy 460.844391 -224.990792) (xy 460.861695 -224.96557) (xy 460.870763 -224.936357) (xy 460.871316 -224.921064)
			(xy 460.871316 -224.112074) (xy 460.870807 -224.096769) (xy 460.861759 -224.067527) (xy 460.844454 -224.042279)
			(xy 460.820446 -224.023291) (xy 460.79189 -224.012269) (xy 460.76135 -224.010202) (xy 460.746348 -224.013268)
			(xy 460.726254 -224.017678) (xy 460.685384 -224.022388) (xy 460.664814 -224.022666) (xy 460.638165 -224.022194)
			(xy 460.585463 -224.014252) (xy 460.534533 -223.998544) (xy 460.486513 -223.975421) (xy 460.442476 -223.945398)
			(xy 460.403406 -223.909148) (xy 460.370175 -223.867479) (xy 460.343525 -223.821322) (xy 460.324053 -223.771709)
			(xy 460.312193 -223.719748) (xy 460.30821 -223.6666) (xy 460.312193 -223.613452) (xy 460.324053 -223.561491)
			(xy 460.343525 -223.511878) (xy 460.370175 -223.465721) (xy 460.403406 -223.424052) (xy 460.442476 -223.387802)
			(xy 460.486513 -223.357779) (xy 460.534533 -223.334656) (xy 460.585463 -223.318948) (xy 460.638165 -223.311006)
			(xy 460.664814 -223.31045) (xy 460.685385 -223.310725) (xy 460.726255 -223.315432) (xy 460.746348 -223.319848)
			(xy 460.761355 -223.322859) (xy 460.791878 -223.320767) (xy 460.820417 -223.309743) (xy 460.84442 -223.290772)
			(xy 460.86174 -223.265552) (xy 460.870828 -223.236339) (xy 460.871316 -223.221042) (xy 460.871316 -222.412306)
			(xy 460.870797 -222.397008) (xy 460.861738 -222.367784) (xy 460.844431 -222.342554) (xy 460.820429 -222.323581)
			(xy 460.791885 -222.312567) (xy 460.761359 -222.310501) (xy 460.746348 -222.3135) (xy 460.726254 -222.317911)
			(xy 460.685384 -222.322622) (xy 460.664814 -222.322898) (xy 460.638163 -222.322426) (xy 460.585456 -222.314483)
			(xy 460.534521 -222.298774) (xy 460.486497 -222.275648) (xy 460.442456 -222.245623) (xy 460.403382 -222.209369)
			(xy 460.370148 -222.167697) (xy 460.343496 -222.121536) (xy 460.324023 -222.071919) (xy 460.312161 -222.019953)
			(xy 460.308178 -221.9668) (xy 460.312161 -221.913647) (xy 460.324023 -221.861681) (xy 460.343496 -221.812064)
			(xy 460.370148 -221.765903) (xy 460.403382 -221.724231) (xy 460.442456 -221.687977) (xy 460.486497 -221.657952)
			(xy 460.534521 -221.634826) (xy 460.585456 -221.619117) (xy 460.638163 -221.611174) (xy 460.664814 -221.610682)
			(xy 460.685385 -221.610957) (xy 460.726255 -221.615664) (xy 460.746348 -221.62008) (xy 460.761352 -221.623092)
			(xy 460.791869 -221.621001) (xy 460.820401 -221.609975) (xy 460.844394 -221.591002) (xy 460.861701 -221.565781)
			(xy 460.870771 -221.536568) (xy 460.871316 -221.521274) (xy 460.871316 -220.712284) (xy 460.870808 -220.696978)
			(xy 460.861762 -220.667733) (xy 460.844458 -220.642482) (xy 460.820448 -220.623492) (xy 460.791891 -220.612469)
			(xy 460.761349 -220.610402) (xy 460.746348 -220.613478) (xy 460.726254 -220.617889) (xy 460.685384 -220.6226)
			(xy 460.664814 -220.622876) (xy 460.638165 -220.622404) (xy 460.585461 -220.614462) (xy 460.534529 -220.598753)
			(xy 460.486508 -220.575629) (xy 460.44247 -220.545606) (xy 460.403398 -220.509354) (xy 460.370166 -220.467684)
			(xy 460.343516 -220.421527) (xy 460.324044 -220.371912) (xy 460.312183 -220.31995) (xy 460.3082 -220.2668)
			(xy 460.312183 -220.21365) (xy 460.324044 -220.161688) (xy 460.343516 -220.112073) (xy 460.370166 -220.065916)
			(xy 460.403398 -220.024246) (xy 460.44247 -219.987994) (xy 460.486508 -219.957971) (xy 460.534529 -219.934847)
			(xy 460.585461 -219.919138) (xy 460.638165 -219.911196) (xy 460.664814 -219.91066) (xy 460.685385 -219.910935)
			(xy 460.726255 -219.915642) (xy 460.746348 -219.920058) (xy 460.761351 -219.92307) (xy 460.791866 -219.920979)
			(xy 460.820396 -219.909953) (xy 460.844386 -219.89098) (xy 460.861688 -219.865757) (xy 460.870753 -219.836545)
			(xy 460.871316 -219.821252) (xy 460.871316 -218.162124) (xy 460.8708 -218.146824) (xy 460.861744 -218.117596)
			(xy 460.844438 -218.092361) (xy 460.820434 -218.073384) (xy 460.791886 -218.062368) (xy 460.761357 -218.060301)
			(xy 460.746348 -218.063318) (xy 460.726254 -218.067729) (xy 460.685384 -218.072439) (xy 460.664814 -218.072716)
			(xy 460.638162 -218.072244) (xy 460.585452 -218.064301) (xy 460.534515 -218.048591) (xy 460.486488 -218.025464)
			(xy 460.442445 -217.995437) (xy 460.403369 -217.959182) (xy 460.370133 -217.917507) (xy 460.34348 -217.871344)
			(xy 460.324005 -217.821724) (xy 460.312144 -217.769756) (xy 460.30816 -217.7166) (xy 460.312144 -217.663444)
			(xy 460.324005 -217.611476) (xy 460.34348 -217.561856) (xy 460.370133 -217.515693) (xy 460.403369 -217.474018)
			(xy 460.442445 -217.437763) (xy 460.486488 -217.407736) (xy 460.534515 -217.384609) (xy 460.585452 -217.368899)
			(xy 460.638162 -217.360956) (xy 460.664814 -217.3605) (xy 460.685385 -217.360775) (xy 460.726255 -217.365482)
			(xy 460.746348 -217.369898) (xy 460.761353 -217.37291) (xy 460.791871 -217.370818) (xy 460.820405 -217.359793)
			(xy 460.844401 -217.340821) (xy 460.861712 -217.3156) (xy 460.870787 -217.286387) (xy 460.871316 -217.271092)
			(xy 460.871316 -216.462102) (xy 460.870797 -216.446805) (xy 460.861737 -216.417582) (xy 460.84443 -216.392353)
			(xy 460.820428 -216.373381) (xy 460.791884 -216.362367) (xy 460.761359 -216.360301) (xy 460.746348 -216.363296)
			(xy 460.726254 -216.367707) (xy 460.685384 -216.372418) (xy 460.664814 -216.372694) (xy 460.638163 -216.372222)
			(xy 460.585457 -216.36428) (xy 460.534523 -216.34857) (xy 460.486499 -216.325445) (xy 460.442459 -216.29542)
			(xy 460.403385 -216.259167) (xy 460.370151 -216.217494) (xy 460.3435 -216.171334) (xy 460.324026 -216.121718)
			(xy 460.312165 -216.069752) (xy 460.308182 -216.0166) (xy 460.312165 -215.963448) (xy 460.324026 -215.911482)
			(xy 460.3435 -215.861866) (xy 460.370151 -215.815706) (xy 460.403385 -215.774033) (xy 460.442459 -215.73778)
			(xy 460.486499 -215.707755) (xy 460.534523 -215.68463) (xy 460.585457 -215.66892) (xy 460.638163 -215.660978)
			(xy 460.664814 -215.660478) (xy 460.685385 -215.660753) (xy 460.726255 -215.66546) (xy 460.746348 -215.669876)
			(xy 460.761352 -215.672888) (xy 460.791868 -215.670797) (xy 460.8204 -215.659771) (xy 460.844393 -215.640798)
			(xy 460.861699 -215.615576) (xy 460.870768 -215.586364) (xy 460.871316 -215.57107) (xy 460.871316 -214.76208)
			(xy 460.870807 -214.746774) (xy 460.861761 -214.717531) (xy 460.844456 -214.692281) (xy 460.820447 -214.673292)
			(xy 460.79189 -214.662269) (xy 460.761349 -214.660202) (xy 460.746348 -214.663274) (xy 460.726254 -214.667684)
			(xy 460.685384 -214.672394) (xy 460.664814 -214.672672) (xy 460.638165 -214.6722) (xy 460.585462 -214.664258)
			(xy 460.534531 -214.64855) (xy 460.48651 -214.625426) (xy 460.442472 -214.595403) (xy 460.403401 -214.559152)
			(xy 460.37017 -214.517482) (xy 460.34352 -214.471325) (xy 460.324047 -214.421711) (xy 460.312187 -214.369749)
			(xy 460.308204 -214.3166) (xy 460.312187 -214.263451) (xy 460.324047 -214.211489) (xy 460.34352 -214.161875)
			(xy 460.37017 -214.115718) (xy 460.403401 -214.074048) (xy 460.442472 -214.037797) (xy 460.48651 -214.007774)
			(xy 460.534531 -213.98465) (xy 460.585462 -213.968942) (xy 460.638165 -213.961) (xy 460.664814 -213.960456)
			(xy 460.685385 -213.960731) (xy 460.726255 -213.965438) (xy 460.746348 -213.969854) (xy 460.761355 -213.972865)
			(xy 460.791879 -213.970773) (xy 460.820419 -213.959748) (xy 460.844423 -213.940778) (xy 460.861744 -213.915559)
			(xy 460.870833 -213.886345) (xy 460.871316 -213.871048) (xy 460.871316 -213.062312) (xy 460.870798 -213.047014)
			(xy 460.86174 -213.017788) (xy 460.844433 -212.992556) (xy 460.820431 -212.973582) (xy 460.791885 -212.962568)
			(xy 460.761358 -212.960501) (xy 460.746348 -212.963506) (xy 460.726254 -212.967917) (xy 460.685384 -212.972627)
			(xy 460.664814 -212.972904) (xy 460.638162 -212.972432) (xy 460.585455 -212.964489) (xy 460.534519 -212.94878)
			(xy 460.486494 -212.925654) (xy 460.442452 -212.895628) (xy 460.403378 -212.859374) (xy 460.370143 -212.8177)
			(xy 460.343491 -212.771539) (xy 460.324017 -212.721921) (xy 460.312155 -212.669954) (xy 460.308172 -212.6168)
			(xy 460.312155 -212.563646) (xy 460.324017 -212.511679) (xy 460.343491 -212.462061) (xy 460.370143 -212.4159)
			(xy 460.403378 -212.374226) (xy 460.442452 -212.337972) (xy 460.486494 -212.307946) (xy 460.534519 -212.28482)
			(xy 460.585455 -212.269111) (xy 460.638162 -212.261168) (xy 460.664814 -212.260688) (xy 460.685385 -212.260963)
			(xy 460.726255 -212.26567) (xy 460.746348 -212.270086) (xy 460.761352 -212.273098) (xy 460.79187 -212.271007)
			(xy 460.820403 -212.259981) (xy 460.844397 -212.241009) (xy 460.861705 -212.215787) (xy 460.870777 -212.186574)
			(xy 460.871316 -212.17128) (xy 460.871316 -211.36229) (xy 460.870809 -211.346983) (xy 460.861764 -211.317737)
			(xy 460.84446 -211.292484) (xy 460.82045 -211.273493) (xy 460.791891 -211.262469) (xy 460.761348 -211.260402)
			(xy 460.746348 -211.263484) (xy 460.726254 -211.267895) (xy 460.685384 -211.272606) (xy 460.664814 -211.272882)
			(xy 460.638164 -211.27241) (xy 460.585459 -211.264468) (xy 460.534527 -211.248759) (xy 460.486505 -211.225635)
			(xy 460.442466 -211.195611) (xy 460.403394 -211.159359) (xy 460.370161 -211.117688) (xy 460.343511 -211.071529)
			(xy 460.324038 -211.021914) (xy 460.312177 -210.969951) (xy 460.308194 -210.9168) (xy 460.312177 -210.863649)
			(xy 460.324038 -210.811686) (xy 460.343511 -210.762071) (xy 460.370161 -210.715912) (xy 460.403394 -210.674241)
			(xy 460.442466 -210.637989) (xy 460.486505 -210.607965) (xy 460.534527 -210.584841) (xy 460.585459 -210.569132)
			(xy 460.638164 -210.56119) (xy 460.664814 -210.560666) (xy 460.685385 -210.560941) (xy 460.726255 -210.565648)
			(xy 460.746348 -210.570064) (xy 460.761351 -210.573076) (xy 460.791866 -210.570985) (xy 460.820397 -210.559959)
			(xy 460.844388 -210.540986) (xy 460.861692 -210.515764) (xy 460.870758 -210.486551) (xy 460.871316 -210.471258)
			(xy 460.871316 -208.81213) (xy 460.870801 -208.79683) (xy 460.861746 -208.767599) (xy 460.84444 -208.742363)
			(xy 460.820435 -208.723385) (xy 460.791886 -208.712368) (xy 460.761356 -208.710301) (xy 460.746348 -208.713324)
			(xy 460.726254 -208.717734) (xy 460.685384 -208.722445) (xy 460.664814 -208.722722) (xy 460.638161 -208.72225)
			(xy 460.585451 -208.714307) (xy 460.534513 -208.698596) (xy 460.486485 -208.675469) (xy 460.442441 -208.645442)
			(xy 460.403365 -208.609186) (xy 460.370128 -208.56751) (xy 460.343475 -208.521347) (xy 460.324 -208.471726)
			(xy 460.312138 -208.419757) (xy 460.308154 -208.3666) (xy 460.312138 -208.313443) (xy 460.324 -208.261474)
			(xy 460.343475 -208.211853) (xy 460.370128 -208.16569) (xy 460.403365 -208.124014) (xy 460.442441 -208.087758)
			(xy 460.486485 -208.057731) (xy 460.534513 -208.034604) (xy 460.585451 -208.018893) (xy 460.638161 -208.01095)
			(xy 460.664814 -208.010506) (xy 460.685385 -208.010781) (xy 460.726255 -208.015488) (xy 460.746348 -208.019904)
			(xy 460.761353 -208.022916) (xy 460.791872 -208.020824) (xy 460.820407 -208.009799) (xy 460.844404 -207.990827)
			(xy 460.861715 -207.965606) (xy 460.870792 -207.936393) (xy 460.871316 -207.921098) (xy 460.871316 -207.112108)
			(xy 460.870798 -207.09681) (xy 460.861739 -207.067586) (xy 460.844432 -207.042355) (xy 460.82043 -207.023382)
			(xy 460.791885 -207.012367) (xy 460.761359 -207.010301) (xy 460.746348 -207.013302) (xy 460.726254 -207.017713)
			(xy 460.685384 -207.022424) (xy 460.664814 -207.0227) (xy 460.638163 -207.022228) (xy 460.585455 -207.014285)
			(xy 460.534521 -206.998576) (xy 460.486496 -206.97545) (xy 460.442455 -206.945425) (xy 460.403381 -206.909171)
			(xy 460.370146 -206.867498) (xy 460.343495 -206.821337) (xy 460.324021 -206.771719) (xy 460.312159 -206.719753)
			(xy 460.308176 -206.6666) (xy 460.312159 -206.613447) (xy 460.324021 -206.561481) (xy 460.343495 -206.511863)
			(xy 460.370146 -206.465702) (xy 460.403381 -206.424029) (xy 460.442455 -206.387775) (xy 460.486496 -206.35775)
			(xy 460.534521 -206.334624) (xy 460.585455 -206.318915) (xy 460.638163 -206.310972) (xy 460.664814 -206.310484)
			(xy 460.685385 -206.310759) (xy 460.726255 -206.315466) (xy 460.746348 -206.319882) (xy 460.761352 -206.322894)
			(xy 460.791869 -206.320802) (xy 460.820401 -206.309777) (xy 460.844395 -206.290804) (xy 460.861702 -206.265583)
			(xy 460.870773 -206.23637) (xy 460.871316 -206.221076) (xy 460.871316 -205.412086) (xy 460.870808 -205.39678)
			(xy 460.861763 -205.367535) (xy 460.844458 -205.342283) (xy 460.820449 -205.323293) (xy 460.791891 -205.312269)
			(xy 460.761349 -205.310202) (xy 460.746348 -205.31328) (xy 460.726254 -205.317691) (xy 460.685384 -205.322402)
			(xy 460.664814 -205.322678) (xy 460.638164 -205.322206) (xy 460.58546 -205.314264) (xy 460.534529 -205.298555)
			(xy 460.486507 -205.275431) (xy 460.442469 -205.245408) (xy 460.403397 -205.209156) (xy 460.370165 -205.167485)
			(xy 460.343514 -205.121327) (xy 460.324042 -205.071713) (xy 460.312181 -205.01975) (xy 460.308198 -204.9666)
			(xy 460.312181 -204.91345) (xy 460.324042 -204.861487) (xy 460.343514 -204.811873) (xy 460.370165 -204.765715)
			(xy 460.403397 -204.724044) (xy 460.442469 -204.687792) (xy 460.486507 -204.657769) (xy 460.534529 -204.634645)
			(xy 460.58546 -204.618936) (xy 460.638164 -204.610994) (xy 460.664814 -204.610462) (xy 460.685385 -204.610737)
			(xy 460.726255 -204.615444) (xy 460.746348 -204.61986) (xy 460.761351 -204.622872) (xy 460.791866 -204.620781)
			(xy 460.820396 -204.609755) (xy 460.844387 -204.590782) (xy 460.86169 -204.565559) (xy 460.870755 -204.536347)
			(xy 460.871316 -204.521054) (xy 460.871316 -203.712318) (xy 460.870799 -203.697019) (xy 460.861742 -203.667792)
			(xy 460.844436 -203.642559) (xy 460.820432 -203.623583) (xy 460.791886 -203.612568) (xy 460.761357 -203.610501)
			(xy 460.746348 -203.613512) (xy 460.726254 -203.617923) (xy 460.685384 -203.622633) (xy 460.664814 -203.62291)
			(xy 460.638162 -203.622438) (xy 460.585453 -203.614495) (xy 460.534517 -203.598785) (xy 460.486491 -203.575659)
			(xy 460.442449 -203.545633) (xy 460.403373 -203.509378) (xy 460.370138 -203.467703) (xy 460.343486 -203.421541)
			(xy 460.324011 -203.371922) (xy 460.31215 -203.319955) (xy 460.308166 -203.2668) (xy 460.31215 -203.213645)
			(xy 460.324011 -203.161678) (xy 460.343486 -203.112059) (xy 460.370138 -203.065897) (xy 460.403373 -203.024222)
			(xy 460.442449 -202.987967) (xy 460.486491 -202.957941) (xy 460.534517 -202.934815) (xy 460.585453 -202.919105)
			(xy 460.638162 -202.911162) (xy 460.664814 -202.910694) (xy 460.685385 -202.910969) (xy 460.726255 -202.915676)
			(xy 460.746348 -202.920092) (xy 460.761352 -202.923104) (xy 460.79187 -202.921013) (xy 460.820404 -202.909987)
			(xy 460.844399 -202.891015) (xy 460.861708 -202.865793) (xy 460.870782 -202.83658) (xy 460.871316 -202.821286)
			(xy 460.871316 -202.012296) (xy 460.870796 -201.996999) (xy 460.861735 -201.967778) (xy 460.844428 -201.942551)
			(xy 460.820427 -201.92358) (xy 460.791884 -201.912567) (xy 460.76136 -201.910501) (xy 460.746348 -201.91349)
			(xy 460.726254 -201.917901) (xy 460.685384 -201.922612) (xy 460.664814 -201.922888) (xy 460.638164 -201.922416)
			(xy 460.585458 -201.914474) (xy 460.534525 -201.898765) (xy 460.486502 -201.87564) (xy 460.442462 -201.845615)
			(xy 460.403389 -201.809363) (xy 460.370156 -201.767691) (xy 460.343505 -201.721532) (xy 460.324032 -201.671916)
			(xy 460.312171 -201.619952) (xy 460.308188 -201.5668) (xy 460.312171 -201.513648) (xy 460.324032 -201.461684)
			(xy 460.343505 -201.412068) (xy 460.370156 -201.365909) (xy 460.403389 -201.324237) (xy 460.442462 -201.287985)
			(xy 460.486502 -201.25796) (xy 460.534525 -201.234835) (xy 460.585458 -201.219126) (xy 460.638164 -201.211184)
			(xy 460.664814 -201.210672) (xy 460.685385 -201.210947) (xy 460.726255 -201.215654) (xy 460.746348 -201.22007)
			(xy 460.761351 -201.223082) (xy 460.791867 -201.220991) (xy 460.820399 -201.209965) (xy 460.844391 -201.190992)
			(xy 460.861695 -201.16577) (xy 460.870763 -201.136557) (xy 460.871316 -201.121264) (xy 460.871316 -199.462136)
			(xy 460.870801 -199.446835) (xy 460.861748 -199.417603) (xy 460.844442 -199.392365) (xy 460.820437 -199.373386)
			(xy 460.791887 -199.362368) (xy 460.761355 -199.360301) (xy 460.746348 -199.36333) (xy 460.726254 -199.36774)
			(xy 460.685384 -199.372451) (xy 460.664814 -199.372728) (xy 460.638161 -199.372256) (xy 460.585449 -199.364313)
			(xy 460.53451 -199.348602) (xy 460.486482 -199.325474) (xy 460.442437 -199.295447) (xy 460.40336 -199.25919)
			(xy 460.370123 -199.217514) (xy 460.343469 -199.171349) (xy 460.323994 -199.121728) (xy 460.312132 -199.069758)
			(xy 460.308148 -199.0166) (xy 460.312132 -198.963442) (xy 460.323994 -198.911472) (xy 460.343469 -198.861851)
			(xy 460.370123 -198.815686) (xy 460.40336 -198.77401) (xy 460.442437 -198.737753) (xy 460.486482 -198.707726)
			(xy 460.53451 -198.684598) (xy 460.585449 -198.668887) (xy 460.638161 -198.660944) (xy 460.664814 -198.660512)
			(xy 460.685385 -198.660787) (xy 460.726255 -198.665495) (xy 460.746348 -198.66991) (xy 460.761353 -198.672922)
			(xy 460.791873 -198.67083) (xy 460.820408 -198.659805) (xy 460.844406 -198.640833) (xy 460.861719 -198.615612)
			(xy 460.870797 -198.586399) (xy 460.871316 -198.571104) (xy 460.871316 -197.762114) (xy 460.870798 -197.746815)
			(xy 460.861741 -197.717589) (xy 460.844434 -197.692357) (xy 460.820431 -197.673382) (xy 460.791885 -197.662368)
			(xy 460.761358 -197.660301) (xy 460.746348 -197.663308) (xy 460.726254 -197.667719) (xy 460.685384 -197.672429)
			(xy 460.664814 -197.672706) (xy 460.638162 -197.672234) (xy 460.585454 -197.664291) (xy 460.534518 -197.648581)
			(xy 460.486493 -197.625455) (xy 460.442451 -197.59543) (xy 460.403376 -197.559175) (xy 460.370141 -197.517501)
			(xy 460.343489 -197.47134) (xy 460.324015 -197.421721) (xy 460.312153 -197.369754) (xy 460.30817 -197.3166)
			(xy 460.312153 -197.263446) (xy 460.324015 -197.211479) (xy 460.343489 -197.16186) (xy 460.370141 -197.115699)
			(xy 460.403376 -197.074025) (xy 460.442451 -197.03777) (xy 460.486493 -197.007745) (xy 460.534518 -196.984619)
			(xy 460.585454 -196.968909) (xy 460.638162 -196.960966) (xy 460.664814 -196.96049) (xy 460.685385 -196.960765)
			(xy 460.726255 -196.965472) (xy 460.746348 -196.969888) (xy 460.761352 -196.9729) (xy 460.79187 -196.970809)
			(xy 460.820403 -196.959783) (xy 460.844398 -196.940811) (xy 460.861706 -196.915589) (xy 460.870778 -196.886376)
			(xy 460.871316 -196.871082) (xy 460.871316 -196.062092) (xy 460.870809 -196.046785) (xy 460.861765 -196.017538)
			(xy 460.84446 -195.992285) (xy 460.82045 -195.973293) (xy 460.791891 -195.962269) (xy 460.761348 -195.960202)
			(xy 460.746348 -195.963286) (xy 460.726254 -195.967697) (xy 460.685384 -195.972408) (xy 460.664814 -195.972684)
			(xy 460.638164 -195.972212) (xy 460.585459 -195.96427) (xy 460.534526 -195.948561) (xy 460.486504 -195.925436)
			(xy 460.442465 -195.895412) (xy 460.403392 -195.85916) (xy 460.37016 -195.817489) (xy 460.343509 -195.77133)
			(xy 460.324036 -195.721715) (xy 460.312175 -195.669751) (xy 460.308192 -195.6166) (xy 460.312175 -195.563449)
			(xy 460.324036 -195.511485) (xy 460.343509 -195.46187) (xy 460.37016 -195.415711) (xy 460.403392 -195.37404)
			(xy 460.442465 -195.337788) (xy 460.486504 -195.307764) (xy 460.534526 -195.284639) (xy 460.585459 -195.26893)
			(xy 460.638164 -195.260988) (xy 460.664814 -195.260468) (xy 460.685385 -195.260743) (xy 460.726255 -195.26545)
			(xy 460.746348 -195.269866) (xy 460.761351 -195.272878) (xy 460.791867 -195.270787) (xy 460.820398 -195.259761)
			(xy 460.844389 -195.240788) (xy 460.861693 -195.215566) (xy 460.87076 -195.186353) (xy 460.871316 -195.17106)
			(xy 460.871316 -190.02502) (xy 460.829406 -190.017654) (xy 460.787522 -190.009812) (xy 460.705319 -189.98735)
			(xy 460.625561 -189.957339) (xy 460.54894 -189.920039) (xy 460.476121 -189.875775) (xy 460.407735 -189.824929)
			(xy 460.344374 -189.767943) (xy 460.286588 -189.705311) (xy 460.234878 -189.637576) (xy 460.189693 -189.565325)
			(xy 460.151424 -189.489184) (xy 460.120402 -189.409813) (xy 460.096898 -189.327902) (xy 460.081114 -189.244159)
			(xy 460.073187 -189.159311) (xy 460.073187 -189.074094) (xy 460.081113 -188.989246) (xy 460.096896 -188.905504)
			(xy 460.1204 -188.823592) (xy 460.151421 -188.744221) (xy 460.18969 -188.66808) (xy 460.234875 -188.595829)
			(xy 460.286585 -188.528093) (xy 460.34437 -188.46546) (xy 460.40773 -188.408474) (xy 460.476117 -188.357628)
			(xy 460.548936 -188.313363) (xy 460.625556 -188.276064) (xy 460.705314 -188.246052) (xy 460.787517 -188.223589)
			(xy 460.829406 -188.215778) (xy 460.871316 -188.208412) (xy 460.871316 -177.233072) (xy 459.113128 -175.474884)
			(xy 436.46725 -175.474884) (xy 436.453196 -175.475337) (xy 436.426152 -175.482997) (xy 436.402212 -175.497726)
			(xy 436.383182 -175.518412) (xy 436.370497 -175.543495) (xy 436.365115 -175.571083) (xy 436.365904 -175.58512)
			(xy 436.367428 -175.61814) (xy 436.366942 -175.645391) (xy 436.359186 -175.699339) (xy 436.343831 -175.751634)
			(xy 436.321189 -175.801211) (xy 436.291723 -175.847061) (xy 436.256032 -175.888252) (xy 436.214841 -175.923943)
			(xy 436.168991 -175.953409) (xy 436.119414 -175.976051) (xy 436.067119 -175.991406) (xy 436.013171 -175.999162)
			(xy 435.958669 -175.999162) (xy 435.904721 -175.991406) (xy 435.852426 -175.976051) (xy 435.802849 -175.953409)
			(xy 435.756999 -175.923943) (xy 435.715808 -175.888252) (xy 435.680117 -175.847061) (xy 435.650651 -175.801211)
			(xy 435.628009 -175.751634) (xy 435.612654 -175.699339) (xy 435.604898 -175.645391) (xy 435.604412 -175.61814)
			(xy 435.605936 -175.58512) (xy 435.606694 -175.571073) (xy 435.60137 -175.543461) (xy 435.588712 -175.518351)
			(xy 435.569679 -175.497651) (xy 435.545719 -175.482931) (xy 435.518651 -175.475311) (xy 435.50459 -175.474884)
			(xy 434.964078 -175.474884) (xy 434.950392 -175.47533) (xy 434.924003 -175.482601) (xy 434.900491 -175.496615)
			(xy 434.881543 -175.516368) (xy 434.868517 -175.540442) (xy 434.862348 -175.56711) (xy 434.862478 -175.580802)
			(xy 434.862732 -175.597058) (xy 434.862247 -175.624428) (xy 434.854466 -175.678612) (xy 434.839057 -175.731137)
			(xy 434.816332 -175.780937) (xy 434.786753 -175.826997) (xy 434.750924 -175.868382) (xy 434.709572 -175.904248)
			(xy 434.663538 -175.933867) (xy 434.613758 -175.956637) (xy 434.561246 -175.972094) (xy 434.507069 -175.979923)
			(xy 434.4797 -175.980344) (xy 434.449253 -175.97974) (xy 434.389132 -175.970069) (xy 434.3313 -175.951003)
			(xy 434.277215 -175.923023) (xy 434.25237 -175.905414) (xy 434.138854 -176.018952) (xy 444.68161 -176.018952)
			(xy 444.682033 -175.991699) (xy 444.689797 -175.937748) (xy 444.705159 -175.885451) (xy 444.727807 -175.835872)
			(xy 444.75728 -175.790021) (xy 444.792978 -175.748831) (xy 444.834174 -175.71314) (xy 444.88003 -175.683675)
			(xy 444.929613 -175.661036) (xy 444.981912 -175.645683) (xy 445.035865 -175.637929) (xy 445.063118 -175.637444)
			(xy 445.08913 -175.637893) (xy 445.140672 -175.644964) (xy 445.190775 -175.658973) (xy 445.238509 -175.67966)
			(xy 445.28299 -175.706641) (xy 445.323393 -175.739415) (xy 445.341502 -175.758094) (xy 445.351381 -175.768042)
			(xy 445.37536 -175.78255) (xy 445.402382 -175.789987) (xy 445.430407 -175.789795) (xy 445.457324 -175.781987)
			(xy 445.481102 -175.767151) (xy 445.490854 -175.757078) (xy 445.509036 -175.737781) (xy 445.549776 -175.703855)
			(xy 445.594821 -175.675895) (xy 445.643302 -175.65444) (xy 445.694287 -175.639904) (xy 445.746794 -175.632565)
			(xy 445.773302 -175.63211) (xy 445.800556 -175.632554) (xy 445.854508 -175.640311) (xy 445.906808 -175.655668)
			(xy 445.956389 -175.678312) (xy 446.002243 -175.707782) (xy 446.043436 -175.743478) (xy 446.07913 -175.784673)
			(xy 446.108597 -175.830529) (xy 446.131239 -175.880111) (xy 446.146593 -175.932411) (xy 446.154348 -175.986364)
			(xy 446.15481 -176.013618) (xy 446.15429 -176.041314) (xy 446.146295 -176.096126) (xy 446.130461 -176.149206)
			(xy 446.10712 -176.19944) (xy 446.076763 -176.245773) (xy 446.040027 -176.28723) (xy 446.019174 -176.305464)
			(xy 446.012336 -176.311719) (xy 446.003266 -176.32786) (xy 446.000545 -176.346174) (xy 446.004531 -176.364255)
			(xy 446.014699 -176.379727) (xy 446.021968 -176.385474) (xy 446.049146 -176.407064) (xy 446.060474 -176.4163)
			(xy 446.087031 -176.428476) (xy 446.115948 -176.432649) (xy 446.144865 -176.428476) (xy 446.171422 -176.4163)
			(xy 446.18275 -176.407064) (xy 446.203685 -176.389429) (xy 446.249658 -176.359718) (xy 446.299405 -176.336882)
			(xy 446.351904 -176.32139) (xy 446.406079 -176.313559) (xy 446.433448 -176.313084) (xy 446.460696 -176.313589)
			(xy 446.514638 -176.321351) (xy 446.566926 -176.33671) (xy 446.616496 -176.359353) (xy 446.662339 -176.38882)
			(xy 446.703523 -176.424511) (xy 446.739209 -176.465699) (xy 446.76867 -176.511546) (xy 446.791307 -176.561119)
			(xy 446.806659 -176.613409) (xy 446.814414 -176.667352) (xy 446.814414 -176.721848) (xy 446.814413 -176.721856)
			(xy 447.068348 -176.721856) (xy 447.068348 -176.667344) (xy 447.076106 -176.613388) (xy 447.091465 -176.561085)
			(xy 447.114111 -176.511501) (xy 447.143584 -176.465645) (xy 447.179284 -176.42445) (xy 447.220483 -176.388755)
			(xy 447.266343 -176.359288) (xy 447.31593 -176.336648) (xy 447.368235 -176.321296) (xy 447.422192 -176.313544)
			(xy 447.449448 -176.313084) (xy 447.477642 -176.3141) (xy 447.491734 -176.314647) (xy 447.519327 -176.308873)
			(xy 447.544292 -176.295778) (xy 447.564729 -176.276361) (xy 447.579082 -176.252098) (xy 447.586259 -176.224836)
			(xy 447.585714 -176.196651) (xy 447.582036 -176.183036) (xy 447.574146 -176.155645) (xy 447.565733 -176.099269)
			(xy 447.565272 -176.070768) (xy 447.565758 -176.043517) (xy 447.573514 -175.989569) (xy 447.588869 -175.937274)
			(xy 447.611511 -175.887697) (xy 447.640977 -175.841847) (xy 447.676668 -175.800656) (xy 447.717859 -175.764965)
			(xy 447.763709 -175.735499) (xy 447.813286 -175.712857) (xy 447.865581 -175.697502) (xy 447.919529 -175.689746)
			(xy 447.974031 -175.689746) (xy 448.027979 -175.697502) (xy 448.080274 -175.712857) (xy 448.129851 -175.735499)
			(xy 448.175701 -175.764965) (xy 448.216892 -175.800656) (xy 448.252583 -175.841847) (xy 448.282049 -175.887697)
			(xy 448.304691 -175.937274) (xy 448.320046 -175.989569) (xy 448.327802 -176.043517) (xy 448.328288 -176.070768)
			(xy 448.327622 -176.102919) (xy 448.316828 -176.166308) (xy 448.295539 -176.226983) (xy 448.280536 -176.255426)
			(xy 448.273907 -176.268551) (xy 448.267588 -176.297251) (xy 448.269715 -176.326561) (xy 448.280112 -176.354047)
			(xy 448.297916 -176.377427) (xy 448.309492 -176.38649) (xy 448.333303 -176.404583) (xy 448.375488 -176.446968)
			(xy 448.410546 -176.495413) (xy 448.43762 -176.548734) (xy 448.456046 -176.605624) (xy 448.465374 -176.664692)
			(xy 448.465956 -176.694592) (xy 448.465415 -176.721841) (xy 448.457661 -176.775784) (xy 448.442309 -176.828075)
			(xy 448.419672 -176.877649) (xy 448.390211 -176.923497) (xy 448.354526 -176.964686) (xy 448.313342 -177.000378)
			(xy 448.267498 -177.029845) (xy 448.217927 -177.052489) (xy 448.165639 -177.067849) (xy 448.111697 -177.075611)
			(xy 448.084448 -177.0761) (xy 448.057079 -177.075606) (xy 448.002901 -177.067795) (xy 447.950398 -177.052312)
			(xy 447.900651 -177.029477) (xy 447.854683 -176.999758) (xy 447.83375 -176.98212) (xy 447.822422 -176.972884)
			(xy 447.795865 -176.960708) (xy 447.766948 -176.956535) (xy 447.738031 -176.960708) (xy 447.711474 -176.972884)
			(xy 447.700146 -176.98212) (xy 447.67921 -176.999754) (xy 447.633238 -177.029466) (xy 447.583491 -177.052303)
			(xy 447.530992 -177.067795) (xy 447.476817 -177.075625) (xy 447.449448 -177.0761) (xy 447.422192 -177.075656)
			(xy 447.368235 -177.067904) (xy 447.31593 -177.052552) (xy 447.266343 -177.029912) (xy 447.220483 -177.000445)
			(xy 447.179284 -176.96475) (xy 447.143584 -176.923555) (xy 447.114111 -176.877699) (xy 447.091465 -176.828115)
			(xy 447.076106 -176.775812) (xy 447.068348 -176.721856) (xy 446.814413 -176.721856) (xy 446.806659 -176.775791)
			(xy 446.791307 -176.828081) (xy 446.76867 -176.877654) (xy 446.739209 -176.923501) (xy 446.703523 -176.964689)
			(xy 446.662339 -177.00038) (xy 446.616496 -177.029847) (xy 446.566926 -177.05249) (xy 446.514638 -177.067849)
			(xy 446.460696 -177.075611) (xy 446.433448 -177.0761) (xy 446.406079 -177.075606) (xy 446.351901 -177.067795)
			(xy 446.299398 -177.052312) (xy 446.249651 -177.029477) (xy 446.203683 -176.999758) (xy 446.18275 -176.98212)
			(xy 446.171422 -176.972884) (xy 446.144865 -176.960708) (xy 446.115948 -176.956535) (xy 446.087031 -176.960708)
			(xy 446.060474 -176.972884) (xy 446.049146 -176.98212) (xy 446.02821 -176.999754) (xy 445.982238 -177.029466)
			(xy 445.932491 -177.052303) (xy 445.879992 -177.067795) (xy 445.825817 -177.075625) (xy 445.798448 -177.0761)
			(xy 445.772434 -177.075691) (xy 445.72089 -177.068614) (xy 445.670786 -177.054599) (xy 445.623051 -177.033904)
			(xy 445.578571 -177.006916) (xy 445.538171 -176.974133) (xy 445.520064 -176.95545) (xy 445.510219 -176.945464)
			(xy 445.486231 -176.930952) (xy 445.4592 -176.923515) (xy 445.431165 -176.923714) (xy 445.404242 -176.931534)
			(xy 445.380462 -176.946385) (xy 445.370712 -176.956466) (xy 445.352556 -176.975788) (xy 445.311809 -177.00971)
			(xy 445.266759 -177.037665) (xy 445.218272 -177.059116) (xy 445.167283 -177.073648) (xy 445.114774 -177.080982)
			(xy 445.088264 -177.081434) (xy 445.061013 -177.080956) (xy 445.007066 -177.073195) (xy 444.954773 -177.057837)
			(xy 444.905197 -177.035193) (xy 444.859349 -177.005726) (xy 444.818159 -176.970034) (xy 444.782468 -176.928843)
			(xy 444.753002 -176.882994) (xy 444.73036 -176.833417) (xy 444.715003 -176.781124) (xy 444.707244 -176.727177)
			(xy 444.706756 -176.699926) (xy 444.707283 -176.671461) (xy 444.715757 -176.615165) (xy 444.732506 -176.560755)
			(xy 444.757158 -176.509439) (xy 444.789165 -176.462358) (xy 444.808102 -176.4411) (xy 444.816772 -176.431026)
			(xy 444.829184 -176.407541) (xy 444.835101 -176.381646) (xy 444.834121 -176.3551) (xy 444.826309 -176.329712)
			(xy 444.812199 -176.307206) (xy 444.802768 -176.297844) (xy 444.784021 -176.279718) (xy 444.751106 -176.239272)
			(xy 444.724005 -176.194722) (xy 444.703222 -176.146895) (xy 444.689146 -176.096685) (xy 444.682038 -176.045025)
			(xy 444.68161 -176.018952) (xy 434.138854 -176.018952) (xy 432.957224 -177.200814) (xy 432.957224 -178.044348)
			(xy 434.953662 -178.044348) (xy 434.957733 -177.988726) (xy 434.969859 -177.934289) (xy 434.989782 -177.882198)
			(xy 435.017078 -177.833563) (xy 435.051164 -177.78942) (xy 435.091313 -177.750711) (xy 435.136671 -177.71826)
			(xy 435.186271 -177.692759) (xy 435.239055 -177.674752) (xy 435.293898 -177.664622) (xy 435.349632 -177.662585)
			(xy 435.405069 -177.668685) (xy 435.459026 -177.682791) (xy 435.510355 -177.704603) (xy 435.557961 -177.733657)
			(xy 435.600829 -177.769332) (xy 435.638046 -177.810869) (xy 435.668819 -177.857382) (xy 435.692491 -177.907879)
			(xy 435.708559 -177.961286) (xy 435.716679 -178.016462) (xy 435.717188 -178.044348) (xy 435.716679 -178.072234)
			(xy 435.708559 -178.12741) (xy 435.692491 -178.180817) (xy 435.668819 -178.231314) (xy 435.638046 -178.277827)
			(xy 435.600829 -178.319364) (xy 435.557961 -178.355039) (xy 435.510355 -178.384093) (xy 435.459026 -178.405905)
			(xy 435.405069 -178.420011) (xy 435.349632 -178.426111) (xy 435.293898 -178.424074) (xy 435.239055 -178.413944)
			(xy 435.186271 -178.395937) (xy 435.136671 -178.370436) (xy 435.091313 -178.337985) (xy 435.051164 -178.299276)
			(xy 435.017078 -178.255133) (xy 434.989782 -178.206498) (xy 434.969859 -178.154407) (xy 434.957733 -178.09997)
			(xy 434.953662 -178.044348) (xy 432.957224 -178.044348) (xy 432.957224 -178.755548) (xy 433.124862 -178.755548)
			(xy 433.128933 -178.699926) (xy 433.141059 -178.645489) (xy 433.160982 -178.593398) (xy 433.188278 -178.544763)
			(xy 433.222364 -178.50062) (xy 433.262513 -178.461911) (xy 433.307871 -178.42946) (xy 433.357471 -178.403959)
			(xy 433.410255 -178.385952) (xy 433.465098 -178.375822) (xy 433.520832 -178.373785) (xy 433.576269 -178.379885)
			(xy 433.630226 -178.393991) (xy 433.681555 -178.415803) (xy 433.729161 -178.444857) (xy 433.772029 -178.480532)
			(xy 433.809246 -178.522069) (xy 433.840019 -178.568582) (xy 433.863691 -178.619079) (xy 433.879759 -178.672486)
			(xy 433.882526 -178.691286) (xy 433.98897 -178.691286) (xy 433.993041 -178.635664) (xy 434.005167 -178.581227)
			(xy 434.02509 -178.529136) (xy 434.052386 -178.480501) (xy 434.086472 -178.436358) (xy 434.126621 -178.397649)
			(xy 434.171979 -178.365198) (xy 434.221579 -178.339697) (xy 434.274363 -178.32169) (xy 434.329206 -178.31156)
			(xy 434.38494 -178.309523) (xy 434.440377 -178.315623) (xy 434.494334 -178.329729) (xy 434.545663 -178.351541)
			(xy 434.593269 -178.380595) (xy 434.636137 -178.41627) (xy 434.673354 -178.457807) (xy 434.704127 -178.50432)
			(xy 434.727799 -178.554817) (xy 434.743867 -178.608224) (xy 434.751987 -178.6634) (xy 434.752496 -178.691286)
			(xy 434.751987 -178.719172) (xy 434.743867 -178.774348) (xy 434.727799 -178.827755) (xy 434.72424 -178.835348)
			(xy 444.707304 -178.835348) (xy 444.707304 -178.780852) (xy 444.715059 -178.726911) (xy 444.730411 -178.674623)
			(xy 444.753048 -178.625052) (xy 444.782509 -178.579206) (xy 444.818194 -178.53802) (xy 444.859377 -178.502331)
			(xy 444.90522 -178.472866) (xy 444.954789 -178.450224) (xy 445.007076 -178.434867) (xy 445.061016 -178.427107)
			(xy 445.088264 -178.426618) (xy 445.114278 -178.427013) (xy 445.165823 -178.434092) (xy 445.215928 -178.44811)
			(xy 445.263663 -178.468807) (xy 445.308143 -178.495798) (xy 445.348542 -178.528584) (xy 445.366648 -178.547268)
			(xy 445.376576 -178.557164) (xy 445.40054 -178.571678) (xy 445.42755 -178.579125) (xy 445.455566 -178.578943)
			(xy 445.482476 -178.571145) (xy 445.506249 -178.55632) (xy 445.516 -178.546252) (xy 445.534154 -178.526928)
			(xy 445.574901 -178.493005) (xy 445.619952 -178.46505) (xy 445.668438 -178.4436) (xy 445.719428 -178.429068)
			(xy 445.771938 -178.421735) (xy 445.798448 -178.421284) (xy 445.825818 -178.42176) (xy 445.879998 -178.429572)
			(xy 445.932501 -178.445058) (xy 445.982249 -178.467898) (xy 446.028215 -178.497622) (xy 446.049146 -178.515264)
			(xy 446.060474 -178.5245) (xy 446.087031 -178.536676) (xy 446.115948 -178.540849) (xy 446.144865 -178.536676)
			(xy 446.171422 -178.5245) (xy 446.18275 -178.515264) (xy 446.203685 -178.497629) (xy 446.249658 -178.467918)
			(xy 446.299405 -178.445082) (xy 446.351904 -178.42959) (xy 446.406079 -178.421759) (xy 446.433448 -178.421284)
			(xy 446.460696 -178.421789) (xy 446.514638 -178.429551) (xy 446.566926 -178.44491) (xy 446.616496 -178.467553)
			(xy 446.662339 -178.49702) (xy 446.703523 -178.532711) (xy 446.739209 -178.573899) (xy 446.76867 -178.619746)
			(xy 446.791307 -178.669319) (xy 446.806659 -178.721609) (xy 446.814414 -178.775552) (xy 446.814414 -178.830048)
			(xy 446.814413 -178.830056) (xy 447.068348 -178.830056) (xy 447.068348 -178.775544) (xy 447.076106 -178.721588)
			(xy 447.091465 -178.669285) (xy 447.114111 -178.619701) (xy 447.143584 -178.573845) (xy 447.179284 -178.53265)
			(xy 447.220483 -178.496955) (xy 447.266343 -178.467488) (xy 447.31593 -178.444848) (xy 447.368235 -178.429496)
			(xy 447.422192 -178.421744) (xy 447.449448 -178.421284) (xy 447.476818 -178.42176) (xy 447.530998 -178.429572)
			(xy 447.583501 -178.445058) (xy 447.633249 -178.467898) (xy 447.679215 -178.497622) (xy 447.700146 -178.515264)
			(xy 447.711474 -178.5245) (xy 447.738031 -178.536676) (xy 447.766948 -178.540849) (xy 447.795865 -178.536676)
			(xy 447.822422 -178.5245) (xy 447.83375 -178.515264) (xy 447.854685 -178.497629) (xy 447.900658 -178.467918)
			(xy 447.950405 -178.445082) (xy 448.002904 -178.42959) (xy 448.057079 -178.421759) (xy 448.084448 -178.421284)
			(xy 448.111696 -178.421789) (xy 448.165638 -178.429551) (xy 448.217926 -178.44491) (xy 448.267496 -178.467553)
			(xy 448.313339 -178.49702) (xy 448.354523 -178.532711) (xy 448.390209 -178.573899) (xy 448.41967 -178.619746)
			(xy 448.442307 -178.669319) (xy 448.457659 -178.721609) (xy 448.465414 -178.775552) (xy 448.465414 -178.830048)
			(xy 448.457659 -178.883991) (xy 448.442307 -178.936281) (xy 448.41967 -178.985854) (xy 448.390209 -179.031701)
			(xy 448.354523 -179.072889) (xy 448.313339 -179.10858) (xy 448.267496 -179.138047) (xy 448.217926 -179.16069)
			(xy 448.165638 -179.176049) (xy 448.111696 -179.183811) (xy 448.084448 -179.1843) (xy 448.057079 -179.183806)
			(xy 448.002901 -179.175995) (xy 447.950398 -179.160512) (xy 447.900651 -179.137677) (xy 447.854683 -179.107958)
			(xy 447.83375 -179.09032) (xy 447.822422 -179.081084) (xy 447.795865 -179.068908) (xy 447.766948 -179.064735)
			(xy 447.738031 -179.068908) (xy 447.711474 -179.081084) (xy 447.700146 -179.09032) (xy 447.67921 -179.107954)
			(xy 447.633238 -179.137666) (xy 447.583491 -179.160503) (xy 447.530992 -179.175995) (xy 447.476817 -179.183825)
			(xy 447.449448 -179.1843) (xy 447.422192 -179.183856) (xy 447.368235 -179.176104) (xy 447.31593 -179.160752)
			(xy 447.266343 -179.138112) (xy 447.220483 -179.108645) (xy 447.179284 -179.07295) (xy 447.143584 -179.031755)
			(xy 447.114111 -178.985899) (xy 447.091465 -178.936315) (xy 447.076106 -178.884012) (xy 447.068348 -178.830056)
			(xy 446.814413 -178.830056) (xy 446.806659 -178.883991) (xy 446.791307 -178.936281) (xy 446.76867 -178.985854)
			(xy 446.739209 -179.031701) (xy 446.703523 -179.072889) (xy 446.662339 -179.10858) (xy 446.616496 -179.138047)
			(xy 446.566926 -179.16069) (xy 446.514638 -179.176049) (xy 446.460696 -179.183811) (xy 446.433448 -179.1843)
			(xy 446.406079 -179.183806) (xy 446.351901 -179.175995) (xy 446.299398 -179.160512) (xy 446.249651 -179.137677)
			(xy 446.203683 -179.107958) (xy 446.18275 -179.09032) (xy 446.171422 -179.081084) (xy 446.144865 -179.068908)
			(xy 446.115948 -179.064735) (xy 446.087031 -179.068908) (xy 446.060474 -179.081084) (xy 446.049146 -179.09032)
			(xy 446.02821 -179.107954) (xy 445.982238 -179.137666) (xy 445.932491 -179.160503) (xy 445.879992 -179.175995)
			(xy 445.825817 -179.183825) (xy 445.798448 -179.1843) (xy 445.772434 -179.183891) (xy 445.72089 -179.176814)
			(xy 445.670786 -179.162799) (xy 445.623051 -179.142104) (xy 445.578571 -179.115116) (xy 445.538171 -179.082333)
			(xy 445.520064 -179.06365) (xy 445.510219 -179.053664) (xy 445.486231 -179.039152) (xy 445.4592 -179.031715)
			(xy 445.431165 -179.031914) (xy 445.404242 -179.039734) (xy 445.380462 -179.054585) (xy 445.370712 -179.064666)
			(xy 445.352556 -179.083988) (xy 445.311809 -179.11791) (xy 445.266759 -179.145865) (xy 445.218272 -179.167316)
			(xy 445.167283 -179.181848) (xy 445.114774 -179.189182) (xy 445.088264 -179.189634) (xy 445.061016 -179.189093)
			(xy 445.007076 -179.181333) (xy 444.954789 -179.165976) (xy 444.90522 -179.143334) (xy 444.859377 -179.113869)
			(xy 444.818194 -179.07818) (xy 444.782509 -179.036994) (xy 444.753048 -178.991148) (xy 444.730411 -178.941577)
			(xy 444.715059 -178.889289) (xy 444.707304 -178.835348) (xy 434.72424 -178.835348) (xy 434.704127 -178.878252)
			(xy 434.673354 -178.924765) (xy 434.636137 -178.966302) (xy 434.593269 -179.001977) (xy 434.545663 -179.031031)
			(xy 434.494334 -179.052843) (xy 434.440377 -179.066949) (xy 434.38494 -179.073049) (xy 434.329206 -179.071012)
			(xy 434.274363 -179.060882) (xy 434.221579 -179.042875) (xy 434.171979 -179.017374) (xy 434.126621 -178.984923)
			(xy 434.086472 -178.946214) (xy 434.052386 -178.902071) (xy 434.02509 -178.853436) (xy 434.005167 -178.801345)
			(xy 433.993041 -178.746908) (xy 433.98897 -178.691286) (xy 433.882526 -178.691286) (xy 433.887879 -178.727662)
			(xy 433.888388 -178.755548) (xy 433.887879 -178.783434) (xy 433.879759 -178.83861) (xy 433.863691 -178.892017)
			(xy 433.840019 -178.942514) (xy 433.809246 -178.989027) (xy 433.772029 -179.030564) (xy 433.729161 -179.066239)
			(xy 433.681555 -179.095293) (xy 433.630226 -179.117105) (xy 433.576269 -179.131211) (xy 433.520832 -179.137311)
			(xy 433.465098 -179.135274) (xy 433.410255 -179.125144) (xy 433.357471 -179.107137) (xy 433.307871 -179.081636)
			(xy 433.262513 -179.049185) (xy 433.222364 -179.010476) (xy 433.188278 -178.966333) (xy 433.160982 -178.917698)
			(xy 433.141059 -178.865607) (xy 433.128933 -178.81117) (xy 433.124862 -178.755548) (xy 432.957224 -178.755548)
			(xy 432.957224 -179.521612) (xy 432.956712 -179.546596) (xy 432.948861 -179.595943) (xy 432.933401 -179.64346)
			(xy 432.91071 -179.687979) (xy 432.881346 -179.72841) (xy 432.864006 -179.746402) (xy 432.731672 -179.878736)
			(xy 432.731672 -180.943548) (xy 444.707304 -180.943548) (xy 444.707304 -180.889052) (xy 444.715059 -180.835111)
			(xy 444.730411 -180.782823) (xy 444.753048 -180.733252) (xy 444.782509 -180.687406) (xy 444.818194 -180.64622)
			(xy 444.859377 -180.610531) (xy 444.90522 -180.581066) (xy 444.954789 -180.558424) (xy 445.007076 -180.543067)
			(xy 445.061016 -180.535307) (xy 445.088264 -180.534818) (xy 445.114278 -180.535213) (xy 445.165823 -180.542292)
			(xy 445.215928 -180.55631) (xy 445.263663 -180.577007) (xy 445.308143 -180.603998) (xy 445.348542 -180.636784)
			(xy 445.366648 -180.655468) (xy 445.376576 -180.665364) (xy 445.40054 -180.679878) (xy 445.42755 -180.687325)
			(xy 445.455566 -180.687143) (xy 445.482476 -180.679345) (xy 445.506249 -180.66452) (xy 445.516 -180.654452)
			(xy 445.534154 -180.635128) (xy 445.574901 -180.601205) (xy 445.619952 -180.57325) (xy 445.668438 -180.5518)
			(xy 445.719428 -180.537268) (xy 445.771938 -180.529935) (xy 445.798448 -180.529484) (xy 445.825818 -180.52996)
			(xy 445.879998 -180.537772) (xy 445.932501 -180.553258) (xy 445.982249 -180.576098) (xy 446.028215 -180.605822)
			(xy 446.049146 -180.623464) (xy 446.060474 -180.6327) (xy 446.087031 -180.644876) (xy 446.115948 -180.649049)
			(xy 446.144865 -180.644876) (xy 446.171422 -180.6327) (xy 446.18275 -180.623464) (xy 446.203685 -180.605829)
			(xy 446.249658 -180.576118) (xy 446.299405 -180.553282) (xy 446.351904 -180.53779) (xy 446.406079 -180.529959)
			(xy 446.433448 -180.529484) (xy 446.460696 -180.529989) (xy 446.514638 -180.537751) (xy 446.566926 -180.55311)
			(xy 446.616496 -180.575753) (xy 446.662339 -180.60522) (xy 446.703523 -180.640911) (xy 446.739209 -180.682099)
			(xy 446.76867 -180.727946) (xy 446.791307 -180.777519) (xy 446.806659 -180.829809) (xy 446.814414 -180.883752)
			(xy 446.814414 -180.938248) (xy 446.814413 -180.938256) (xy 447.068348 -180.938256) (xy 447.068348 -180.883744)
			(xy 447.076106 -180.829788) (xy 447.091465 -180.777485) (xy 447.114111 -180.727901) (xy 447.143584 -180.682045)
			(xy 447.179284 -180.64085) (xy 447.220483 -180.605155) (xy 447.266343 -180.575688) (xy 447.31593 -180.553048)
			(xy 447.368235 -180.537696) (xy 447.422192 -180.529944) (xy 447.449448 -180.529484) (xy 447.476818 -180.52996)
			(xy 447.530998 -180.537772) (xy 447.583501 -180.553258) (xy 447.633249 -180.576098) (xy 447.679215 -180.605822)
			(xy 447.700146 -180.623464) (xy 447.711474 -180.6327) (xy 447.738031 -180.644876) (xy 447.766948 -180.649049)
			(xy 447.795865 -180.644876) (xy 447.822422 -180.6327) (xy 447.83375 -180.623464) (xy 447.854685 -180.605829)
			(xy 447.900658 -180.576118) (xy 447.950405 -180.553282) (xy 448.002904 -180.53779) (xy 448.057079 -180.529959)
			(xy 448.084448 -180.529484) (xy 448.111696 -180.529989) (xy 448.165638 -180.537751) (xy 448.217926 -180.55311)
			(xy 448.267496 -180.575753) (xy 448.313339 -180.60522) (xy 448.354523 -180.640911) (xy 448.390209 -180.682099)
			(xy 448.41967 -180.727946) (xy 448.442307 -180.777519) (xy 448.457659 -180.829809) (xy 448.465414 -180.883752)
			(xy 448.465414 -180.938248) (xy 448.457659 -180.992191) (xy 448.442307 -181.044481) (xy 448.41967 -181.094054)
			(xy 448.390209 -181.139901) (xy 448.354523 -181.181089) (xy 448.313339 -181.21678) (xy 448.267496 -181.246247)
			(xy 448.217926 -181.26889) (xy 448.165638 -181.284249) (xy 448.111696 -181.292011) (xy 448.084448 -181.2925)
			(xy 448.057079 -181.292006) (xy 448.002901 -181.284195) (xy 447.950398 -181.268712) (xy 447.900651 -181.245877)
			(xy 447.854683 -181.216158) (xy 447.83375 -181.19852) (xy 447.822422 -181.189284) (xy 447.795865 -181.177108)
			(xy 447.766948 -181.172935) (xy 447.738031 -181.177108) (xy 447.711474 -181.189284) (xy 447.700146 -181.19852)
			(xy 447.67921 -181.216154) (xy 447.633238 -181.245866) (xy 447.583491 -181.268703) (xy 447.530992 -181.284195)
			(xy 447.476817 -181.292025) (xy 447.449448 -181.2925) (xy 447.422192 -181.292056) (xy 447.368235 -181.284304)
			(xy 447.31593 -181.268952) (xy 447.266343 -181.246312) (xy 447.220483 -181.216845) (xy 447.179284 -181.18115)
			(xy 447.143584 -181.139955) (xy 447.114111 -181.094099) (xy 447.091465 -181.044515) (xy 447.076106 -180.992212)
			(xy 447.068348 -180.938256) (xy 446.814413 -180.938256) (xy 446.806659 -180.992191) (xy 446.791307 -181.044481)
			(xy 446.76867 -181.094054) (xy 446.739209 -181.139901) (xy 446.703523 -181.181089) (xy 446.662339 -181.21678)
			(xy 446.616496 -181.246247) (xy 446.566926 -181.26889) (xy 446.514638 -181.284249) (xy 446.460696 -181.292011)
			(xy 446.433448 -181.2925) (xy 446.406079 -181.292006) (xy 446.351901 -181.284195) (xy 446.299398 -181.268712)
			(xy 446.249651 -181.245877) (xy 446.203683 -181.216158) (xy 446.18275 -181.19852) (xy 446.171422 -181.189284)
			(xy 446.144865 -181.177108) (xy 446.115948 -181.172935) (xy 446.087031 -181.177108) (xy 446.060474 -181.189284)
			(xy 446.049146 -181.19852) (xy 446.02821 -181.216154) (xy 445.982238 -181.245866) (xy 445.932491 -181.268703)
			(xy 445.879992 -181.284195) (xy 445.825817 -181.292025) (xy 445.798448 -181.2925) (xy 445.772434 -181.292091)
			(xy 445.72089 -181.285014) (xy 445.670786 -181.270999) (xy 445.623051 -181.250304) (xy 445.578571 -181.223316)
			(xy 445.538171 -181.190533) (xy 445.520064 -181.17185) (xy 445.510219 -181.161864) (xy 445.486231 -181.147352)
			(xy 445.4592 -181.139915) (xy 445.431165 -181.140114) (xy 445.404242 -181.147934) (xy 445.380462 -181.162785)
			(xy 445.370712 -181.172866) (xy 445.352556 -181.192188) (xy 445.311809 -181.22611) (xy 445.266759 -181.254065)
			(xy 445.218272 -181.275516) (xy 445.167283 -181.290048) (xy 445.114774 -181.297382) (xy 445.088264 -181.297834)
			(xy 445.061016 -181.297293) (xy 445.007076 -181.289533) (xy 444.954789 -181.274176) (xy 444.90522 -181.251534)
			(xy 444.859377 -181.222069) (xy 444.818194 -181.18638) (xy 444.782509 -181.145194) (xy 444.753048 -181.099348)
			(xy 444.730411 -181.049777) (xy 444.715059 -180.997489) (xy 444.707304 -180.943548) (xy 432.731672 -180.943548)
			(xy 432.731672 -182.697882) (xy 433.533298 -182.697882) (xy 433.537342 -182.619428) (xy 433.549431 -182.541806)
			(xy 433.569438 -182.465838) (xy 433.597149 -182.39233) (xy 433.632272 -182.322061) (xy 433.674434 -182.255776)
			(xy 433.723188 -182.194177) (xy 433.778017 -182.137917) (xy 433.83834 -182.087593) (xy 433.903518 -182.043739)
			(xy 433.972859 -182.006818) (xy 434.04563 -181.977223) (xy 434.121057 -181.955268) (xy 434.198342 -181.941184)
			(xy 434.276666 -181.935121) (xy 434.355198 -181.937144) (xy 434.433106 -181.94723) (xy 434.509563 -181.965274)
			(xy 434.583761 -181.991084) (xy 434.654911 -182.024386) (xy 434.72226 -182.064827) (xy 434.785094 -182.111978)
			(xy 434.842746 -182.165341) (xy 434.894606 -182.224348) (xy 434.940125 -182.288375) (xy 434.978818 -182.356743)
			(xy 435.010277 -182.428727) (xy 435.034168 -182.503564) (xy 435.050237 -182.580461) (xy 435.058314 -182.658603)
			(xy 435.05882 -182.697882) (xy 435.058314 -182.737161) (xy 435.050237 -182.815303) (xy 435.034168 -182.8922)
			(xy 435.010277 -182.967037) (xy 434.978818 -183.039021) (xy 434.977327 -183.041655) (xy 444.697021 -183.041655)
			(xy 444.697021 -182.987145) (xy 444.704779 -182.933188) (xy 444.720136 -182.880885) (xy 444.742781 -182.831301)
			(xy 444.772252 -182.785443) (xy 444.80795 -182.744247) (xy 444.849146 -182.70855) (xy 444.895004 -182.679079)
			(xy 444.944589 -182.656435) (xy 444.996892 -182.641078) (xy 445.050849 -182.633321) (xy 445.078104 -182.632858)
			(xy 445.104116 -182.633312) (xy 445.155658 -182.640381) (xy 445.205761 -182.654389) (xy 445.253495 -182.675075)
			(xy 445.297977 -182.702055) (xy 445.338379 -182.734829) (xy 445.356488 -182.753508) (xy 445.366376 -182.76345)
			(xy 445.39035 -182.77797) (xy 445.417371 -182.785417) (xy 445.445399 -182.785227) (xy 445.472317 -182.777415)
			(xy 445.496092 -182.76257) (xy 445.50584 -182.752492) (xy 445.524031 -182.733205) (xy 445.564769 -182.699277)
			(xy 445.609812 -182.671316) (xy 445.658292 -182.649859) (xy 445.709275 -182.63532) (xy 445.76178 -182.62798)
			(xy 445.788288 -182.627524) (xy 445.815658 -182.627991) (xy 445.869838 -182.635808) (xy 445.922341 -182.651296)
			(xy 445.972088 -182.674138) (xy 446.018054 -182.703863) (xy 446.038986 -182.721504) (xy 446.050314 -182.73074)
			(xy 446.076871 -182.742916) (xy 446.105788 -182.747089) (xy 446.134705 -182.742916) (xy 446.161262 -182.73074)
			(xy 446.17259 -182.721504) (xy 446.193516 -182.703857) (xy 446.23949 -182.674146) (xy 446.289239 -182.651312)
			(xy 446.341741 -182.635822) (xy 446.395918 -182.627997) (xy 446.423288 -182.627524) (xy 446.450544 -182.627922)
			(xy 446.504501 -182.635678) (xy 446.556804 -182.651035) (xy 446.60639 -182.673678) (xy 446.652249 -182.703149)
			(xy 446.693446 -182.738845) (xy 446.729144 -182.780042) (xy 446.758616 -182.825899) (xy 446.781261 -182.875484)
			(xy 446.796619 -182.927788) (xy 446.804377 -182.981744) (xy 446.804377 -183.036248) (xy 447.05831 -183.036248)
			(xy 447.05831 -182.981752) (xy 447.066066 -182.92781) (xy 447.081419 -182.87552) (xy 447.104057 -182.825948)
			(xy 447.13352 -182.780102) (xy 447.169207 -182.738916) (xy 447.210392 -182.703227) (xy 447.256237 -182.673763)
			(xy 447.305809 -182.651123) (xy 447.358098 -182.635768) (xy 447.41204 -182.628011) (xy 447.439288 -182.627524)
			(xy 447.466658 -182.627991) (xy 447.520838 -182.635808) (xy 447.573341 -182.651296) (xy 447.623088 -182.674138)
			(xy 447.669054 -182.703863) (xy 447.689986 -182.721504) (xy 447.701314 -182.73074) (xy 447.727871 -182.742916)
			(xy 447.756788 -182.747089) (xy 447.785705 -182.742916) (xy 447.812262 -182.73074) (xy 447.82359 -182.721504)
			(xy 447.844516 -182.703857) (xy 447.89049 -182.674146) (xy 447.940239 -182.651312) (xy 447.992741 -182.635822)
			(xy 448.046918 -182.627997) (xy 448.074288 -182.627524) (xy 448.101544 -182.627922) (xy 448.155501 -182.635678)
			(xy 448.207804 -182.651035) (xy 448.25739 -182.673678) (xy 448.303249 -182.703149) (xy 448.344446 -182.738845)
			(xy 448.380144 -182.780042) (xy 448.409616 -182.825899) (xy 448.432261 -182.875484) (xy 448.447619 -182.927788)
			(xy 448.455377 -182.981744) (xy 448.455377 -183.036256) (xy 448.447619 -183.090212) (xy 448.432261 -183.142516)
			(xy 448.409616 -183.192101) (xy 448.380144 -183.237958) (xy 448.344446 -183.279155) (xy 448.303249 -183.314851)
			(xy 448.25739 -183.344322) (xy 448.207804 -183.366965) (xy 448.155501 -183.382322) (xy 448.101544 -183.390078)
			(xy 448.074288 -183.39054) (xy 448.046917 -183.390096) (xy 447.992736 -183.382275) (xy 447.940232 -183.366781)
			(xy 447.890486 -183.343935) (xy 447.84452 -183.314204) (xy 447.82359 -183.29656) (xy 447.812262 -183.287324)
			(xy 447.785705 -183.275148) (xy 447.756788 -183.270975) (xy 447.727871 -183.275148) (xy 447.701314 -183.287324)
			(xy 447.689986 -183.29656) (xy 447.669027 -183.314166) (xy 447.623062 -183.343884) (xy 447.573322 -183.366727)
			(xy 447.520827 -183.382226) (xy 447.466655 -183.390062) (xy 447.439288 -183.39054) (xy 447.41204 -183.389989)
			(xy 447.358098 -183.382232) (xy 447.305809 -183.366877) (xy 447.256237 -183.344237) (xy 447.210392 -183.314773)
			(xy 447.169207 -183.279084) (xy 447.13352 -183.237898) (xy 447.104057 -183.192052) (xy 447.081419 -183.14248)
			(xy 447.066066 -183.09019) (xy 447.05831 -183.036248) (xy 446.804377 -183.036248) (xy 446.804377 -183.036256)
			(xy 446.796619 -183.090212) (xy 446.781261 -183.142516) (xy 446.758616 -183.192101) (xy 446.729144 -183.237958)
			(xy 446.693446 -183.279155) (xy 446.652249 -183.314851) (xy 446.60639 -183.344322) (xy 446.556804 -183.366965)
			(xy 446.504501 -183.382322) (xy 446.450544 -183.390078) (xy 446.423288 -183.39054) (xy 446.395917 -183.390096)
			(xy 446.341736 -183.382275) (xy 446.289232 -183.366781) (xy 446.239486 -183.343935) (xy 446.19352 -183.314204)
			(xy 446.17259 -183.29656) (xy 446.161262 -183.287324) (xy 446.134705 -183.275148) (xy 446.105788 -183.270975)
			(xy 446.076871 -183.275148) (xy 446.050314 -183.287324) (xy 446.038986 -183.29656) (xy 446.018027 -183.314166)
			(xy 445.972062 -183.343884) (xy 445.922322 -183.366727) (xy 445.869827 -183.382226) (xy 445.815655 -183.390062)
			(xy 445.788288 -183.39054) (xy 445.762276 -183.390092) (xy 445.710734 -183.383021) (xy 445.660631 -183.369013)
			(xy 445.612896 -183.348326) (xy 445.568415 -183.321344) (xy 445.528013 -183.288569) (xy 445.509904 -183.26989)
			(xy 445.500024 -183.25994) (xy 445.476048 -183.24542) (xy 445.449024 -183.237975) (xy 445.420995 -183.238166)
			(xy 445.394076 -183.24598) (xy 445.3703 -183.260827) (xy 445.360552 -183.270906) (xy 445.342364 -183.290197)
			(xy 445.301626 -183.324124) (xy 445.256582 -183.352085) (xy 445.208102 -183.373541) (xy 445.157118 -183.388079)
			(xy 445.104612 -183.395419) (xy 445.078104 -183.395874) (xy 445.050849 -183.395479) (xy 444.996892 -183.387722)
			(xy 444.944589 -183.372365) (xy 444.895004 -183.349721) (xy 444.849146 -183.32025) (xy 444.80795 -183.284553)
			(xy 444.772252 -183.243357) (xy 444.742781 -183.197499) (xy 444.720136 -183.147915) (xy 444.704779 -183.095612)
			(xy 444.697021 -183.041655) (xy 434.977327 -183.041655) (xy 434.940125 -183.107389) (xy 434.894606 -183.171416)
			(xy 434.842746 -183.230423) (xy 434.785094 -183.283786) (xy 434.72226 -183.330937) (xy 434.654911 -183.371378)
			(xy 434.583761 -183.40468) (xy 434.509563 -183.43049) (xy 434.433106 -183.448534) (xy 434.355198 -183.45862)
			(xy 434.276666 -183.460643) (xy 434.198342 -183.45458) (xy 434.121057 -183.440496) (xy 434.04563 -183.418541)
			(xy 433.972859 -183.388946) (xy 433.903518 -183.352025) (xy 433.83834 -183.308171) (xy 433.778017 -183.257847)
			(xy 433.723188 -183.201587) (xy 433.674434 -183.139988) (xy 433.632272 -183.073703) (xy 433.597149 -183.003434)
			(xy 433.569438 -182.929926) (xy 433.549431 -182.853958) (xy 433.537342 -182.776336) (xy 433.533298 -182.697882)
			(xy 432.731672 -182.697882) (xy 432.731672 -182.826406) (xy 432.002692 -183.555386) (xy 431.999898 -183.571388)
			(xy 431.994363 -183.600139) (xy 431.97565 -183.655615) (xy 431.948681 -183.707581) (xy 431.91409 -183.754817)
			(xy 431.872689 -183.796214) (xy 431.825449 -183.830801) (xy 431.773481 -183.857764) (xy 431.718003 -183.876473)
			(xy 431.689256 -183.88203) (xy 431.673254 -183.884824) (xy 431.217832 -184.340246) (xy 431.12817 -184.340246)
			(xy 431.127916 -184.3405) (xy 425.63415 -184.3405) (xy 425.619159 -184.341026) (xy 425.590466 -184.349723)
			(xy 425.565538 -184.366381) (xy 425.546525 -184.389564) (xy 425.535068 -184.41727) (xy 425.532155 -184.44711)
			(xy 425.534582 -184.461912) (xy 425.538041 -184.480387) (xy 425.541732 -184.517794) (xy 425.541948 -184.536588)
			(xy 425.541462 -184.563839) (xy 425.533706 -184.617787) (xy 425.518351 -184.670082) (xy 425.495709 -184.719659)
			(xy 425.466243 -184.765509) (xy 425.430552 -184.8067) (xy 425.389361 -184.842391) (xy 425.343511 -184.871857)
			(xy 425.293934 -184.894499) (xy 425.241639 -184.909854) (xy 425.187691 -184.91761) (xy 425.133189 -184.91761)
			(xy 425.079241 -184.909854) (xy 425.026946 -184.894499) (xy 424.977369 -184.871857) (xy 424.931519 -184.842391)
			(xy 424.890328 -184.8067) (xy 424.854637 -184.765509) (xy 424.825171 -184.719659) (xy 424.802529 -184.670082)
			(xy 424.787174 -184.617787) (xy 424.779418 -184.563839) (xy 424.778932 -184.536588) (xy 424.779168 -184.517795)
			(xy 424.782862 -184.48039) (xy 424.786298 -184.461912) (xy 424.788699 -184.447109) (xy 424.785763 -184.41728)
			(xy 424.774301 -184.389585) (xy 424.755298 -184.366405) (xy 424.73039 -184.349733) (xy 424.701716 -184.341002)
			(xy 424.68673 -184.3405) (xy 413.799528 -184.3405) (xy 413.65551 -184.484264) (xy 413.276796 -184.862978)
			(xy 413.276796 -185.2193) (xy 432.315942 -185.2193) (xy 432.319856 -185.142113) (xy 432.33156 -185.065719)
			(xy 432.350931 -184.9909) (xy 432.377773 -184.918425) (xy 432.411809 -184.849038) (xy 432.45269 -184.78345)
			(xy 432.499996 -184.722334) (xy 432.553243 -184.666317) (xy 432.611884 -184.615975) (xy 432.675317 -184.571823)
			(xy 432.742891 -184.534316) (xy 432.813913 -184.503837) (xy 432.887655 -184.4807) (xy 432.963358 -184.465142)
			(xy 433.040247 -184.457322) (xy 433.07889 -184.456832) (xy 433.117654 -184.457295) (xy 433.194781 -184.465161)
			(xy 433.270712 -184.480814) (xy 433.344662 -184.504091) (xy 433.415869 -184.534752) (xy 433.483596 -184.572481)
			(xy 433.547146 -184.616888) (xy 433.60586 -184.667515) (xy 433.659134 -184.723839) (xy 433.683156 -184.754266)
			(xy 433.692409 -184.765626) (xy 433.716103 -184.782845) (xy 433.743705 -184.792647) (xy 433.772952 -184.794229)
			(xy 433.80145 -184.787462) (xy 433.826864 -184.772899) (xy 433.837334 -184.762648) (xy 433.855367 -184.744315)
			(xy 433.895538 -184.712208) (xy 433.939662 -184.685796) (xy 433.986938 -184.665557) (xy 434.036506 -184.651861)
			(xy 434.087465 -184.644955) (xy 434.113178 -184.644538) (xy 434.140435 -184.644907) (xy 434.194395 -184.652663)
			(xy 434.246702 -184.668019) (xy 434.296291 -184.690663) (xy 434.342152 -184.720134) (xy 434.383353 -184.755832)
			(xy 434.419053 -184.79703) (xy 434.448527 -184.84289) (xy 434.471173 -184.892477) (xy 434.486532 -184.944783)
			(xy 434.494291 -184.998743) (xy 434.494291 -185.053257) (xy 434.486532 -185.107217) (xy 434.471173 -185.159523)
			(xy 434.448527 -185.20911) (xy 434.419053 -185.25497) (xy 434.383353 -185.296168) (xy 434.342152 -185.331866)
			(xy 434.296291 -185.361337) (xy 434.246702 -185.383981) (xy 434.194395 -185.399337) (xy 434.140435 -185.407093)
			(xy 434.113178 -185.407554) (xy 434.08527 -185.407085) (xy 434.030045 -185.398984) (xy 433.976597 -185.382902)
			(xy 433.951126 -185.371486) (xy 433.937674 -185.365703) (xy 433.908751 -185.361238) (xy 433.879749 -185.365164)
			(xy 433.853053 -185.377158) (xy 433.830859 -185.396235) (xy 433.814991 -185.420826) (xy 433.81041 -185.434732)
			(xy 433.799278 -185.47073) (xy 433.770959 -185.540559) (xy 433.735891 -185.607255) (xy 433.694417 -185.670168)
			(xy 433.64694 -185.728683) (xy 433.593924 -185.782231) (xy 433.535885 -185.830289) (xy 433.473389 -185.872389)
			(xy 433.407046 -185.90812) (xy 433.337503 -185.937134) (xy 433.265437 -185.959148) (xy 433.191551 -185.973947)
			(xy 433.116567 -185.981387) (xy 433.07889 -185.981848) (xy 433.040247 -185.981278) (xy 432.963358 -185.973458)
			(xy 432.887655 -185.9579) (xy 432.813913 -185.934763) (xy 432.742891 -185.904284) (xy 432.675317 -185.866777)
			(xy 432.611884 -185.822625) (xy 432.553243 -185.772283) (xy 432.499996 -185.716266) (xy 432.45269 -185.65515)
			(xy 432.411809 -185.589562) (xy 432.377773 -185.520175) (xy 432.350931 -185.4477) (xy 432.33156 -185.372881)
			(xy 432.319856 -185.296487) (xy 432.315942 -185.2193) (xy 413.276796 -185.2193) (xy 413.276796 -189.158978)
			(xy 414.810381 -189.158978) (xy 414.810381 -189.074422) (xy 414.818183 -188.990228) (xy 414.833721 -188.907113)
			(xy 414.856861 -188.825786) (xy 414.887407 -188.746941) (xy 414.925098 -188.671251) (xy 414.969611 -188.599362)
			(xy 415.020569 -188.531886) (xy 415.077535 -188.469401) (xy 415.140023 -188.412438) (xy 415.207501 -188.361484)
			(xy 415.279393 -188.316974) (xy 415.355085 -188.279288) (xy 415.433931 -188.248746) (xy 415.51526 -188.22561)
			(xy 415.598376 -188.210077) (xy 415.68257 -188.202279) (xy 415.724848 -188.201808) (xy 416.969448 -188.201808)
			(xy 417.011723 -188.202266) (xy 417.095913 -188.210072) (xy 417.179024 -188.225612) (xy 417.260346 -188.248754)
			(xy 417.339187 -188.279301) (xy 417.414872 -188.316991) (xy 417.486757 -188.361504) (xy 417.554229 -188.412459)
			(xy 417.616711 -188.469423) (xy 417.673671 -188.531908) (xy 417.724623 -188.599382) (xy 417.769132 -188.67127)
			(xy 417.806819 -188.746957) (xy 417.837361 -188.825799) (xy 417.860499 -188.907123) (xy 417.876035 -188.990234)
			(xy 417.883836 -189.074424) (xy 417.883836 -189.158976) (xy 417.883836 -189.158978) (xy 422.354181 -189.158978)
			(xy 422.354181 -189.074422) (xy 422.361983 -188.990228) (xy 422.377521 -188.907113) (xy 422.400661 -188.825786)
			(xy 422.431207 -188.746941) (xy 422.468898 -188.671251) (xy 422.513411 -188.599362) (xy 422.564369 -188.531886)
			(xy 422.621335 -188.469401) (xy 422.683823 -188.412438) (xy 422.751301 -188.361484) (xy 422.823193 -188.316974)
			(xy 422.898885 -188.279288) (xy 422.977731 -188.248746) (xy 423.05906 -188.22561) (xy 423.142176 -188.210077)
			(xy 423.22637 -188.202279) (xy 423.268648 -188.201808) (xy 424.513248 -188.201808) (xy 424.555523 -188.202266)
			(xy 424.639713 -188.210072) (xy 424.722824 -188.225612) (xy 424.804146 -188.248754) (xy 424.882987 -188.279301)
			(xy 424.958672 -188.316991) (xy 425.030557 -188.361504) (xy 425.098029 -188.412459) (xy 425.160511 -188.469423)
			(xy 425.217471 -188.531908) (xy 425.268423 -188.599382) (xy 425.312932 -188.67127) (xy 425.350619 -188.746957)
			(xy 425.381161 -188.825799) (xy 425.404299 -188.907123) (xy 425.419835 -188.990234) (xy 425.427636 -189.074424)
			(xy 425.427636 -189.158976) (xy 425.427636 -189.158978) (xy 429.897981 -189.158978) (xy 429.897981 -189.074422)
			(xy 429.905783 -188.990228) (xy 429.921321 -188.907113) (xy 429.944461 -188.825786) (xy 429.975007 -188.746941)
			(xy 430.012698 -188.671251) (xy 430.057211 -188.599362) (xy 430.108169 -188.531886) (xy 430.165135 -188.469401)
			(xy 430.227623 -188.412438) (xy 430.295101 -188.361484) (xy 430.366993 -188.316974) (xy 430.442685 -188.279288)
			(xy 430.521531 -188.248746) (xy 430.60286 -188.22561) (xy 430.685976 -188.210077) (xy 430.77017 -188.202279)
			(xy 430.812448 -188.201808) (xy 432.057048 -188.201808) (xy 432.099325 -188.202234) (xy 432.183519 -188.21004)
			(xy 432.266634 -188.225581) (xy 432.34796 -188.248725) (xy 432.426803 -188.279273) (xy 432.502492 -188.316966)
			(xy 432.574381 -188.361481) (xy 432.641855 -188.412439) (xy 432.70434 -188.469406) (xy 432.761302 -188.531894)
			(xy 432.812255 -188.599372) (xy 432.856766 -188.671264) (xy 432.894453 -188.746955) (xy 432.924996 -188.825801)
			(xy 432.948133 -188.907129) (xy 432.963668 -188.990244) (xy 432.971468 -189.074439) (xy 432.971956 -189.116716)
			(xy 432.971445 -189.158978) (xy 437.441781 -189.158978) (xy 437.441781 -189.074422) (xy 437.449583 -188.990228)
			(xy 437.465121 -188.907113) (xy 437.488261 -188.825786) (xy 437.518807 -188.746941) (xy 437.556498 -188.671251)
			(xy 437.601011 -188.599362) (xy 437.651969 -188.531886) (xy 437.708935 -188.469401) (xy 437.771423 -188.412438)
			(xy 437.838901 -188.361484) (xy 437.910793 -188.316974) (xy 437.986485 -188.279288) (xy 438.065331 -188.248746)
			(xy 438.14666 -188.22561) (xy 438.229776 -188.210077) (xy 438.31397 -188.202279) (xy 438.356248 -188.201808)
			(xy 439.600848 -188.201808) (xy 439.643123 -188.202266) (xy 439.727313 -188.210072) (xy 439.810424 -188.225612)
			(xy 439.891746 -188.248754) (xy 439.970587 -188.279301) (xy 440.046272 -188.316991) (xy 440.118157 -188.361504)
			(xy 440.185629 -188.412459) (xy 440.248111 -188.469423) (xy 440.305071 -188.531908) (xy 440.356023 -188.599382)
			(xy 440.400532 -188.67127) (xy 440.438219 -188.746957) (xy 440.468761 -188.825799) (xy 440.491899 -188.907123)
			(xy 440.507435 -188.990234) (xy 440.515236 -189.074424) (xy 440.515236 -189.158976) (xy 440.515236 -189.158978)
			(xy 444.985581 -189.158978) (xy 444.985581 -189.074422) (xy 444.993383 -188.990228) (xy 445.008921 -188.907113)
			(xy 445.032061 -188.825786) (xy 445.062607 -188.746941) (xy 445.100298 -188.671251) (xy 445.144811 -188.599362)
			(xy 445.195769 -188.531886) (xy 445.252735 -188.469401) (xy 445.315223 -188.412438) (xy 445.382701 -188.361484)
			(xy 445.454593 -188.316974) (xy 445.530285 -188.279288) (xy 445.609131 -188.248746) (xy 445.69046 -188.22561)
			(xy 445.773576 -188.210077) (xy 445.85777 -188.202279) (xy 445.900048 -188.201808) (xy 447.144648 -188.201808)
			(xy 447.186923 -188.202266) (xy 447.271113 -188.210072) (xy 447.354224 -188.225612) (xy 447.435546 -188.248754)
			(xy 447.514387 -188.279301) (xy 447.590072 -188.316991) (xy 447.661957 -188.361504) (xy 447.729429 -188.412459)
			(xy 447.791911 -188.469423) (xy 447.848871 -188.531908) (xy 447.899823 -188.599382) (xy 447.944332 -188.67127)
			(xy 447.982019 -188.746957) (xy 448.012561 -188.825799) (xy 448.035699 -188.907123) (xy 448.051235 -188.990234)
			(xy 448.059036 -189.074424) (xy 448.059036 -189.158976) (xy 448.059036 -189.158978) (xy 452.529381 -189.158978)
			(xy 452.529381 -189.074422) (xy 452.537183 -188.990228) (xy 452.552721 -188.907113) (xy 452.575861 -188.825786)
			(xy 452.606407 -188.746941) (xy 452.644098 -188.671251) (xy 452.688611 -188.599362) (xy 452.739569 -188.531886)
			(xy 452.796535 -188.469401) (xy 452.859023 -188.412438) (xy 452.926501 -188.361484) (xy 452.998393 -188.316974)
			(xy 453.074085 -188.279288) (xy 453.152931 -188.248746) (xy 453.23426 -188.22561) (xy 453.317376 -188.210077)
			(xy 453.40157 -188.202279) (xy 453.443848 -188.201808) (xy 454.688448 -188.201808) (xy 454.730723 -188.202266)
			(xy 454.814913 -188.210072) (xy 454.898024 -188.225612) (xy 454.979346 -188.248754) (xy 455.058187 -188.279301)
			(xy 455.133872 -188.316991) (xy 455.205757 -188.361504) (xy 455.273229 -188.412459) (xy 455.335711 -188.469423)
			(xy 455.392671 -188.531908) (xy 455.443623 -188.599382) (xy 455.488132 -188.67127) (xy 455.525819 -188.746957)
			(xy 455.556361 -188.825799) (xy 455.579499 -188.907123) (xy 455.595035 -188.990234) (xy 455.602836 -189.074424)
			(xy 455.602836 -189.158976) (xy 455.595035 -189.243166) (xy 455.579499 -189.326277) (xy 455.556361 -189.407601)
			(xy 455.525819 -189.486443) (xy 455.488132 -189.56213) (xy 455.443623 -189.634018) (xy 455.392671 -189.701492)
			(xy 455.335711 -189.763977) (xy 455.273229 -189.820941) (xy 455.205757 -189.871896) (xy 455.133872 -189.916409)
			(xy 455.058187 -189.954099) (xy 454.979346 -189.984646) (xy 454.898024 -190.007788) (xy 454.814913 -190.023328)
			(xy 454.730723 -190.031134) (xy 454.688448 -190.031624) (xy 453.443848 -190.031624) (xy 453.40157 -190.031121)
			(xy 453.317376 -190.023323) (xy 453.23426 -190.00779) (xy 453.152931 -189.984654) (xy 453.074085 -189.954112)
			(xy 452.998393 -189.916426) (xy 452.926501 -189.871916) (xy 452.859023 -189.820962) (xy 452.796535 -189.763999)
			(xy 452.739569 -189.701514) (xy 452.688611 -189.634038) (xy 452.644098 -189.562149) (xy 452.606407 -189.486459)
			(xy 452.575861 -189.407614) (xy 452.552721 -189.326287) (xy 452.537183 -189.243172) (xy 452.529381 -189.158978)
			(xy 448.059036 -189.158978) (xy 448.051235 -189.243166) (xy 448.035699 -189.326277) (xy 448.012561 -189.407601)
			(xy 447.982019 -189.486443) (xy 447.944332 -189.56213) (xy 447.899823 -189.634018) (xy 447.848871 -189.701492)
			(xy 447.791911 -189.763977) (xy 447.729429 -189.820941) (xy 447.661957 -189.871896) (xy 447.590072 -189.916409)
			(xy 447.514387 -189.954099) (xy 447.435546 -189.984646) (xy 447.354224 -190.007788) (xy 447.271113 -190.023328)
			(xy 447.186923 -190.031134) (xy 447.144648 -190.031624) (xy 445.900048 -190.031624) (xy 445.85777 -190.031121)
			(xy 445.773576 -190.023323) (xy 445.69046 -190.00779) (xy 445.609131 -189.984654) (xy 445.530285 -189.954112)
			(xy 445.454593 -189.916426) (xy 445.382701 -189.871916) (xy 445.315223 -189.820962) (xy 445.252735 -189.763999)
			(xy 445.195769 -189.701514) (xy 445.144811 -189.634038) (xy 445.100298 -189.562149) (xy 445.062607 -189.486459)
			(xy 445.032061 -189.407614) (xy 445.008921 -189.326287) (xy 444.993383 -189.243172) (xy 444.985581 -189.158978)
			(xy 440.515236 -189.158978) (xy 440.507435 -189.243166) (xy 440.491899 -189.326277) (xy 440.468761 -189.407601)
			(xy 440.438219 -189.486443) (xy 440.400532 -189.56213) (xy 440.356023 -189.634018) (xy 440.305071 -189.701492)
			(xy 440.248111 -189.763977) (xy 440.185629 -189.820941) (xy 440.118157 -189.871896) (xy 440.046272 -189.916409)
			(xy 439.970587 -189.954099) (xy 439.891746 -189.984646) (xy 439.810424 -190.007788) (xy 439.727313 -190.023328)
			(xy 439.643123 -190.031134) (xy 439.600848 -190.031624) (xy 438.356248 -190.031624) (xy 438.31397 -190.031121)
			(xy 438.229776 -190.023323) (xy 438.14666 -190.00779) (xy 438.065331 -189.984654) (xy 437.986485 -189.954112)
			(xy 437.910793 -189.916426) (xy 437.838901 -189.871916) (xy 437.771423 -189.820962) (xy 437.708935 -189.763999)
			(xy 437.651969 -189.701514) (xy 437.601011 -189.634038) (xy 437.556498 -189.562149) (xy 437.518807 -189.486459)
			(xy 437.488261 -189.407614) (xy 437.465121 -189.326287) (xy 437.449583 -189.243172) (xy 437.441781 -189.158978)
			(xy 432.971445 -189.158978) (xy 432.971429 -189.160318) (xy 432.96312 -189.247124) (xy 432.946588 -189.332746)
			(xy 432.921984 -189.416406) (xy 432.889531 -189.497346) (xy 432.849523 -189.57483) (xy 432.802323 -189.648155)
			(xy 432.74836 -189.716657) (xy 432.688124 -189.779712) (xy 432.655472 -189.808612) (xy 432.644945 -189.81839)
			(xy 432.629354 -189.842508) (xy 432.6211 -189.870015) (xy 432.620837 -189.898732) (xy 432.628585 -189.926386)
			(xy 432.643731 -189.950786) (xy 432.665075 -189.97) (xy 432.690928 -189.982506) (xy 432.705002 -189.985396)
			(xy 432.731293 -189.990361) (xy 432.782255 -190.006657) (xy 432.830441 -190.029914) (xy 432.874905 -190.059673)
			(xy 432.914775 -190.095353) (xy 432.949269 -190.136253) (xy 432.977712 -190.181572) (xy 432.999544 -190.230419)
			(xy 433.014337 -190.281837) (xy 433.021803 -190.334818) (xy 433.022248 -190.36157) (xy 433.021762 -190.388821)
			(xy 433.014006 -190.442769) (xy 432.998651 -190.495064) (xy 432.976009 -190.544641) (xy 432.946543 -190.590491)
			(xy 432.910852 -190.631682) (xy 432.869661 -190.667373) (xy 432.823811 -190.696839) (xy 432.774234 -190.719481)
			(xy 432.721939 -190.734836) (xy 432.667991 -190.742592) (xy 432.613489 -190.742592) (xy 432.559541 -190.734836)
			(xy 432.507246 -190.719481) (xy 432.457669 -190.696839) (xy 432.411819 -190.667373) (xy 432.370628 -190.631682)
			(xy 432.334937 -190.590491) (xy 432.305471 -190.544641) (xy 432.282829 -190.495064) (xy 432.267474 -190.442769)
			(xy 432.259718 -190.388821) (xy 432.259232 -190.36157) (xy 432.259603 -190.33652) (xy 432.266154 -190.286851)
			(xy 432.279141 -190.238464) (xy 432.29834 -190.192189) (xy 432.31054 -190.170308) (xy 432.317244 -190.15759)
			(xy 432.324171 -190.129708) (xy 432.323048 -190.101) (xy 432.313965 -190.073744) (xy 432.297642 -190.050102)
			(xy 432.275373 -190.031949) (xy 432.248927 -190.020726) (xy 432.220399 -190.017323) (xy 432.206146 -190.019178)
			(xy 432.169142 -190.024964) (xy 432.094499 -190.031196) (xy 432.057048 -190.031624) (xy 430.812448 -190.031624)
			(xy 430.77017 -190.031121) (xy 430.685976 -190.023323) (xy 430.60286 -190.00779) (xy 430.521531 -189.984654)
			(xy 430.442685 -189.954112) (xy 430.366993 -189.916426) (xy 430.295101 -189.871916) (xy 430.227623 -189.820962)
			(xy 430.165135 -189.763999) (xy 430.108169 -189.701514) (xy 430.057211 -189.634038) (xy 430.012698 -189.562149)
			(xy 429.975007 -189.486459) (xy 429.944461 -189.407614) (xy 429.921321 -189.326287) (xy 429.905783 -189.243172)
			(xy 429.897981 -189.158978) (xy 425.427636 -189.158978) (xy 425.419835 -189.243166) (xy 425.404299 -189.326277)
			(xy 425.381161 -189.407601) (xy 425.350619 -189.486443) (xy 425.312932 -189.56213) (xy 425.268423 -189.634018)
			(xy 425.217471 -189.701492) (xy 425.160511 -189.763977) (xy 425.098029 -189.820941) (xy 425.030557 -189.871896)
			(xy 424.958672 -189.916409) (xy 424.882987 -189.954099) (xy 424.804146 -189.984646) (xy 424.722824 -190.007788)
			(xy 424.639713 -190.023328) (xy 424.555523 -190.031134) (xy 424.513248 -190.031624) (xy 423.268648 -190.031624)
			(xy 423.22637 -190.031121) (xy 423.142176 -190.023323) (xy 423.05906 -190.00779) (xy 422.977731 -189.984654)
			(xy 422.898885 -189.954112) (xy 422.823193 -189.916426) (xy 422.751301 -189.871916) (xy 422.683823 -189.820962)
			(xy 422.621335 -189.763999) (xy 422.564369 -189.701514) (xy 422.513411 -189.634038) (xy 422.468898 -189.562149)
			(xy 422.431207 -189.486459) (xy 422.400661 -189.407614) (xy 422.377521 -189.326287) (xy 422.361983 -189.243172)
			(xy 422.354181 -189.158978) (xy 417.883836 -189.158978) (xy 417.876035 -189.243166) (xy 417.860499 -189.326277)
			(xy 417.837361 -189.407601) (xy 417.806819 -189.486443) (xy 417.769132 -189.56213) (xy 417.724623 -189.634018)
			(xy 417.673671 -189.701492) (xy 417.616711 -189.763977) (xy 417.554229 -189.820941) (xy 417.486757 -189.871896)
			(xy 417.414872 -189.916409) (xy 417.339187 -189.954099) (xy 417.260346 -189.984646) (xy 417.179024 -190.007788)
			(xy 417.095913 -190.023328) (xy 417.011723 -190.031134) (xy 416.969448 -190.031624) (xy 415.724848 -190.031624)
			(xy 415.68257 -190.031121) (xy 415.598376 -190.023323) (xy 415.51526 -190.00779) (xy 415.433931 -189.984654)
			(xy 415.355085 -189.954112) (xy 415.279393 -189.916426) (xy 415.207501 -189.871916) (xy 415.140023 -189.820962)
			(xy 415.077535 -189.763999) (xy 415.020569 -189.701514) (xy 414.969611 -189.634038) (xy 414.925098 -189.562149)
			(xy 414.887407 -189.486459) (xy 414.856861 -189.407614) (xy 414.833721 -189.326287) (xy 414.818183 -189.243172)
			(xy 414.810381 -189.158978) (xy 413.276796 -189.158978) (xy 413.276796 -191.25057) (xy 426.797722 -191.25057)
			(xy 426.801793 -191.194948) (xy 426.813919 -191.140511) (xy 426.833842 -191.08842) (xy 426.861138 -191.039785)
			(xy 426.895224 -190.995642) (xy 426.935373 -190.956933) (xy 426.980731 -190.924482) (xy 427.030331 -190.898981)
			(xy 427.083115 -190.880974) (xy 427.137958 -190.870844) (xy 427.193692 -190.868807) (xy 427.249129 -190.874907)
			(xy 427.303086 -190.889013) (xy 427.354415 -190.910825) (xy 427.402021 -190.939879) (xy 427.444889 -190.975554)
			(xy 427.482106 -191.017091) (xy 427.512879 -191.063604) (xy 427.536551 -191.114101) (xy 427.552619 -191.167508)
			(xy 427.560739 -191.222684) (xy 427.561248 -191.25057) (xy 427.560951 -191.266826) (xy 432.681124 -191.266826)
			(xy 432.685195 -191.211204) (xy 432.697321 -191.156767) (xy 432.717244 -191.104676) (xy 432.74454 -191.056041)
			(xy 432.778626 -191.011898) (xy 432.818775 -190.973189) (xy 432.864133 -190.940738) (xy 432.913733 -190.915237)
			(xy 432.966517 -190.89723) (xy 433.02136 -190.8871) (xy 433.077094 -190.885063) (xy 433.132531 -190.891163)
			(xy 433.186488 -190.905269) (xy 433.237817 -190.927081) (xy 433.285423 -190.956135) (xy 433.328291 -190.99181)
			(xy 433.365508 -191.033347) (xy 433.396281 -191.07986) (xy 433.419953 -191.130357) (xy 433.436021 -191.183764)
			(xy 433.444141 -191.23894) (xy 433.44465 -191.266826) (xy 433.444141 -191.294712) (xy 433.436021 -191.349888)
			(xy 433.419953 -191.403295) (xy 433.396281 -191.453792) (xy 433.365508 -191.500305) (xy 433.328291 -191.541842)
			(xy 433.285423 -191.577517) (xy 433.237817 -191.606571) (xy 433.186488 -191.628383) (xy 433.132531 -191.642489)
			(xy 433.077094 -191.648589) (xy 433.02136 -191.646552) (xy 432.966517 -191.636422) (xy 432.913733 -191.618415)
			(xy 432.864133 -191.592914) (xy 432.818775 -191.560463) (xy 432.778626 -191.521754) (xy 432.74454 -191.477611)
			(xy 432.717244 -191.428976) (xy 432.697321 -191.376885) (xy 432.685195 -191.322448) (xy 432.681124 -191.266826)
			(xy 427.560951 -191.266826) (xy 427.560739 -191.278456) (xy 427.552619 -191.333632) (xy 427.536551 -191.387039)
			(xy 427.512879 -191.437536) (xy 427.482106 -191.484049) (xy 427.444889 -191.525586) (xy 427.402021 -191.561261)
			(xy 427.354415 -191.590315) (xy 427.303086 -191.612127) (xy 427.249129 -191.626233) (xy 427.193692 -191.632333)
			(xy 427.137958 -191.630296) (xy 427.083115 -191.620166) (xy 427.030331 -191.602159) (xy 426.980731 -191.576658)
			(xy 426.935373 -191.544207) (xy 426.895224 -191.505498) (xy 426.861138 -191.461355) (xy 426.833842 -191.41272)
			(xy 426.813919 -191.360629) (xy 426.801793 -191.306192) (xy 426.797722 -191.25057) (xy 413.276796 -191.25057)
			(xy 413.276796 -192.148968) (xy 419.101268 -192.148968) (xy 419.105339 -192.093346) (xy 419.117465 -192.038909)
			(xy 419.137388 -191.986818) (xy 419.164684 -191.938183) (xy 419.19877 -191.89404) (xy 419.238919 -191.855331)
			(xy 419.284277 -191.82288) (xy 419.333877 -191.797379) (xy 419.386661 -191.779372) (xy 419.441504 -191.769242)
			(xy 419.497238 -191.767205) (xy 419.552675 -191.773305) (xy 419.606632 -191.787411) (xy 419.657961 -191.809223)
			(xy 419.705567 -191.838277) (xy 419.748435 -191.873952) (xy 419.785652 -191.915489) (xy 419.816425 -191.962002)
			(xy 419.840097 -192.012499) (xy 419.856165 -192.065906) (xy 419.864285 -192.121082) (xy 419.864794 -192.148968)
			(xy 419.864285 -192.176854) (xy 419.856165 -192.23203) (xy 419.840097 -192.285437) (xy 419.824294 -192.319148)
			(xy 422.956226 -192.319148) (xy 422.960297 -192.263526) (xy 422.972423 -192.209089) (xy 422.992346 -192.156998)
			(xy 423.019642 -192.108363) (xy 423.053728 -192.06422) (xy 423.093877 -192.025511) (xy 423.139235 -191.99306)
			(xy 423.188835 -191.967559) (xy 423.241619 -191.949552) (xy 423.296462 -191.939422) (xy 423.352196 -191.937385)
			(xy 423.407633 -191.943485) (xy 423.46159 -191.957591) (xy 423.512919 -191.979403) (xy 423.560525 -192.008457)
			(xy 423.603393 -192.044132) (xy 423.64061 -192.085669) (xy 423.671383 -192.132182) (xy 423.695055 -192.182679)
			(xy 423.711123 -192.236086) (xy 423.719243 -192.291262) (xy 423.719752 -192.319148) (xy 423.719243 -192.347034)
			(xy 423.711123 -192.40221) (xy 423.695055 -192.455617) (xy 423.671383 -192.506114) (xy 423.64061 -192.552627)
			(xy 423.603393 -192.594164) (xy 423.560525 -192.629839) (xy 423.512919 -192.658893) (xy 423.46159 -192.680705)
			(xy 423.407633 -192.694811) (xy 423.352196 -192.700911) (xy 423.296462 -192.698874) (xy 423.241619 -192.688744)
			(xy 423.188835 -192.670737) (xy 423.139235 -192.645236) (xy 423.093877 -192.612785) (xy 423.053728 -192.574076)
			(xy 423.019642 -192.529933) (xy 422.992346 -192.481298) (xy 422.972423 -192.429207) (xy 422.960297 -192.37477)
			(xy 422.956226 -192.319148) (xy 419.824294 -192.319148) (xy 419.816425 -192.335934) (xy 419.785652 -192.382447)
			(xy 419.748435 -192.423984) (xy 419.705567 -192.459659) (xy 419.657961 -192.488713) (xy 419.606632 -192.510525)
			(xy 419.552675 -192.524631) (xy 419.497238 -192.530731) (xy 419.441504 -192.528694) (xy 419.386661 -192.518564)
			(xy 419.333877 -192.500557) (xy 419.284277 -192.475056) (xy 419.238919 -192.442605) (xy 419.19877 -192.403896)
			(xy 419.164684 -192.359753) (xy 419.137388 -192.311118) (xy 419.117465 -192.259027) (xy 419.105339 -192.20459)
			(xy 419.101268 -192.148968) (xy 413.276796 -192.148968) (xy 413.276796 -193.218308) (xy 429.035462 -193.218308)
			(xy 429.039533 -193.162686) (xy 429.051659 -193.108249) (xy 429.071582 -193.056158) (xy 429.098878 -193.007523)
			(xy 429.132964 -192.96338) (xy 429.173113 -192.924671) (xy 429.218471 -192.89222) (xy 429.268071 -192.866719)
			(xy 429.320855 -192.848712) (xy 429.375698 -192.838582) (xy 429.431432 -192.836545) (xy 429.486869 -192.842645)
			(xy 429.540826 -192.856751) (xy 429.592155 -192.878563) (xy 429.639761 -192.907617) (xy 429.682629 -192.943292)
			(xy 429.719846 -192.984829) (xy 429.750619 -193.031342) (xy 429.774291 -193.081839) (xy 429.790359 -193.135246)
			(xy 429.798479 -193.190422) (xy 429.798988 -193.218308) (xy 429.798479 -193.246194) (xy 429.790359 -193.30137)
			(xy 429.774291 -193.354777) (xy 429.750619 -193.405274) (xy 429.719846 -193.451787) (xy 429.682629 -193.493324)
			(xy 429.639761 -193.528999) (xy 429.592155 -193.558053) (xy 429.540826 -193.579865) (xy 429.486869 -193.593971)
			(xy 429.431432 -193.600071) (xy 429.375698 -193.598034) (xy 429.320855 -193.587904) (xy 429.268071 -193.569897)
			(xy 429.218471 -193.544396) (xy 429.173113 -193.511945) (xy 429.132964 -193.473236) (xy 429.098878 -193.429093)
			(xy 429.071582 -193.380458) (xy 429.051659 -193.328367) (xy 429.039533 -193.27393) (xy 429.035462 -193.218308)
			(xy 413.276796 -193.218308) (xy 413.276796 -193.282062) (xy 413.699452 -193.704718) (xy 448.188842 -193.704718)
			(xy 449.172838 -194.688714) (xy 449.183588 -194.698776) (xy 449.209465 -194.7128) (xy 449.238266 -194.718866)
			(xy 449.267602 -194.716468) (xy 449.295036 -194.705808) (xy 449.318293 -194.687769) (xy 449.335443 -194.663848)
			(xy 449.340732 -194.650106) (xy 449.350238 -194.624236) (xy 449.376084 -194.575561) (xy 449.409124 -194.53145)
			(xy 449.448568 -194.492959) (xy 449.493472 -194.461007) (xy 449.542765 -194.436357) (xy 449.595267 -194.419599)
			(xy 449.649726 -194.411132) (xy 449.677282 -194.410584) (xy 449.705269 -194.411103) (xy 449.760553 -194.419856)
			(xy 449.813787 -194.43715) (xy 449.863661 -194.46256) (xy 449.908945 -194.495458) (xy 449.948525 -194.535035)
			(xy 449.981427 -194.580317) (xy 450.00684 -194.630189) (xy 450.024138 -194.683422) (xy 450.032895 -194.738706)
			(xy 450.03339 -194.766692) (xy 450.032869 -194.794245) (xy 450.02437 -194.848692) (xy 450.007589 -194.901182)
			(xy 449.992027 -194.932279) (xy 450.128376 -194.932279) (xy 450.128376 -194.878981) (xy 450.136319 -194.826277)
			(xy 450.152029 -194.775347) (xy 450.175155 -194.727326) (xy 450.205179 -194.683289) (xy 450.241431 -194.644218)
			(xy 450.283102 -194.610987) (xy 450.32926 -194.584338) (xy 450.378874 -194.564866) (xy 450.430836 -194.553006)
			(xy 450.483986 -194.549023) (xy 450.537136 -194.553006) (xy 450.589098 -194.564866) (xy 450.638712 -194.584338)
			(xy 450.68487 -194.610987) (xy 450.726541 -194.644218) (xy 450.762793 -194.683289) (xy 450.792817 -194.727326)
			(xy 450.815943 -194.775347) (xy 450.821493 -194.793341) (xy 454.655672 -194.793341) (xy 454.655672 -194.740043)
			(xy 454.663615 -194.687339) (xy 454.679325 -194.636409) (xy 454.702451 -194.588388) (xy 454.732475 -194.544351)
			(xy 454.768727 -194.50528) (xy 454.810398 -194.472049) (xy 454.856556 -194.4454) (xy 454.90617 -194.425928)
			(xy 454.958132 -194.414068) (xy 455.011282 -194.410085) (xy 455.064432 -194.414068) (xy 455.116394 -194.425928)
			(xy 455.166008 -194.4454) (xy 455.212166 -194.472049) (xy 455.253837 -194.50528) (xy 455.290089 -194.544351)
			(xy 455.320113 -194.588388) (xy 455.343239 -194.636409) (xy 455.358949 -194.687339) (xy 455.366892 -194.740043)
			(xy 455.36739 -194.766692) (xy 455.366892 -194.793341) (xy 456.865472 -194.793341) (xy 456.865472 -194.740043)
			(xy 456.873415 -194.687339) (xy 456.889125 -194.636409) (xy 456.912251 -194.588388) (xy 456.942275 -194.544351)
			(xy 456.978527 -194.50528) (xy 457.020198 -194.472049) (xy 457.066356 -194.4454) (xy 457.11597 -194.425928)
			(xy 457.167932 -194.414068) (xy 457.221082 -194.410085) (xy 457.274232 -194.414068) (xy 457.326194 -194.425928)
			(xy 457.375808 -194.4454) (xy 457.421966 -194.472049) (xy 457.463637 -194.50528) (xy 457.499889 -194.544351)
			(xy 457.529913 -194.588388) (xy 457.553039 -194.636409) (xy 457.568749 -194.687339) (xy 457.576692 -194.740043)
			(xy 457.57719 -194.766692) (xy 457.576692 -194.793341) (xy 458.074004 -194.793341) (xy 458.074004 -194.740043)
			(xy 458.081947 -194.687339) (xy 458.097657 -194.636409) (xy 458.120783 -194.588388) (xy 458.150807 -194.544351)
			(xy 458.187059 -194.50528) (xy 458.22873 -194.472049) (xy 458.274888 -194.4454) (xy 458.324502 -194.425928)
			(xy 458.376464 -194.414068) (xy 458.429614 -194.410085) (xy 458.482764 -194.414068) (xy 458.534726 -194.425928)
			(xy 458.58434 -194.4454) (xy 458.630498 -194.472049) (xy 458.672169 -194.50528) (xy 458.708421 -194.544351)
			(xy 458.738445 -194.588388) (xy 458.761571 -194.636409) (xy 458.777281 -194.687339) (xy 458.785224 -194.740043)
			(xy 458.785722 -194.766692) (xy 458.785224 -194.793341) (xy 458.777281 -194.846045) (xy 458.761571 -194.896975)
			(xy 458.738445 -194.944996) (xy 458.708421 -194.989033) (xy 458.672169 -195.028104) (xy 458.630498 -195.061335)
			(xy 458.58434 -195.087984) (xy 458.534726 -195.107456) (xy 458.482764 -195.119316) (xy 458.429614 -195.1233)
			(xy 458.376464 -195.119316) (xy 458.324502 -195.107456) (xy 458.274888 -195.087984) (xy 458.22873 -195.061335)
			(xy 458.187059 -195.028104) (xy 458.150807 -194.989033) (xy 458.120783 -194.944996) (xy 458.097657 -194.896975)
			(xy 458.081947 -194.846045) (xy 458.074004 -194.793341) (xy 457.576692 -194.793341) (xy 457.568749 -194.846045)
			(xy 457.553039 -194.896975) (xy 457.529913 -194.944996) (xy 457.499889 -194.989033) (xy 457.463637 -195.028104)
			(xy 457.421966 -195.061335) (xy 457.375808 -195.087984) (xy 457.326194 -195.107456) (xy 457.274232 -195.119316)
			(xy 457.221082 -195.1233) (xy 457.167932 -195.119316) (xy 457.11597 -195.107456) (xy 457.066356 -195.087984)
			(xy 457.020198 -195.061335) (xy 456.978527 -195.028104) (xy 456.942275 -194.989033) (xy 456.912251 -194.944996)
			(xy 456.889125 -194.896975) (xy 456.873415 -194.846045) (xy 456.865472 -194.793341) (xy 455.366892 -194.793341)
			(xy 455.358949 -194.846045) (xy 455.343239 -194.896975) (xy 455.320113 -194.944996) (xy 455.290089 -194.989033)
			(xy 455.253837 -195.028104) (xy 455.212166 -195.061335) (xy 455.166008 -195.087984) (xy 455.116394 -195.107456)
			(xy 455.064432 -195.119316) (xy 455.011282 -195.1233) (xy 454.958132 -195.119316) (xy 454.90617 -195.107456)
			(xy 454.856556 -195.087984) (xy 454.810398 -195.061335) (xy 454.768727 -195.028104) (xy 454.732475 -194.989033)
			(xy 454.702451 -194.944996) (xy 454.679325 -194.896975) (xy 454.663615 -194.846045) (xy 454.655672 -194.793341)
			(xy 450.821493 -194.793341) (xy 450.831653 -194.826277) (xy 450.839596 -194.878981) (xy 450.840094 -194.90563)
			(xy 450.839596 -194.932279) (xy 450.831653 -194.984983) (xy 450.815943 -195.035913) (xy 450.792817 -195.083934)
			(xy 450.762793 -195.127971) (xy 450.726541 -195.167042) (xy 450.68487 -195.200273) (xy 450.638712 -195.226922)
			(xy 450.589098 -195.246394) (xy 450.537136 -195.258254) (xy 450.483986 -195.262238) (xy 450.430836 -195.258254)
			(xy 450.378874 -195.246394) (xy 450.32926 -195.226922) (xy 450.283102 -195.200273) (xy 450.241431 -195.167042)
			(xy 450.205179 -195.127971) (xy 450.175155 -195.083934) (xy 450.152029 -195.035913) (xy 450.136319 -194.984983)
			(xy 450.128376 -194.932279) (xy 449.992027 -194.932279) (xy 449.982927 -194.950462) (xy 449.950972 -194.995357)
			(xy 449.912485 -195.034797) (xy 449.868384 -195.06784) (xy 449.819722 -195.0937) (xy 449.793868 -195.103242)
			(xy 449.780129 -195.108528) (xy 449.756228 -195.125692) (xy 449.738204 -195.148952) (xy 449.727551 -195.176381)
			(xy 449.72515 -195.205709) (xy 449.731201 -195.234506) (xy 449.745202 -195.260387) (xy 449.75526 -195.271136)
			(xy 449.793868 -195.309744) (xy 449.793868 -195.643225) (xy 450.555604 -195.643225) (xy 450.555604 -195.589927)
			(xy 450.563547 -195.537223) (xy 450.579257 -195.486293) (xy 450.602383 -195.438272) (xy 450.632407 -195.394235)
			(xy 450.668659 -195.355164) (xy 450.71033 -195.321933) (xy 450.756488 -195.295284) (xy 450.806102 -195.275812)
			(xy 450.858064 -195.263952) (xy 450.911214 -195.259969) (xy 450.964364 -195.263952) (xy 451.016326 -195.275812)
			(xy 451.06594 -195.295284) (xy 451.112098 -195.321933) (xy 451.153769 -195.355164) (xy 451.190021 -195.394235)
			(xy 451.220045 -195.438272) (xy 451.243171 -195.486293) (xy 451.258881 -195.537223) (xy 451.266824 -195.589927)
			(xy 451.267322 -195.616576) (xy 451.266824 -195.643225) (xy 452.765404 -195.643225) (xy 452.765404 -195.589927)
			(xy 452.773347 -195.537223) (xy 452.789057 -195.486293) (xy 452.812183 -195.438272) (xy 452.842207 -195.394235)
			(xy 452.878459 -195.355164) (xy 452.92013 -195.321933) (xy 452.966288 -195.295284) (xy 453.015902 -195.275812)
			(xy 453.067864 -195.263952) (xy 453.121014 -195.259969) (xy 453.174164 -195.263952) (xy 453.226126 -195.275812)
			(xy 453.27574 -195.295284) (xy 453.321898 -195.321933) (xy 453.363569 -195.355164) (xy 453.399821 -195.394235)
			(xy 453.429845 -195.438272) (xy 453.452971 -195.486293) (xy 453.468681 -195.537223) (xy 453.476624 -195.589927)
			(xy 453.477122 -195.616576) (xy 453.476624 -195.643225) (xy 454.655672 -195.643225) (xy 454.655672 -195.589927)
			(xy 454.663615 -195.537223) (xy 454.679325 -195.486293) (xy 454.702451 -195.438272) (xy 454.732475 -195.394235)
			(xy 454.768727 -195.355164) (xy 454.810398 -195.321933) (xy 454.856556 -195.295284) (xy 454.90617 -195.275812)
			(xy 454.958132 -195.263952) (xy 455.011282 -195.259969) (xy 455.064432 -195.263952) (xy 455.116394 -195.275812)
			(xy 455.166008 -195.295284) (xy 455.212166 -195.321933) (xy 455.253837 -195.355164) (xy 455.290089 -195.394235)
			(xy 455.320113 -195.438272) (xy 455.343239 -195.486293) (xy 455.358949 -195.537223) (xy 455.366892 -195.589927)
			(xy 455.36739 -195.616576) (xy 455.366892 -195.643225) (xy 458.099404 -195.643225) (xy 458.099404 -195.589927)
			(xy 458.107347 -195.537223) (xy 458.123057 -195.486293) (xy 458.146183 -195.438272) (xy 458.176207 -195.394235)
			(xy 458.212459 -195.355164) (xy 458.25413 -195.321933) (xy 458.300288 -195.295284) (xy 458.349902 -195.275812)
			(xy 458.401864 -195.263952) (xy 458.455014 -195.259969) (xy 458.508164 -195.263952) (xy 458.560126 -195.275812)
			(xy 458.60974 -195.295284) (xy 458.655898 -195.321933) (xy 458.697569 -195.355164) (xy 458.733821 -195.394235)
			(xy 458.763845 -195.438272) (xy 458.786971 -195.486293) (xy 458.802681 -195.537223) (xy 458.810624 -195.589927)
			(xy 458.811122 -195.616576) (xy 458.810624 -195.643225) (xy 458.802681 -195.695929) (xy 458.786971 -195.746859)
			(xy 458.763845 -195.79488) (xy 458.733821 -195.838917) (xy 458.697569 -195.877988) (xy 458.655898 -195.911219)
			(xy 458.60974 -195.937868) (xy 458.560126 -195.95734) (xy 458.508164 -195.9692) (xy 458.455014 -195.973184)
			(xy 458.401864 -195.9692) (xy 458.349902 -195.95734) (xy 458.300288 -195.937868) (xy 458.25413 -195.911219)
			(xy 458.212459 -195.877988) (xy 458.176207 -195.838917) (xy 458.146183 -195.79488) (xy 458.123057 -195.746859)
			(xy 458.107347 -195.695929) (xy 458.099404 -195.643225) (xy 455.366892 -195.643225) (xy 455.358949 -195.695929)
			(xy 455.343239 -195.746859) (xy 455.320113 -195.79488) (xy 455.290089 -195.838917) (xy 455.253837 -195.877988)
			(xy 455.212166 -195.911219) (xy 455.166008 -195.937868) (xy 455.116394 -195.95734) (xy 455.064432 -195.9692)
			(xy 455.011282 -195.973184) (xy 454.958132 -195.9692) (xy 454.90617 -195.95734) (xy 454.856556 -195.937868)
			(xy 454.810398 -195.911219) (xy 454.768727 -195.877988) (xy 454.732475 -195.838917) (xy 454.702451 -195.79488)
			(xy 454.679325 -195.746859) (xy 454.663615 -195.695929) (xy 454.655672 -195.643225) (xy 453.476624 -195.643225)
			(xy 453.468681 -195.695929) (xy 453.452971 -195.746859) (xy 453.429845 -195.79488) (xy 453.399821 -195.838917)
			(xy 453.363569 -195.877988) (xy 453.321898 -195.911219) (xy 453.27574 -195.937868) (xy 453.226126 -195.95734)
			(xy 453.174164 -195.9692) (xy 453.121014 -195.973184) (xy 453.067864 -195.9692) (xy 453.015902 -195.95734)
			(xy 452.966288 -195.937868) (xy 452.92013 -195.911219) (xy 452.878459 -195.877988) (xy 452.842207 -195.838917)
			(xy 452.812183 -195.79488) (xy 452.789057 -195.746859) (xy 452.773347 -195.695929) (xy 452.765404 -195.643225)
			(xy 451.266824 -195.643225) (xy 451.258881 -195.695929) (xy 451.243171 -195.746859) (xy 451.220045 -195.79488)
			(xy 451.190021 -195.838917) (xy 451.153769 -195.877988) (xy 451.112098 -195.911219) (xy 451.06594 -195.937868)
			(xy 451.016326 -195.95734) (xy 450.964364 -195.9692) (xy 450.911214 -195.973184) (xy 450.858064 -195.9692)
			(xy 450.806102 -195.95734) (xy 450.756488 -195.937868) (xy 450.71033 -195.911219) (xy 450.668659 -195.877988)
			(xy 450.632407 -195.838917) (xy 450.602383 -195.79488) (xy 450.579257 -195.746859) (xy 450.563547 -195.695929)
			(xy 450.555604 -195.643225) (xy 449.793868 -195.643225) (xy 449.793868 -196.12864) (xy 449.82384 -196.142102)
			(xy 449.848455 -196.153782) (xy 449.894117 -196.183501) (xy 449.93472 -196.219827) (xy 449.969317 -196.261914)
			(xy 449.9971 -196.308779) (xy 450.017422 -196.359328) (xy 450.029807 -196.412383) (xy 450.033967 -196.466706)
			(xy 450.031925 -196.493363) (xy 450.555604 -196.493363) (xy 450.555604 -196.440065) (xy 450.563547 -196.387361)
			(xy 450.579257 -196.336431) (xy 450.602383 -196.28841) (xy 450.632407 -196.244373) (xy 450.668659 -196.205302)
			(xy 450.71033 -196.172071) (xy 450.756488 -196.145422) (xy 450.806102 -196.12595) (xy 450.858064 -196.11409)
			(xy 450.911214 -196.110107) (xy 450.964364 -196.11409) (xy 451.016326 -196.12595) (xy 451.06594 -196.145422)
			(xy 451.112098 -196.172071) (xy 451.153769 -196.205302) (xy 451.190021 -196.244373) (xy 451.220045 -196.28841)
			(xy 451.243171 -196.336431) (xy 451.258881 -196.387361) (xy 451.266824 -196.440065) (xy 451.267322 -196.466714)
			(xy 451.266824 -196.493363) (xy 454.655672 -196.493363) (xy 454.655672 -196.440065) (xy 454.663615 -196.387361)
			(xy 454.679325 -196.336431) (xy 454.702451 -196.28841) (xy 454.732475 -196.244373) (xy 454.768727 -196.205302)
			(xy 454.810398 -196.172071) (xy 454.856556 -196.145422) (xy 454.90617 -196.12595) (xy 454.958132 -196.11409)
			(xy 455.011282 -196.110107) (xy 455.064432 -196.11409) (xy 455.116394 -196.12595) (xy 455.166008 -196.145422)
			(xy 455.212166 -196.172071) (xy 455.253837 -196.205302) (xy 455.290089 -196.244373) (xy 455.320113 -196.28841)
			(xy 455.343239 -196.336431) (xy 455.358949 -196.387361) (xy 455.366892 -196.440065) (xy 455.36739 -196.466714)
			(xy 455.366892 -196.493363) (xy 456.865472 -196.493363) (xy 456.865472 -196.440065) (xy 456.873415 -196.387361)
			(xy 456.889125 -196.336431) (xy 456.912251 -196.28841) (xy 456.942275 -196.244373) (xy 456.978527 -196.205302)
			(xy 457.020198 -196.172071) (xy 457.066356 -196.145422) (xy 457.11597 -196.12595) (xy 457.167932 -196.11409)
			(xy 457.221082 -196.110107) (xy 457.274232 -196.11409) (xy 457.326194 -196.12595) (xy 457.375808 -196.145422)
			(xy 457.421966 -196.172071) (xy 457.463637 -196.205302) (xy 457.499889 -196.244373) (xy 457.529913 -196.28841)
			(xy 457.553039 -196.336431) (xy 457.568749 -196.387361) (xy 457.576692 -196.440065) (xy 457.57719 -196.466714)
			(xy 457.576692 -196.493363) (xy 457.568749 -196.546067) (xy 457.553039 -196.596997) (xy 457.529913 -196.645018)
			(xy 457.499889 -196.689055) (xy 457.463637 -196.728126) (xy 457.421966 -196.761357) (xy 457.375808 -196.788006)
			(xy 457.326194 -196.807478) (xy 457.274232 -196.819338) (xy 457.221082 -196.823322) (xy 457.167932 -196.819338)
			(xy 457.11597 -196.807478) (xy 457.066356 -196.788006) (xy 457.020198 -196.761357) (xy 456.978527 -196.728126)
			(xy 456.942275 -196.689055) (xy 456.912251 -196.645018) (xy 456.889125 -196.596997) (xy 456.873415 -196.546067)
			(xy 456.865472 -196.493363) (xy 455.366892 -196.493363) (xy 455.358949 -196.546067) (xy 455.343239 -196.596997)
			(xy 455.320113 -196.645018) (xy 455.290089 -196.689055) (xy 455.253837 -196.728126) (xy 455.212166 -196.761357)
			(xy 455.166008 -196.788006) (xy 455.116394 -196.807478) (xy 455.064432 -196.819338) (xy 455.011282 -196.823322)
			(xy 454.958132 -196.819338) (xy 454.90617 -196.807478) (xy 454.856556 -196.788006) (xy 454.810398 -196.761357)
			(xy 454.768727 -196.728126) (xy 454.732475 -196.689055) (xy 454.702451 -196.645018) (xy 454.679325 -196.596997)
			(xy 454.663615 -196.546067) (xy 454.655672 -196.493363) (xy 451.266824 -196.493363) (xy 451.258881 -196.546067)
			(xy 451.243171 -196.596997) (xy 451.220045 -196.645018) (xy 451.190021 -196.689055) (xy 451.153769 -196.728126)
			(xy 451.112098 -196.761357) (xy 451.06594 -196.788006) (xy 451.016326 -196.807478) (xy 450.964364 -196.819338)
			(xy 450.911214 -196.823322) (xy 450.858064 -196.819338) (xy 450.806102 -196.807478) (xy 450.756488 -196.788006)
			(xy 450.71033 -196.761357) (xy 450.668659 -196.728126) (xy 450.632407 -196.689055) (xy 450.602383 -196.645018)
			(xy 450.579257 -196.596997) (xy 450.563547 -196.546067) (xy 450.555604 -196.493363) (xy 450.031925 -196.493363)
			(xy 450.029805 -196.521028) (xy 450.017418 -196.574083) (xy 449.997095 -196.624632) (xy 449.96931 -196.671496)
			(xy 449.934712 -196.713581) (xy 449.894108 -196.749906) (xy 449.848445 -196.779623) (xy 449.82384 -196.791326)
			(xy 449.793868 -196.804788) (xy 449.793868 -197.343247) (xy 450.555604 -197.343247) (xy 450.555604 -197.289949)
			(xy 450.563547 -197.237245) (xy 450.579257 -197.186315) (xy 450.602383 -197.138294) (xy 450.632407 -197.094257)
			(xy 450.668659 -197.055186) (xy 450.71033 -197.021955) (xy 450.756488 -196.995306) (xy 450.806102 -196.975834)
			(xy 450.858064 -196.963974) (xy 450.911214 -196.959991) (xy 450.964364 -196.963974) (xy 451.016326 -196.975834)
			(xy 451.06594 -196.995306) (xy 451.112098 -197.021955) (xy 451.153769 -197.055186) (xy 451.190021 -197.094257)
			(xy 451.220045 -197.138294) (xy 451.243171 -197.186315) (xy 451.258881 -197.237245) (xy 451.266824 -197.289949)
			(xy 451.267322 -197.316598) (xy 451.266824 -197.343247) (xy 452.765404 -197.343247) (xy 452.765404 -197.289949)
			(xy 452.773347 -197.237245) (xy 452.789057 -197.186315) (xy 452.812183 -197.138294) (xy 452.842207 -197.094257)
			(xy 452.878459 -197.055186) (xy 452.92013 -197.021955) (xy 452.966288 -196.995306) (xy 453.015902 -196.975834)
			(xy 453.067864 -196.963974) (xy 453.121014 -196.959991) (xy 453.174164 -196.963974) (xy 453.226126 -196.975834)
			(xy 453.27574 -196.995306) (xy 453.321898 -197.021955) (xy 453.363569 -197.055186) (xy 453.399821 -197.094257)
			(xy 453.429845 -197.138294) (xy 453.452971 -197.186315) (xy 453.468681 -197.237245) (xy 453.476624 -197.289949)
			(xy 453.477122 -197.316598) (xy 453.476624 -197.343247) (xy 454.655672 -197.343247) (xy 454.655672 -197.289949)
			(xy 454.663615 -197.237245) (xy 454.679325 -197.186315) (xy 454.702451 -197.138294) (xy 454.732475 -197.094257)
			(xy 454.768727 -197.055186) (xy 454.810398 -197.021955) (xy 454.856556 -196.995306) (xy 454.90617 -196.975834)
			(xy 454.958132 -196.963974) (xy 455.011282 -196.959991) (xy 455.064432 -196.963974) (xy 455.116394 -196.975834)
			(xy 455.166008 -196.995306) (xy 455.212166 -197.021955) (xy 455.253837 -197.055186) (xy 455.290089 -197.094257)
			(xy 455.320113 -197.138294) (xy 455.343239 -197.186315) (xy 455.358949 -197.237245) (xy 455.366892 -197.289949)
			(xy 455.36739 -197.316598) (xy 455.366892 -197.343247) (xy 458.099404 -197.343247) (xy 458.099404 -197.289949)
			(xy 458.107347 -197.237245) (xy 458.123057 -197.186315) (xy 458.146183 -197.138294) (xy 458.176207 -197.094257)
			(xy 458.212459 -197.055186) (xy 458.25413 -197.021955) (xy 458.300288 -196.995306) (xy 458.349902 -196.975834)
			(xy 458.401864 -196.963974) (xy 458.455014 -196.959991) (xy 458.508164 -196.963974) (xy 458.560126 -196.975834)
			(xy 458.60974 -196.995306) (xy 458.655898 -197.021955) (xy 458.697569 -197.055186) (xy 458.733821 -197.094257)
			(xy 458.763845 -197.138294) (xy 458.786971 -197.186315) (xy 458.802681 -197.237245) (xy 458.810624 -197.289949)
			(xy 458.811122 -197.316598) (xy 458.810624 -197.343247) (xy 458.802681 -197.395951) (xy 458.786971 -197.446881)
			(xy 458.763845 -197.494902) (xy 458.733821 -197.538939) (xy 458.697569 -197.57801) (xy 458.655898 -197.611241)
			(xy 458.60974 -197.63789) (xy 458.560126 -197.657362) (xy 458.508164 -197.669222) (xy 458.455014 -197.673206)
			(xy 458.401864 -197.669222) (xy 458.349902 -197.657362) (xy 458.300288 -197.63789) (xy 458.25413 -197.611241)
			(xy 458.212459 -197.57801) (xy 458.176207 -197.538939) (xy 458.146183 -197.494902) (xy 458.123057 -197.446881)
			(xy 458.107347 -197.395951) (xy 458.099404 -197.343247) (xy 455.366892 -197.343247) (xy 455.358949 -197.395951)
			(xy 455.343239 -197.446881) (xy 455.320113 -197.494902) (xy 455.290089 -197.538939) (xy 455.253837 -197.57801)
			(xy 455.212166 -197.611241) (xy 455.166008 -197.63789) (xy 455.116394 -197.657362) (xy 455.064432 -197.669222)
			(xy 455.011282 -197.673206) (xy 454.958132 -197.669222) (xy 454.90617 -197.657362) (xy 454.856556 -197.63789)
			(xy 454.810398 -197.611241) (xy 454.768727 -197.57801) (xy 454.732475 -197.538939) (xy 454.702451 -197.494902)
			(xy 454.679325 -197.446881) (xy 454.663615 -197.395951) (xy 454.655672 -197.343247) (xy 453.476624 -197.343247)
			(xy 453.468681 -197.395951) (xy 453.452971 -197.446881) (xy 453.429845 -197.494902) (xy 453.399821 -197.538939)
			(xy 453.363569 -197.57801) (xy 453.321898 -197.611241) (xy 453.27574 -197.63789) (xy 453.226126 -197.657362)
			(xy 453.174164 -197.669222) (xy 453.121014 -197.673206) (xy 453.067864 -197.669222) (xy 453.015902 -197.657362)
			(xy 452.966288 -197.63789) (xy 452.92013 -197.611241) (xy 452.878459 -197.57801) (xy 452.842207 -197.538939)
			(xy 452.812183 -197.494902) (xy 452.789057 -197.446881) (xy 452.773347 -197.395951) (xy 452.765404 -197.343247)
			(xy 451.266824 -197.343247) (xy 451.258881 -197.395951) (xy 451.243171 -197.446881) (xy 451.220045 -197.494902)
			(xy 451.190021 -197.538939) (xy 451.153769 -197.57801) (xy 451.112098 -197.611241) (xy 451.06594 -197.63789)
			(xy 451.016326 -197.657362) (xy 450.964364 -197.669222) (xy 450.911214 -197.673206) (xy 450.858064 -197.669222)
			(xy 450.806102 -197.657362) (xy 450.756488 -197.63789) (xy 450.71033 -197.611241) (xy 450.668659 -197.57801)
			(xy 450.632407 -197.538939) (xy 450.602383 -197.494902) (xy 450.579257 -197.446881) (xy 450.563547 -197.395951)
			(xy 450.555604 -197.343247) (xy 449.793868 -197.343247) (xy 449.793868 -197.828662) (xy 449.82384 -197.842124)
			(xy 449.848453 -197.853804) (xy 449.894112 -197.883522) (xy 449.934712 -197.919848) (xy 449.969306 -197.961933)
			(xy 449.997086 -198.008796) (xy 450.017405 -198.059343) (xy 450.029788 -198.112395) (xy 450.033947 -198.166715)
			(xy 450.031903 -198.193385) (xy 450.555604 -198.193385) (xy 450.555604 -198.140087) (xy 450.563547 -198.087383)
			(xy 450.579257 -198.036453) (xy 450.602383 -197.988432) (xy 450.632407 -197.944395) (xy 450.668659 -197.905324)
			(xy 450.71033 -197.872093) (xy 450.756488 -197.845444) (xy 450.806102 -197.825972) (xy 450.858064 -197.814112)
			(xy 450.911214 -197.810129) (xy 450.964364 -197.814112) (xy 451.016326 -197.825972) (xy 451.06594 -197.845444)
			(xy 451.112098 -197.872093) (xy 451.153769 -197.905324) (xy 451.190021 -197.944395) (xy 451.220045 -197.988432)
			(xy 451.243171 -198.036453) (xy 451.258881 -198.087383) (xy 451.266824 -198.140087) (xy 451.267322 -198.166736)
			(xy 451.266824 -198.193385) (xy 454.655672 -198.193385) (xy 454.655672 -198.140087) (xy 454.663615 -198.087383)
			(xy 454.679325 -198.036453) (xy 454.702451 -197.988432) (xy 454.732475 -197.944395) (xy 454.768727 -197.905324)
			(xy 454.810398 -197.872093) (xy 454.856556 -197.845444) (xy 454.90617 -197.825972) (xy 454.958132 -197.814112)
			(xy 455.011282 -197.810129) (xy 455.064432 -197.814112) (xy 455.116394 -197.825972) (xy 455.166008 -197.845444)
			(xy 455.212166 -197.872093) (xy 455.253837 -197.905324) (xy 455.290089 -197.944395) (xy 455.320113 -197.988432)
			(xy 455.343239 -198.036453) (xy 455.358949 -198.087383) (xy 455.366892 -198.140087) (xy 455.36739 -198.166736)
			(xy 455.366892 -198.193385) (xy 456.865472 -198.193385) (xy 456.865472 -198.140087) (xy 456.873415 -198.087383)
			(xy 456.889125 -198.036453) (xy 456.912251 -197.988432) (xy 456.942275 -197.944395) (xy 456.978527 -197.905324)
			(xy 457.020198 -197.872093) (xy 457.066356 -197.845444) (xy 457.11597 -197.825972) (xy 457.167932 -197.814112)
			(xy 457.221082 -197.810129) (xy 457.274232 -197.814112) (xy 457.326194 -197.825972) (xy 457.375808 -197.845444)
			(xy 457.421966 -197.872093) (xy 457.463637 -197.905324) (xy 457.499889 -197.944395) (xy 457.529913 -197.988432)
			(xy 457.553039 -198.036453) (xy 457.568749 -198.087383) (xy 457.576692 -198.140087) (xy 457.57719 -198.166736)
			(xy 457.576692 -198.193385) (xy 457.568749 -198.246089) (xy 457.553039 -198.297019) (xy 457.529913 -198.34504)
			(xy 457.499889 -198.389077) (xy 457.463637 -198.428148) (xy 457.421966 -198.461379) (xy 457.375808 -198.488028)
			(xy 457.326194 -198.5075) (xy 457.274232 -198.51936) (xy 457.221082 -198.523344) (xy 457.167932 -198.51936)
			(xy 457.11597 -198.5075) (xy 457.066356 -198.488028) (xy 457.020198 -198.461379) (xy 456.978527 -198.428148)
			(xy 456.942275 -198.389077) (xy 456.912251 -198.34504) (xy 456.889125 -198.297019) (xy 456.873415 -198.246089)
			(xy 456.865472 -198.193385) (xy 455.366892 -198.193385) (xy 455.358949 -198.246089) (xy 455.343239 -198.297019)
			(xy 455.320113 -198.34504) (xy 455.290089 -198.389077) (xy 455.253837 -198.428148) (xy 455.212166 -198.461379)
			(xy 455.166008 -198.488028) (xy 455.116394 -198.5075) (xy 455.064432 -198.51936) (xy 455.011282 -198.523344)
			(xy 454.958132 -198.51936) (xy 454.90617 -198.5075) (xy 454.856556 -198.488028) (xy 454.810398 -198.461379)
			(xy 454.768727 -198.428148) (xy 454.732475 -198.389077) (xy 454.702451 -198.34504) (xy 454.679325 -198.297019)
			(xy 454.663615 -198.246089) (xy 454.655672 -198.193385) (xy 451.266824 -198.193385) (xy 451.258881 -198.246089)
			(xy 451.243171 -198.297019) (xy 451.220045 -198.34504) (xy 451.190021 -198.389077) (xy 451.153769 -198.428148)
			(xy 451.112098 -198.461379) (xy 451.06594 -198.488028) (xy 451.016326 -198.5075) (xy 450.964364 -198.51936)
			(xy 450.911214 -198.523344) (xy 450.858064 -198.51936) (xy 450.806102 -198.5075) (xy 450.756488 -198.488028)
			(xy 450.71033 -198.461379) (xy 450.668659 -198.428148) (xy 450.632407 -198.389077) (xy 450.602383 -198.34504)
			(xy 450.579257 -198.297019) (xy 450.563547 -198.246089) (xy 450.555604 -198.193385) (xy 450.031903 -198.193385)
			(xy 450.029784 -198.221034) (xy 450.017396 -198.274085) (xy 449.997073 -198.324631) (xy 449.969289 -198.371491)
			(xy 449.934692 -198.413574) (xy 449.894089 -198.449896) (xy 449.848427 -198.47961) (xy 449.82384 -198.491348)
			(xy 449.793868 -198.50481) (xy 449.793868 -199.043269) (xy 450.555604 -199.043269) (xy 450.555604 -198.989971)
			(xy 450.563547 -198.937267) (xy 450.579257 -198.886337) (xy 450.602383 -198.838316) (xy 450.632407 -198.794279)
			(xy 450.668659 -198.755208) (xy 450.71033 -198.721977) (xy 450.756488 -198.695328) (xy 450.806102 -198.675856)
			(xy 450.858064 -198.663996) (xy 450.911214 -198.660013) (xy 450.964364 -198.663996) (xy 451.016326 -198.675856)
			(xy 451.06594 -198.695328) (xy 451.112098 -198.721977) (xy 451.153769 -198.755208) (xy 451.190021 -198.794279)
			(xy 451.220045 -198.838316) (xy 451.243171 -198.886337) (xy 451.258881 -198.937267) (xy 451.266824 -198.989971)
			(xy 451.267322 -199.01662) (xy 451.266824 -199.043269) (xy 452.765404 -199.043269) (xy 452.765404 -198.989971)
			(xy 452.773347 -198.937267) (xy 452.789057 -198.886337) (xy 452.812183 -198.838316) (xy 452.842207 -198.794279)
			(xy 452.878459 -198.755208) (xy 452.92013 -198.721977) (xy 452.966288 -198.695328) (xy 453.015902 -198.675856)
			(xy 453.067864 -198.663996) (xy 453.121014 -198.660013) (xy 453.174164 -198.663996) (xy 453.226126 -198.675856)
			(xy 453.27574 -198.695328) (xy 453.321898 -198.721977) (xy 453.363569 -198.755208) (xy 453.399821 -198.794279)
			(xy 453.429845 -198.838316) (xy 453.452971 -198.886337) (xy 453.468681 -198.937267) (xy 453.476624 -198.989971)
			(xy 453.477122 -199.01662) (xy 453.476624 -199.043269) (xy 454.655672 -199.043269) (xy 454.655672 -198.989971)
			(xy 454.663615 -198.937267) (xy 454.679325 -198.886337) (xy 454.702451 -198.838316) (xy 454.732475 -198.794279)
			(xy 454.768727 -198.755208) (xy 454.810398 -198.721977) (xy 454.856556 -198.695328) (xy 454.90617 -198.675856)
			(xy 454.958132 -198.663996) (xy 455.011282 -198.660013) (xy 455.064432 -198.663996) (xy 455.116394 -198.675856)
			(xy 455.166008 -198.695328) (xy 455.212166 -198.721977) (xy 455.253837 -198.755208) (xy 455.290089 -198.794279)
			(xy 455.320113 -198.838316) (xy 455.343239 -198.886337) (xy 455.358949 -198.937267) (xy 455.366892 -198.989971)
			(xy 455.36739 -199.01662) (xy 455.366892 -199.043269) (xy 458.099404 -199.043269) (xy 458.099404 -198.989971)
			(xy 458.107347 -198.937267) (xy 458.123057 -198.886337) (xy 458.146183 -198.838316) (xy 458.176207 -198.794279)
			(xy 458.212459 -198.755208) (xy 458.25413 -198.721977) (xy 458.300288 -198.695328) (xy 458.349902 -198.675856)
			(xy 458.401864 -198.663996) (xy 458.455014 -198.660013) (xy 458.508164 -198.663996) (xy 458.560126 -198.675856)
			(xy 458.60974 -198.695328) (xy 458.655898 -198.721977) (xy 458.697569 -198.755208) (xy 458.733821 -198.794279)
			(xy 458.763845 -198.838316) (xy 458.786971 -198.886337) (xy 458.802681 -198.937267) (xy 458.810624 -198.989971)
			(xy 458.811122 -199.01662) (xy 458.810624 -199.043269) (xy 458.802681 -199.095973) (xy 458.786971 -199.146903)
			(xy 458.763845 -199.194924) (xy 458.733821 -199.238961) (xy 458.697569 -199.278032) (xy 458.655898 -199.311263)
			(xy 458.60974 -199.337912) (xy 458.560126 -199.357384) (xy 458.508164 -199.369244) (xy 458.455014 -199.373228)
			(xy 458.401864 -199.369244) (xy 458.349902 -199.357384) (xy 458.300288 -199.337912) (xy 458.25413 -199.311263)
			(xy 458.212459 -199.278032) (xy 458.176207 -199.238961) (xy 458.146183 -199.194924) (xy 458.123057 -199.146903)
			(xy 458.107347 -199.095973) (xy 458.099404 -199.043269) (xy 455.366892 -199.043269) (xy 455.358949 -199.095973)
			(xy 455.343239 -199.146903) (xy 455.320113 -199.194924) (xy 455.290089 -199.238961) (xy 455.253837 -199.278032)
			(xy 455.212166 -199.311263) (xy 455.166008 -199.337912) (xy 455.116394 -199.357384) (xy 455.064432 -199.369244)
			(xy 455.011282 -199.373228) (xy 454.958132 -199.369244) (xy 454.90617 -199.357384) (xy 454.856556 -199.337912)
			(xy 454.810398 -199.311263) (xy 454.768727 -199.278032) (xy 454.732475 -199.238961) (xy 454.702451 -199.194924)
			(xy 454.679325 -199.146903) (xy 454.663615 -199.095973) (xy 454.655672 -199.043269) (xy 453.476624 -199.043269)
			(xy 453.468681 -199.095973) (xy 453.452971 -199.146903) (xy 453.429845 -199.194924) (xy 453.399821 -199.238961)
			(xy 453.363569 -199.278032) (xy 453.321898 -199.311263) (xy 453.27574 -199.337912) (xy 453.226126 -199.357384)
			(xy 453.174164 -199.369244) (xy 453.121014 -199.373228) (xy 453.067864 -199.369244) (xy 453.015902 -199.357384)
			(xy 452.966288 -199.337912) (xy 452.92013 -199.311263) (xy 452.878459 -199.278032) (xy 452.842207 -199.238961)
			(xy 452.812183 -199.194924) (xy 452.789057 -199.146903) (xy 452.773347 -199.095973) (xy 452.765404 -199.043269)
			(xy 451.266824 -199.043269) (xy 451.258881 -199.095973) (xy 451.243171 -199.146903) (xy 451.220045 -199.194924)
			(xy 451.190021 -199.238961) (xy 451.153769 -199.278032) (xy 451.112098 -199.311263) (xy 451.06594 -199.337912)
			(xy 451.016326 -199.357384) (xy 450.964364 -199.369244) (xy 450.911214 -199.373228) (xy 450.858064 -199.369244)
			(xy 450.806102 -199.357384) (xy 450.756488 -199.337912) (xy 450.71033 -199.311263) (xy 450.668659 -199.278032)
			(xy 450.632407 -199.238961) (xy 450.602383 -199.194924) (xy 450.579257 -199.146903) (xy 450.563547 -199.095973)
			(xy 450.555604 -199.043269) (xy 449.793868 -199.043269) (xy 449.793868 -199.893407) (xy 450.555604 -199.893407)
			(xy 450.555604 -199.840109) (xy 450.563547 -199.787405) (xy 450.579257 -199.736475) (xy 450.602383 -199.688454)
			(xy 450.632407 -199.644417) (xy 450.668659 -199.605346) (xy 450.71033 -199.572115) (xy 450.756488 -199.545466)
			(xy 450.806102 -199.525994) (xy 450.858064 -199.514134) (xy 450.911214 -199.510151) (xy 450.964364 -199.514134)
			(xy 451.016326 -199.525994) (xy 451.06594 -199.545466) (xy 451.112098 -199.572115) (xy 451.153769 -199.605346)
			(xy 451.190021 -199.644417) (xy 451.220045 -199.688454) (xy 451.243171 -199.736475) (xy 451.258881 -199.787405)
			(xy 451.266824 -199.840109) (xy 451.267322 -199.866758) (xy 451.266824 -199.893407) (xy 454.655672 -199.893407)
			(xy 454.655672 -199.840109) (xy 454.663615 -199.787405) (xy 454.679325 -199.736475) (xy 454.702451 -199.688454)
			(xy 454.732475 -199.644417) (xy 454.768727 -199.605346) (xy 454.810398 -199.572115) (xy 454.856556 -199.545466)
			(xy 454.90617 -199.525994) (xy 454.958132 -199.514134) (xy 455.011282 -199.510151) (xy 455.064432 -199.514134)
			(xy 455.116394 -199.525994) (xy 455.166008 -199.545466) (xy 455.212166 -199.572115) (xy 455.253837 -199.605346)
			(xy 455.290089 -199.644417) (xy 455.320113 -199.688454) (xy 455.343239 -199.736475) (xy 455.358949 -199.787405)
			(xy 455.366892 -199.840109) (xy 455.36739 -199.866758) (xy 455.366892 -199.893407) (xy 455.358949 -199.946111)
			(xy 455.343239 -199.997041) (xy 455.320113 -200.045062) (xy 455.290089 -200.089099) (xy 455.253837 -200.12817)
			(xy 455.212166 -200.161401) (xy 455.166008 -200.18805) (xy 455.116394 -200.207522) (xy 455.064432 -200.219382)
			(xy 455.011282 -200.223366) (xy 454.958132 -200.219382) (xy 454.90617 -200.207522) (xy 454.856556 -200.18805)
			(xy 454.810398 -200.161401) (xy 454.768727 -200.12817) (xy 454.732475 -200.089099) (xy 454.702451 -200.045062)
			(xy 454.679325 -199.997041) (xy 454.663615 -199.946111) (xy 454.655672 -199.893407) (xy 451.266824 -199.893407)
			(xy 451.258881 -199.946111) (xy 451.243171 -199.997041) (xy 451.220045 -200.045062) (xy 451.190021 -200.089099)
			(xy 451.153769 -200.12817) (xy 451.112098 -200.161401) (xy 451.06594 -200.18805) (xy 451.016326 -200.207522)
			(xy 450.964364 -200.219382) (xy 450.911214 -200.223366) (xy 450.858064 -200.219382) (xy 450.806102 -200.207522)
			(xy 450.756488 -200.18805) (xy 450.71033 -200.161401) (xy 450.668659 -200.12817) (xy 450.632407 -200.089099)
			(xy 450.602383 -200.045062) (xy 450.579257 -199.997041) (xy 450.563547 -199.946111) (xy 450.555604 -199.893407)
			(xy 449.793868 -199.893407) (xy 449.793868 -200.378568) (xy 449.82384 -200.39203) (xy 449.848453 -200.40371)
			(xy 449.894111 -200.433428) (xy 449.93471 -200.469753) (xy 449.969303 -200.511838) (xy 449.997083 -200.5587)
			(xy 450.017401 -200.609247) (xy 450.029783 -200.662299) (xy 450.033941 -200.716617) (xy 450.031897 -200.743291)
			(xy 450.555604 -200.743291) (xy 450.555604 -200.689993) (xy 450.563547 -200.637289) (xy 450.579257 -200.586359)
			(xy 450.602383 -200.538338) (xy 450.632407 -200.494301) (xy 450.668659 -200.45523) (xy 450.71033 -200.421999)
			(xy 450.756488 -200.39535) (xy 450.806102 -200.375878) (xy 450.858064 -200.364018) (xy 450.911214 -200.360035)
			(xy 450.964364 -200.364018) (xy 451.016326 -200.375878) (xy 451.06594 -200.39535) (xy 451.112098 -200.421999)
			(xy 451.153769 -200.45523) (xy 451.190021 -200.494301) (xy 451.220045 -200.538338) (xy 451.243171 -200.586359)
			(xy 451.258881 -200.637289) (xy 451.266824 -200.689993) (xy 451.267322 -200.716642) (xy 451.266824 -200.743291)
			(xy 454.655672 -200.743291) (xy 454.655672 -200.689993) (xy 454.663615 -200.637289) (xy 454.679325 -200.586359)
			(xy 454.702451 -200.538338) (xy 454.732475 -200.494301) (xy 454.768727 -200.45523) (xy 454.810398 -200.421999)
			(xy 454.856556 -200.39535) (xy 454.90617 -200.375878) (xy 454.958132 -200.364018) (xy 455.011282 -200.360035)
			(xy 455.064432 -200.364018) (xy 455.116394 -200.375878) (xy 455.166008 -200.39535) (xy 455.212166 -200.421999)
			(xy 455.253837 -200.45523) (xy 455.290089 -200.494301) (xy 455.320113 -200.538338) (xy 455.343239 -200.586359)
			(xy 455.358949 -200.637289) (xy 455.366892 -200.689993) (xy 455.36739 -200.716642) (xy 455.366892 -200.743291)
			(xy 456.865472 -200.743291) (xy 456.865472 -200.689993) (xy 456.873415 -200.637289) (xy 456.889125 -200.586359)
			(xy 456.912251 -200.538338) (xy 456.942275 -200.494301) (xy 456.978527 -200.45523) (xy 457.020198 -200.421999)
			(xy 457.066356 -200.39535) (xy 457.11597 -200.375878) (xy 457.167932 -200.364018) (xy 457.221082 -200.360035)
			(xy 457.274232 -200.364018) (xy 457.326194 -200.375878) (xy 457.375808 -200.39535) (xy 457.421966 -200.421999)
			(xy 457.463637 -200.45523) (xy 457.499889 -200.494301) (xy 457.529913 -200.538338) (xy 457.553039 -200.586359)
			(xy 457.568749 -200.637289) (xy 457.576692 -200.689993) (xy 457.57719 -200.716642) (xy 457.576692 -200.743291)
			(xy 457.568749 -200.795995) (xy 457.553039 -200.846925) (xy 457.529913 -200.894946) (xy 457.499889 -200.938983)
			(xy 457.463637 -200.978054) (xy 457.421966 -201.011285) (xy 457.375808 -201.037934) (xy 457.326194 -201.057406)
			(xy 457.274232 -201.069266) (xy 457.221082 -201.07325) (xy 457.167932 -201.069266) (xy 457.11597 -201.057406)
			(xy 457.066356 -201.037934) (xy 457.020198 -201.011285) (xy 456.978527 -200.978054) (xy 456.942275 -200.938983)
			(xy 456.912251 -200.894946) (xy 456.889125 -200.846925) (xy 456.873415 -200.795995) (xy 456.865472 -200.743291)
			(xy 455.366892 -200.743291) (xy 455.358949 -200.795995) (xy 455.343239 -200.846925) (xy 455.320113 -200.894946)
			(xy 455.290089 -200.938983) (xy 455.253837 -200.978054) (xy 455.212166 -201.011285) (xy 455.166008 -201.037934)
			(xy 455.116394 -201.057406) (xy 455.064432 -201.069266) (xy 455.011282 -201.07325) (xy 454.958132 -201.069266)
			(xy 454.90617 -201.057406) (xy 454.856556 -201.037934) (xy 454.810398 -201.011285) (xy 454.768727 -200.978054)
			(xy 454.732475 -200.938983) (xy 454.702451 -200.894946) (xy 454.679325 -200.846925) (xy 454.663615 -200.795995)
			(xy 454.655672 -200.743291) (xy 451.266824 -200.743291) (xy 451.258881 -200.795995) (xy 451.243171 -200.846925)
			(xy 451.220045 -200.894946) (xy 451.190021 -200.938983) (xy 451.153769 -200.978054) (xy 451.112098 -201.011285)
			(xy 451.06594 -201.037934) (xy 451.016326 -201.057406) (xy 450.964364 -201.069266) (xy 450.911214 -201.07325)
			(xy 450.858064 -201.069266) (xy 450.806102 -201.057406) (xy 450.756488 -201.037934) (xy 450.71033 -201.011285)
			(xy 450.668659 -200.978054) (xy 450.632407 -200.938983) (xy 450.602383 -200.894946) (xy 450.579257 -200.846925)
			(xy 450.563547 -200.795995) (xy 450.555604 -200.743291) (xy 450.031897 -200.743291) (xy 450.029778 -200.770935)
			(xy 450.01739 -200.823986) (xy 449.997067 -200.874531) (xy 449.969283 -200.92139) (xy 449.934686 -200.963472)
			(xy 449.894083 -200.999793) (xy 449.848422 -201.029506) (xy 449.82384 -201.041254) (xy 449.793868 -201.054716)
			(xy 449.793868 -201.593429) (xy 450.555604 -201.593429) (xy 450.555604 -201.540131) (xy 450.563547 -201.487427)
			(xy 450.579257 -201.436497) (xy 450.602383 -201.388476) (xy 450.632407 -201.344439) (xy 450.668659 -201.305368)
			(xy 450.71033 -201.272137) (xy 450.756488 -201.245488) (xy 450.806102 -201.226016) (xy 450.858064 -201.214156)
			(xy 450.911214 -201.210173) (xy 450.964364 -201.214156) (xy 451.016326 -201.226016) (xy 451.06594 -201.245488)
			(xy 451.112098 -201.272137) (xy 451.153769 -201.305368) (xy 451.190021 -201.344439) (xy 451.220045 -201.388476)
			(xy 451.243171 -201.436497) (xy 451.258881 -201.487427) (xy 451.266824 -201.540131) (xy 451.267322 -201.56678)
			(xy 451.266824 -201.593429) (xy 452.765404 -201.593429) (xy 452.765404 -201.540131) (xy 452.773347 -201.487427)
			(xy 452.789057 -201.436497) (xy 452.812183 -201.388476) (xy 452.842207 -201.344439) (xy 452.878459 -201.305368)
			(xy 452.92013 -201.272137) (xy 452.966288 -201.245488) (xy 453.015902 -201.226016) (xy 453.067864 -201.214156)
			(xy 453.121014 -201.210173) (xy 453.174164 -201.214156) (xy 453.226126 -201.226016) (xy 453.27574 -201.245488)
			(xy 453.321898 -201.272137) (xy 453.363569 -201.305368) (xy 453.399821 -201.344439) (xy 453.429845 -201.388476)
			(xy 453.452971 -201.436497) (xy 453.468681 -201.487427) (xy 453.476624 -201.540131) (xy 453.477122 -201.56678)
			(xy 453.476624 -201.593429) (xy 454.655672 -201.593429) (xy 454.655672 -201.540131) (xy 454.663615 -201.487427)
			(xy 454.679325 -201.436497) (xy 454.702451 -201.388476) (xy 454.732475 -201.344439) (xy 454.768727 -201.305368)
			(xy 454.810398 -201.272137) (xy 454.856556 -201.245488) (xy 454.90617 -201.226016) (xy 454.958132 -201.214156)
			(xy 455.011282 -201.210173) (xy 455.064432 -201.214156) (xy 455.116394 -201.226016) (xy 455.166008 -201.245488)
			(xy 455.212166 -201.272137) (xy 455.253837 -201.305368) (xy 455.290089 -201.344439) (xy 455.320113 -201.388476)
			(xy 455.343239 -201.436497) (xy 455.358949 -201.487427) (xy 455.366892 -201.540131) (xy 455.36739 -201.56678)
			(xy 455.366892 -201.593429) (xy 458.099404 -201.593429) (xy 458.099404 -201.540131) (xy 458.107347 -201.487427)
			(xy 458.123057 -201.436497) (xy 458.146183 -201.388476) (xy 458.176207 -201.344439) (xy 458.212459 -201.305368)
			(xy 458.25413 -201.272137) (xy 458.300288 -201.245488) (xy 458.349902 -201.226016) (xy 458.401864 -201.214156)
			(xy 458.455014 -201.210173) (xy 458.508164 -201.214156) (xy 458.560126 -201.226016) (xy 458.60974 -201.245488)
			(xy 458.655898 -201.272137) (xy 458.697569 -201.305368) (xy 458.733821 -201.344439) (xy 458.763845 -201.388476)
			(xy 458.786971 -201.436497) (xy 458.802681 -201.487427) (xy 458.810624 -201.540131) (xy 458.811122 -201.56678)
			(xy 458.810624 -201.593429) (xy 458.802681 -201.646133) (xy 458.786971 -201.697063) (xy 458.763845 -201.745084)
			(xy 458.733821 -201.789121) (xy 458.697569 -201.828192) (xy 458.655898 -201.861423) (xy 458.60974 -201.888072)
			(xy 458.560126 -201.907544) (xy 458.508164 -201.919404) (xy 458.455014 -201.923388) (xy 458.401864 -201.919404)
			(xy 458.349902 -201.907544) (xy 458.300288 -201.888072) (xy 458.25413 -201.861423) (xy 458.212459 -201.828192)
			(xy 458.176207 -201.789121) (xy 458.146183 -201.745084) (xy 458.123057 -201.697063) (xy 458.107347 -201.646133)
			(xy 458.099404 -201.593429) (xy 455.366892 -201.593429) (xy 455.358949 -201.646133) (xy 455.343239 -201.697063)
			(xy 455.320113 -201.745084) (xy 455.290089 -201.789121) (xy 455.253837 -201.828192) (xy 455.212166 -201.861423)
			(xy 455.166008 -201.888072) (xy 455.116394 -201.907544) (xy 455.064432 -201.919404) (xy 455.011282 -201.923388)
			(xy 454.958132 -201.919404) (xy 454.90617 -201.907544) (xy 454.856556 -201.888072) (xy 454.810398 -201.861423)
			(xy 454.768727 -201.828192) (xy 454.732475 -201.789121) (xy 454.702451 -201.745084) (xy 454.679325 -201.697063)
			(xy 454.663615 -201.646133) (xy 454.655672 -201.593429) (xy 453.476624 -201.593429) (xy 453.468681 -201.646133)
			(xy 453.452971 -201.697063) (xy 453.429845 -201.745084) (xy 453.399821 -201.789121) (xy 453.363569 -201.828192)
			(xy 453.321898 -201.861423) (xy 453.27574 -201.888072) (xy 453.226126 -201.907544) (xy 453.174164 -201.919404)
			(xy 453.121014 -201.923388) (xy 453.067864 -201.919404) (xy 453.015902 -201.907544) (xy 452.966288 -201.888072)
			(xy 452.92013 -201.861423) (xy 452.878459 -201.828192) (xy 452.842207 -201.789121) (xy 452.812183 -201.745084)
			(xy 452.789057 -201.697063) (xy 452.773347 -201.646133) (xy 452.765404 -201.593429) (xy 451.266824 -201.593429)
			(xy 451.258881 -201.646133) (xy 451.243171 -201.697063) (xy 451.220045 -201.745084) (xy 451.190021 -201.789121)
			(xy 451.153769 -201.828192) (xy 451.112098 -201.861423) (xy 451.06594 -201.888072) (xy 451.016326 -201.907544)
			(xy 450.964364 -201.919404) (xy 450.911214 -201.923388) (xy 450.858064 -201.919404) (xy 450.806102 -201.907544)
			(xy 450.756488 -201.888072) (xy 450.71033 -201.861423) (xy 450.668659 -201.828192) (xy 450.632407 -201.789121)
			(xy 450.602383 -201.745084) (xy 450.579257 -201.697063) (xy 450.563547 -201.646133) (xy 450.555604 -201.593429)
			(xy 449.793868 -201.593429) (xy 449.793868 -202.07859) (xy 449.82384 -202.092052) (xy 449.848459 -202.103733)
			(xy 449.894128 -202.133452) (xy 449.934739 -202.169781) (xy 449.969343 -202.211871) (xy 449.997132 -202.25874)
			(xy 450.017459 -202.309295) (xy 450.029849 -202.362356) (xy 450.034013 -202.416685) (xy 450.031974 -202.443313)
			(xy 450.555604 -202.443313) (xy 450.555604 -202.390015) (xy 450.563547 -202.337311) (xy 450.579257 -202.286381)
			(xy 450.602383 -202.23836) (xy 450.632407 -202.194323) (xy 450.668659 -202.155252) (xy 450.71033 -202.122021)
			(xy 450.756488 -202.095372) (xy 450.806102 -202.0759) (xy 450.858064 -202.06404) (xy 450.911214 -202.060057)
			(xy 450.964364 -202.06404) (xy 451.016326 -202.0759) (xy 451.06594 -202.095372) (xy 451.112098 -202.122021)
			(xy 451.153769 -202.155252) (xy 451.190021 -202.194323) (xy 451.220045 -202.23836) (xy 451.243171 -202.286381)
			(xy 451.258881 -202.337311) (xy 451.266824 -202.390015) (xy 451.267322 -202.416664) (xy 451.266824 -202.443313)
			(xy 454.655672 -202.443313) (xy 454.655672 -202.390015) (xy 454.663615 -202.337311) (xy 454.679325 -202.286381)
			(xy 454.702451 -202.23836) (xy 454.732475 -202.194323) (xy 454.768727 -202.155252) (xy 454.810398 -202.122021)
			(xy 454.856556 -202.095372) (xy 454.90617 -202.0759) (xy 454.958132 -202.06404) (xy 455.011282 -202.060057)
			(xy 455.064432 -202.06404) (xy 455.116394 -202.0759) (xy 455.166008 -202.095372) (xy 455.212166 -202.122021)
			(xy 455.253837 -202.155252) (xy 455.290089 -202.194323) (xy 455.320113 -202.23836) (xy 455.343239 -202.286381)
			(xy 455.358949 -202.337311) (xy 455.366892 -202.390015) (xy 455.36739 -202.416664) (xy 455.366892 -202.443313)
			(xy 456.865472 -202.443313) (xy 456.865472 -202.390015) (xy 456.873415 -202.337311) (xy 456.889125 -202.286381)
			(xy 456.912251 -202.23836) (xy 456.942275 -202.194323) (xy 456.978527 -202.155252) (xy 457.020198 -202.122021)
			(xy 457.066356 -202.095372) (xy 457.11597 -202.0759) (xy 457.167932 -202.06404) (xy 457.221082 -202.060057)
			(xy 457.274232 -202.06404) (xy 457.326194 -202.0759) (xy 457.375808 -202.095372) (xy 457.421966 -202.122021)
			(xy 457.463637 -202.155252) (xy 457.499889 -202.194323) (xy 457.529913 -202.23836) (xy 457.553039 -202.286381)
			(xy 457.568749 -202.337311) (xy 457.576692 -202.390015) (xy 457.57719 -202.416664) (xy 457.576692 -202.443313)
			(xy 457.568749 -202.496017) (xy 457.553039 -202.546947) (xy 457.529913 -202.594968) (xy 457.499889 -202.639005)
			(xy 457.463637 -202.678076) (xy 457.421966 -202.711307) (xy 457.375808 -202.737956) (xy 457.326194 -202.757428)
			(xy 457.274232 -202.769288) (xy 457.221082 -202.773272) (xy 457.167932 -202.769288) (xy 457.11597 -202.757428)
			(xy 457.066356 -202.737956) (xy 457.020198 -202.711307) (xy 456.978527 -202.678076) (xy 456.942275 -202.639005)
			(xy 456.912251 -202.594968) (xy 456.889125 -202.546947) (xy 456.873415 -202.496017) (xy 456.865472 -202.443313)
			(xy 455.366892 -202.443313) (xy 455.358949 -202.496017) (xy 455.343239 -202.546947) (xy 455.320113 -202.594968)
			(xy 455.290089 -202.639005) (xy 455.253837 -202.678076) (xy 455.212166 -202.711307) (xy 455.166008 -202.737956)
			(xy 455.116394 -202.757428) (xy 455.064432 -202.769288) (xy 455.011282 -202.773272) (xy 454.958132 -202.769288)
			(xy 454.90617 -202.757428) (xy 454.856556 -202.737956) (xy 454.810398 -202.711307) (xy 454.768727 -202.678076)
			(xy 454.732475 -202.639005) (xy 454.702451 -202.594968) (xy 454.679325 -202.546947) (xy 454.663615 -202.496017)
			(xy 454.655672 -202.443313) (xy 451.266824 -202.443313) (xy 451.258881 -202.496017) (xy 451.243171 -202.546947)
			(xy 451.220045 -202.594968) (xy 451.190021 -202.639005) (xy 451.153769 -202.678076) (xy 451.112098 -202.711307)
			(xy 451.06594 -202.737956) (xy 451.016326 -202.757428) (xy 450.964364 -202.769288) (xy 450.911214 -202.773272)
			(xy 450.858064 -202.769288) (xy 450.806102 -202.757428) (xy 450.756488 -202.737956) (xy 450.71033 -202.711307)
			(xy 450.668659 -202.678076) (xy 450.632407 -202.639005) (xy 450.602383 -202.594968) (xy 450.579257 -202.546947)
			(xy 450.563547 -202.496017) (xy 450.555604 -202.443313) (xy 450.031974 -202.443313) (xy 450.029853 -202.471015)
			(xy 450.017468 -202.524077) (xy 449.997145 -202.574633) (xy 449.96936 -202.621505) (xy 449.934759 -202.663598)
			(xy 449.894152 -202.69993) (xy 449.848485 -202.729653) (xy 449.82384 -202.741276) (xy 449.793868 -202.754738)
			(xy 449.793868 -203.293451) (xy 450.555604 -203.293451) (xy 450.555604 -203.240153) (xy 450.563547 -203.187449)
			(xy 450.579257 -203.136519) (xy 450.602383 -203.088498) (xy 450.632407 -203.044461) (xy 450.668659 -203.00539)
			(xy 450.71033 -202.972159) (xy 450.756488 -202.94551) (xy 450.806102 -202.926038) (xy 450.858064 -202.914178)
			(xy 450.911214 -202.910195) (xy 450.964364 -202.914178) (xy 451.016326 -202.926038) (xy 451.06594 -202.94551)
			(xy 451.112098 -202.972159) (xy 451.153769 -203.00539) (xy 451.190021 -203.044461) (xy 451.220045 -203.088498)
			(xy 451.243171 -203.136519) (xy 451.258881 -203.187449) (xy 451.266824 -203.240153) (xy 451.267322 -203.266802)
			(xy 451.266824 -203.293451) (xy 452.765404 -203.293451) (xy 452.765404 -203.240153) (xy 452.773347 -203.187449)
			(xy 452.789057 -203.136519) (xy 452.812183 -203.088498) (xy 452.842207 -203.044461) (xy 452.878459 -203.00539)
			(xy 452.92013 -202.972159) (xy 452.966288 -202.94551) (xy 453.015902 -202.926038) (xy 453.067864 -202.914178)
			(xy 453.121014 -202.910195) (xy 453.174164 -202.914178) (xy 453.226126 -202.926038) (xy 453.27574 -202.94551)
			(xy 453.321898 -202.972159) (xy 453.363569 -203.00539) (xy 453.399821 -203.044461) (xy 453.429845 -203.088498)
			(xy 453.452971 -203.136519) (xy 453.468681 -203.187449) (xy 453.476624 -203.240153) (xy 453.477122 -203.266802)
			(xy 453.476624 -203.293451) (xy 454.655672 -203.293451) (xy 454.655672 -203.240153) (xy 454.663615 -203.187449)
			(xy 454.679325 -203.136519) (xy 454.702451 -203.088498) (xy 454.732475 -203.044461) (xy 454.768727 -203.00539)
			(xy 454.810398 -202.972159) (xy 454.856556 -202.94551) (xy 454.90617 -202.926038) (xy 454.958132 -202.914178)
			(xy 455.011282 -202.910195) (xy 455.064432 -202.914178) (xy 455.116394 -202.926038) (xy 455.166008 -202.94551)
			(xy 455.212166 -202.972159) (xy 455.253837 -203.00539) (xy 455.290089 -203.044461) (xy 455.320113 -203.088498)
			(xy 455.343239 -203.136519) (xy 455.358949 -203.187449) (xy 455.366892 -203.240153) (xy 455.36739 -203.266802)
			(xy 455.366892 -203.293451) (xy 458.099404 -203.293451) (xy 458.099404 -203.240153) (xy 458.107347 -203.187449)
			(xy 458.123057 -203.136519) (xy 458.146183 -203.088498) (xy 458.176207 -203.044461) (xy 458.212459 -203.00539)
			(xy 458.25413 -202.972159) (xy 458.300288 -202.94551) (xy 458.349902 -202.926038) (xy 458.401864 -202.914178)
			(xy 458.455014 -202.910195) (xy 458.508164 -202.914178) (xy 458.560126 -202.926038) (xy 458.60974 -202.94551)
			(xy 458.655898 -202.972159) (xy 458.697569 -203.00539) (xy 458.733821 -203.044461) (xy 458.763845 -203.088498)
			(xy 458.786971 -203.136519) (xy 458.802681 -203.187449) (xy 458.810624 -203.240153) (xy 458.811122 -203.266802)
			(xy 458.810624 -203.293451) (xy 458.802681 -203.346155) (xy 458.786971 -203.397085) (xy 458.763845 -203.445106)
			(xy 458.733821 -203.489143) (xy 458.697569 -203.528214) (xy 458.655898 -203.561445) (xy 458.60974 -203.588094)
			(xy 458.560126 -203.607566) (xy 458.508164 -203.619426) (xy 458.455014 -203.62341) (xy 458.401864 -203.619426)
			(xy 458.349902 -203.607566) (xy 458.300288 -203.588094) (xy 458.25413 -203.561445) (xy 458.212459 -203.528214)
			(xy 458.176207 -203.489143) (xy 458.146183 -203.445106) (xy 458.123057 -203.397085) (xy 458.107347 -203.346155)
			(xy 458.099404 -203.293451) (xy 455.366892 -203.293451) (xy 455.358949 -203.346155) (xy 455.343239 -203.397085)
			(xy 455.320113 -203.445106) (xy 455.290089 -203.489143) (xy 455.253837 -203.528214) (xy 455.212166 -203.561445)
			(xy 455.166008 -203.588094) (xy 455.116394 -203.607566) (xy 455.064432 -203.619426) (xy 455.011282 -203.62341)
			(xy 454.958132 -203.619426) (xy 454.90617 -203.607566) (xy 454.856556 -203.588094) (xy 454.810398 -203.561445)
			(xy 454.768727 -203.528214) (xy 454.732475 -203.489143) (xy 454.702451 -203.445106) (xy 454.679325 -203.397085)
			(xy 454.663615 -203.346155) (xy 454.655672 -203.293451) (xy 453.476624 -203.293451) (xy 453.468681 -203.346155)
			(xy 453.452971 -203.397085) (xy 453.429845 -203.445106) (xy 453.399821 -203.489143) (xy 453.363569 -203.528214)
			(xy 453.321898 -203.561445) (xy 453.27574 -203.588094) (xy 453.226126 -203.607566) (xy 453.174164 -203.619426)
			(xy 453.121014 -203.62341) (xy 453.067864 -203.619426) (xy 453.015902 -203.607566) (xy 452.966288 -203.588094)
			(xy 452.92013 -203.561445) (xy 452.878459 -203.528214) (xy 452.842207 -203.489143) (xy 452.812183 -203.445106)
			(xy 452.789057 -203.397085) (xy 452.773347 -203.346155) (xy 452.765404 -203.293451) (xy 451.266824 -203.293451)
			(xy 451.258881 -203.346155) (xy 451.243171 -203.397085) (xy 451.220045 -203.445106) (xy 451.190021 -203.489143)
			(xy 451.153769 -203.528214) (xy 451.112098 -203.561445) (xy 451.06594 -203.588094) (xy 451.016326 -203.607566)
			(xy 450.964364 -203.619426) (xy 450.911214 -203.62341) (xy 450.858064 -203.619426) (xy 450.806102 -203.607566)
			(xy 450.756488 -203.588094) (xy 450.71033 -203.561445) (xy 450.668659 -203.528214) (xy 450.632407 -203.489143)
			(xy 450.602383 -203.445106) (xy 450.579257 -203.397085) (xy 450.563547 -203.346155) (xy 450.555604 -203.293451)
			(xy 449.793868 -203.293451) (xy 449.793868 -203.778612) (xy 449.82384 -203.792074) (xy 449.848457 -203.803755)
			(xy 449.894123 -203.833474) (xy 449.934731 -203.869801) (xy 449.969331 -203.91189) (xy 449.997118 -203.958757)
			(xy 450.017442 -204.00931) (xy 450.02983 -204.062368) (xy 450.033993 -204.116694) (xy 450.031952 -204.143335)
			(xy 450.555604 -204.143335) (xy 450.555604 -204.090037) (xy 450.563547 -204.037333) (xy 450.579257 -203.986403)
			(xy 450.602383 -203.938382) (xy 450.632407 -203.894345) (xy 450.668659 -203.855274) (xy 450.71033 -203.822043)
			(xy 450.756488 -203.795394) (xy 450.806102 -203.775922) (xy 450.858064 -203.764062) (xy 450.911214 -203.760079)
			(xy 450.964364 -203.764062) (xy 451.016326 -203.775922) (xy 451.06594 -203.795394) (xy 451.112098 -203.822043)
			(xy 451.153769 -203.855274) (xy 451.190021 -203.894345) (xy 451.220045 -203.938382) (xy 451.243171 -203.986403)
			(xy 451.258881 -204.037333) (xy 451.266824 -204.090037) (xy 451.267322 -204.116686) (xy 451.266824 -204.143335)
			(xy 454.655672 -204.143335) (xy 454.655672 -204.090037) (xy 454.663615 -204.037333) (xy 454.679325 -203.986403)
			(xy 454.702451 -203.938382) (xy 454.732475 -203.894345) (xy 454.768727 -203.855274) (xy 454.810398 -203.822043)
			(xy 454.856556 -203.795394) (xy 454.90617 -203.775922) (xy 454.958132 -203.764062) (xy 455.011282 -203.760079)
			(xy 455.064432 -203.764062) (xy 455.116394 -203.775922) (xy 455.166008 -203.795394) (xy 455.212166 -203.822043)
			(xy 455.253837 -203.855274) (xy 455.290089 -203.894345) (xy 455.320113 -203.938382) (xy 455.343239 -203.986403)
			(xy 455.358949 -204.037333) (xy 455.366892 -204.090037) (xy 455.36739 -204.116686) (xy 455.366892 -204.143335)
			(xy 456.865472 -204.143335) (xy 456.865472 -204.090037) (xy 456.873415 -204.037333) (xy 456.889125 -203.986403)
			(xy 456.912251 -203.938382) (xy 456.942275 -203.894345) (xy 456.978527 -203.855274) (xy 457.020198 -203.822043)
			(xy 457.066356 -203.795394) (xy 457.11597 -203.775922) (xy 457.167932 -203.764062) (xy 457.221082 -203.760079)
			(xy 457.274232 -203.764062) (xy 457.326194 -203.775922) (xy 457.375808 -203.795394) (xy 457.421966 -203.822043)
			(xy 457.463637 -203.855274) (xy 457.499889 -203.894345) (xy 457.529913 -203.938382) (xy 457.553039 -203.986403)
			(xy 457.568749 -204.037333) (xy 457.576692 -204.090037) (xy 457.57719 -204.116686) (xy 457.576692 -204.143335)
			(xy 457.568749 -204.196039) (xy 457.553039 -204.246969) (xy 457.529913 -204.29499) (xy 457.499889 -204.339027)
			(xy 457.463637 -204.378098) (xy 457.421966 -204.411329) (xy 457.375808 -204.437978) (xy 457.326194 -204.45745)
			(xy 457.274232 -204.46931) (xy 457.221082 -204.473294) (xy 457.167932 -204.46931) (xy 457.11597 -204.45745)
			(xy 457.066356 -204.437978) (xy 457.020198 -204.411329) (xy 456.978527 -204.378098) (xy 456.942275 -204.339027)
			(xy 456.912251 -204.29499) (xy 456.889125 -204.246969) (xy 456.873415 -204.196039) (xy 456.865472 -204.143335)
			(xy 455.366892 -204.143335) (xy 455.358949 -204.196039) (xy 455.343239 -204.246969) (xy 455.320113 -204.29499)
			(xy 455.290089 -204.339027) (xy 455.253837 -204.378098) (xy 455.212166 -204.411329) (xy 455.166008 -204.437978)
			(xy 455.116394 -204.45745) (xy 455.064432 -204.46931) (xy 455.011282 -204.473294) (xy 454.958132 -204.46931)
			(xy 454.90617 -204.45745) (xy 454.856556 -204.437978) (xy 454.810398 -204.411329) (xy 454.768727 -204.378098)
			(xy 454.732475 -204.339027) (xy 454.702451 -204.29499) (xy 454.679325 -204.246969) (xy 454.663615 -204.196039)
			(xy 454.655672 -204.143335) (xy 451.266824 -204.143335) (xy 451.258881 -204.196039) (xy 451.243171 -204.246969)
			(xy 451.220045 -204.29499) (xy 451.190021 -204.339027) (xy 451.153769 -204.378098) (xy 451.112098 -204.411329)
			(xy 451.06594 -204.437978) (xy 451.016326 -204.45745) (xy 450.964364 -204.46931) (xy 450.911214 -204.473294)
			(xy 450.858064 -204.46931) (xy 450.806102 -204.45745) (xy 450.756488 -204.437978) (xy 450.71033 -204.411329)
			(xy 450.668659 -204.378098) (xy 450.632407 -204.339027) (xy 450.602383 -204.29499) (xy 450.579257 -204.246969)
			(xy 450.563547 -204.196039) (xy 450.555604 -204.143335) (xy 450.031952 -204.143335) (xy 450.029832 -204.17102)
			(xy 450.017446 -204.224079) (xy 449.997123 -204.274633) (xy 449.969338 -204.321501) (xy 449.934739 -204.36359)
			(xy 449.894133 -204.399919) (xy 449.848467 -204.42964) (xy 449.82384 -204.441298) (xy 449.793868 -204.45476)
			(xy 449.793868 -204.993219) (xy 450.555604 -204.993219) (xy 450.555604 -204.939921) (xy 450.563547 -204.887217)
			(xy 450.579257 -204.836287) (xy 450.602383 -204.788266) (xy 450.632407 -204.744229) (xy 450.668659 -204.705158)
			(xy 450.71033 -204.671927) (xy 450.756488 -204.645278) (xy 450.806102 -204.625806) (xy 450.858064 -204.613946)
			(xy 450.911214 -204.609963) (xy 450.964364 -204.613946) (xy 451.016326 -204.625806) (xy 451.06594 -204.645278)
			(xy 451.112098 -204.671927) (xy 451.153769 -204.705158) (xy 451.190021 -204.744229) (xy 451.220045 -204.788266)
			(xy 451.243171 -204.836287) (xy 451.258881 -204.887217) (xy 451.266824 -204.939921) (xy 451.267322 -204.96657)
			(xy 451.266824 -204.993219) (xy 452.765404 -204.993219) (xy 452.765404 -204.939921) (xy 452.773347 -204.887217)
			(xy 452.789057 -204.836287) (xy 452.812183 -204.788266) (xy 452.842207 -204.744229) (xy 452.878459 -204.705158)
			(xy 452.92013 -204.671927) (xy 452.966288 -204.645278) (xy 453.015902 -204.625806) (xy 453.067864 -204.613946)
			(xy 453.121014 -204.609963) (xy 453.174164 -204.613946) (xy 453.226126 -204.625806) (xy 453.27574 -204.645278)
			(xy 453.321898 -204.671927) (xy 453.363569 -204.705158) (xy 453.399821 -204.744229) (xy 453.429845 -204.788266)
			(xy 453.452971 -204.836287) (xy 453.468681 -204.887217) (xy 453.476624 -204.939921) (xy 453.477122 -204.96657)
			(xy 453.476624 -204.993219) (xy 454.655672 -204.993219) (xy 454.655672 -204.939921) (xy 454.663615 -204.887217)
			(xy 454.679325 -204.836287) (xy 454.702451 -204.788266) (xy 454.732475 -204.744229) (xy 454.768727 -204.705158)
			(xy 454.810398 -204.671927) (xy 454.856556 -204.645278) (xy 454.90617 -204.625806) (xy 454.958132 -204.613946)
			(xy 455.011282 -204.609963) (xy 455.064432 -204.613946) (xy 455.116394 -204.625806) (xy 455.166008 -204.645278)
			(xy 455.212166 -204.671927) (xy 455.253837 -204.705158) (xy 455.290089 -204.744229) (xy 455.320113 -204.788266)
			(xy 455.343239 -204.836287) (xy 455.358949 -204.887217) (xy 455.366892 -204.939921) (xy 455.36739 -204.96657)
			(xy 455.366892 -204.993219) (xy 458.099404 -204.993219) (xy 458.099404 -204.939921) (xy 458.107347 -204.887217)
			(xy 458.123057 -204.836287) (xy 458.146183 -204.788266) (xy 458.176207 -204.744229) (xy 458.212459 -204.705158)
			(xy 458.25413 -204.671927) (xy 458.300288 -204.645278) (xy 458.349902 -204.625806) (xy 458.401864 -204.613946)
			(xy 458.455014 -204.609963) (xy 458.508164 -204.613946) (xy 458.560126 -204.625806) (xy 458.60974 -204.645278)
			(xy 458.655898 -204.671927) (xy 458.697569 -204.705158) (xy 458.733821 -204.744229) (xy 458.763845 -204.788266)
			(xy 458.786971 -204.836287) (xy 458.802681 -204.887217) (xy 458.810624 -204.939921) (xy 458.811122 -204.96657)
			(xy 458.810624 -204.993219) (xy 458.802681 -205.045923) (xy 458.786971 -205.096853) (xy 458.763845 -205.144874)
			(xy 458.733821 -205.188911) (xy 458.697569 -205.227982) (xy 458.655898 -205.261213) (xy 458.60974 -205.287862)
			(xy 458.560126 -205.307334) (xy 458.508164 -205.319194) (xy 458.455014 -205.323178) (xy 458.401864 -205.319194)
			(xy 458.349902 -205.307334) (xy 458.300288 -205.287862) (xy 458.25413 -205.261213) (xy 458.212459 -205.227982)
			(xy 458.176207 -205.188911) (xy 458.146183 -205.144874) (xy 458.123057 -205.096853) (xy 458.107347 -205.045923)
			(xy 458.099404 -204.993219) (xy 455.366892 -204.993219) (xy 455.358949 -205.045923) (xy 455.343239 -205.096853)
			(xy 455.320113 -205.144874) (xy 455.290089 -205.188911) (xy 455.253837 -205.227982) (xy 455.212166 -205.261213)
			(xy 455.166008 -205.287862) (xy 455.116394 -205.307334) (xy 455.064432 -205.319194) (xy 455.011282 -205.323178)
			(xy 454.958132 -205.319194) (xy 454.90617 -205.307334) (xy 454.856556 -205.287862) (xy 454.810398 -205.261213)
			(xy 454.768727 -205.227982) (xy 454.732475 -205.188911) (xy 454.702451 -205.144874) (xy 454.679325 -205.096853)
			(xy 454.663615 -205.045923) (xy 454.655672 -204.993219) (xy 453.476624 -204.993219) (xy 453.468681 -205.045923)
			(xy 453.452971 -205.096853) (xy 453.429845 -205.144874) (xy 453.399821 -205.188911) (xy 453.363569 -205.227982)
			(xy 453.321898 -205.261213) (xy 453.27574 -205.287862) (xy 453.226126 -205.307334) (xy 453.174164 -205.319194)
			(xy 453.121014 -205.323178) (xy 453.067864 -205.319194) (xy 453.015902 -205.307334) (xy 452.966288 -205.287862)
			(xy 452.92013 -205.261213) (xy 452.878459 -205.227982) (xy 452.842207 -205.188911) (xy 452.812183 -205.144874)
			(xy 452.789057 -205.096853) (xy 452.773347 -205.045923) (xy 452.765404 -204.993219) (xy 451.266824 -204.993219)
			(xy 451.258881 -205.045923) (xy 451.243171 -205.096853) (xy 451.220045 -205.144874) (xy 451.190021 -205.188911)
			(xy 451.153769 -205.227982) (xy 451.112098 -205.261213) (xy 451.06594 -205.287862) (xy 451.016326 -205.307334)
			(xy 450.964364 -205.319194) (xy 450.911214 -205.323178) (xy 450.858064 -205.319194) (xy 450.806102 -205.307334)
			(xy 450.756488 -205.287862) (xy 450.71033 -205.261213) (xy 450.668659 -205.227982) (xy 450.632407 -205.188911)
			(xy 450.602383 -205.144874) (xy 450.579257 -205.096853) (xy 450.563547 -205.045923) (xy 450.555604 -204.993219)
			(xy 449.793868 -204.993219) (xy 449.793868 -205.478634) (xy 449.82384 -205.492096) (xy 449.848455 -205.503777)
			(xy 449.894118 -205.533495) (xy 449.934723 -205.569822) (xy 449.96932 -205.611909) (xy 449.997104 -205.658774)
			(xy 450.017426 -205.709324) (xy 450.029812 -205.76238) (xy 450.033972 -205.816703) (xy 450.03193 -205.843357)
			(xy 450.555604 -205.843357) (xy 450.555604 -205.790059) (xy 450.563547 -205.737355) (xy 450.579257 -205.686425)
			(xy 450.602383 -205.638404) (xy 450.632407 -205.594367) (xy 450.668659 -205.555296) (xy 450.71033 -205.522065)
			(xy 450.756488 -205.495416) (xy 450.806102 -205.475944) (xy 450.858064 -205.464084) (xy 450.911214 -205.460101)
			(xy 450.964364 -205.464084) (xy 451.016326 -205.475944) (xy 451.06594 -205.495416) (xy 451.112098 -205.522065)
			(xy 451.153769 -205.555296) (xy 451.190021 -205.594367) (xy 451.220045 -205.638404) (xy 451.243171 -205.686425)
			(xy 451.258881 -205.737355) (xy 451.266824 -205.790059) (xy 451.267322 -205.816708) (xy 451.266824 -205.843357)
			(xy 454.655672 -205.843357) (xy 454.655672 -205.790059) (xy 454.663615 -205.737355) (xy 454.679325 -205.686425)
			(xy 454.702451 -205.638404) (xy 454.732475 -205.594367) (xy 454.768727 -205.555296) (xy 454.810398 -205.522065)
			(xy 454.856556 -205.495416) (xy 454.90617 -205.475944) (xy 454.958132 -205.464084) (xy 455.011282 -205.460101)
			(xy 455.064432 -205.464084) (xy 455.116394 -205.475944) (xy 455.166008 -205.495416) (xy 455.212166 -205.522065)
			(xy 455.253837 -205.555296) (xy 455.290089 -205.594367) (xy 455.320113 -205.638404) (xy 455.343239 -205.686425)
			(xy 455.358949 -205.737355) (xy 455.366892 -205.790059) (xy 455.36739 -205.816708) (xy 455.366892 -205.843357)
			(xy 456.865472 -205.843357) (xy 456.865472 -205.790059) (xy 456.873415 -205.737355) (xy 456.889125 -205.686425)
			(xy 456.912251 -205.638404) (xy 456.942275 -205.594367) (xy 456.978527 -205.555296) (xy 457.020198 -205.522065)
			(xy 457.066356 -205.495416) (xy 457.11597 -205.475944) (xy 457.167932 -205.464084) (xy 457.221082 -205.460101)
			(xy 457.274232 -205.464084) (xy 457.326194 -205.475944) (xy 457.375808 -205.495416) (xy 457.421966 -205.522065)
			(xy 457.463637 -205.555296) (xy 457.499889 -205.594367) (xy 457.529913 -205.638404) (xy 457.553039 -205.686425)
			(xy 457.568749 -205.737355) (xy 457.576692 -205.790059) (xy 457.57719 -205.816708) (xy 457.576692 -205.843357)
			(xy 457.568749 -205.896061) (xy 457.553039 -205.946991) (xy 457.529913 -205.995012) (xy 457.499889 -206.039049)
			(xy 457.463637 -206.07812) (xy 457.421966 -206.111351) (xy 457.375808 -206.138) (xy 457.326194 -206.157472)
			(xy 457.274232 -206.169332) (xy 457.221082 -206.173316) (xy 457.167932 -206.169332) (xy 457.11597 -206.157472)
			(xy 457.066356 -206.138) (xy 457.020198 -206.111351) (xy 456.978527 -206.07812) (xy 456.942275 -206.039049)
			(xy 456.912251 -205.995012) (xy 456.889125 -205.946991) (xy 456.873415 -205.896061) (xy 456.865472 -205.843357)
			(xy 455.366892 -205.843357) (xy 455.358949 -205.896061) (xy 455.343239 -205.946991) (xy 455.320113 -205.995012)
			(xy 455.290089 -206.039049) (xy 455.253837 -206.07812) (xy 455.212166 -206.111351) (xy 455.166008 -206.138)
			(xy 455.116394 -206.157472) (xy 455.064432 -206.169332) (xy 455.011282 -206.173316) (xy 454.958132 -206.169332)
			(xy 454.90617 -206.157472) (xy 454.856556 -206.138) (xy 454.810398 -206.111351) (xy 454.768727 -206.07812)
			(xy 454.732475 -206.039049) (xy 454.702451 -205.995012) (xy 454.679325 -205.946991) (xy 454.663615 -205.896061)
			(xy 454.655672 -205.843357) (xy 451.266824 -205.843357) (xy 451.258881 -205.896061) (xy 451.243171 -205.946991)
			(xy 451.220045 -205.995012) (xy 451.190021 -206.039049) (xy 451.153769 -206.07812) (xy 451.112098 -206.111351)
			(xy 451.06594 -206.138) (xy 451.016326 -206.157472) (xy 450.964364 -206.169332) (xy 450.911214 -206.173316)
			(xy 450.858064 -206.169332) (xy 450.806102 -206.157472) (xy 450.756488 -206.138) (xy 450.71033 -206.111351)
			(xy 450.668659 -206.07812) (xy 450.632407 -206.039049) (xy 450.602383 -205.995012) (xy 450.579257 -205.946991)
			(xy 450.563547 -205.896061) (xy 450.555604 -205.843357) (xy 450.03193 -205.843357) (xy 450.029811 -205.871026)
			(xy 450.017424 -205.924082) (xy 449.997101 -205.974632) (xy 449.969316 -206.021497) (xy 449.934718 -206.063583)
			(xy 449.894113 -206.099909) (xy 449.84845 -206.129627) (xy 449.82384 -206.14132) (xy 449.793868 -206.154782)
			(xy 449.793868 -206.693241) (xy 450.555604 -206.693241) (xy 450.555604 -206.639943) (xy 450.563547 -206.587239)
			(xy 450.579257 -206.536309) (xy 450.602383 -206.488288) (xy 450.632407 -206.444251) (xy 450.668659 -206.40518)
			(xy 450.71033 -206.371949) (xy 450.756488 -206.3453) (xy 450.806102 -206.325828) (xy 450.858064 -206.313968)
			(xy 450.911214 -206.309985) (xy 450.964364 -206.313968) (xy 451.016326 -206.325828) (xy 451.06594 -206.3453)
			(xy 451.112098 -206.371949) (xy 451.153769 -206.40518) (xy 451.190021 -206.444251) (xy 451.220045 -206.488288)
			(xy 451.243171 -206.536309) (xy 451.258881 -206.587239) (xy 451.266824 -206.639943) (xy 451.267322 -206.666592)
			(xy 451.266824 -206.693241) (xy 452.765404 -206.693241) (xy 452.765404 -206.639943) (xy 452.773347 -206.587239)
			(xy 452.789057 -206.536309) (xy 452.812183 -206.488288) (xy 452.842207 -206.444251) (xy 452.878459 -206.40518)
			(xy 452.92013 -206.371949) (xy 452.966288 -206.3453) (xy 453.015902 -206.325828) (xy 453.067864 -206.313968)
			(xy 453.121014 -206.309985) (xy 453.174164 -206.313968) (xy 453.226126 -206.325828) (xy 453.27574 -206.3453)
			(xy 453.321898 -206.371949) (xy 453.363569 -206.40518) (xy 453.399821 -206.444251) (xy 453.429845 -206.488288)
			(xy 453.452971 -206.536309) (xy 453.468681 -206.587239) (xy 453.476624 -206.639943) (xy 453.477122 -206.666592)
			(xy 453.476624 -206.693241) (xy 454.655672 -206.693241) (xy 454.655672 -206.639943) (xy 454.663615 -206.587239)
			(xy 454.679325 -206.536309) (xy 454.702451 -206.488288) (xy 454.732475 -206.444251) (xy 454.768727 -206.40518)
			(xy 454.810398 -206.371949) (xy 454.856556 -206.3453) (xy 454.90617 -206.325828) (xy 454.958132 -206.313968)
			(xy 455.011282 -206.309985) (xy 455.064432 -206.313968) (xy 455.116394 -206.325828) (xy 455.166008 -206.3453)
			(xy 455.212166 -206.371949) (xy 455.253837 -206.40518) (xy 455.290089 -206.444251) (xy 455.320113 -206.488288)
			(xy 455.343239 -206.536309) (xy 455.358949 -206.587239) (xy 455.366892 -206.639943) (xy 455.36739 -206.666592)
			(xy 455.366892 -206.693241) (xy 458.099404 -206.693241) (xy 458.099404 -206.639943) (xy 458.107347 -206.587239)
			(xy 458.123057 -206.536309) (xy 458.146183 -206.488288) (xy 458.176207 -206.444251) (xy 458.212459 -206.40518)
			(xy 458.25413 -206.371949) (xy 458.300288 -206.3453) (xy 458.349902 -206.325828) (xy 458.401864 -206.313968)
			(xy 458.455014 -206.309985) (xy 458.508164 -206.313968) (xy 458.560126 -206.325828) (xy 458.60974 -206.3453)
			(xy 458.655898 -206.371949) (xy 458.697569 -206.40518) (xy 458.733821 -206.444251) (xy 458.763845 -206.488288)
			(xy 458.786971 -206.536309) (xy 458.802681 -206.587239) (xy 458.810624 -206.639943) (xy 458.811122 -206.666592)
			(xy 458.810624 -206.693241) (xy 458.802681 -206.745945) (xy 458.786971 -206.796875) (xy 458.763845 -206.844896)
			(xy 458.733821 -206.888933) (xy 458.697569 -206.928004) (xy 458.655898 -206.961235) (xy 458.60974 -206.987884)
			(xy 458.560126 -207.007356) (xy 458.508164 -207.019216) (xy 458.455014 -207.0232) (xy 458.401864 -207.019216)
			(xy 458.349902 -207.007356) (xy 458.300288 -206.987884) (xy 458.25413 -206.961235) (xy 458.212459 -206.928004)
			(xy 458.176207 -206.888933) (xy 458.146183 -206.844896) (xy 458.123057 -206.796875) (xy 458.107347 -206.745945)
			(xy 458.099404 -206.693241) (xy 455.366892 -206.693241) (xy 455.358949 -206.745945) (xy 455.343239 -206.796875)
			(xy 455.320113 -206.844896) (xy 455.290089 -206.888933) (xy 455.253837 -206.928004) (xy 455.212166 -206.961235)
			(xy 455.166008 -206.987884) (xy 455.116394 -207.007356) (xy 455.064432 -207.019216) (xy 455.011282 -207.0232)
			(xy 454.958132 -207.019216) (xy 454.90617 -207.007356) (xy 454.856556 -206.987884) (xy 454.810398 -206.961235)
			(xy 454.768727 -206.928004) (xy 454.732475 -206.888933) (xy 454.702451 -206.844896) (xy 454.679325 -206.796875)
			(xy 454.663615 -206.745945) (xy 454.655672 -206.693241) (xy 453.476624 -206.693241) (xy 453.468681 -206.745945)
			(xy 453.452971 -206.796875) (xy 453.429845 -206.844896) (xy 453.399821 -206.888933) (xy 453.363569 -206.928004)
			(xy 453.321898 -206.961235) (xy 453.27574 -206.987884) (xy 453.226126 -207.007356) (xy 453.174164 -207.019216)
			(xy 453.121014 -207.0232) (xy 453.067864 -207.019216) (xy 453.015902 -207.007356) (xy 452.966288 -206.987884)
			(xy 452.92013 -206.961235) (xy 452.878459 -206.928004) (xy 452.842207 -206.888933) (xy 452.812183 -206.844896)
			(xy 452.789057 -206.796875) (xy 452.773347 -206.745945) (xy 452.765404 -206.693241) (xy 451.266824 -206.693241)
			(xy 451.258881 -206.745945) (xy 451.243171 -206.796875) (xy 451.220045 -206.844896) (xy 451.190021 -206.888933)
			(xy 451.153769 -206.928004) (xy 451.112098 -206.961235) (xy 451.06594 -206.987884) (xy 451.016326 -207.007356)
			(xy 450.964364 -207.019216) (xy 450.911214 -207.0232) (xy 450.858064 -207.019216) (xy 450.806102 -207.007356)
			(xy 450.756488 -206.987884) (xy 450.71033 -206.961235) (xy 450.668659 -206.928004) (xy 450.632407 -206.888933)
			(xy 450.602383 -206.844896) (xy 450.579257 -206.796875) (xy 450.563547 -206.745945) (xy 450.555604 -206.693241)
			(xy 449.793868 -206.693241) (xy 449.793868 -207.178656) (xy 449.82384 -207.192118) (xy 449.848454 -207.203798)
			(xy 449.894113 -207.233517) (xy 449.934714 -207.269842) (xy 449.969309 -207.311928) (xy 449.99709 -207.358791)
			(xy 450.01741 -207.409339) (xy 450.029793 -207.462392) (xy 450.033952 -207.516712) (xy 450.031909 -207.543379)
			(xy 450.555604 -207.543379) (xy 450.555604 -207.490081) (xy 450.563547 -207.437377) (xy 450.579257 -207.386447)
			(xy 450.602383 -207.338426) (xy 450.632407 -207.294389) (xy 450.668659 -207.255318) (xy 450.71033 -207.222087)
			(xy 450.756488 -207.195438) (xy 450.806102 -207.175966) (xy 450.858064 -207.164106) (xy 450.911214 -207.160123)
			(xy 450.964364 -207.164106) (xy 451.016326 -207.175966) (xy 451.06594 -207.195438) (xy 451.112098 -207.222087)
			(xy 451.153769 -207.255318) (xy 451.190021 -207.294389) (xy 451.220045 -207.338426) (xy 451.243171 -207.386447)
			(xy 451.258881 -207.437377) (xy 451.266824 -207.490081) (xy 451.267322 -207.51673) (xy 451.266824 -207.543379)
			(xy 454.655672 -207.543379) (xy 454.655672 -207.490081) (xy 454.663615 -207.437377) (xy 454.679325 -207.386447)
			(xy 454.702451 -207.338426) (xy 454.732475 -207.294389) (xy 454.768727 -207.255318) (xy 454.810398 -207.222087)
			(xy 454.856556 -207.195438) (xy 454.90617 -207.175966) (xy 454.958132 -207.164106) (xy 455.011282 -207.160123)
			(xy 455.064432 -207.164106) (xy 455.116394 -207.175966) (xy 455.166008 -207.195438) (xy 455.212166 -207.222087)
			(xy 455.253837 -207.255318) (xy 455.290089 -207.294389) (xy 455.320113 -207.338426) (xy 455.343239 -207.386447)
			(xy 455.358949 -207.437377) (xy 455.366892 -207.490081) (xy 455.36739 -207.51673) (xy 455.366892 -207.543379)
			(xy 456.865472 -207.543379) (xy 456.865472 -207.490081) (xy 456.873415 -207.437377) (xy 456.889125 -207.386447)
			(xy 456.912251 -207.338426) (xy 456.942275 -207.294389) (xy 456.978527 -207.255318) (xy 457.020198 -207.222087)
			(xy 457.066356 -207.195438) (xy 457.11597 -207.175966) (xy 457.167932 -207.164106) (xy 457.221082 -207.160123)
			(xy 457.274232 -207.164106) (xy 457.326194 -207.175966) (xy 457.375808 -207.195438) (xy 457.421966 -207.222087)
			(xy 457.463637 -207.255318) (xy 457.499889 -207.294389) (xy 457.529913 -207.338426) (xy 457.553039 -207.386447)
			(xy 457.568749 -207.437377) (xy 457.576692 -207.490081) (xy 457.57719 -207.51673) (xy 457.576692 -207.543379)
			(xy 457.568749 -207.596083) (xy 457.553039 -207.647013) (xy 457.529913 -207.695034) (xy 457.499889 -207.739071)
			(xy 457.463637 -207.778142) (xy 457.421966 -207.811373) (xy 457.375808 -207.838022) (xy 457.326194 -207.857494)
			(xy 457.274232 -207.869354) (xy 457.221082 -207.873338) (xy 457.167932 -207.869354) (xy 457.11597 -207.857494)
			(xy 457.066356 -207.838022) (xy 457.020198 -207.811373) (xy 456.978527 -207.778142) (xy 456.942275 -207.739071)
			(xy 456.912251 -207.695034) (xy 456.889125 -207.647013) (xy 456.873415 -207.596083) (xy 456.865472 -207.543379)
			(xy 455.366892 -207.543379) (xy 455.358949 -207.596083) (xy 455.343239 -207.647013) (xy 455.320113 -207.695034)
			(xy 455.290089 -207.739071) (xy 455.253837 -207.778142) (xy 455.212166 -207.811373) (xy 455.166008 -207.838022)
			(xy 455.116394 -207.857494) (xy 455.064432 -207.869354) (xy 455.011282 -207.873338) (xy 454.958132 -207.869354)
			(xy 454.90617 -207.857494) (xy 454.856556 -207.838022) (xy 454.810398 -207.811373) (xy 454.768727 -207.778142)
			(xy 454.732475 -207.739071) (xy 454.702451 -207.695034) (xy 454.679325 -207.647013) (xy 454.663615 -207.596083)
			(xy 454.655672 -207.543379) (xy 451.266824 -207.543379) (xy 451.258881 -207.596083) (xy 451.243171 -207.647013)
			(xy 451.220045 -207.695034) (xy 451.190021 -207.739071) (xy 451.153769 -207.778142) (xy 451.112098 -207.811373)
			(xy 451.06594 -207.838022) (xy 451.016326 -207.857494) (xy 450.964364 -207.869354) (xy 450.911214 -207.873338)
			(xy 450.858064 -207.869354) (xy 450.806102 -207.857494) (xy 450.756488 -207.838022) (xy 450.71033 -207.811373)
			(xy 450.668659 -207.778142) (xy 450.632407 -207.739071) (xy 450.602383 -207.695034) (xy 450.579257 -207.647013)
			(xy 450.563547 -207.596083) (xy 450.555604 -207.543379) (xy 450.031909 -207.543379) (xy 450.02979 -207.571032)
			(xy 450.017402 -207.624084) (xy 449.997079 -207.674631) (xy 449.969295 -207.721493) (xy 449.934697 -207.763576)
			(xy 449.894094 -207.799899) (xy 449.848432 -207.829613) (xy 449.82384 -207.841342) (xy 449.793868 -207.854804)
			(xy 449.793868 -208.393263) (xy 450.555604 -208.393263) (xy 450.555604 -208.339965) (xy 450.563547 -208.287261)
			(xy 450.579257 -208.236331) (xy 450.602383 -208.18831) (xy 450.632407 -208.144273) (xy 450.668659 -208.105202)
			(xy 450.71033 -208.071971) (xy 450.756488 -208.045322) (xy 450.806102 -208.02585) (xy 450.858064 -208.01399)
			(xy 450.911214 -208.010007) (xy 450.964364 -208.01399) (xy 451.016326 -208.02585) (xy 451.06594 -208.045322)
			(xy 451.112098 -208.071971) (xy 451.153769 -208.105202) (xy 451.190021 -208.144273) (xy 451.220045 -208.18831)
			(xy 451.243171 -208.236331) (xy 451.258881 -208.287261) (xy 451.266824 -208.339965) (xy 451.267322 -208.366614)
			(xy 451.266824 -208.393263) (xy 452.765404 -208.393263) (xy 452.765404 -208.339965) (xy 452.773347 -208.287261)
			(xy 452.789057 -208.236331) (xy 452.812183 -208.18831) (xy 452.842207 -208.144273) (xy 452.878459 -208.105202)
			(xy 452.92013 -208.071971) (xy 452.966288 -208.045322) (xy 453.015902 -208.02585) (xy 453.067864 -208.01399)
			(xy 453.121014 -208.010007) (xy 453.174164 -208.01399) (xy 453.226126 -208.02585) (xy 453.27574 -208.045322)
			(xy 453.321898 -208.071971) (xy 453.363569 -208.105202) (xy 453.399821 -208.144273) (xy 453.429845 -208.18831)
			(xy 453.452971 -208.236331) (xy 453.468681 -208.287261) (xy 453.476624 -208.339965) (xy 453.477122 -208.366614)
			(xy 453.476624 -208.393263) (xy 454.655672 -208.393263) (xy 454.655672 -208.339965) (xy 454.663615 -208.287261)
			(xy 454.679325 -208.236331) (xy 454.702451 -208.18831) (xy 454.732475 -208.144273) (xy 454.768727 -208.105202)
			(xy 454.810398 -208.071971) (xy 454.856556 -208.045322) (xy 454.90617 -208.02585) (xy 454.958132 -208.01399)
			(xy 455.011282 -208.010007) (xy 455.064432 -208.01399) (xy 455.116394 -208.02585) (xy 455.166008 -208.045322)
			(xy 455.212166 -208.071971) (xy 455.253837 -208.105202) (xy 455.290089 -208.144273) (xy 455.320113 -208.18831)
			(xy 455.343239 -208.236331) (xy 455.358949 -208.287261) (xy 455.366892 -208.339965) (xy 455.36739 -208.366614)
			(xy 455.366892 -208.393263) (xy 458.099404 -208.393263) (xy 458.099404 -208.339965) (xy 458.107347 -208.287261)
			(xy 458.123057 -208.236331) (xy 458.146183 -208.18831) (xy 458.176207 -208.144273) (xy 458.212459 -208.105202)
			(xy 458.25413 -208.071971) (xy 458.300288 -208.045322) (xy 458.349902 -208.02585) (xy 458.401864 -208.01399)
			(xy 458.455014 -208.010007) (xy 458.508164 -208.01399) (xy 458.560126 -208.02585) (xy 458.60974 -208.045322)
			(xy 458.655898 -208.071971) (xy 458.697569 -208.105202) (xy 458.733821 -208.144273) (xy 458.763845 -208.18831)
			(xy 458.786971 -208.236331) (xy 458.802681 -208.287261) (xy 458.810624 -208.339965) (xy 458.811122 -208.366614)
			(xy 458.810624 -208.393263) (xy 458.802681 -208.445967) (xy 458.786971 -208.496897) (xy 458.763845 -208.544918)
			(xy 458.733821 -208.588955) (xy 458.697569 -208.628026) (xy 458.655898 -208.661257) (xy 458.60974 -208.687906)
			(xy 458.560126 -208.707378) (xy 458.508164 -208.719238) (xy 458.455014 -208.723222) (xy 458.401864 -208.719238)
			(xy 458.349902 -208.707378) (xy 458.300288 -208.687906) (xy 458.25413 -208.661257) (xy 458.212459 -208.628026)
			(xy 458.176207 -208.588955) (xy 458.146183 -208.544918) (xy 458.123057 -208.496897) (xy 458.107347 -208.445967)
			(xy 458.099404 -208.393263) (xy 455.366892 -208.393263) (xy 455.358949 -208.445967) (xy 455.343239 -208.496897)
			(xy 455.320113 -208.544918) (xy 455.290089 -208.588955) (xy 455.253837 -208.628026) (xy 455.212166 -208.661257)
			(xy 455.166008 -208.687906) (xy 455.116394 -208.707378) (xy 455.064432 -208.719238) (xy 455.011282 -208.723222)
			(xy 454.958132 -208.719238) (xy 454.90617 -208.707378) (xy 454.856556 -208.687906) (xy 454.810398 -208.661257)
			(xy 454.768727 -208.628026) (xy 454.732475 -208.588955) (xy 454.702451 -208.544918) (xy 454.679325 -208.496897)
			(xy 454.663615 -208.445967) (xy 454.655672 -208.393263) (xy 453.476624 -208.393263) (xy 453.468681 -208.445967)
			(xy 453.452971 -208.496897) (xy 453.429845 -208.544918) (xy 453.399821 -208.588955) (xy 453.363569 -208.628026)
			(xy 453.321898 -208.661257) (xy 453.27574 -208.687906) (xy 453.226126 -208.707378) (xy 453.174164 -208.719238)
			(xy 453.121014 -208.723222) (xy 453.067864 -208.719238) (xy 453.015902 -208.707378) (xy 452.966288 -208.687906)
			(xy 452.92013 -208.661257) (xy 452.878459 -208.628026) (xy 452.842207 -208.588955) (xy 452.812183 -208.544918)
			(xy 452.789057 -208.496897) (xy 452.773347 -208.445967) (xy 452.765404 -208.393263) (xy 451.266824 -208.393263)
			(xy 451.258881 -208.445967) (xy 451.243171 -208.496897) (xy 451.220045 -208.544918) (xy 451.190021 -208.588955)
			(xy 451.153769 -208.628026) (xy 451.112098 -208.661257) (xy 451.06594 -208.687906) (xy 451.016326 -208.707378)
			(xy 450.964364 -208.719238) (xy 450.911214 -208.723222) (xy 450.858064 -208.719238) (xy 450.806102 -208.707378)
			(xy 450.756488 -208.687906) (xy 450.71033 -208.661257) (xy 450.668659 -208.628026) (xy 450.632407 -208.588955)
			(xy 450.602383 -208.544918) (xy 450.579257 -208.496897) (xy 450.563547 -208.445967) (xy 450.555604 -208.393263)
			(xy 449.793868 -208.393263) (xy 449.793868 -209.243401) (xy 450.555604 -209.243401) (xy 450.555604 -209.190103)
			(xy 450.563547 -209.137399) (xy 450.579257 -209.086469) (xy 450.602383 -209.038448) (xy 450.632407 -208.994411)
			(xy 450.668659 -208.95534) (xy 450.71033 -208.922109) (xy 450.756488 -208.89546) (xy 450.806102 -208.875988)
			(xy 450.858064 -208.864128) (xy 450.911214 -208.860145) (xy 450.964364 -208.864128) (xy 451.016326 -208.875988)
			(xy 451.06594 -208.89546) (xy 451.112098 -208.922109) (xy 451.153769 -208.95534) (xy 451.190021 -208.994411)
			(xy 451.220045 -209.038448) (xy 451.243171 -209.086469) (xy 451.258881 -209.137399) (xy 451.266824 -209.190103)
			(xy 451.267322 -209.216752) (xy 451.266824 -209.243401) (xy 454.655672 -209.243401) (xy 454.655672 -209.190103)
			(xy 454.663615 -209.137399) (xy 454.679325 -209.086469) (xy 454.702451 -209.038448) (xy 454.732475 -208.994411)
			(xy 454.768727 -208.95534) (xy 454.810398 -208.922109) (xy 454.856556 -208.89546) (xy 454.90617 -208.875988)
			(xy 454.958132 -208.864128) (xy 455.011282 -208.860145) (xy 455.064432 -208.864128) (xy 455.116394 -208.875988)
			(xy 455.166008 -208.89546) (xy 455.212166 -208.922109) (xy 455.253837 -208.95534) (xy 455.290089 -208.994411)
			(xy 455.320113 -209.038448) (xy 455.343239 -209.086469) (xy 455.358949 -209.137399) (xy 455.366892 -209.190103)
			(xy 455.36739 -209.216752) (xy 455.366892 -209.243401) (xy 455.358949 -209.296105) (xy 455.343239 -209.347035)
			(xy 455.320113 -209.395056) (xy 455.290089 -209.439093) (xy 455.253837 -209.478164) (xy 455.212166 -209.511395)
			(xy 455.166008 -209.538044) (xy 455.116394 -209.557516) (xy 455.064432 -209.569376) (xy 455.011282 -209.57336)
			(xy 454.958132 -209.569376) (xy 454.90617 -209.557516) (xy 454.856556 -209.538044) (xy 454.810398 -209.511395)
			(xy 454.768727 -209.478164) (xy 454.732475 -209.439093) (xy 454.702451 -209.395056) (xy 454.679325 -209.347035)
			(xy 454.663615 -209.296105) (xy 454.655672 -209.243401) (xy 451.266824 -209.243401) (xy 451.258881 -209.296105)
			(xy 451.243171 -209.347035) (xy 451.220045 -209.395056) (xy 451.190021 -209.439093) (xy 451.153769 -209.478164)
			(xy 451.112098 -209.511395) (xy 451.06594 -209.538044) (xy 451.016326 -209.557516) (xy 450.964364 -209.569376)
			(xy 450.911214 -209.57336) (xy 450.858064 -209.569376) (xy 450.806102 -209.557516) (xy 450.756488 -209.538044)
			(xy 450.71033 -209.511395) (xy 450.668659 -209.478164) (xy 450.632407 -209.439093) (xy 450.602383 -209.395056)
			(xy 450.579257 -209.347035) (xy 450.563547 -209.296105) (xy 450.555604 -209.243401) (xy 449.793868 -209.243401)
			(xy 449.793868 -209.728562) (xy 449.82384 -209.742024) (xy 449.848453 -209.753704) (xy 449.894112 -209.783422)
			(xy 449.934712 -209.819748) (xy 449.969306 -209.861833) (xy 449.997086 -209.908696) (xy 450.017405 -209.959243)
			(xy 450.029788 -210.012295) (xy 450.033947 -210.066615) (xy 450.031903 -210.093285) (xy 450.555604 -210.093285)
			(xy 450.555604 -210.039987) (xy 450.563547 -209.987283) (xy 450.579257 -209.936353) (xy 450.602383 -209.888332)
			(xy 450.632407 -209.844295) (xy 450.668659 -209.805224) (xy 450.71033 -209.771993) (xy 450.756488 -209.745344)
			(xy 450.806102 -209.725872) (xy 450.858064 -209.714012) (xy 450.911214 -209.710029) (xy 450.964364 -209.714012)
			(xy 451.016326 -209.725872) (xy 451.06594 -209.745344) (xy 451.112098 -209.771993) (xy 451.153769 -209.805224)
			(xy 451.190021 -209.844295) (xy 451.220045 -209.888332) (xy 451.243171 -209.936353) (xy 451.258881 -209.987283)
			(xy 451.266824 -210.039987) (xy 451.267322 -210.066636) (xy 451.266824 -210.093285) (xy 454.655672 -210.093285)
			(xy 454.655672 -210.039987) (xy 454.663615 -209.987283) (xy 454.679325 -209.936353) (xy 454.702451 -209.888332)
			(xy 454.732475 -209.844295) (xy 454.768727 -209.805224) (xy 454.810398 -209.771993) (xy 454.856556 -209.745344)
			(xy 454.90617 -209.725872) (xy 454.958132 -209.714012) (xy 455.011282 -209.710029) (xy 455.064432 -209.714012)
			(xy 455.116394 -209.725872) (xy 455.166008 -209.745344) (xy 455.212166 -209.771993) (xy 455.253837 -209.805224)
			(xy 455.290089 -209.844295) (xy 455.320113 -209.888332) (xy 455.343239 -209.936353) (xy 455.358949 -209.987283)
			(xy 455.366892 -210.039987) (xy 455.36739 -210.066636) (xy 455.366892 -210.093285) (xy 456.865472 -210.093285)
			(xy 456.865472 -210.039987) (xy 456.873415 -209.987283) (xy 456.889125 -209.936353) (xy 456.912251 -209.888332)
			(xy 456.942275 -209.844295) (xy 456.978527 -209.805224) (xy 457.020198 -209.771993) (xy 457.066356 -209.745344)
			(xy 457.11597 -209.725872) (xy 457.167932 -209.714012) (xy 457.221082 -209.710029) (xy 457.274232 -209.714012)
			(xy 457.326194 -209.725872) (xy 457.375808 -209.745344) (xy 457.421966 -209.771993) (xy 457.463637 -209.805224)
			(xy 457.499889 -209.844295) (xy 457.529913 -209.888332) (xy 457.553039 -209.936353) (xy 457.568749 -209.987283)
			(xy 457.576692 -210.039987) (xy 457.57719 -210.066636) (xy 457.576692 -210.093285) (xy 457.568749 -210.145989)
			(xy 457.553039 -210.196919) (xy 457.529913 -210.24494) (xy 457.499889 -210.288977) (xy 457.463637 -210.328048)
			(xy 457.421966 -210.361279) (xy 457.375808 -210.387928) (xy 457.326194 -210.4074) (xy 457.274232 -210.41926)
			(xy 457.221082 -210.423244) (xy 457.167932 -210.41926) (xy 457.11597 -210.4074) (xy 457.066356 -210.387928)
			(xy 457.020198 -210.361279) (xy 456.978527 -210.328048) (xy 456.942275 -210.288977) (xy 456.912251 -210.24494)
			(xy 456.889125 -210.196919) (xy 456.873415 -210.145989) (xy 456.865472 -210.093285) (xy 455.366892 -210.093285)
			(xy 455.358949 -210.145989) (xy 455.343239 -210.196919) (xy 455.320113 -210.24494) (xy 455.290089 -210.288977)
			(xy 455.253837 -210.328048) (xy 455.212166 -210.361279) (xy 455.166008 -210.387928) (xy 455.116394 -210.4074)
			(xy 455.064432 -210.41926) (xy 455.011282 -210.423244) (xy 454.958132 -210.41926) (xy 454.90617 -210.4074)
			(xy 454.856556 -210.387928) (xy 454.810398 -210.361279) (xy 454.768727 -210.328048) (xy 454.732475 -210.288977)
			(xy 454.702451 -210.24494) (xy 454.679325 -210.196919) (xy 454.663615 -210.145989) (xy 454.655672 -210.093285)
			(xy 451.266824 -210.093285) (xy 451.258881 -210.145989) (xy 451.243171 -210.196919) (xy 451.220045 -210.24494)
			(xy 451.190021 -210.288977) (xy 451.153769 -210.328048) (xy 451.112098 -210.361279) (xy 451.06594 -210.387928)
			(xy 451.016326 -210.4074) (xy 450.964364 -210.41926) (xy 450.911214 -210.423244) (xy 450.858064 -210.41926)
			(xy 450.806102 -210.4074) (xy 450.756488 -210.387928) (xy 450.71033 -210.361279) (xy 450.668659 -210.328048)
			(xy 450.632407 -210.288977) (xy 450.602383 -210.24494) (xy 450.579257 -210.196919) (xy 450.563547 -210.145989)
			(xy 450.555604 -210.093285) (xy 450.031903 -210.093285) (xy 450.029784 -210.120934) (xy 450.017396 -210.173985)
			(xy 449.997073 -210.224531) (xy 449.969289 -210.271391) (xy 449.934692 -210.313474) (xy 449.894089 -210.349796)
			(xy 449.848427 -210.37951) (xy 449.82384 -210.391248) (xy 449.793868 -210.40471) (xy 449.793868 -210.943423)
			(xy 450.555604 -210.943423) (xy 450.555604 -210.890125) (xy 450.563547 -210.837421) (xy 450.579257 -210.786491)
			(xy 450.602383 -210.73847) (xy 450.632407 -210.694433) (xy 450.668659 -210.655362) (xy 450.71033 -210.622131)
			(xy 450.756488 -210.595482) (xy 450.806102 -210.57601) (xy 450.858064 -210.56415) (xy 450.911214 -210.560167)
			(xy 450.964364 -210.56415) (xy 451.016326 -210.57601) (xy 451.06594 -210.595482) (xy 451.112098 -210.622131)
			(xy 451.153769 -210.655362) (xy 451.190021 -210.694433) (xy 451.220045 -210.73847) (xy 451.243171 -210.786491)
			(xy 451.258881 -210.837421) (xy 451.266824 -210.890125) (xy 451.267322 -210.916774) (xy 451.266824 -210.943423)
			(xy 452.765404 -210.943423) (xy 452.765404 -210.890125) (xy 452.773347 -210.837421) (xy 452.789057 -210.786491)
			(xy 452.812183 -210.73847) (xy 452.842207 -210.694433) (xy 452.878459 -210.655362) (xy 452.92013 -210.622131)
			(xy 452.966288 -210.595482) (xy 453.015902 -210.57601) (xy 453.067864 -210.56415) (xy 453.121014 -210.560167)
			(xy 453.174164 -210.56415) (xy 453.226126 -210.57601) (xy 453.27574 -210.595482) (xy 453.321898 -210.622131)
			(xy 453.363569 -210.655362) (xy 453.399821 -210.694433) (xy 453.429845 -210.73847) (xy 453.452971 -210.786491)
			(xy 453.468681 -210.837421) (xy 453.476624 -210.890125) (xy 453.477122 -210.916774) (xy 453.476624 -210.943423)
			(xy 454.655672 -210.943423) (xy 454.655672 -210.890125) (xy 454.663615 -210.837421) (xy 454.679325 -210.786491)
			(xy 454.702451 -210.73847) (xy 454.732475 -210.694433) (xy 454.768727 -210.655362) (xy 454.810398 -210.622131)
			(xy 454.856556 -210.595482) (xy 454.90617 -210.57601) (xy 454.958132 -210.56415) (xy 455.011282 -210.560167)
			(xy 455.064432 -210.56415) (xy 455.116394 -210.57601) (xy 455.166008 -210.595482) (xy 455.212166 -210.622131)
			(xy 455.253837 -210.655362) (xy 455.290089 -210.694433) (xy 455.320113 -210.73847) (xy 455.343239 -210.786491)
			(xy 455.358949 -210.837421) (xy 455.366892 -210.890125) (xy 455.36739 -210.916774) (xy 455.366892 -210.943423)
			(xy 458.099404 -210.943423) (xy 458.099404 -210.890125) (xy 458.107347 -210.837421) (xy 458.123057 -210.786491)
			(xy 458.146183 -210.73847) (xy 458.176207 -210.694433) (xy 458.212459 -210.655362) (xy 458.25413 -210.622131)
			(xy 458.300288 -210.595482) (xy 458.349902 -210.57601) (xy 458.401864 -210.56415) (xy 458.455014 -210.560167)
			(xy 458.508164 -210.56415) (xy 458.560126 -210.57601) (xy 458.60974 -210.595482) (xy 458.655898 -210.622131)
			(xy 458.697569 -210.655362) (xy 458.733821 -210.694433) (xy 458.763845 -210.73847) (xy 458.786971 -210.786491)
			(xy 458.802681 -210.837421) (xy 458.810624 -210.890125) (xy 458.811122 -210.916774) (xy 458.810624 -210.943423)
			(xy 458.802681 -210.996127) (xy 458.786971 -211.047057) (xy 458.763845 -211.095078) (xy 458.733821 -211.139115)
			(xy 458.697569 -211.178186) (xy 458.655898 -211.211417) (xy 458.60974 -211.238066) (xy 458.560126 -211.257538)
			(xy 458.508164 -211.269398) (xy 458.455014 -211.273382) (xy 458.401864 -211.269398) (xy 458.349902 -211.257538)
			(xy 458.300288 -211.238066) (xy 458.25413 -211.211417) (xy 458.212459 -211.178186) (xy 458.176207 -211.139115)
			(xy 458.146183 -211.095078) (xy 458.123057 -211.047057) (xy 458.107347 -210.996127) (xy 458.099404 -210.943423)
			(xy 455.366892 -210.943423) (xy 455.358949 -210.996127) (xy 455.343239 -211.047057) (xy 455.320113 -211.095078)
			(xy 455.290089 -211.139115) (xy 455.253837 -211.178186) (xy 455.212166 -211.211417) (xy 455.166008 -211.238066)
			(xy 455.116394 -211.257538) (xy 455.064432 -211.269398) (xy 455.011282 -211.273382) (xy 454.958132 -211.269398)
			(xy 454.90617 -211.257538) (xy 454.856556 -211.238066) (xy 454.810398 -211.211417) (xy 454.768727 -211.178186)
			(xy 454.732475 -211.139115) (xy 454.702451 -211.095078) (xy 454.679325 -211.047057) (xy 454.663615 -210.996127)
			(xy 454.655672 -210.943423) (xy 453.476624 -210.943423) (xy 453.468681 -210.996127) (xy 453.452971 -211.047057)
			(xy 453.429845 -211.095078) (xy 453.399821 -211.139115) (xy 453.363569 -211.178186) (xy 453.321898 -211.211417)
			(xy 453.27574 -211.238066) (xy 453.226126 -211.257538) (xy 453.174164 -211.269398) (xy 453.121014 -211.273382)
			(xy 453.067864 -211.269398) (xy 453.015902 -211.257538) (xy 452.966288 -211.238066) (xy 452.92013 -211.211417)
			(xy 452.878459 -211.178186) (xy 452.842207 -211.139115) (xy 452.812183 -211.095078) (xy 452.789057 -211.047057)
			(xy 452.773347 -210.996127) (xy 452.765404 -210.943423) (xy 451.266824 -210.943423) (xy 451.258881 -210.996127)
			(xy 451.243171 -211.047057) (xy 451.220045 -211.095078) (xy 451.190021 -211.139115) (xy 451.153769 -211.178186)
			(xy 451.112098 -211.211417) (xy 451.06594 -211.238066) (xy 451.016326 -211.257538) (xy 450.964364 -211.269398)
			(xy 450.911214 -211.273382) (xy 450.858064 -211.269398) (xy 450.806102 -211.257538) (xy 450.756488 -211.238066)
			(xy 450.71033 -211.211417) (xy 450.668659 -211.178186) (xy 450.632407 -211.139115) (xy 450.602383 -211.095078)
			(xy 450.579257 -211.047057) (xy 450.563547 -210.996127) (xy 450.555604 -210.943423) (xy 449.793868 -210.943423)
			(xy 449.793868 -211.428584) (xy 449.82384 -211.442046) (xy 449.848459 -211.453727) (xy 449.89413 -211.483446)
			(xy 449.934741 -211.519775) (xy 449.969346 -211.561866) (xy 449.997136 -211.608735) (xy 450.017463 -211.659291)
			(xy 450.029854 -211.712353) (xy 450.034018 -211.766683) (xy 450.03198 -211.793307) (xy 450.555604 -211.793307)
			(xy 450.555604 -211.740009) (xy 450.563547 -211.687305) (xy 450.579257 -211.636375) (xy 450.602383 -211.588354)
			(xy 450.632407 -211.544317) (xy 450.668659 -211.505246) (xy 450.71033 -211.472015) (xy 450.756488 -211.445366)
			(xy 450.806102 -211.425894) (xy 450.858064 -211.414034) (xy 450.911214 -211.410051) (xy 450.964364 -211.414034)
			(xy 451.016326 -211.425894) (xy 451.06594 -211.445366) (xy 451.112098 -211.472015) (xy 451.153769 -211.505246)
			(xy 451.190021 -211.544317) (xy 451.220045 -211.588354) (xy 451.243171 -211.636375) (xy 451.258881 -211.687305)
			(xy 451.266824 -211.740009) (xy 451.267322 -211.766658) (xy 451.266824 -211.793307) (xy 454.655672 -211.793307)
			(xy 454.655672 -211.740009) (xy 454.663615 -211.687305) (xy 454.679325 -211.636375) (xy 454.702451 -211.588354)
			(xy 454.732475 -211.544317) (xy 454.768727 -211.505246) (xy 454.810398 -211.472015) (xy 454.856556 -211.445366)
			(xy 454.90617 -211.425894) (xy 454.958132 -211.414034) (xy 455.011282 -211.410051) (xy 455.064432 -211.414034)
			(xy 455.116394 -211.425894) (xy 455.166008 -211.445366) (xy 455.212166 -211.472015) (xy 455.253837 -211.505246)
			(xy 455.290089 -211.544317) (xy 455.320113 -211.588354) (xy 455.343239 -211.636375) (xy 455.358949 -211.687305)
			(xy 455.366892 -211.740009) (xy 455.36739 -211.766658) (xy 455.366892 -211.793307) (xy 456.865472 -211.793307)
			(xy 456.865472 -211.740009) (xy 456.873415 -211.687305) (xy 456.889125 -211.636375) (xy 456.912251 -211.588354)
			(xy 456.942275 -211.544317) (xy 456.978527 -211.505246) (xy 457.020198 -211.472015) (xy 457.066356 -211.445366)
			(xy 457.11597 -211.425894) (xy 457.167932 -211.414034) (xy 457.221082 -211.410051) (xy 457.274232 -211.414034)
			(xy 457.326194 -211.425894) (xy 457.375808 -211.445366) (xy 457.421966 -211.472015) (xy 457.463637 -211.505246)
			(xy 457.499889 -211.544317) (xy 457.529913 -211.588354) (xy 457.553039 -211.636375) (xy 457.568749 -211.687305)
			(xy 457.576692 -211.740009) (xy 457.57719 -211.766658) (xy 457.576692 -211.793307) (xy 457.568749 -211.846011)
			(xy 457.553039 -211.896941) (xy 457.529913 -211.944962) (xy 457.499889 -211.988999) (xy 457.463637 -212.02807)
			(xy 457.421966 -212.061301) (xy 457.375808 -212.08795) (xy 457.326194 -212.107422) (xy 457.274232 -212.119282)
			(xy 457.221082 -212.123266) (xy 457.167932 -212.119282) (xy 457.11597 -212.107422) (xy 457.066356 -212.08795)
			(xy 457.020198 -212.061301) (xy 456.978527 -212.02807) (xy 456.942275 -211.988999) (xy 456.912251 -211.944962)
			(xy 456.889125 -211.896941) (xy 456.873415 -211.846011) (xy 456.865472 -211.793307) (xy 455.366892 -211.793307)
			(xy 455.358949 -211.846011) (xy 455.343239 -211.896941) (xy 455.320113 -211.944962) (xy 455.290089 -211.988999)
			(xy 455.253837 -212.02807) (xy 455.212166 -212.061301) (xy 455.166008 -212.08795) (xy 455.116394 -212.107422)
			(xy 455.064432 -212.119282) (xy 455.011282 -212.123266) (xy 454.958132 -212.119282) (xy 454.90617 -212.107422)
			(xy 454.856556 -212.08795) (xy 454.810398 -212.061301) (xy 454.768727 -212.02807) (xy 454.732475 -211.988999)
			(xy 454.702451 -211.944962) (xy 454.679325 -211.896941) (xy 454.663615 -211.846011) (xy 454.655672 -211.793307)
			(xy 451.266824 -211.793307) (xy 451.258881 -211.846011) (xy 451.243171 -211.896941) (xy 451.220045 -211.944962)
			(xy 451.190021 -211.988999) (xy 451.153769 -212.02807) (xy 451.112098 -212.061301) (xy 451.06594 -212.08795)
			(xy 451.016326 -212.107422) (xy 450.964364 -212.119282) (xy 450.911214 -212.123266) (xy 450.858064 -212.119282)
			(xy 450.806102 -212.107422) (xy 450.756488 -212.08795) (xy 450.71033 -212.061301) (xy 450.668659 -212.02807)
			(xy 450.632407 -211.988999) (xy 450.602383 -211.944962) (xy 450.579257 -211.896941) (xy 450.563547 -211.846011)
			(xy 450.555604 -211.793307) (xy 450.03198 -211.793307) (xy 450.029859 -211.821013) (xy 450.017474 -211.874076)
			(xy 449.997151 -211.924633) (xy 449.969366 -211.971506) (xy 449.934765 -212.0136) (xy 449.894157 -212.049933)
			(xy 449.848489 -212.079657) (xy 449.82384 -212.09127) (xy 449.793868 -212.104732) (xy 449.793868 -212.643445)
			(xy 450.555604 -212.643445) (xy 450.555604 -212.590147) (xy 450.563547 -212.537443) (xy 450.579257 -212.486513)
			(xy 450.602383 -212.438492) (xy 450.632407 -212.394455) (xy 450.668659 -212.355384) (xy 450.71033 -212.322153)
			(xy 450.756488 -212.295504) (xy 450.806102 -212.276032) (xy 450.858064 -212.264172) (xy 450.911214 -212.260189)
			(xy 450.964364 -212.264172) (xy 451.016326 -212.276032) (xy 451.06594 -212.295504) (xy 451.112098 -212.322153)
			(xy 451.153769 -212.355384) (xy 451.190021 -212.394455) (xy 451.220045 -212.438492) (xy 451.243171 -212.486513)
			(xy 451.258881 -212.537443) (xy 451.266824 -212.590147) (xy 451.267322 -212.616796) (xy 451.266824 -212.643445)
			(xy 452.765404 -212.643445) (xy 452.765404 -212.590147) (xy 452.773347 -212.537443) (xy 452.789057 -212.486513)
			(xy 452.812183 -212.438492) (xy 452.842207 -212.394455) (xy 452.878459 -212.355384) (xy 452.92013 -212.322153)
			(xy 452.966288 -212.295504) (xy 453.015902 -212.276032) (xy 453.067864 -212.264172) (xy 453.121014 -212.260189)
			(xy 453.174164 -212.264172) (xy 453.226126 -212.276032) (xy 453.27574 -212.295504) (xy 453.321898 -212.322153)
			(xy 453.363569 -212.355384) (xy 453.399821 -212.394455) (xy 453.429845 -212.438492) (xy 453.452971 -212.486513)
			(xy 453.468681 -212.537443) (xy 453.476624 -212.590147) (xy 453.477122 -212.616796) (xy 453.476624 -212.643445)
			(xy 454.655672 -212.643445) (xy 454.655672 -212.590147) (xy 454.663615 -212.537443) (xy 454.679325 -212.486513)
			(xy 454.702451 -212.438492) (xy 454.732475 -212.394455) (xy 454.768727 -212.355384) (xy 454.810398 -212.322153)
			(xy 454.856556 -212.295504) (xy 454.90617 -212.276032) (xy 454.958132 -212.264172) (xy 455.011282 -212.260189)
			(xy 455.064432 -212.264172) (xy 455.116394 -212.276032) (xy 455.166008 -212.295504) (xy 455.212166 -212.322153)
			(xy 455.253837 -212.355384) (xy 455.290089 -212.394455) (xy 455.320113 -212.438492) (xy 455.343239 -212.486513)
			(xy 455.358949 -212.537443) (xy 455.366892 -212.590147) (xy 455.36739 -212.616796) (xy 455.366892 -212.643445)
			(xy 458.099404 -212.643445) (xy 458.099404 -212.590147) (xy 458.107347 -212.537443) (xy 458.123057 -212.486513)
			(xy 458.146183 -212.438492) (xy 458.176207 -212.394455) (xy 458.212459 -212.355384) (xy 458.25413 -212.322153)
			(xy 458.300288 -212.295504) (xy 458.349902 -212.276032) (xy 458.401864 -212.264172) (xy 458.455014 -212.260189)
			(xy 458.508164 -212.264172) (xy 458.560126 -212.276032) (xy 458.60974 -212.295504) (xy 458.655898 -212.322153)
			(xy 458.697569 -212.355384) (xy 458.733821 -212.394455) (xy 458.763845 -212.438492) (xy 458.786971 -212.486513)
			(xy 458.802681 -212.537443) (xy 458.810624 -212.590147) (xy 458.811122 -212.616796) (xy 458.810624 -212.643445)
			(xy 458.802681 -212.696149) (xy 458.786971 -212.747079) (xy 458.763845 -212.7951) (xy 458.733821 -212.839137)
			(xy 458.697569 -212.878208) (xy 458.655898 -212.911439) (xy 458.60974 -212.938088) (xy 458.560126 -212.95756)
			(xy 458.508164 -212.96942) (xy 458.455014 -212.973404) (xy 458.401864 -212.96942) (xy 458.349902 -212.95756)
			(xy 458.300288 -212.938088) (xy 458.25413 -212.911439) (xy 458.212459 -212.878208) (xy 458.176207 -212.839137)
			(xy 458.146183 -212.7951) (xy 458.123057 -212.747079) (xy 458.107347 -212.696149) (xy 458.099404 -212.643445)
			(xy 455.366892 -212.643445) (xy 455.358949 -212.696149) (xy 455.343239 -212.747079) (xy 455.320113 -212.7951)
			(xy 455.290089 -212.839137) (xy 455.253837 -212.878208) (xy 455.212166 -212.911439) (xy 455.166008 -212.938088)
			(xy 455.116394 -212.95756) (xy 455.064432 -212.96942) (xy 455.011282 -212.973404) (xy 454.958132 -212.96942)
			(xy 454.90617 -212.95756) (xy 454.856556 -212.938088) (xy 454.810398 -212.911439) (xy 454.768727 -212.878208)
			(xy 454.732475 -212.839137) (xy 454.702451 -212.7951) (xy 454.679325 -212.747079) (xy 454.663615 -212.696149)
			(xy 454.655672 -212.643445) (xy 453.476624 -212.643445) (xy 453.468681 -212.696149) (xy 453.452971 -212.747079)
			(xy 453.429845 -212.7951) (xy 453.399821 -212.839137) (xy 453.363569 -212.878208) (xy 453.321898 -212.911439)
			(xy 453.27574 -212.938088) (xy 453.226126 -212.95756) (xy 453.174164 -212.96942) (xy 453.121014 -212.973404)
			(xy 453.067864 -212.96942) (xy 453.015902 -212.95756) (xy 452.966288 -212.938088) (xy 452.92013 -212.911439)
			(xy 452.878459 -212.878208) (xy 452.842207 -212.839137) (xy 452.812183 -212.7951) (xy 452.789057 -212.747079)
			(xy 452.773347 -212.696149) (xy 452.765404 -212.643445) (xy 451.266824 -212.643445) (xy 451.258881 -212.696149)
			(xy 451.243171 -212.747079) (xy 451.220045 -212.7951) (xy 451.190021 -212.839137) (xy 451.153769 -212.878208)
			(xy 451.112098 -212.911439) (xy 451.06594 -212.938088) (xy 451.016326 -212.95756) (xy 450.964364 -212.96942)
			(xy 450.911214 -212.973404) (xy 450.858064 -212.96942) (xy 450.806102 -212.95756) (xy 450.756488 -212.938088)
			(xy 450.71033 -212.911439) (xy 450.668659 -212.878208) (xy 450.632407 -212.839137) (xy 450.602383 -212.7951)
			(xy 450.579257 -212.747079) (xy 450.563547 -212.696149) (xy 450.555604 -212.643445) (xy 449.793868 -212.643445)
			(xy 449.793868 -213.128606) (xy 449.82384 -213.142068) (xy 449.848457 -213.153749) (xy 449.894125 -213.183468)
			(xy 449.934733 -213.219796) (xy 449.969334 -213.261885) (xy 449.997122 -213.308752) (xy 450.017447 -213.359306)
			(xy 450.029835 -213.412365) (xy 450.033998 -213.466692) (xy 450.031958 -213.493329) (xy 450.555604 -213.493329)
			(xy 450.555604 -213.440031) (xy 450.563547 -213.387327) (xy 450.579257 -213.336397) (xy 450.602383 -213.288376)
			(xy 450.632407 -213.244339) (xy 450.668659 -213.205268) (xy 450.71033 -213.172037) (xy 450.756488 -213.145388)
			(xy 450.806102 -213.125916) (xy 450.858064 -213.114056) (xy 450.911214 -213.110073) (xy 450.964364 -213.114056)
			(xy 451.016326 -213.125916) (xy 451.06594 -213.145388) (xy 451.112098 -213.172037) (xy 451.153769 -213.205268)
			(xy 451.190021 -213.244339) (xy 451.220045 -213.288376) (xy 451.243171 -213.336397) (xy 451.258881 -213.387327)
			(xy 451.266824 -213.440031) (xy 451.267322 -213.46668) (xy 451.266824 -213.493329) (xy 454.655672 -213.493329)
			(xy 454.655672 -213.440031) (xy 454.663615 -213.387327) (xy 454.679325 -213.336397) (xy 454.702451 -213.288376)
			(xy 454.732475 -213.244339) (xy 454.768727 -213.205268) (xy 454.810398 -213.172037) (xy 454.856556 -213.145388)
			(xy 454.90617 -213.125916) (xy 454.958132 -213.114056) (xy 455.011282 -213.110073) (xy 455.064432 -213.114056)
			(xy 455.116394 -213.125916) (xy 455.166008 -213.145388) (xy 455.212166 -213.172037) (xy 455.253837 -213.205268)
			(xy 455.290089 -213.244339) (xy 455.320113 -213.288376) (xy 455.343239 -213.336397) (xy 455.358949 -213.387327)
			(xy 455.366892 -213.440031) (xy 455.36739 -213.46668) (xy 455.366892 -213.493329) (xy 456.865472 -213.493329)
			(xy 456.865472 -213.440031) (xy 456.873415 -213.387327) (xy 456.889125 -213.336397) (xy 456.912251 -213.288376)
			(xy 456.942275 -213.244339) (xy 456.978527 -213.205268) (xy 457.020198 -213.172037) (xy 457.066356 -213.145388)
			(xy 457.11597 -213.125916) (xy 457.167932 -213.114056) (xy 457.221082 -213.110073) (xy 457.274232 -213.114056)
			(xy 457.326194 -213.125916) (xy 457.375808 -213.145388) (xy 457.421966 -213.172037) (xy 457.463637 -213.205268)
			(xy 457.499889 -213.244339) (xy 457.529913 -213.288376) (xy 457.553039 -213.336397) (xy 457.568749 -213.387327)
			(xy 457.576692 -213.440031) (xy 457.57719 -213.46668) (xy 457.576692 -213.493329) (xy 457.568749 -213.546033)
			(xy 457.553039 -213.596963) (xy 457.529913 -213.644984) (xy 457.499889 -213.689021) (xy 457.463637 -213.728092)
			(xy 457.421966 -213.761323) (xy 457.375808 -213.787972) (xy 457.326194 -213.807444) (xy 457.274232 -213.819304)
			(xy 457.221082 -213.823288) (xy 457.167932 -213.819304) (xy 457.11597 -213.807444) (xy 457.066356 -213.787972)
			(xy 457.020198 -213.761323) (xy 456.978527 -213.728092) (xy 456.942275 -213.689021) (xy 456.912251 -213.644984)
			(xy 456.889125 -213.596963) (xy 456.873415 -213.546033) (xy 456.865472 -213.493329) (xy 455.366892 -213.493329)
			(xy 455.358949 -213.546033) (xy 455.343239 -213.596963) (xy 455.320113 -213.644984) (xy 455.290089 -213.689021)
			(xy 455.253837 -213.728092) (xy 455.212166 -213.761323) (xy 455.166008 -213.787972) (xy 455.116394 -213.807444)
			(xy 455.064432 -213.819304) (xy 455.011282 -213.823288) (xy 454.958132 -213.819304) (xy 454.90617 -213.807444)
			(xy 454.856556 -213.787972) (xy 454.810398 -213.761323) (xy 454.768727 -213.728092) (xy 454.732475 -213.689021)
			(xy 454.702451 -213.644984) (xy 454.679325 -213.596963) (xy 454.663615 -213.546033) (xy 454.655672 -213.493329)
			(xy 451.266824 -213.493329) (xy 451.258881 -213.546033) (xy 451.243171 -213.596963) (xy 451.220045 -213.644984)
			(xy 451.190021 -213.689021) (xy 451.153769 -213.728092) (xy 451.112098 -213.761323) (xy 451.06594 -213.787972)
			(xy 451.016326 -213.807444) (xy 450.964364 -213.819304) (xy 450.911214 -213.823288) (xy 450.858064 -213.819304)
			(xy 450.806102 -213.807444) (xy 450.756488 -213.787972) (xy 450.71033 -213.761323) (xy 450.668659 -213.728092)
			(xy 450.632407 -213.689021) (xy 450.602383 -213.644984) (xy 450.579257 -213.596963) (xy 450.563547 -213.546033)
			(xy 450.555604 -213.493329) (xy 450.031958 -213.493329) (xy 450.029838 -213.521019) (xy 450.017452 -213.574079)
			(xy 449.997129 -213.624633) (xy 449.969344 -213.671502) (xy 449.934744 -213.713592) (xy 449.894138 -213.749922)
			(xy 449.848472 -213.779644) (xy 449.82384 -213.791292) (xy 449.793868 -213.804754) (xy 449.793868 -214.343213)
			(xy 450.555604 -214.343213) (xy 450.555604 -214.289915) (xy 450.563547 -214.237211) (xy 450.579257 -214.186281)
			(xy 450.602383 -214.13826) (xy 450.632407 -214.094223) (xy 450.668659 -214.055152) (xy 450.71033 -214.021921)
			(xy 450.756488 -213.995272) (xy 450.806102 -213.9758) (xy 450.858064 -213.96394) (xy 450.911214 -213.959957)
			(xy 450.964364 -213.96394) (xy 451.016326 -213.9758) (xy 451.06594 -213.995272) (xy 451.112098 -214.021921)
			(xy 451.153769 -214.055152) (xy 451.190021 -214.094223) (xy 451.220045 -214.13826) (xy 451.243171 -214.186281)
			(xy 451.258881 -214.237211) (xy 451.266824 -214.289915) (xy 451.267322 -214.316564) (xy 451.266824 -214.343213)
			(xy 452.765404 -214.343213) (xy 452.765404 -214.289915) (xy 452.773347 -214.237211) (xy 452.789057 -214.186281)
			(xy 452.812183 -214.13826) (xy 452.842207 -214.094223) (xy 452.878459 -214.055152) (xy 452.92013 -214.021921)
			(xy 452.966288 -213.995272) (xy 453.015902 -213.9758) (xy 453.067864 -213.96394) (xy 453.121014 -213.959957)
			(xy 453.174164 -213.96394) (xy 453.226126 -213.9758) (xy 453.27574 -213.995272) (xy 453.321898 -214.021921)
			(xy 453.363569 -214.055152) (xy 453.399821 -214.094223) (xy 453.429845 -214.13826) (xy 453.452971 -214.186281)
			(xy 453.468681 -214.237211) (xy 453.476624 -214.289915) (xy 453.477122 -214.316564) (xy 453.476624 -214.343213)
			(xy 454.655672 -214.343213) (xy 454.655672 -214.289915) (xy 454.663615 -214.237211) (xy 454.679325 -214.186281)
			(xy 454.702451 -214.13826) (xy 454.732475 -214.094223) (xy 454.768727 -214.055152) (xy 454.810398 -214.021921)
			(xy 454.856556 -213.995272) (xy 454.90617 -213.9758) (xy 454.958132 -213.96394) (xy 455.011282 -213.959957)
			(xy 455.064432 -213.96394) (xy 455.116394 -213.9758) (xy 455.166008 -213.995272) (xy 455.212166 -214.021921)
			(xy 455.253837 -214.055152) (xy 455.290089 -214.094223) (xy 455.320113 -214.13826) (xy 455.343239 -214.186281)
			(xy 455.358949 -214.237211) (xy 455.366892 -214.289915) (xy 455.36739 -214.316564) (xy 455.366892 -214.343213)
			(xy 458.099404 -214.343213) (xy 458.099404 -214.289915) (xy 458.107347 -214.237211) (xy 458.123057 -214.186281)
			(xy 458.146183 -214.13826) (xy 458.176207 -214.094223) (xy 458.212459 -214.055152) (xy 458.25413 -214.021921)
			(xy 458.300288 -213.995272) (xy 458.349902 -213.9758) (xy 458.401864 -213.96394) (xy 458.455014 -213.959957)
			(xy 458.508164 -213.96394) (xy 458.560126 -213.9758) (xy 458.60974 -213.995272) (xy 458.655898 -214.021921)
			(xy 458.697569 -214.055152) (xy 458.733821 -214.094223) (xy 458.763845 -214.13826) (xy 458.786971 -214.186281)
			(xy 458.802681 -214.237211) (xy 458.810624 -214.289915) (xy 458.811122 -214.316564) (xy 458.810624 -214.343213)
			(xy 458.802681 -214.395917) (xy 458.786971 -214.446847) (xy 458.763845 -214.494868) (xy 458.733821 -214.538905)
			(xy 458.697569 -214.577976) (xy 458.655898 -214.611207) (xy 458.60974 -214.637856) (xy 458.560126 -214.657328)
			(xy 458.508164 -214.669188) (xy 458.455014 -214.673172) (xy 458.401864 -214.669188) (xy 458.349902 -214.657328)
			(xy 458.300288 -214.637856) (xy 458.25413 -214.611207) (xy 458.212459 -214.577976) (xy 458.176207 -214.538905)
			(xy 458.146183 -214.494868) (xy 458.123057 -214.446847) (xy 458.107347 -214.395917) (xy 458.099404 -214.343213)
			(xy 455.366892 -214.343213) (xy 455.358949 -214.395917) (xy 455.343239 -214.446847) (xy 455.320113 -214.494868)
			(xy 455.290089 -214.538905) (xy 455.253837 -214.577976) (xy 455.212166 -214.611207) (xy 455.166008 -214.637856)
			(xy 455.116394 -214.657328) (xy 455.064432 -214.669188) (xy 455.011282 -214.673172) (xy 454.958132 -214.669188)
			(xy 454.90617 -214.657328) (xy 454.856556 -214.637856) (xy 454.810398 -214.611207) (xy 454.768727 -214.577976)
			(xy 454.732475 -214.538905) (xy 454.702451 -214.494868) (xy 454.679325 -214.446847) (xy 454.663615 -214.395917)
			(xy 454.655672 -214.343213) (xy 453.476624 -214.343213) (xy 453.468681 -214.395917) (xy 453.452971 -214.446847)
			(xy 453.429845 -214.494868) (xy 453.399821 -214.538905) (xy 453.363569 -214.577976) (xy 453.321898 -214.611207)
			(xy 453.27574 -214.637856) (xy 453.226126 -214.657328) (xy 453.174164 -214.669188) (xy 453.121014 -214.673172)
			(xy 453.067864 -214.669188) (xy 453.015902 -214.657328) (xy 452.966288 -214.637856) (xy 452.92013 -214.611207)
			(xy 452.878459 -214.577976) (xy 452.842207 -214.538905) (xy 452.812183 -214.494868) (xy 452.789057 -214.446847)
			(xy 452.773347 -214.395917) (xy 452.765404 -214.343213) (xy 451.266824 -214.343213) (xy 451.258881 -214.395917)
			(xy 451.243171 -214.446847) (xy 451.220045 -214.494868) (xy 451.190021 -214.538905) (xy 451.153769 -214.577976)
			(xy 451.112098 -214.611207) (xy 451.06594 -214.637856) (xy 451.016326 -214.657328) (xy 450.964364 -214.669188)
			(xy 450.911214 -214.673172) (xy 450.858064 -214.669188) (xy 450.806102 -214.657328) (xy 450.756488 -214.637856)
			(xy 450.71033 -214.611207) (xy 450.668659 -214.577976) (xy 450.632407 -214.538905) (xy 450.602383 -214.494868)
			(xy 450.579257 -214.446847) (xy 450.563547 -214.395917) (xy 450.555604 -214.343213) (xy 449.793868 -214.343213)
			(xy 449.793868 -214.828628) (xy 449.82384 -214.84209) (xy 449.848456 -214.853771) (xy 449.89412 -214.883489)
			(xy 449.934725 -214.919816) (xy 449.969323 -214.961904) (xy 449.997108 -215.00877) (xy 450.017431 -215.05932)
			(xy 450.029817 -215.112377) (xy 450.033978 -215.166701) (xy 450.031937 -215.193351) (xy 450.555604 -215.193351)
			(xy 450.555604 -215.140053) (xy 450.563547 -215.087349) (xy 450.579257 -215.036419) (xy 450.602383 -214.988398)
			(xy 450.632407 -214.944361) (xy 450.668659 -214.90529) (xy 450.71033 -214.872059) (xy 450.756488 -214.84541)
			(xy 450.806102 -214.825938) (xy 450.858064 -214.814078) (xy 450.911214 -214.810095) (xy 450.964364 -214.814078)
			(xy 451.016326 -214.825938) (xy 451.06594 -214.84541) (xy 451.112098 -214.872059) (xy 451.153769 -214.90529)
			(xy 451.190021 -214.944361) (xy 451.220045 -214.988398) (xy 451.243171 -215.036419) (xy 451.258881 -215.087349)
			(xy 451.266824 -215.140053) (xy 451.267322 -215.166702) (xy 451.266824 -215.193351) (xy 454.655672 -215.193351)
			(xy 454.655672 -215.140053) (xy 454.663615 -215.087349) (xy 454.679325 -215.036419) (xy 454.702451 -214.988398)
			(xy 454.732475 -214.944361) (xy 454.768727 -214.90529) (xy 454.810398 -214.872059) (xy 454.856556 -214.84541)
			(xy 454.90617 -214.825938) (xy 454.958132 -214.814078) (xy 455.011282 -214.810095) (xy 455.064432 -214.814078)
			(xy 455.116394 -214.825938) (xy 455.166008 -214.84541) (xy 455.212166 -214.872059) (xy 455.253837 -214.90529)
			(xy 455.290089 -214.944361) (xy 455.320113 -214.988398) (xy 455.343239 -215.036419) (xy 455.358949 -215.087349)
			(xy 455.366892 -215.140053) (xy 455.36739 -215.166702) (xy 455.366892 -215.193351) (xy 456.865472 -215.193351)
			(xy 456.865472 -215.140053) (xy 456.873415 -215.087349) (xy 456.889125 -215.036419) (xy 456.912251 -214.988398)
			(xy 456.942275 -214.944361) (xy 456.978527 -214.90529) (xy 457.020198 -214.872059) (xy 457.066356 -214.84541)
			(xy 457.11597 -214.825938) (xy 457.167932 -214.814078) (xy 457.221082 -214.810095) (xy 457.274232 -214.814078)
			(xy 457.326194 -214.825938) (xy 457.375808 -214.84541) (xy 457.421966 -214.872059) (xy 457.463637 -214.90529)
			(xy 457.499889 -214.944361) (xy 457.529913 -214.988398) (xy 457.553039 -215.036419) (xy 457.568749 -215.087349)
			(xy 457.576692 -215.140053) (xy 457.57719 -215.166702) (xy 457.576692 -215.193351) (xy 457.568749 -215.246055)
			(xy 457.553039 -215.296985) (xy 457.529913 -215.345006) (xy 457.499889 -215.389043) (xy 457.463637 -215.428114)
			(xy 457.421966 -215.461345) (xy 457.375808 -215.487994) (xy 457.326194 -215.507466) (xy 457.274232 -215.519326)
			(xy 457.221082 -215.52331) (xy 457.167932 -215.519326) (xy 457.11597 -215.507466) (xy 457.066356 -215.487994)
			(xy 457.020198 -215.461345) (xy 456.978527 -215.428114) (xy 456.942275 -215.389043) (xy 456.912251 -215.345006)
			(xy 456.889125 -215.296985) (xy 456.873415 -215.246055) (xy 456.865472 -215.193351) (xy 455.366892 -215.193351)
			(xy 455.358949 -215.246055) (xy 455.343239 -215.296985) (xy 455.320113 -215.345006) (xy 455.290089 -215.389043)
			(xy 455.253837 -215.428114) (xy 455.212166 -215.461345) (xy 455.166008 -215.487994) (xy 455.116394 -215.507466)
			(xy 455.064432 -215.519326) (xy 455.011282 -215.52331) (xy 454.958132 -215.519326) (xy 454.90617 -215.507466)
			(xy 454.856556 -215.487994) (xy 454.810398 -215.461345) (xy 454.768727 -215.428114) (xy 454.732475 -215.389043)
			(xy 454.702451 -215.345006) (xy 454.679325 -215.296985) (xy 454.663615 -215.246055) (xy 454.655672 -215.193351)
			(xy 451.266824 -215.193351) (xy 451.258881 -215.246055) (xy 451.243171 -215.296985) (xy 451.220045 -215.345006)
			(xy 451.190021 -215.389043) (xy 451.153769 -215.428114) (xy 451.112098 -215.461345) (xy 451.06594 -215.487994)
			(xy 451.016326 -215.507466) (xy 450.964364 -215.519326) (xy 450.911214 -215.52331) (xy 450.858064 -215.519326)
			(xy 450.806102 -215.507466) (xy 450.756488 -215.487994) (xy 450.71033 -215.461345) (xy 450.668659 -215.428114)
			(xy 450.632407 -215.389043) (xy 450.602383 -215.345006) (xy 450.579257 -215.296985) (xy 450.563547 -215.246055)
			(xy 450.555604 -215.193351) (xy 450.031937 -215.193351) (xy 450.029817 -215.221025) (xy 450.01743 -215.274081)
			(xy 449.997107 -215.324632) (xy 449.969322 -215.371498) (xy 449.934724 -215.413585) (xy 449.894118 -215.449912)
			(xy 449.848454 -215.47963) (xy 449.82384 -215.491314) (xy 449.793868 -215.504776) (xy 449.793868 -216.043235)
			(xy 450.555604 -216.043235) (xy 450.555604 -215.989937) (xy 450.563547 -215.937233) (xy 450.579257 -215.886303)
			(xy 450.602383 -215.838282) (xy 450.632407 -215.794245) (xy 450.668659 -215.755174) (xy 450.71033 -215.721943)
			(xy 450.756488 -215.695294) (xy 450.806102 -215.675822) (xy 450.858064 -215.663962) (xy 450.911214 -215.659979)
			(xy 450.964364 -215.663962) (xy 451.016326 -215.675822) (xy 451.06594 -215.695294) (xy 451.112098 -215.721943)
			(xy 451.153769 -215.755174) (xy 451.190021 -215.794245) (xy 451.220045 -215.838282) (xy 451.243171 -215.886303)
			(xy 451.258881 -215.937233) (xy 451.266824 -215.989937) (xy 451.267322 -216.016586) (xy 451.266824 -216.043235)
			(xy 452.765404 -216.043235) (xy 452.765404 -215.989937) (xy 452.773347 -215.937233) (xy 452.789057 -215.886303)
			(xy 452.812183 -215.838282) (xy 452.842207 -215.794245) (xy 452.878459 -215.755174) (xy 452.92013 -215.721943)
			(xy 452.966288 -215.695294) (xy 453.015902 -215.675822) (xy 453.067864 -215.663962) (xy 453.121014 -215.659979)
			(xy 453.174164 -215.663962) (xy 453.226126 -215.675822) (xy 453.27574 -215.695294) (xy 453.321898 -215.721943)
			(xy 453.363569 -215.755174) (xy 453.399821 -215.794245) (xy 453.429845 -215.838282) (xy 453.452971 -215.886303)
			(xy 453.468681 -215.937233) (xy 453.476624 -215.989937) (xy 453.477122 -216.016586) (xy 453.476624 -216.043235)
			(xy 454.655672 -216.043235) (xy 454.655672 -215.989937) (xy 454.663615 -215.937233) (xy 454.679325 -215.886303)
			(xy 454.702451 -215.838282) (xy 454.732475 -215.794245) (xy 454.768727 -215.755174) (xy 454.810398 -215.721943)
			(xy 454.856556 -215.695294) (xy 454.90617 -215.675822) (xy 454.958132 -215.663962) (xy 455.011282 -215.659979)
			(xy 455.064432 -215.663962) (xy 455.116394 -215.675822) (xy 455.166008 -215.695294) (xy 455.212166 -215.721943)
			(xy 455.253837 -215.755174) (xy 455.290089 -215.794245) (xy 455.320113 -215.838282) (xy 455.343239 -215.886303)
			(xy 455.358949 -215.937233) (xy 455.366892 -215.989937) (xy 455.36739 -216.016586) (xy 455.366892 -216.043235)
			(xy 458.099404 -216.043235) (xy 458.099404 -215.989937) (xy 458.107347 -215.937233) (xy 458.123057 -215.886303)
			(xy 458.146183 -215.838282) (xy 458.176207 -215.794245) (xy 458.212459 -215.755174) (xy 458.25413 -215.721943)
			(xy 458.300288 -215.695294) (xy 458.349902 -215.675822) (xy 458.401864 -215.663962) (xy 458.455014 -215.659979)
			(xy 458.508164 -215.663962) (xy 458.560126 -215.675822) (xy 458.60974 -215.695294) (xy 458.655898 -215.721943)
			(xy 458.697569 -215.755174) (xy 458.733821 -215.794245) (xy 458.763845 -215.838282) (xy 458.786971 -215.886303)
			(xy 458.802681 -215.937233) (xy 458.810624 -215.989937) (xy 458.811122 -216.016586) (xy 458.810624 -216.043235)
			(xy 458.802681 -216.095939) (xy 458.786971 -216.146869) (xy 458.763845 -216.19489) (xy 458.733821 -216.238927)
			(xy 458.697569 -216.277998) (xy 458.655898 -216.311229) (xy 458.60974 -216.337878) (xy 458.560126 -216.35735)
			(xy 458.508164 -216.36921) (xy 458.455014 -216.373194) (xy 458.401864 -216.36921) (xy 458.349902 -216.35735)
			(xy 458.300288 -216.337878) (xy 458.25413 -216.311229) (xy 458.212459 -216.277998) (xy 458.176207 -216.238927)
			(xy 458.146183 -216.19489) (xy 458.123057 -216.146869) (xy 458.107347 -216.095939) (xy 458.099404 -216.043235)
			(xy 455.366892 -216.043235) (xy 455.358949 -216.095939) (xy 455.343239 -216.146869) (xy 455.320113 -216.19489)
			(xy 455.290089 -216.238927) (xy 455.253837 -216.277998) (xy 455.212166 -216.311229) (xy 455.166008 -216.337878)
			(xy 455.116394 -216.35735) (xy 455.064432 -216.36921) (xy 455.011282 -216.373194) (xy 454.958132 -216.36921)
			(xy 454.90617 -216.35735) (xy 454.856556 -216.337878) (xy 454.810398 -216.311229) (xy 454.768727 -216.277998)
			(xy 454.732475 -216.238927) (xy 454.702451 -216.19489) (xy 454.679325 -216.146869) (xy 454.663615 -216.095939)
			(xy 454.655672 -216.043235) (xy 453.476624 -216.043235) (xy 453.468681 -216.095939) (xy 453.452971 -216.146869)
			(xy 453.429845 -216.19489) (xy 453.399821 -216.238927) (xy 453.363569 -216.277998) (xy 453.321898 -216.311229)
			(xy 453.27574 -216.337878) (xy 453.226126 -216.35735) (xy 453.174164 -216.36921) (xy 453.121014 -216.373194)
			(xy 453.067864 -216.36921) (xy 453.015902 -216.35735) (xy 452.966288 -216.337878) (xy 452.92013 -216.311229)
			(xy 452.878459 -216.277998) (xy 452.842207 -216.238927) (xy 452.812183 -216.19489) (xy 452.789057 -216.146869)
			(xy 452.773347 -216.095939) (xy 452.765404 -216.043235) (xy 451.266824 -216.043235) (xy 451.258881 -216.095939)
			(xy 451.243171 -216.146869) (xy 451.220045 -216.19489) (xy 451.190021 -216.238927) (xy 451.153769 -216.277998)
			(xy 451.112098 -216.311229) (xy 451.06594 -216.337878) (xy 451.016326 -216.35735) (xy 450.964364 -216.36921)
			(xy 450.911214 -216.373194) (xy 450.858064 -216.36921) (xy 450.806102 -216.35735) (xy 450.756488 -216.337878)
			(xy 450.71033 -216.311229) (xy 450.668659 -216.277998) (xy 450.632407 -216.238927) (xy 450.602383 -216.19489)
			(xy 450.579257 -216.146869) (xy 450.563547 -216.095939) (xy 450.555604 -216.043235) (xy 449.793868 -216.043235)
			(xy 449.793868 -216.52865) (xy 449.82384 -216.542112) (xy 449.848454 -216.553792) (xy 449.894115 -216.583511)
			(xy 449.934717 -216.619837) (xy 449.969312 -216.661922) (xy 449.997094 -216.708787) (xy 450.017414 -216.759335)
			(xy 450.029798 -216.812389) (xy 450.033958 -216.86671) (xy 450.031915 -216.893373) (xy 450.555604 -216.893373)
			(xy 450.555604 -216.840075) (xy 450.563547 -216.787371) (xy 450.579257 -216.736441) (xy 450.602383 -216.68842)
			(xy 450.632407 -216.644383) (xy 450.668659 -216.605312) (xy 450.71033 -216.572081) (xy 450.756488 -216.545432)
			(xy 450.806102 -216.52596) (xy 450.858064 -216.5141) (xy 450.911214 -216.510117) (xy 450.964364 -216.5141)
			(xy 451.016326 -216.52596) (xy 451.06594 -216.545432) (xy 451.112098 -216.572081) (xy 451.153769 -216.605312)
			(xy 451.190021 -216.644383) (xy 451.220045 -216.68842) (xy 451.243171 -216.736441) (xy 451.258881 -216.787371)
			(xy 451.266824 -216.840075) (xy 451.267322 -216.866724) (xy 451.266824 -216.893373) (xy 454.655672 -216.893373)
			(xy 454.655672 -216.840075) (xy 454.663615 -216.787371) (xy 454.679325 -216.736441) (xy 454.702451 -216.68842)
			(xy 454.732475 -216.644383) (xy 454.768727 -216.605312) (xy 454.810398 -216.572081) (xy 454.856556 -216.545432)
			(xy 454.90617 -216.52596) (xy 454.958132 -216.5141) (xy 455.011282 -216.510117) (xy 455.064432 -216.5141)
			(xy 455.116394 -216.52596) (xy 455.166008 -216.545432) (xy 455.212166 -216.572081) (xy 455.253837 -216.605312)
			(xy 455.290089 -216.644383) (xy 455.320113 -216.68842) (xy 455.343239 -216.736441) (xy 455.358949 -216.787371)
			(xy 455.366892 -216.840075) (xy 455.36739 -216.866724) (xy 455.366892 -216.893373) (xy 456.865472 -216.893373)
			(xy 456.865472 -216.840075) (xy 456.873415 -216.787371) (xy 456.889125 -216.736441) (xy 456.912251 -216.68842)
			(xy 456.942275 -216.644383) (xy 456.978527 -216.605312) (xy 457.020198 -216.572081) (xy 457.066356 -216.545432)
			(xy 457.11597 -216.52596) (xy 457.167932 -216.5141) (xy 457.221082 -216.510117) (xy 457.274232 -216.5141)
			(xy 457.326194 -216.52596) (xy 457.375808 -216.545432) (xy 457.421966 -216.572081) (xy 457.463637 -216.605312)
			(xy 457.499889 -216.644383) (xy 457.529913 -216.68842) (xy 457.553039 -216.736441) (xy 457.568749 -216.787371)
			(xy 457.576692 -216.840075) (xy 457.57719 -216.866724) (xy 457.576692 -216.893373) (xy 457.568749 -216.946077)
			(xy 457.553039 -216.997007) (xy 457.529913 -217.045028) (xy 457.499889 -217.089065) (xy 457.463637 -217.128136)
			(xy 457.421966 -217.161367) (xy 457.375808 -217.188016) (xy 457.326194 -217.207488) (xy 457.274232 -217.219348)
			(xy 457.221082 -217.223332) (xy 457.167932 -217.219348) (xy 457.11597 -217.207488) (xy 457.066356 -217.188016)
			(xy 457.020198 -217.161367) (xy 456.978527 -217.128136) (xy 456.942275 -217.089065) (xy 456.912251 -217.045028)
			(xy 456.889125 -216.997007) (xy 456.873415 -216.946077) (xy 456.865472 -216.893373) (xy 455.366892 -216.893373)
			(xy 455.358949 -216.946077) (xy 455.343239 -216.997007) (xy 455.320113 -217.045028) (xy 455.290089 -217.089065)
			(xy 455.253837 -217.128136) (xy 455.212166 -217.161367) (xy 455.166008 -217.188016) (xy 455.116394 -217.207488)
			(xy 455.064432 -217.219348) (xy 455.011282 -217.223332) (xy 454.958132 -217.219348) (xy 454.90617 -217.207488)
			(xy 454.856556 -217.188016) (xy 454.810398 -217.161367) (xy 454.768727 -217.128136) (xy 454.732475 -217.089065)
			(xy 454.702451 -217.045028) (xy 454.679325 -216.997007) (xy 454.663615 -216.946077) (xy 454.655672 -216.893373)
			(xy 451.266824 -216.893373) (xy 451.258881 -216.946077) (xy 451.243171 -216.997007) (xy 451.220045 -217.045028)
			(xy 451.190021 -217.089065) (xy 451.153769 -217.128136) (xy 451.112098 -217.161367) (xy 451.06594 -217.188016)
			(xy 451.016326 -217.207488) (xy 450.964364 -217.219348) (xy 450.911214 -217.223332) (xy 450.858064 -217.219348)
			(xy 450.806102 -217.207488) (xy 450.756488 -217.188016) (xy 450.71033 -217.161367) (xy 450.668659 -217.128136)
			(xy 450.632407 -217.089065) (xy 450.602383 -217.045028) (xy 450.579257 -216.997007) (xy 450.563547 -216.946077)
			(xy 450.555604 -216.893373) (xy 450.031915 -216.893373) (xy 450.029795 -216.921031) (xy 450.017408 -216.974084)
			(xy 449.997085 -217.024631) (xy 449.969301 -217.071494) (xy 449.934703 -217.113578) (xy 449.894099 -217.149901)
			(xy 449.848437 -217.179617) (xy 449.82384 -217.191336) (xy 449.793868 -217.204798) (xy 449.793868 -217.743257)
			(xy 450.555604 -217.743257) (xy 450.555604 -217.689959) (xy 450.563547 -217.637255) (xy 450.579257 -217.586325)
			(xy 450.602383 -217.538304) (xy 450.632407 -217.494267) (xy 450.668659 -217.455196) (xy 450.71033 -217.421965)
			(xy 450.756488 -217.395316) (xy 450.806102 -217.375844) (xy 450.858064 -217.363984) (xy 450.911214 -217.360001)
			(xy 450.964364 -217.363984) (xy 451.016326 -217.375844) (xy 451.06594 -217.395316) (xy 451.112098 -217.421965)
			(xy 451.153769 -217.455196) (xy 451.190021 -217.494267) (xy 451.220045 -217.538304) (xy 451.243171 -217.586325)
			(xy 451.258881 -217.637255) (xy 451.266824 -217.689959) (xy 451.267322 -217.716608) (xy 451.266824 -217.743257)
			(xy 452.765404 -217.743257) (xy 452.765404 -217.689959) (xy 452.773347 -217.637255) (xy 452.789057 -217.586325)
			(xy 452.812183 -217.538304) (xy 452.842207 -217.494267) (xy 452.878459 -217.455196) (xy 452.92013 -217.421965)
			(xy 452.966288 -217.395316) (xy 453.015902 -217.375844) (xy 453.067864 -217.363984) (xy 453.121014 -217.360001)
			(xy 453.174164 -217.363984) (xy 453.226126 -217.375844) (xy 453.27574 -217.395316) (xy 453.321898 -217.421965)
			(xy 453.363569 -217.455196) (xy 453.399821 -217.494267) (xy 453.429845 -217.538304) (xy 453.452971 -217.586325)
			(xy 453.468681 -217.637255) (xy 453.476624 -217.689959) (xy 453.477122 -217.716608) (xy 453.476624 -217.743257)
			(xy 454.655672 -217.743257) (xy 454.655672 -217.689959) (xy 454.663615 -217.637255) (xy 454.679325 -217.586325)
			(xy 454.702451 -217.538304) (xy 454.732475 -217.494267) (xy 454.768727 -217.455196) (xy 454.810398 -217.421965)
			(xy 454.856556 -217.395316) (xy 454.90617 -217.375844) (xy 454.958132 -217.363984) (xy 455.011282 -217.360001)
			(xy 455.064432 -217.363984) (xy 455.116394 -217.375844) (xy 455.166008 -217.395316) (xy 455.212166 -217.421965)
			(xy 455.253837 -217.455196) (xy 455.290089 -217.494267) (xy 455.320113 -217.538304) (xy 455.343239 -217.586325)
			(xy 455.358949 -217.637255) (xy 455.366892 -217.689959) (xy 455.36739 -217.716608) (xy 455.366892 -217.743257)
			(xy 458.099404 -217.743257) (xy 458.099404 -217.689959) (xy 458.107347 -217.637255) (xy 458.123057 -217.586325)
			(xy 458.146183 -217.538304) (xy 458.176207 -217.494267) (xy 458.212459 -217.455196) (xy 458.25413 -217.421965)
			(xy 458.300288 -217.395316) (xy 458.349902 -217.375844) (xy 458.401864 -217.363984) (xy 458.455014 -217.360001)
			(xy 458.508164 -217.363984) (xy 458.560126 -217.375844) (xy 458.60974 -217.395316) (xy 458.655898 -217.421965)
			(xy 458.697569 -217.455196) (xy 458.733821 -217.494267) (xy 458.763845 -217.538304) (xy 458.786971 -217.586325)
			(xy 458.802681 -217.637255) (xy 458.810624 -217.689959) (xy 458.811122 -217.716608) (xy 458.810624 -217.743257)
			(xy 458.802681 -217.795961) (xy 458.786971 -217.846891) (xy 458.763845 -217.894912) (xy 458.733821 -217.938949)
			(xy 458.697569 -217.97802) (xy 458.655898 -218.011251) (xy 458.60974 -218.0379) (xy 458.560126 -218.057372)
			(xy 458.508164 -218.069232) (xy 458.455014 -218.073216) (xy 458.401864 -218.069232) (xy 458.349902 -218.057372)
			(xy 458.300288 -218.0379) (xy 458.25413 -218.011251) (xy 458.212459 -217.97802) (xy 458.176207 -217.938949)
			(xy 458.146183 -217.894912) (xy 458.123057 -217.846891) (xy 458.107347 -217.795961) (xy 458.099404 -217.743257)
			(xy 455.366892 -217.743257) (xy 455.358949 -217.795961) (xy 455.343239 -217.846891) (xy 455.320113 -217.894912)
			(xy 455.290089 -217.938949) (xy 455.253837 -217.97802) (xy 455.212166 -218.011251) (xy 455.166008 -218.0379)
			(xy 455.116394 -218.057372) (xy 455.064432 -218.069232) (xy 455.011282 -218.073216) (xy 454.958132 -218.069232)
			(xy 454.90617 -218.057372) (xy 454.856556 -218.0379) (xy 454.810398 -218.011251) (xy 454.768727 -217.97802)
			(xy 454.732475 -217.938949) (xy 454.702451 -217.894912) (xy 454.679325 -217.846891) (xy 454.663615 -217.795961)
			(xy 454.655672 -217.743257) (xy 453.476624 -217.743257) (xy 453.468681 -217.795961) (xy 453.452971 -217.846891)
			(xy 453.429845 -217.894912) (xy 453.399821 -217.938949) (xy 453.363569 -217.97802) (xy 453.321898 -218.011251)
			(xy 453.27574 -218.0379) (xy 453.226126 -218.057372) (xy 453.174164 -218.069232) (xy 453.121014 -218.073216)
			(xy 453.067864 -218.069232) (xy 453.015902 -218.057372) (xy 452.966288 -218.0379) (xy 452.92013 -218.011251)
			(xy 452.878459 -217.97802) (xy 452.842207 -217.938949) (xy 452.812183 -217.894912) (xy 452.789057 -217.846891)
			(xy 452.773347 -217.795961) (xy 452.765404 -217.743257) (xy 451.266824 -217.743257) (xy 451.258881 -217.795961)
			(xy 451.243171 -217.846891) (xy 451.220045 -217.894912) (xy 451.190021 -217.938949) (xy 451.153769 -217.97802)
			(xy 451.112098 -218.011251) (xy 451.06594 -218.0379) (xy 451.016326 -218.057372) (xy 450.964364 -218.069232)
			(xy 450.911214 -218.073216) (xy 450.858064 -218.069232) (xy 450.806102 -218.057372) (xy 450.756488 -218.0379)
			(xy 450.71033 -218.011251) (xy 450.668659 -217.97802) (xy 450.632407 -217.938949) (xy 450.602383 -217.894912)
			(xy 450.579257 -217.846891) (xy 450.563547 -217.795961) (xy 450.555604 -217.743257) (xy 449.793868 -217.743257)
			(xy 449.793868 -218.593395) (xy 450.555604 -218.593395) (xy 450.555604 -218.540097) (xy 450.563547 -218.487393)
			(xy 450.579257 -218.436463) (xy 450.602383 -218.388442) (xy 450.632407 -218.344405) (xy 450.668659 -218.305334)
			(xy 450.71033 -218.272103) (xy 450.756488 -218.245454) (xy 450.806102 -218.225982) (xy 450.858064 -218.214122)
			(xy 450.911214 -218.210139) (xy 450.964364 -218.214122) (xy 451.016326 -218.225982) (xy 451.06594 -218.245454)
			(xy 451.112098 -218.272103) (xy 451.153769 -218.305334) (xy 451.190021 -218.344405) (xy 451.220045 -218.388442)
			(xy 451.243171 -218.436463) (xy 451.258881 -218.487393) (xy 451.266824 -218.540097) (xy 451.267322 -218.566746)
			(xy 451.266824 -218.593395) (xy 454.655672 -218.593395) (xy 454.655672 -218.540097) (xy 454.663615 -218.487393)
			(xy 454.679325 -218.436463) (xy 454.702451 -218.388442) (xy 454.732475 -218.344405) (xy 454.768727 -218.305334)
			(xy 454.810398 -218.272103) (xy 454.856556 -218.245454) (xy 454.90617 -218.225982) (xy 454.958132 -218.214122)
			(xy 455.011282 -218.210139) (xy 455.064432 -218.214122) (xy 455.116394 -218.225982) (xy 455.166008 -218.245454)
			(xy 455.212166 -218.272103) (xy 455.253837 -218.305334) (xy 455.290089 -218.344405) (xy 455.320113 -218.388442)
			(xy 455.343239 -218.436463) (xy 455.358949 -218.487393) (xy 455.366892 -218.540097) (xy 455.36739 -218.566746)
			(xy 455.366892 -218.593395) (xy 455.358949 -218.646099) (xy 455.343239 -218.697029) (xy 455.320113 -218.74505)
			(xy 455.290089 -218.789087) (xy 455.253837 -218.828158) (xy 455.212166 -218.861389) (xy 455.166008 -218.888038)
			(xy 455.116394 -218.90751) (xy 455.064432 -218.91937) (xy 455.011282 -218.923354) (xy 454.958132 -218.91937)
			(xy 454.90617 -218.90751) (xy 454.856556 -218.888038) (xy 454.810398 -218.861389) (xy 454.768727 -218.828158)
			(xy 454.732475 -218.789087) (xy 454.702451 -218.74505) (xy 454.679325 -218.697029) (xy 454.663615 -218.646099)
			(xy 454.655672 -218.593395) (xy 451.266824 -218.593395) (xy 451.258881 -218.646099) (xy 451.243171 -218.697029)
			(xy 451.220045 -218.74505) (xy 451.190021 -218.789087) (xy 451.153769 -218.828158) (xy 451.112098 -218.861389)
			(xy 451.06594 -218.888038) (xy 451.016326 -218.90751) (xy 450.964364 -218.91937) (xy 450.911214 -218.923354)
			(xy 450.858064 -218.91937) (xy 450.806102 -218.90751) (xy 450.756488 -218.888038) (xy 450.71033 -218.861389)
			(xy 450.668659 -218.828158) (xy 450.632407 -218.789087) (xy 450.602383 -218.74505) (xy 450.579257 -218.697029)
			(xy 450.563547 -218.646099) (xy 450.555604 -218.593395) (xy 449.793868 -218.593395) (xy 449.793868 -219.078556)
			(xy 449.82384 -219.092018) (xy 449.848454 -219.103698) (xy 449.894113 -219.133417) (xy 449.934714 -219.169742)
			(xy 449.969309 -219.211828) (xy 449.99709 -219.258691) (xy 450.01741 -219.309239) (xy 450.029793 -219.362292)
			(xy 450.033952 -219.416612) (xy 450.031909 -219.443279) (xy 450.555604 -219.443279) (xy 450.555604 -219.389981)
			(xy 450.563547 -219.337277) (xy 450.579257 -219.286347) (xy 450.602383 -219.238326) (xy 450.632407 -219.194289)
			(xy 450.668659 -219.155218) (xy 450.71033 -219.121987) (xy 450.756488 -219.095338) (xy 450.806102 -219.075866)
			(xy 450.858064 -219.064006) (xy 450.911214 -219.060023) (xy 450.964364 -219.064006) (xy 451.016326 -219.075866)
			(xy 451.06594 -219.095338) (xy 451.112098 -219.121987) (xy 451.153769 -219.155218) (xy 451.190021 -219.194289)
			(xy 451.220045 -219.238326) (xy 451.243171 -219.286347) (xy 451.258881 -219.337277) (xy 451.266824 -219.389981)
			(xy 451.267322 -219.41663) (xy 451.266824 -219.443279) (xy 454.655672 -219.443279) (xy 454.655672 -219.389981)
			(xy 454.663615 -219.337277) (xy 454.679325 -219.286347) (xy 454.702451 -219.238326) (xy 454.732475 -219.194289)
			(xy 454.768727 -219.155218) (xy 454.810398 -219.121987) (xy 454.856556 -219.095338) (xy 454.90617 -219.075866)
			(xy 454.958132 -219.064006) (xy 455.011282 -219.060023) (xy 455.064432 -219.064006) (xy 455.116394 -219.075866)
			(xy 455.166008 -219.095338) (xy 455.212166 -219.121987) (xy 455.253837 -219.155218) (xy 455.290089 -219.194289)
			(xy 455.320113 -219.238326) (xy 455.343239 -219.286347) (xy 455.358949 -219.337277) (xy 455.366892 -219.389981)
			(xy 455.36739 -219.41663) (xy 455.366892 -219.443279) (xy 456.865472 -219.443279) (xy 456.865472 -219.389981)
			(xy 456.873415 -219.337277) (xy 456.889125 -219.286347) (xy 456.912251 -219.238326) (xy 456.942275 -219.194289)
			(xy 456.978527 -219.155218) (xy 457.020198 -219.121987) (xy 457.066356 -219.095338) (xy 457.11597 -219.075866)
			(xy 457.167932 -219.064006) (xy 457.221082 -219.060023) (xy 457.274232 -219.064006) (xy 457.326194 -219.075866)
			(xy 457.375808 -219.095338) (xy 457.421966 -219.121987) (xy 457.463637 -219.155218) (xy 457.499889 -219.194289)
			(xy 457.529913 -219.238326) (xy 457.553039 -219.286347) (xy 457.568749 -219.337277) (xy 457.576692 -219.389981)
			(xy 457.57719 -219.41663) (xy 457.576692 -219.443279) (xy 457.568749 -219.495983) (xy 457.553039 -219.546913)
			(xy 457.529913 -219.594934) (xy 457.499889 -219.638971) (xy 457.463637 -219.678042) (xy 457.421966 -219.711273)
			(xy 457.375808 -219.737922) (xy 457.326194 -219.757394) (xy 457.274232 -219.769254) (xy 457.221082 -219.773238)
			(xy 457.167932 -219.769254) (xy 457.11597 -219.757394) (xy 457.066356 -219.737922) (xy 457.020198 -219.711273)
			(xy 456.978527 -219.678042) (xy 456.942275 -219.638971) (xy 456.912251 -219.594934) (xy 456.889125 -219.546913)
			(xy 456.873415 -219.495983) (xy 456.865472 -219.443279) (xy 455.366892 -219.443279) (xy 455.358949 -219.495983)
			(xy 455.343239 -219.546913) (xy 455.320113 -219.594934) (xy 455.290089 -219.638971) (xy 455.253837 -219.678042)
			(xy 455.212166 -219.711273) (xy 455.166008 -219.737922) (xy 455.116394 -219.757394) (xy 455.064432 -219.769254)
			(xy 455.011282 -219.773238) (xy 454.958132 -219.769254) (xy 454.90617 -219.757394) (xy 454.856556 -219.737922)
			(xy 454.810398 -219.711273) (xy 454.768727 -219.678042) (xy 454.732475 -219.638971) (xy 454.702451 -219.594934)
			(xy 454.679325 -219.546913) (xy 454.663615 -219.495983) (xy 454.655672 -219.443279) (xy 451.266824 -219.443279)
			(xy 451.258881 -219.495983) (xy 451.243171 -219.546913) (xy 451.220045 -219.594934) (xy 451.190021 -219.638971)
			(xy 451.153769 -219.678042) (xy 451.112098 -219.711273) (xy 451.06594 -219.737922) (xy 451.016326 -219.757394)
			(xy 450.964364 -219.769254) (xy 450.911214 -219.773238) (xy 450.858064 -219.769254) (xy 450.806102 -219.757394)
			(xy 450.756488 -219.737922) (xy 450.71033 -219.711273) (xy 450.668659 -219.678042) (xy 450.632407 -219.638971)
			(xy 450.602383 -219.594934) (xy 450.579257 -219.546913) (xy 450.563547 -219.495983) (xy 450.555604 -219.443279)
			(xy 450.031909 -219.443279) (xy 450.02979 -219.470932) (xy 450.017402 -219.523984) (xy 449.997079 -219.574531)
			(xy 449.969295 -219.621393) (xy 449.934697 -219.663476) (xy 449.894094 -219.699799) (xy 449.848432 -219.729513)
			(xy 449.82384 -219.741242) (xy 449.793868 -219.754704) (xy 449.793868 -220.293417) (xy 450.555604 -220.293417)
			(xy 450.555604 -220.240119) (xy 450.563547 -220.187415) (xy 450.579257 -220.136485) (xy 450.602383 -220.088464)
			(xy 450.632407 -220.044427) (xy 450.668659 -220.005356) (xy 450.71033 -219.972125) (xy 450.756488 -219.945476)
			(xy 450.806102 -219.926004) (xy 450.858064 -219.914144) (xy 450.911214 -219.910161) (xy 450.964364 -219.914144)
			(xy 451.016326 -219.926004) (xy 451.06594 -219.945476) (xy 451.112098 -219.972125) (xy 451.153769 -220.005356)
			(xy 451.190021 -220.044427) (xy 451.220045 -220.088464) (xy 451.243171 -220.136485) (xy 451.258881 -220.187415)
			(xy 451.266824 -220.240119) (xy 451.267322 -220.266768) (xy 451.266824 -220.293417) (xy 452.765404 -220.293417)
			(xy 452.765404 -220.240119) (xy 452.773347 -220.187415) (xy 452.789057 -220.136485) (xy 452.812183 -220.088464)
			(xy 452.842207 -220.044427) (xy 452.878459 -220.005356) (xy 452.92013 -219.972125) (xy 452.966288 -219.945476)
			(xy 453.015902 -219.926004) (xy 453.067864 -219.914144) (xy 453.121014 -219.910161) (xy 453.174164 -219.914144)
			(xy 453.226126 -219.926004) (xy 453.27574 -219.945476) (xy 453.321898 -219.972125) (xy 453.363569 -220.005356)
			(xy 453.399821 -220.044427) (xy 453.429845 -220.088464) (xy 453.452971 -220.136485) (xy 453.468681 -220.187415)
			(xy 453.476624 -220.240119) (xy 453.477122 -220.266768) (xy 453.476624 -220.293417) (xy 454.655672 -220.293417)
			(xy 454.655672 -220.240119) (xy 454.663615 -220.187415) (xy 454.679325 -220.136485) (xy 454.702451 -220.088464)
			(xy 454.732475 -220.044427) (xy 454.768727 -220.005356) (xy 454.810398 -219.972125) (xy 454.856556 -219.945476)
			(xy 454.90617 -219.926004) (xy 454.958132 -219.914144) (xy 455.011282 -219.910161) (xy 455.064432 -219.914144)
			(xy 455.116394 -219.926004) (xy 455.166008 -219.945476) (xy 455.212166 -219.972125) (xy 455.253837 -220.005356)
			(xy 455.290089 -220.044427) (xy 455.320113 -220.088464) (xy 455.343239 -220.136485) (xy 455.358949 -220.187415)
			(xy 455.366892 -220.240119) (xy 455.36739 -220.266768) (xy 455.366892 -220.293417) (xy 458.099404 -220.293417)
			(xy 458.099404 -220.240119) (xy 458.107347 -220.187415) (xy 458.123057 -220.136485) (xy 458.146183 -220.088464)
			(xy 458.176207 -220.044427) (xy 458.212459 -220.005356) (xy 458.25413 -219.972125) (xy 458.300288 -219.945476)
			(xy 458.349902 -219.926004) (xy 458.401864 -219.914144) (xy 458.455014 -219.910161) (xy 458.508164 -219.914144)
			(xy 458.560126 -219.926004) (xy 458.60974 -219.945476) (xy 458.655898 -219.972125) (xy 458.697569 -220.005356)
			(xy 458.733821 -220.044427) (xy 458.763845 -220.088464) (xy 458.786971 -220.136485) (xy 458.802681 -220.187415)
			(xy 458.810624 -220.240119) (xy 458.811122 -220.266768) (xy 458.810624 -220.293417) (xy 458.802681 -220.346121)
			(xy 458.786971 -220.397051) (xy 458.763845 -220.445072) (xy 458.733821 -220.489109) (xy 458.697569 -220.52818)
			(xy 458.655898 -220.561411) (xy 458.60974 -220.58806) (xy 458.560126 -220.607532) (xy 458.508164 -220.619392)
			(xy 458.455014 -220.623376) (xy 458.401864 -220.619392) (xy 458.349902 -220.607532) (xy 458.300288 -220.58806)
			(xy 458.25413 -220.561411) (xy 458.212459 -220.52818) (xy 458.176207 -220.489109) (xy 458.146183 -220.445072)
			(xy 458.123057 -220.397051) (xy 458.107347 -220.346121) (xy 458.099404 -220.293417) (xy 455.366892 -220.293417)
			(xy 455.358949 -220.346121) (xy 455.343239 -220.397051) (xy 455.320113 -220.445072) (xy 455.290089 -220.489109)
			(xy 455.253837 -220.52818) (xy 455.212166 -220.561411) (xy 455.166008 -220.58806) (xy 455.116394 -220.607532)
			(xy 455.064432 -220.619392) (xy 455.011282 -220.623376) (xy 454.958132 -220.619392) (xy 454.90617 -220.607532)
			(xy 454.856556 -220.58806) (xy 454.810398 -220.561411) (xy 454.768727 -220.52818) (xy 454.732475 -220.489109)
			(xy 454.702451 -220.445072) (xy 454.679325 -220.397051) (xy 454.663615 -220.346121) (xy 454.655672 -220.293417)
			(xy 453.476624 -220.293417) (xy 453.468681 -220.346121) (xy 453.452971 -220.397051) (xy 453.429845 -220.445072)
			(xy 453.399821 -220.489109) (xy 453.363569 -220.52818) (xy 453.321898 -220.561411) (xy 453.27574 -220.58806)
			(xy 453.226126 -220.607532) (xy 453.174164 -220.619392) (xy 453.121014 -220.623376) (xy 453.067864 -220.619392)
			(xy 453.015902 -220.607532) (xy 452.966288 -220.58806) (xy 452.92013 -220.561411) (xy 452.878459 -220.52818)
			(xy 452.842207 -220.489109) (xy 452.812183 -220.445072) (xy 452.789057 -220.397051) (xy 452.773347 -220.346121)
			(xy 452.765404 -220.293417) (xy 451.266824 -220.293417) (xy 451.258881 -220.346121) (xy 451.243171 -220.397051)
			(xy 451.220045 -220.445072) (xy 451.190021 -220.489109) (xy 451.153769 -220.52818) (xy 451.112098 -220.561411)
			(xy 451.06594 -220.58806) (xy 451.016326 -220.607532) (xy 450.964364 -220.619392) (xy 450.911214 -220.623376)
			(xy 450.858064 -220.619392) (xy 450.806102 -220.607532) (xy 450.756488 -220.58806) (xy 450.71033 -220.561411)
			(xy 450.668659 -220.52818) (xy 450.632407 -220.489109) (xy 450.602383 -220.445072) (xy 450.579257 -220.397051)
			(xy 450.563547 -220.346121) (xy 450.555604 -220.293417) (xy 449.793868 -220.293417) (xy 449.793868 -220.778578)
			(xy 449.82384 -220.79204) (xy 449.84846 -220.803721) (xy 449.894131 -220.833441) (xy 449.934743 -220.86977)
			(xy 449.969349 -220.911861) (xy 449.99714 -220.958731) (xy 450.017468 -221.009287) (xy 450.029859 -221.06235)
			(xy 450.034024 -221.11668) (xy 450.031986 -221.143301) (xy 450.555604 -221.143301) (xy 450.555604 -221.090003)
			(xy 450.563547 -221.037299) (xy 450.579257 -220.986369) (xy 450.602383 -220.938348) (xy 450.632407 -220.894311)
			(xy 450.668659 -220.85524) (xy 450.71033 -220.822009) (xy 450.756488 -220.79536) (xy 450.806102 -220.775888)
			(xy 450.858064 -220.764028) (xy 450.911214 -220.760045) (xy 450.964364 -220.764028) (xy 451.016326 -220.775888)
			(xy 451.06594 -220.79536) (xy 451.112098 -220.822009) (xy 451.153769 -220.85524) (xy 451.190021 -220.894311)
			(xy 451.220045 -220.938348) (xy 451.243171 -220.986369) (xy 451.258881 -221.037299) (xy 451.266824 -221.090003)
			(xy 451.267322 -221.116652) (xy 451.266824 -221.143301) (xy 454.655672 -221.143301) (xy 454.655672 -221.090003)
			(xy 454.663615 -221.037299) (xy 454.679325 -220.986369) (xy 454.702451 -220.938348) (xy 454.732475 -220.894311)
			(xy 454.768727 -220.85524) (xy 454.810398 -220.822009) (xy 454.856556 -220.79536) (xy 454.90617 -220.775888)
			(xy 454.958132 -220.764028) (xy 455.011282 -220.760045) (xy 455.064432 -220.764028) (xy 455.116394 -220.775888)
			(xy 455.166008 -220.79536) (xy 455.212166 -220.822009) (xy 455.253837 -220.85524) (xy 455.290089 -220.894311)
			(xy 455.320113 -220.938348) (xy 455.343239 -220.986369) (xy 455.358949 -221.037299) (xy 455.366892 -221.090003)
			(xy 455.36739 -221.116652) (xy 455.366892 -221.143301) (xy 456.865472 -221.143301) (xy 456.865472 -221.090003)
			(xy 456.873415 -221.037299) (xy 456.889125 -220.986369) (xy 456.912251 -220.938348) (xy 456.942275 -220.894311)
			(xy 456.978527 -220.85524) (xy 457.020198 -220.822009) (xy 457.066356 -220.79536) (xy 457.11597 -220.775888)
			(xy 457.167932 -220.764028) (xy 457.221082 -220.760045) (xy 457.274232 -220.764028) (xy 457.326194 -220.775888)
			(xy 457.375808 -220.79536) (xy 457.421966 -220.822009) (xy 457.463637 -220.85524) (xy 457.499889 -220.894311)
			(xy 457.529913 -220.938348) (xy 457.553039 -220.986369) (xy 457.568749 -221.037299) (xy 457.576692 -221.090003)
			(xy 457.57719 -221.116652) (xy 457.576692 -221.143301) (xy 457.568749 -221.196005) (xy 457.553039 -221.246935)
			(xy 457.529913 -221.294956) (xy 457.499889 -221.338993) (xy 457.463637 -221.378064) (xy 457.421966 -221.411295)
			(xy 457.375808 -221.437944) (xy 457.326194 -221.457416) (xy 457.274232 -221.469276) (xy 457.221082 -221.47326)
			(xy 457.167932 -221.469276) (xy 457.11597 -221.457416) (xy 457.066356 -221.437944) (xy 457.020198 -221.411295)
			(xy 456.978527 -221.378064) (xy 456.942275 -221.338993) (xy 456.912251 -221.294956) (xy 456.889125 -221.246935)
			(xy 456.873415 -221.196005) (xy 456.865472 -221.143301) (xy 455.366892 -221.143301) (xy 455.358949 -221.196005)
			(xy 455.343239 -221.246935) (xy 455.320113 -221.294956) (xy 455.290089 -221.338993) (xy 455.253837 -221.378064)
			(xy 455.212166 -221.411295) (xy 455.166008 -221.437944) (xy 455.116394 -221.457416) (xy 455.064432 -221.469276)
			(xy 455.011282 -221.47326) (xy 454.958132 -221.469276) (xy 454.90617 -221.457416) (xy 454.856556 -221.437944)
			(xy 454.810398 -221.411295) (xy 454.768727 -221.378064) (xy 454.732475 -221.338993) (xy 454.702451 -221.294956)
			(xy 454.679325 -221.246935) (xy 454.663615 -221.196005) (xy 454.655672 -221.143301) (xy 451.266824 -221.143301)
			(xy 451.258881 -221.196005) (xy 451.243171 -221.246935) (xy 451.220045 -221.294956) (xy 451.190021 -221.338993)
			(xy 451.153769 -221.378064) (xy 451.112098 -221.411295) (xy 451.06594 -221.437944) (xy 451.016326 -221.457416)
			(xy 450.964364 -221.469276) (xy 450.911214 -221.47326) (xy 450.858064 -221.469276) (xy 450.806102 -221.457416)
			(xy 450.756488 -221.437944) (xy 450.71033 -221.411295) (xy 450.668659 -221.378064) (xy 450.632407 -221.338993)
			(xy 450.602383 -221.294956) (xy 450.579257 -221.246935) (xy 450.563547 -221.196005) (xy 450.555604 -221.143301)
			(xy 450.031986 -221.143301) (xy 450.029865 -221.171011) (xy 450.01748 -221.224075) (xy 449.997157 -221.274634)
			(xy 449.969371 -221.321507) (xy 449.934771 -221.363602) (xy 449.894163 -221.399935) (xy 449.848494 -221.42966)
			(xy 449.82384 -221.441264) (xy 449.793868 -221.454726) (xy 449.793868 -221.993439) (xy 450.555604 -221.993439)
			(xy 450.555604 -221.940141) (xy 450.563547 -221.887437) (xy 450.579257 -221.836507) (xy 450.602383 -221.788486)
			(xy 450.632407 -221.744449) (xy 450.668659 -221.705378) (xy 450.71033 -221.672147) (xy 450.756488 -221.645498)
			(xy 450.806102 -221.626026) (xy 450.858064 -221.614166) (xy 450.911214 -221.610183) (xy 450.964364 -221.614166)
			(xy 451.016326 -221.626026) (xy 451.06594 -221.645498) (xy 451.112098 -221.672147) (xy 451.153769 -221.705378)
			(xy 451.190021 -221.744449) (xy 451.220045 -221.788486) (xy 451.243171 -221.836507) (xy 451.258881 -221.887437)
			(xy 451.266824 -221.940141) (xy 451.267322 -221.96679) (xy 451.266824 -221.993439) (xy 452.765404 -221.993439)
			(xy 452.765404 -221.940141) (xy 452.773347 -221.887437) (xy 452.789057 -221.836507) (xy 452.812183 -221.788486)
			(xy 452.842207 -221.744449) (xy 452.878459 -221.705378) (xy 452.92013 -221.672147) (xy 452.966288 -221.645498)
			(xy 453.015902 -221.626026) (xy 453.067864 -221.614166) (xy 453.121014 -221.610183) (xy 453.174164 -221.614166)
			(xy 453.226126 -221.626026) (xy 453.27574 -221.645498) (xy 453.321898 -221.672147) (xy 453.363569 -221.705378)
			(xy 453.399821 -221.744449) (xy 453.429845 -221.788486) (xy 453.452971 -221.836507) (xy 453.468681 -221.887437)
			(xy 453.476624 -221.940141) (xy 453.477122 -221.96679) (xy 453.476624 -221.993439) (xy 454.655672 -221.993439)
			(xy 454.655672 -221.940141) (xy 454.663615 -221.887437) (xy 454.679325 -221.836507) (xy 454.702451 -221.788486)
			(xy 454.732475 -221.744449) (xy 454.768727 -221.705378) (xy 454.810398 -221.672147) (xy 454.856556 -221.645498)
			(xy 454.90617 -221.626026) (xy 454.958132 -221.614166) (xy 455.011282 -221.610183) (xy 455.064432 -221.614166)
			(xy 455.116394 -221.626026) (xy 455.166008 -221.645498) (xy 455.212166 -221.672147) (xy 455.253837 -221.705378)
			(xy 455.290089 -221.744449) (xy 455.320113 -221.788486) (xy 455.343239 -221.836507) (xy 455.358949 -221.887437)
			(xy 455.366892 -221.940141) (xy 455.36739 -221.96679) (xy 455.366892 -221.993439) (xy 458.099404 -221.993439)
			(xy 458.099404 -221.940141) (xy 458.107347 -221.887437) (xy 458.123057 -221.836507) (xy 458.146183 -221.788486)
			(xy 458.176207 -221.744449) (xy 458.212459 -221.705378) (xy 458.25413 -221.672147) (xy 458.300288 -221.645498)
			(xy 458.349902 -221.626026) (xy 458.401864 -221.614166) (xy 458.455014 -221.610183) (xy 458.508164 -221.614166)
			(xy 458.560126 -221.626026) (xy 458.60974 -221.645498) (xy 458.655898 -221.672147) (xy 458.697569 -221.705378)
			(xy 458.733821 -221.744449) (xy 458.763845 -221.788486) (xy 458.786971 -221.836507) (xy 458.802681 -221.887437)
			(xy 458.810624 -221.940141) (xy 458.811122 -221.96679) (xy 458.810624 -221.993439) (xy 458.802681 -222.046143)
			(xy 458.786971 -222.097073) (xy 458.763845 -222.145094) (xy 458.733821 -222.189131) (xy 458.697569 -222.228202)
			(xy 458.655898 -222.261433) (xy 458.60974 -222.288082) (xy 458.560126 -222.307554) (xy 458.508164 -222.319414)
			(xy 458.455014 -222.323398) (xy 458.401864 -222.319414) (xy 458.349902 -222.307554) (xy 458.300288 -222.288082)
			(xy 458.25413 -222.261433) (xy 458.212459 -222.228202) (xy 458.176207 -222.189131) (xy 458.146183 -222.145094)
			(xy 458.123057 -222.097073) (xy 458.107347 -222.046143) (xy 458.099404 -221.993439) (xy 455.366892 -221.993439)
			(xy 455.358949 -222.046143) (xy 455.343239 -222.097073) (xy 455.320113 -222.145094) (xy 455.290089 -222.189131)
			(xy 455.253837 -222.228202) (xy 455.212166 -222.261433) (xy 455.166008 -222.288082) (xy 455.116394 -222.307554)
			(xy 455.064432 -222.319414) (xy 455.011282 -222.323398) (xy 454.958132 -222.319414) (xy 454.90617 -222.307554)
			(xy 454.856556 -222.288082) (xy 454.810398 -222.261433) (xy 454.768727 -222.228202) (xy 454.732475 -222.189131)
			(xy 454.702451 -222.145094) (xy 454.679325 -222.097073) (xy 454.663615 -222.046143) (xy 454.655672 -221.993439)
			(xy 453.476624 -221.993439) (xy 453.468681 -222.046143) (xy 453.452971 -222.097073) (xy 453.429845 -222.145094)
			(xy 453.399821 -222.189131) (xy 453.363569 -222.228202) (xy 453.321898 -222.261433) (xy 453.27574 -222.288082)
			(xy 453.226126 -222.307554) (xy 453.174164 -222.319414) (xy 453.121014 -222.323398) (xy 453.067864 -222.319414)
			(xy 453.015902 -222.307554) (xy 452.966288 -222.288082) (xy 452.92013 -222.261433) (xy 452.878459 -222.228202)
			(xy 452.842207 -222.189131) (xy 452.812183 -222.145094) (xy 452.789057 -222.097073) (xy 452.773347 -222.046143)
			(xy 452.765404 -221.993439) (xy 451.266824 -221.993439) (xy 451.258881 -222.046143) (xy 451.243171 -222.097073)
			(xy 451.220045 -222.145094) (xy 451.190021 -222.189131) (xy 451.153769 -222.228202) (xy 451.112098 -222.261433)
			(xy 451.06594 -222.288082) (xy 451.016326 -222.307554) (xy 450.964364 -222.319414) (xy 450.911214 -222.323398)
			(xy 450.858064 -222.319414) (xy 450.806102 -222.307554) (xy 450.756488 -222.288082) (xy 450.71033 -222.261433)
			(xy 450.668659 -222.228202) (xy 450.632407 -222.189131) (xy 450.602383 -222.145094) (xy 450.579257 -222.097073)
			(xy 450.563547 -222.046143) (xy 450.555604 -221.993439) (xy 449.793868 -221.993439) (xy 449.793868 -222.4786)
			(xy 449.82384 -222.492062) (xy 449.848458 -222.503743) (xy 449.894126 -222.533462) (xy 449.934735 -222.56979)
			(xy 449.969337 -222.611879) (xy 449.997126 -222.658748) (xy 450.017451 -222.709302) (xy 450.02984 -222.762362)
			(xy 450.034003 -222.816689) (xy 450.031964 -222.843323) (xy 450.555604 -222.843323) (xy 450.555604 -222.790025)
			(xy 450.563547 -222.737321) (xy 450.579257 -222.686391) (xy 450.602383 -222.63837) (xy 450.632407 -222.594333)
			(xy 450.668659 -222.555262) (xy 450.71033 -222.522031) (xy 450.756488 -222.495382) (xy 450.806102 -222.47591)
			(xy 450.858064 -222.46405) (xy 450.911214 -222.460067) (xy 450.964364 -222.46405) (xy 451.016326 -222.47591)
			(xy 451.06594 -222.495382) (xy 451.112098 -222.522031) (xy 451.153769 -222.555262) (xy 451.190021 -222.594333)
			(xy 451.220045 -222.63837) (xy 451.243171 -222.686391) (xy 451.258881 -222.737321) (xy 451.266824 -222.790025)
			(xy 451.267322 -222.816674) (xy 451.266824 -222.843323) (xy 454.655672 -222.843323) (xy 454.655672 -222.790025)
			(xy 454.663615 -222.737321) (xy 454.679325 -222.686391) (xy 454.702451 -222.63837) (xy 454.732475 -222.594333)
			(xy 454.768727 -222.555262) (xy 454.810398 -222.522031) (xy 454.856556 -222.495382) (xy 454.90617 -222.47591)
			(xy 454.958132 -222.46405) (xy 455.011282 -222.460067) (xy 455.064432 -222.46405) (xy 455.116394 -222.47591)
			(xy 455.166008 -222.495382) (xy 455.212166 -222.522031) (xy 455.253837 -222.555262) (xy 455.290089 -222.594333)
			(xy 455.320113 -222.63837) (xy 455.343239 -222.686391) (xy 455.358949 -222.737321) (xy 455.366892 -222.790025)
			(xy 455.36739 -222.816674) (xy 455.366892 -222.843323) (xy 456.865472 -222.843323) (xy 456.865472 -222.790025)
			(xy 456.873415 -222.737321) (xy 456.889125 -222.686391) (xy 456.912251 -222.63837) (xy 456.942275 -222.594333)
			(xy 456.978527 -222.555262) (xy 457.020198 -222.522031) (xy 457.066356 -222.495382) (xy 457.11597 -222.47591)
			(xy 457.167932 -222.46405) (xy 457.221082 -222.460067) (xy 457.274232 -222.46405) (xy 457.326194 -222.47591)
			(xy 457.375808 -222.495382) (xy 457.421966 -222.522031) (xy 457.463637 -222.555262) (xy 457.499889 -222.594333)
			(xy 457.529913 -222.63837) (xy 457.553039 -222.686391) (xy 457.568749 -222.737321) (xy 457.576692 -222.790025)
			(xy 457.57719 -222.816674) (xy 457.576692 -222.843323) (xy 457.568749 -222.896027) (xy 457.553039 -222.946957)
			(xy 457.529913 -222.994978) (xy 457.499889 -223.039015) (xy 457.463637 -223.078086) (xy 457.421966 -223.111317)
			(xy 457.375808 -223.137966) (xy 457.326194 -223.157438) (xy 457.274232 -223.169298) (xy 457.221082 -223.173282)
			(xy 457.167932 -223.169298) (xy 457.11597 -223.157438) (xy 457.066356 -223.137966) (xy 457.020198 -223.111317)
			(xy 456.978527 -223.078086) (xy 456.942275 -223.039015) (xy 456.912251 -222.994978) (xy 456.889125 -222.946957)
			(xy 456.873415 -222.896027) (xy 456.865472 -222.843323) (xy 455.366892 -222.843323) (xy 455.358949 -222.896027)
			(xy 455.343239 -222.946957) (xy 455.320113 -222.994978) (xy 455.290089 -223.039015) (xy 455.253837 -223.078086)
			(xy 455.212166 -223.111317) (xy 455.166008 -223.137966) (xy 455.116394 -223.157438) (xy 455.064432 -223.169298)
			(xy 455.011282 -223.173282) (xy 454.958132 -223.169298) (xy 454.90617 -223.157438) (xy 454.856556 -223.137966)
			(xy 454.810398 -223.111317) (xy 454.768727 -223.078086) (xy 454.732475 -223.039015) (xy 454.702451 -222.994978)
			(xy 454.679325 -222.946957) (xy 454.663615 -222.896027) (xy 454.655672 -222.843323) (xy 451.266824 -222.843323)
			(xy 451.258881 -222.896027) (xy 451.243171 -222.946957) (xy 451.220045 -222.994978) (xy 451.190021 -223.039015)
			(xy 451.153769 -223.078086) (xy 451.112098 -223.111317) (xy 451.06594 -223.137966) (xy 451.016326 -223.157438)
			(xy 450.964364 -223.169298) (xy 450.911214 -223.173282) (xy 450.858064 -223.169298) (xy 450.806102 -223.157438)
			(xy 450.756488 -223.137966) (xy 450.71033 -223.111317) (xy 450.668659 -223.078086) (xy 450.632407 -223.039015)
			(xy 450.602383 -222.994978) (xy 450.579257 -222.946957) (xy 450.563547 -222.896027) (xy 450.555604 -222.843323)
			(xy 450.031964 -222.843323) (xy 450.029844 -222.871017) (xy 450.017458 -222.924078) (xy 449.997135 -222.974633)
			(xy 449.96935 -223.021503) (xy 449.93475 -223.063594) (xy 449.894143 -223.099925) (xy 449.848477 -223.129647)
			(xy 449.82384 -223.141286) (xy 449.793868 -223.154748) (xy 449.793868 -223.693207) (xy 450.555604 -223.693207)
			(xy 450.555604 -223.639909) (xy 450.563547 -223.587205) (xy 450.579257 -223.536275) (xy 450.602383 -223.488254)
			(xy 450.632407 -223.444217) (xy 450.668659 -223.405146) (xy 450.71033 -223.371915) (xy 450.756488 -223.345266)
			(xy 450.806102 -223.325794) (xy 450.858064 -223.313934) (xy 450.911214 -223.309951) (xy 450.964364 -223.313934)
			(xy 451.016326 -223.325794) (xy 451.06594 -223.345266) (xy 451.112098 -223.371915) (xy 451.153769 -223.405146)
			(xy 451.190021 -223.444217) (xy 451.220045 -223.488254) (xy 451.243171 -223.536275) (xy 451.258881 -223.587205)
			(xy 451.266824 -223.639909) (xy 451.267322 -223.666558) (xy 451.266824 -223.693207) (xy 452.765404 -223.693207)
			(xy 452.765404 -223.639909) (xy 452.773347 -223.587205) (xy 452.789057 -223.536275) (xy 452.812183 -223.488254)
			(xy 452.842207 -223.444217) (xy 452.878459 -223.405146) (xy 452.92013 -223.371915) (xy 452.966288 -223.345266)
			(xy 453.015902 -223.325794) (xy 453.067864 -223.313934) (xy 453.121014 -223.309951) (xy 453.174164 -223.313934)
			(xy 453.226126 -223.325794) (xy 453.27574 -223.345266) (xy 453.321898 -223.371915) (xy 453.363569 -223.405146)
			(xy 453.399821 -223.444217) (xy 453.429845 -223.488254) (xy 453.452971 -223.536275) (xy 453.468681 -223.587205)
			(xy 453.476624 -223.639909) (xy 453.477122 -223.666558) (xy 453.476624 -223.693207) (xy 454.655672 -223.693207)
			(xy 454.655672 -223.639909) (xy 454.663615 -223.587205) (xy 454.679325 -223.536275) (xy 454.702451 -223.488254)
			(xy 454.732475 -223.444217) (xy 454.768727 -223.405146) (xy 454.810398 -223.371915) (xy 454.856556 -223.345266)
			(xy 454.90617 -223.325794) (xy 454.958132 -223.313934) (xy 455.011282 -223.309951) (xy 455.064432 -223.313934)
			(xy 455.116394 -223.325794) (xy 455.166008 -223.345266) (xy 455.212166 -223.371915) (xy 455.253837 -223.405146)
			(xy 455.290089 -223.444217) (xy 455.320113 -223.488254) (xy 455.343239 -223.536275) (xy 455.358949 -223.587205)
			(xy 455.366892 -223.639909) (xy 455.36739 -223.666558) (xy 455.366892 -223.693207) (xy 458.099404 -223.693207)
			(xy 458.099404 -223.639909) (xy 458.107347 -223.587205) (xy 458.123057 -223.536275) (xy 458.146183 -223.488254)
			(xy 458.176207 -223.444217) (xy 458.212459 -223.405146) (xy 458.25413 -223.371915) (xy 458.300288 -223.345266)
			(xy 458.349902 -223.325794) (xy 458.401864 -223.313934) (xy 458.455014 -223.309951) (xy 458.508164 -223.313934)
			(xy 458.560126 -223.325794) (xy 458.60974 -223.345266) (xy 458.655898 -223.371915) (xy 458.697569 -223.405146)
			(xy 458.733821 -223.444217) (xy 458.763845 -223.488254) (xy 458.786971 -223.536275) (xy 458.802681 -223.587205)
			(xy 458.810624 -223.639909) (xy 458.811122 -223.666558) (xy 458.810624 -223.693207) (xy 458.802681 -223.745911)
			(xy 458.786971 -223.796841) (xy 458.763845 -223.844862) (xy 458.733821 -223.888899) (xy 458.697569 -223.92797)
			(xy 458.655898 -223.961201) (xy 458.60974 -223.98785) (xy 458.560126 -224.007322) (xy 458.508164 -224.019182)
			(xy 458.455014 -224.023166) (xy 458.401864 -224.019182) (xy 458.349902 -224.007322) (xy 458.300288 -223.98785)
			(xy 458.25413 -223.961201) (xy 458.212459 -223.92797) (xy 458.176207 -223.888899) (xy 458.146183 -223.844862)
			(xy 458.123057 -223.796841) (xy 458.107347 -223.745911) (xy 458.099404 -223.693207) (xy 455.366892 -223.693207)
			(xy 455.358949 -223.745911) (xy 455.343239 -223.796841) (xy 455.320113 -223.844862) (xy 455.290089 -223.888899)
			(xy 455.253837 -223.92797) (xy 455.212166 -223.961201) (xy 455.166008 -223.98785) (xy 455.116394 -224.007322)
			(xy 455.064432 -224.019182) (xy 455.011282 -224.023166) (xy 454.958132 -224.019182) (xy 454.90617 -224.007322)
			(xy 454.856556 -223.98785) (xy 454.810398 -223.961201) (xy 454.768727 -223.92797) (xy 454.732475 -223.888899)
			(xy 454.702451 -223.844862) (xy 454.679325 -223.796841) (xy 454.663615 -223.745911) (xy 454.655672 -223.693207)
			(xy 453.476624 -223.693207) (xy 453.468681 -223.745911) (xy 453.452971 -223.796841) (xy 453.429845 -223.844862)
			(xy 453.399821 -223.888899) (xy 453.363569 -223.92797) (xy 453.321898 -223.961201) (xy 453.27574 -223.98785)
			(xy 453.226126 -224.007322) (xy 453.174164 -224.019182) (xy 453.121014 -224.023166) (xy 453.067864 -224.019182)
			(xy 453.015902 -224.007322) (xy 452.966288 -223.98785) (xy 452.92013 -223.961201) (xy 452.878459 -223.92797)
			(xy 452.842207 -223.888899) (xy 452.812183 -223.844862) (xy 452.789057 -223.796841) (xy 452.773347 -223.745911)
			(xy 452.765404 -223.693207) (xy 451.266824 -223.693207) (xy 451.258881 -223.745911) (xy 451.243171 -223.796841)
			(xy 451.220045 -223.844862) (xy 451.190021 -223.888899) (xy 451.153769 -223.92797) (xy 451.112098 -223.961201)
			(xy 451.06594 -223.98785) (xy 451.016326 -224.007322) (xy 450.964364 -224.019182) (xy 450.911214 -224.023166)
			(xy 450.858064 -224.019182) (xy 450.806102 -224.007322) (xy 450.756488 -223.98785) (xy 450.71033 -223.961201)
			(xy 450.668659 -223.92797) (xy 450.632407 -223.888899) (xy 450.602383 -223.844862) (xy 450.579257 -223.796841)
			(xy 450.563547 -223.745911) (xy 450.555604 -223.693207) (xy 449.793868 -223.693207) (xy 449.793868 -224.178622)
			(xy 449.82384 -224.192084) (xy 449.848456 -224.203765) (xy 449.894121 -224.233483) (xy 449.934727 -224.269811)
			(xy 449.969326 -224.311898) (xy 449.997112 -224.358765) (xy 450.017435 -224.409316) (xy 450.029822 -224.462374)
			(xy 450.033983 -224.516698) (xy 450.031942 -224.543345) (xy 450.555604 -224.543345) (xy 450.555604 -224.490047)
			(xy 450.563547 -224.437343) (xy 450.579257 -224.386413) (xy 450.602383 -224.338392) (xy 450.632407 -224.294355)
			(xy 450.668659 -224.255284) (xy 450.71033 -224.222053) (xy 450.756488 -224.195404) (xy 450.806102 -224.175932)
			(xy 450.858064 -224.164072) (xy 450.911214 -224.160089) (xy 450.964364 -224.164072) (xy 451.016326 -224.175932)
			(xy 451.06594 -224.195404) (xy 451.112098 -224.222053) (xy 451.153769 -224.255284) (xy 451.190021 -224.294355)
			(xy 451.220045 -224.338392) (xy 451.243171 -224.386413) (xy 451.258881 -224.437343) (xy 451.266824 -224.490047)
			(xy 451.267322 -224.516696) (xy 451.266824 -224.543345) (xy 454.655672 -224.543345) (xy 454.655672 -224.490047)
			(xy 454.663615 -224.437343) (xy 454.679325 -224.386413) (xy 454.702451 -224.338392) (xy 454.732475 -224.294355)
			(xy 454.768727 -224.255284) (xy 454.810398 -224.222053) (xy 454.856556 -224.195404) (xy 454.90617 -224.175932)
			(xy 454.958132 -224.164072) (xy 455.011282 -224.160089) (xy 455.064432 -224.164072) (xy 455.116394 -224.175932)
			(xy 455.166008 -224.195404) (xy 455.212166 -224.222053) (xy 455.253837 -224.255284) (xy 455.290089 -224.294355)
			(xy 455.320113 -224.338392) (xy 455.343239 -224.386413) (xy 455.358949 -224.437343) (xy 455.366892 -224.490047)
			(xy 455.36739 -224.516696) (xy 455.366892 -224.543345) (xy 456.865472 -224.543345) (xy 456.865472 -224.490047)
			(xy 456.873415 -224.437343) (xy 456.889125 -224.386413) (xy 456.912251 -224.338392) (xy 456.942275 -224.294355)
			(xy 456.978527 -224.255284) (xy 457.020198 -224.222053) (xy 457.066356 -224.195404) (xy 457.11597 -224.175932)
			(xy 457.167932 -224.164072) (xy 457.221082 -224.160089) (xy 457.274232 -224.164072) (xy 457.326194 -224.175932)
			(xy 457.375808 -224.195404) (xy 457.421966 -224.222053) (xy 457.463637 -224.255284) (xy 457.499889 -224.294355)
			(xy 457.529913 -224.338392) (xy 457.553039 -224.386413) (xy 457.568749 -224.437343) (xy 457.576692 -224.490047)
			(xy 457.57719 -224.516696) (xy 457.576692 -224.543345) (xy 457.568749 -224.596049) (xy 457.553039 -224.646979)
			(xy 457.529913 -224.695) (xy 457.499889 -224.739037) (xy 457.463637 -224.778108) (xy 457.421966 -224.811339)
			(xy 457.375808 -224.837988) (xy 457.326194 -224.85746) (xy 457.274232 -224.86932) (xy 457.221082 -224.873304)
			(xy 457.167932 -224.86932) (xy 457.11597 -224.85746) (xy 457.066356 -224.837988) (xy 457.020198 -224.811339)
			(xy 456.978527 -224.778108) (xy 456.942275 -224.739037) (xy 456.912251 -224.695) (xy 456.889125 -224.646979)
			(xy 456.873415 -224.596049) (xy 456.865472 -224.543345) (xy 455.366892 -224.543345) (xy 455.358949 -224.596049)
			(xy 455.343239 -224.646979) (xy 455.320113 -224.695) (xy 455.290089 -224.739037) (xy 455.253837 -224.778108)
			(xy 455.212166 -224.811339) (xy 455.166008 -224.837988) (xy 455.116394 -224.85746) (xy 455.064432 -224.86932)
			(xy 455.011282 -224.873304) (xy 454.958132 -224.86932) (xy 454.90617 -224.85746) (xy 454.856556 -224.837988)
			(xy 454.810398 -224.811339) (xy 454.768727 -224.778108) (xy 454.732475 -224.739037) (xy 454.702451 -224.695)
			(xy 454.679325 -224.646979) (xy 454.663615 -224.596049) (xy 454.655672 -224.543345) (xy 451.266824 -224.543345)
			(xy 451.258881 -224.596049) (xy 451.243171 -224.646979) (xy 451.220045 -224.695) (xy 451.190021 -224.739037)
			(xy 451.153769 -224.778108) (xy 451.112098 -224.811339) (xy 451.06594 -224.837988) (xy 451.016326 -224.85746)
			(xy 450.964364 -224.86932) (xy 450.911214 -224.873304) (xy 450.858064 -224.86932) (xy 450.806102 -224.85746)
			(xy 450.756488 -224.837988) (xy 450.71033 -224.811339) (xy 450.668659 -224.778108) (xy 450.632407 -224.739037)
			(xy 450.602383 -224.695) (xy 450.579257 -224.646979) (xy 450.563547 -224.596049) (xy 450.555604 -224.543345)
			(xy 450.031942 -224.543345) (xy 450.029822 -224.571023) (xy 450.017436 -224.62408) (xy 449.997113 -224.674632)
			(xy 449.969328 -224.721499) (xy 449.934729 -224.763587) (xy 449.894124 -224.799915) (xy 449.848459 -224.829634)
			(xy 449.82384 -224.841308) (xy 449.793868 -224.85477) (xy 449.793868 -225.393229) (xy 450.555604 -225.393229)
			(xy 450.555604 -225.339931) (xy 450.563547 -225.287227) (xy 450.579257 -225.236297) (xy 450.602383 -225.188276)
			(xy 450.632407 -225.144239) (xy 450.668659 -225.105168) (xy 450.71033 -225.071937) (xy 450.756488 -225.045288)
			(xy 450.806102 -225.025816) (xy 450.858064 -225.013956) (xy 450.911214 -225.009973) (xy 450.964364 -225.013956)
			(xy 451.016326 -225.025816) (xy 451.06594 -225.045288) (xy 451.112098 -225.071937) (xy 451.153769 -225.105168)
			(xy 451.190021 -225.144239) (xy 451.220045 -225.188276) (xy 451.243171 -225.236297) (xy 451.258881 -225.287227)
			(xy 451.266824 -225.339931) (xy 451.267322 -225.36658) (xy 451.266824 -225.393229) (xy 452.765404 -225.393229)
			(xy 452.765404 -225.339931) (xy 452.773347 -225.287227) (xy 452.789057 -225.236297) (xy 452.812183 -225.188276)
			(xy 452.842207 -225.144239) (xy 452.878459 -225.105168) (xy 452.92013 -225.071937) (xy 452.966288 -225.045288)
			(xy 453.015902 -225.025816) (xy 453.067864 -225.013956) (xy 453.121014 -225.009973) (xy 453.174164 -225.013956)
			(xy 453.226126 -225.025816) (xy 453.27574 -225.045288) (xy 453.321898 -225.071937) (xy 453.363569 -225.105168)
			(xy 453.399821 -225.144239) (xy 453.429845 -225.188276) (xy 453.452971 -225.236297) (xy 453.468681 -225.287227)
			(xy 453.476624 -225.339931) (xy 453.477122 -225.36658) (xy 453.476624 -225.393229) (xy 454.655672 -225.393229)
			(xy 454.655672 -225.339931) (xy 454.663615 -225.287227) (xy 454.679325 -225.236297) (xy 454.702451 -225.188276)
			(xy 454.732475 -225.144239) (xy 454.768727 -225.105168) (xy 454.810398 -225.071937) (xy 454.856556 -225.045288)
			(xy 454.90617 -225.025816) (xy 454.958132 -225.013956) (xy 455.011282 -225.009973) (xy 455.064432 -225.013956)
			(xy 455.116394 -225.025816) (xy 455.166008 -225.045288) (xy 455.212166 -225.071937) (xy 455.253837 -225.105168)
			(xy 455.290089 -225.144239) (xy 455.320113 -225.188276) (xy 455.343239 -225.236297) (xy 455.358949 -225.287227)
			(xy 455.366892 -225.339931) (xy 455.36739 -225.36658) (xy 455.366892 -225.393229) (xy 458.099404 -225.393229)
			(xy 458.099404 -225.339931) (xy 458.107347 -225.287227) (xy 458.123057 -225.236297) (xy 458.146183 -225.188276)
			(xy 458.176207 -225.144239) (xy 458.212459 -225.105168) (xy 458.25413 -225.071937) (xy 458.300288 -225.045288)
			(xy 458.349902 -225.025816) (xy 458.401864 -225.013956) (xy 458.455014 -225.009973) (xy 458.508164 -225.013956)
			(xy 458.560126 -225.025816) (xy 458.60974 -225.045288) (xy 458.655898 -225.071937) (xy 458.697569 -225.105168)
			(xy 458.733821 -225.144239) (xy 458.763845 -225.188276) (xy 458.786971 -225.236297) (xy 458.802681 -225.287227)
			(xy 458.810624 -225.339931) (xy 458.811122 -225.36658) (xy 458.810624 -225.393229) (xy 458.802681 -225.445933)
			(xy 458.786971 -225.496863) (xy 458.763845 -225.544884) (xy 458.733821 -225.588921) (xy 458.697569 -225.627992)
			(xy 458.655898 -225.661223) (xy 458.60974 -225.687872) (xy 458.560126 -225.707344) (xy 458.508164 -225.719204)
			(xy 458.455014 -225.723188) (xy 458.401864 -225.719204) (xy 458.349902 -225.707344) (xy 458.300288 -225.687872)
			(xy 458.25413 -225.661223) (xy 458.212459 -225.627992) (xy 458.176207 -225.588921) (xy 458.146183 -225.544884)
			(xy 458.123057 -225.496863) (xy 458.107347 -225.445933) (xy 458.099404 -225.393229) (xy 455.366892 -225.393229)
			(xy 455.358949 -225.445933) (xy 455.343239 -225.496863) (xy 455.320113 -225.544884) (xy 455.290089 -225.588921)
			(xy 455.253837 -225.627992) (xy 455.212166 -225.661223) (xy 455.166008 -225.687872) (xy 455.116394 -225.707344)
			(xy 455.064432 -225.719204) (xy 455.011282 -225.723188) (xy 454.958132 -225.719204) (xy 454.90617 -225.707344)
			(xy 454.856556 -225.687872) (xy 454.810398 -225.661223) (xy 454.768727 -225.627992) (xy 454.732475 -225.588921)
			(xy 454.702451 -225.544884) (xy 454.679325 -225.496863) (xy 454.663615 -225.445933) (xy 454.655672 -225.393229)
			(xy 453.476624 -225.393229) (xy 453.468681 -225.445933) (xy 453.452971 -225.496863) (xy 453.429845 -225.544884)
			(xy 453.399821 -225.588921) (xy 453.363569 -225.627992) (xy 453.321898 -225.661223) (xy 453.27574 -225.687872)
			(xy 453.226126 -225.707344) (xy 453.174164 -225.719204) (xy 453.121014 -225.723188) (xy 453.067864 -225.719204)
			(xy 453.015902 -225.707344) (xy 452.966288 -225.687872) (xy 452.92013 -225.661223) (xy 452.878459 -225.627992)
			(xy 452.842207 -225.588921) (xy 452.812183 -225.544884) (xy 452.789057 -225.496863) (xy 452.773347 -225.445933)
			(xy 452.765404 -225.393229) (xy 451.266824 -225.393229) (xy 451.258881 -225.445933) (xy 451.243171 -225.496863)
			(xy 451.220045 -225.544884) (xy 451.190021 -225.588921) (xy 451.153769 -225.627992) (xy 451.112098 -225.661223)
			(xy 451.06594 -225.687872) (xy 451.016326 -225.707344) (xy 450.964364 -225.719204) (xy 450.911214 -225.723188)
			(xy 450.858064 -225.719204) (xy 450.806102 -225.707344) (xy 450.756488 -225.687872) (xy 450.71033 -225.661223)
			(xy 450.668659 -225.627992) (xy 450.632407 -225.588921) (xy 450.602383 -225.544884) (xy 450.579257 -225.496863)
			(xy 450.563547 -225.445933) (xy 450.555604 -225.393229) (xy 449.793868 -225.393229) (xy 449.793868 -225.878644)
			(xy 449.82384 -225.892106) (xy 449.848455 -225.903786) (xy 449.894116 -225.933505) (xy 449.934719 -225.969831)
			(xy 449.969315 -226.011917) (xy 449.997098 -226.058782) (xy 450.017419 -226.109331) (xy 450.029803 -226.162386)
			(xy 450.033963 -226.216707) (xy 450.03192 -226.243367) (xy 450.555604 -226.243367) (xy 450.555604 -226.190069)
			(xy 450.563547 -226.137365) (xy 450.579257 -226.086435) (xy 450.602383 -226.038414) (xy 450.632407 -225.994377)
			(xy 450.668659 -225.955306) (xy 450.71033 -225.922075) (xy 450.756488 -225.895426) (xy 450.806102 -225.875954)
			(xy 450.858064 -225.864094) (xy 450.911214 -225.860111) (xy 450.964364 -225.864094) (xy 451.016326 -225.875954)
			(xy 451.06594 -225.895426) (xy 451.112098 -225.922075) (xy 451.153769 -225.955306) (xy 451.190021 -225.994377)
			(xy 451.220045 -226.038414) (xy 451.243171 -226.086435) (xy 451.258881 -226.137365) (xy 451.266824 -226.190069)
			(xy 451.267322 -226.216718) (xy 451.266824 -226.243367) (xy 454.655672 -226.243367) (xy 454.655672 -226.190069)
			(xy 454.663615 -226.137365) (xy 454.679325 -226.086435) (xy 454.702451 -226.038414) (xy 454.732475 -225.994377)
			(xy 454.768727 -225.955306) (xy 454.810398 -225.922075) (xy 454.856556 -225.895426) (xy 454.90617 -225.875954)
			(xy 454.958132 -225.864094) (xy 455.011282 -225.860111) (xy 455.064432 -225.864094) (xy 455.116394 -225.875954)
			(xy 455.166008 -225.895426) (xy 455.212166 -225.922075) (xy 455.253837 -225.955306) (xy 455.290089 -225.994377)
			(xy 455.320113 -226.038414) (xy 455.343239 -226.086435) (xy 455.358949 -226.137365) (xy 455.366892 -226.190069)
			(xy 455.36739 -226.216718) (xy 455.366892 -226.243367) (xy 456.865472 -226.243367) (xy 456.865472 -226.190069)
			(xy 456.873415 -226.137365) (xy 456.889125 -226.086435) (xy 456.912251 -226.038414) (xy 456.942275 -225.994377)
			(xy 456.978527 -225.955306) (xy 457.020198 -225.922075) (xy 457.066356 -225.895426) (xy 457.11597 -225.875954)
			(xy 457.167932 -225.864094) (xy 457.221082 -225.860111) (xy 457.274232 -225.864094) (xy 457.326194 -225.875954)
			(xy 457.375808 -225.895426) (xy 457.421966 -225.922075) (xy 457.463637 -225.955306) (xy 457.499889 -225.994377)
			(xy 457.529913 -226.038414) (xy 457.553039 -226.086435) (xy 457.568749 -226.137365) (xy 457.576692 -226.190069)
			(xy 457.57719 -226.216718) (xy 457.576692 -226.243367) (xy 457.568749 -226.296071) (xy 457.553039 -226.347001)
			(xy 457.529913 -226.395022) (xy 457.499889 -226.439059) (xy 457.463637 -226.47813) (xy 457.421966 -226.511361)
			(xy 457.375808 -226.53801) (xy 457.326194 -226.557482) (xy 457.274232 -226.569342) (xy 457.221082 -226.573326)
			(xy 457.167932 -226.569342) (xy 457.11597 -226.557482) (xy 457.066356 -226.53801) (xy 457.020198 -226.511361)
			(xy 456.978527 -226.47813) (xy 456.942275 -226.439059) (xy 456.912251 -226.395022) (xy 456.889125 -226.347001)
			(xy 456.873415 -226.296071) (xy 456.865472 -226.243367) (xy 455.366892 -226.243367) (xy 455.358949 -226.296071)
			(xy 455.343239 -226.347001) (xy 455.320113 -226.395022) (xy 455.290089 -226.439059) (xy 455.253837 -226.47813)
			(xy 455.212166 -226.511361) (xy 455.166008 -226.53801) (xy 455.116394 -226.557482) (xy 455.064432 -226.569342)
			(xy 455.011282 -226.573326) (xy 454.958132 -226.569342) (xy 454.90617 -226.557482) (xy 454.856556 -226.53801)
			(xy 454.810398 -226.511361) (xy 454.768727 -226.47813) (xy 454.732475 -226.439059) (xy 454.702451 -226.395022)
			(xy 454.679325 -226.347001) (xy 454.663615 -226.296071) (xy 454.655672 -226.243367) (xy 451.266824 -226.243367)
			(xy 451.258881 -226.296071) (xy 451.243171 -226.347001) (xy 451.220045 -226.395022) (xy 451.190021 -226.439059)
			(xy 451.153769 -226.47813) (xy 451.112098 -226.511361) (xy 451.06594 -226.53801) (xy 451.016326 -226.557482)
			(xy 450.964364 -226.569342) (xy 450.911214 -226.573326) (xy 450.858064 -226.569342) (xy 450.806102 -226.557482)
			(xy 450.756488 -226.53801) (xy 450.71033 -226.511361) (xy 450.668659 -226.47813) (xy 450.632407 -226.439059)
			(xy 450.602383 -226.395022) (xy 450.579257 -226.347001) (xy 450.563547 -226.296071) (xy 450.555604 -226.243367)
			(xy 450.03192 -226.243367) (xy 450.029801 -226.271029) (xy 450.017414 -226.324083) (xy 449.997091 -226.374631)
			(xy 449.969307 -226.421495) (xy 449.934709 -226.46358) (xy 449.894104 -226.499904) (xy 449.848442 -226.529621)
			(xy 449.82384 -226.54133) (xy 449.793868 -226.554792) (xy 449.793868 -227.093251) (xy 450.555604 -227.093251)
			(xy 450.555604 -227.039953) (xy 450.563547 -226.987249) (xy 450.579257 -226.936319) (xy 450.602383 -226.888298)
			(xy 450.632407 -226.844261) (xy 450.668659 -226.80519) (xy 450.71033 -226.771959) (xy 450.756488 -226.74531)
			(xy 450.806102 -226.725838) (xy 450.858064 -226.713978) (xy 450.911214 -226.709995) (xy 450.964364 -226.713978)
			(xy 451.016326 -226.725838) (xy 451.06594 -226.74531) (xy 451.112098 -226.771959) (xy 451.153769 -226.80519)
			(xy 451.190021 -226.844261) (xy 451.220045 -226.888298) (xy 451.243171 -226.936319) (xy 451.258881 -226.987249)
			(xy 451.266824 -227.039953) (xy 451.267322 -227.066602) (xy 451.266824 -227.093251) (xy 452.765404 -227.093251)
			(xy 452.765404 -227.039953) (xy 452.773347 -226.987249) (xy 452.789057 -226.936319) (xy 452.812183 -226.888298)
			(xy 452.842207 -226.844261) (xy 452.878459 -226.80519) (xy 452.92013 -226.771959) (xy 452.966288 -226.74531)
			(xy 453.015902 -226.725838) (xy 453.067864 -226.713978) (xy 453.121014 -226.709995) (xy 453.174164 -226.713978)
			(xy 453.226126 -226.725838) (xy 453.27574 -226.74531) (xy 453.321898 -226.771959) (xy 453.363569 -226.80519)
			(xy 453.399821 -226.844261) (xy 453.429845 -226.888298) (xy 453.452971 -226.936319) (xy 453.468681 -226.987249)
			(xy 453.476624 -227.039953) (xy 453.477122 -227.066602) (xy 453.476624 -227.093251) (xy 454.655672 -227.093251)
			(xy 454.655672 -227.039953) (xy 454.663615 -226.987249) (xy 454.679325 -226.936319) (xy 454.702451 -226.888298)
			(xy 454.732475 -226.844261) (xy 454.768727 -226.80519) (xy 454.810398 -226.771959) (xy 454.856556 -226.74531)
			(xy 454.90617 -226.725838) (xy 454.958132 -226.713978) (xy 455.011282 -226.709995) (xy 455.064432 -226.713978)
			(xy 455.116394 -226.725838) (xy 455.166008 -226.74531) (xy 455.212166 -226.771959) (xy 455.253837 -226.80519)
			(xy 455.290089 -226.844261) (xy 455.320113 -226.888298) (xy 455.343239 -226.936319) (xy 455.358949 -226.987249)
			(xy 455.366892 -227.039953) (xy 455.36739 -227.066602) (xy 455.366892 -227.093251) (xy 458.099404 -227.093251)
			(xy 458.099404 -227.039953) (xy 458.107347 -226.987249) (xy 458.123057 -226.936319) (xy 458.146183 -226.888298)
			(xy 458.176207 -226.844261) (xy 458.212459 -226.80519) (xy 458.25413 -226.771959) (xy 458.300288 -226.74531)
			(xy 458.349902 -226.725838) (xy 458.401864 -226.713978) (xy 458.455014 -226.709995) (xy 458.508164 -226.713978)
			(xy 458.560126 -226.725838) (xy 458.60974 -226.74531) (xy 458.655898 -226.771959) (xy 458.697569 -226.80519)
			(xy 458.733821 -226.844261) (xy 458.763845 -226.888298) (xy 458.786971 -226.936319) (xy 458.802681 -226.987249)
			(xy 458.810624 -227.039953) (xy 458.811122 -227.066602) (xy 458.810624 -227.093251) (xy 458.802681 -227.145955)
			(xy 458.786971 -227.196885) (xy 458.763845 -227.244906) (xy 458.733821 -227.288943) (xy 458.697569 -227.328014)
			(xy 458.655898 -227.361245) (xy 458.60974 -227.387894) (xy 458.560126 -227.407366) (xy 458.508164 -227.419226)
			(xy 458.455014 -227.42321) (xy 458.401864 -227.419226) (xy 458.349902 -227.407366) (xy 458.300288 -227.387894)
			(xy 458.25413 -227.361245) (xy 458.212459 -227.328014) (xy 458.176207 -227.288943) (xy 458.146183 -227.244906)
			(xy 458.123057 -227.196885) (xy 458.107347 -227.145955) (xy 458.099404 -227.093251) (xy 455.366892 -227.093251)
			(xy 455.358949 -227.145955) (xy 455.343239 -227.196885) (xy 455.320113 -227.244906) (xy 455.290089 -227.288943)
			(xy 455.253837 -227.328014) (xy 455.212166 -227.361245) (xy 455.166008 -227.387894) (xy 455.116394 -227.407366)
			(xy 455.064432 -227.419226) (xy 455.011282 -227.42321) (xy 454.958132 -227.419226) (xy 454.90617 -227.407366)
			(xy 454.856556 -227.387894) (xy 454.810398 -227.361245) (xy 454.768727 -227.328014) (xy 454.732475 -227.288943)
			(xy 454.702451 -227.244906) (xy 454.679325 -227.196885) (xy 454.663615 -227.145955) (xy 454.655672 -227.093251)
			(xy 453.476624 -227.093251) (xy 453.468681 -227.145955) (xy 453.452971 -227.196885) (xy 453.429845 -227.244906)
			(xy 453.399821 -227.288943) (xy 453.363569 -227.328014) (xy 453.321898 -227.361245) (xy 453.27574 -227.387894)
			(xy 453.226126 -227.407366) (xy 453.174164 -227.419226) (xy 453.121014 -227.42321) (xy 453.067864 -227.419226)
			(xy 453.015902 -227.407366) (xy 452.966288 -227.387894) (xy 452.92013 -227.361245) (xy 452.878459 -227.328014)
			(xy 452.842207 -227.288943) (xy 452.812183 -227.244906) (xy 452.789057 -227.196885) (xy 452.773347 -227.145955)
			(xy 452.765404 -227.093251) (xy 451.266824 -227.093251) (xy 451.258881 -227.145955) (xy 451.243171 -227.196885)
			(xy 451.220045 -227.244906) (xy 451.190021 -227.288943) (xy 451.153769 -227.328014) (xy 451.112098 -227.361245)
			(xy 451.06594 -227.387894) (xy 451.016326 -227.407366) (xy 450.964364 -227.419226) (xy 450.911214 -227.42321)
			(xy 450.858064 -227.419226) (xy 450.806102 -227.407366) (xy 450.756488 -227.387894) (xy 450.71033 -227.361245)
			(xy 450.668659 -227.328014) (xy 450.632407 -227.288943) (xy 450.602383 -227.244906) (xy 450.579257 -227.196885)
			(xy 450.563547 -227.145955) (xy 450.555604 -227.093251) (xy 449.793868 -227.093251) (xy 449.793868 -227.943389)
			(xy 450.555604 -227.943389) (xy 450.555604 -227.890091) (xy 450.563547 -227.837387) (xy 450.579257 -227.786457)
			(xy 450.602383 -227.738436) (xy 450.632407 -227.694399) (xy 450.668659 -227.655328) (xy 450.71033 -227.622097)
			(xy 450.756488 -227.595448) (xy 450.806102 -227.575976) (xy 450.858064 -227.564116) (xy 450.911214 -227.560133)
			(xy 450.964364 -227.564116) (xy 451.016326 -227.575976) (xy 451.06594 -227.595448) (xy 451.112098 -227.622097)
			(xy 451.153769 -227.655328) (xy 451.190021 -227.694399) (xy 451.220045 -227.738436) (xy 451.243171 -227.786457)
			(xy 451.258881 -227.837387) (xy 451.266824 -227.890091) (xy 451.267322 -227.91674) (xy 451.266824 -227.943389)
			(xy 454.655672 -227.943389) (xy 454.655672 -227.890091) (xy 454.663615 -227.837387) (xy 454.679325 -227.786457)
			(xy 454.702451 -227.738436) (xy 454.732475 -227.694399) (xy 454.768727 -227.655328) (xy 454.810398 -227.622097)
			(xy 454.856556 -227.595448) (xy 454.90617 -227.575976) (xy 454.958132 -227.564116) (xy 455.011282 -227.560133)
			(xy 455.064432 -227.564116) (xy 455.116394 -227.575976) (xy 455.166008 -227.595448) (xy 455.212166 -227.622097)
			(xy 455.253837 -227.655328) (xy 455.290089 -227.694399) (xy 455.320113 -227.738436) (xy 455.343239 -227.786457)
			(xy 455.358949 -227.837387) (xy 455.366892 -227.890091) (xy 455.36739 -227.91674) (xy 455.366892 -227.943389)
			(xy 455.358949 -227.996093) (xy 455.343239 -228.047023) (xy 455.320113 -228.095044) (xy 455.290089 -228.139081)
			(xy 455.253837 -228.178152) (xy 455.212166 -228.211383) (xy 455.166008 -228.238032) (xy 455.116394 -228.257504)
			(xy 455.064432 -228.269364) (xy 455.011282 -228.273348) (xy 454.958132 -228.269364) (xy 454.90617 -228.257504)
			(xy 454.856556 -228.238032) (xy 454.810398 -228.211383) (xy 454.768727 -228.178152) (xy 454.732475 -228.139081)
			(xy 454.702451 -228.095044) (xy 454.679325 -228.047023) (xy 454.663615 -227.996093) (xy 454.655672 -227.943389)
			(xy 451.266824 -227.943389) (xy 451.258881 -227.996093) (xy 451.243171 -228.047023) (xy 451.220045 -228.095044)
			(xy 451.190021 -228.139081) (xy 451.153769 -228.178152) (xy 451.112098 -228.211383) (xy 451.06594 -228.238032)
			(xy 451.016326 -228.257504) (xy 450.964364 -228.269364) (xy 450.911214 -228.273348) (xy 450.858064 -228.269364)
			(xy 450.806102 -228.257504) (xy 450.756488 -228.238032) (xy 450.71033 -228.211383) (xy 450.668659 -228.178152)
			(xy 450.632407 -228.139081) (xy 450.602383 -228.095044) (xy 450.579257 -228.047023) (xy 450.563547 -227.996093)
			(xy 450.555604 -227.943389) (xy 449.793868 -227.943389) (xy 449.793868 -228.42855) (xy 449.82384 -228.442012)
			(xy 449.848454 -228.453692) (xy 449.894115 -228.483411) (xy 449.934717 -228.519737) (xy 449.969312 -228.561822)
			(xy 449.997094 -228.608687) (xy 450.017414 -228.659235) (xy 450.029798 -228.712289) (xy 450.033958 -228.76661)
			(xy 450.031915 -228.793273) (xy 450.555604 -228.793273) (xy 450.555604 -228.739975) (xy 450.563547 -228.687271)
			(xy 450.579257 -228.636341) (xy 450.602383 -228.58832) (xy 450.632407 -228.544283) (xy 450.668659 -228.505212)
			(xy 450.71033 -228.471981) (xy 450.756488 -228.445332) (xy 450.806102 -228.42586) (xy 450.858064 -228.414)
			(xy 450.911214 -228.410017) (xy 450.964364 -228.414) (xy 451.016326 -228.42586) (xy 451.06594 -228.445332)
			(xy 451.112098 -228.471981) (xy 451.153769 -228.505212) (xy 451.190021 -228.544283) (xy 451.220045 -228.58832)
			(xy 451.243171 -228.636341) (xy 451.258881 -228.687271) (xy 451.266824 -228.739975) (xy 451.267322 -228.766624)
			(xy 451.266824 -228.793273) (xy 454.655672 -228.793273) (xy 454.655672 -228.739975) (xy 454.663615 -228.687271)
			(xy 454.679325 -228.636341) (xy 454.702451 -228.58832) (xy 454.732475 -228.544283) (xy 454.768727 -228.505212)
			(xy 454.810398 -228.471981) (xy 454.856556 -228.445332) (xy 454.90617 -228.42586) (xy 454.958132 -228.414)
			(xy 455.011282 -228.410017) (xy 455.064432 -228.414) (xy 455.116394 -228.42586) (xy 455.166008 -228.445332)
			(xy 455.212166 -228.471981) (xy 455.253837 -228.505212) (xy 455.290089 -228.544283) (xy 455.320113 -228.58832)
			(xy 455.343239 -228.636341) (xy 455.358949 -228.687271) (xy 455.366892 -228.739975) (xy 455.36739 -228.766624)
			(xy 455.366892 -228.793273) (xy 456.865472 -228.793273) (xy 456.865472 -228.739975) (xy 456.873415 -228.687271)
			(xy 456.889125 -228.636341) (xy 456.912251 -228.58832) (xy 456.942275 -228.544283) (xy 456.978527 -228.505212)
			(xy 457.020198 -228.471981) (xy 457.066356 -228.445332) (xy 457.11597 -228.42586) (xy 457.167932 -228.414)
			(xy 457.221082 -228.410017) (xy 457.274232 -228.414) (xy 457.326194 -228.42586) (xy 457.375808 -228.445332)
			(xy 457.421966 -228.471981) (xy 457.463637 -228.505212) (xy 457.499889 -228.544283) (xy 457.529913 -228.58832)
			(xy 457.553039 -228.636341) (xy 457.568749 -228.687271) (xy 457.576692 -228.739975) (xy 457.57719 -228.766624)
			(xy 457.576692 -228.793273) (xy 457.568749 -228.845977) (xy 457.553039 -228.896907) (xy 457.529913 -228.944928)
			(xy 457.499889 -228.988965) (xy 457.463637 -229.028036) (xy 457.421966 -229.061267) (xy 457.375808 -229.087916)
			(xy 457.326194 -229.107388) (xy 457.274232 -229.119248) (xy 457.221082 -229.123232) (xy 457.167932 -229.119248)
			(xy 457.11597 -229.107388) (xy 457.066356 -229.087916) (xy 457.020198 -229.061267) (xy 456.978527 -229.028036)
			(xy 456.942275 -228.988965) (xy 456.912251 -228.944928) (xy 456.889125 -228.896907) (xy 456.873415 -228.845977)
			(xy 456.865472 -228.793273) (xy 455.366892 -228.793273) (xy 455.358949 -228.845977) (xy 455.343239 -228.896907)
			(xy 455.320113 -228.944928) (xy 455.290089 -228.988965) (xy 455.253837 -229.028036) (xy 455.212166 -229.061267)
			(xy 455.166008 -229.087916) (xy 455.116394 -229.107388) (xy 455.064432 -229.119248) (xy 455.011282 -229.123232)
			(xy 454.958132 -229.119248) (xy 454.90617 -229.107388) (xy 454.856556 -229.087916) (xy 454.810398 -229.061267)
			(xy 454.768727 -229.028036) (xy 454.732475 -228.988965) (xy 454.702451 -228.944928) (xy 454.679325 -228.896907)
			(xy 454.663615 -228.845977) (xy 454.655672 -228.793273) (xy 451.266824 -228.793273) (xy 451.258881 -228.845977)
			(xy 451.243171 -228.896907) (xy 451.220045 -228.944928) (xy 451.190021 -228.988965) (xy 451.153769 -229.028036)
			(xy 451.112098 -229.061267) (xy 451.06594 -229.087916) (xy 451.016326 -229.107388) (xy 450.964364 -229.119248)
			(xy 450.911214 -229.123232) (xy 450.858064 -229.119248) (xy 450.806102 -229.107388) (xy 450.756488 -229.087916)
			(xy 450.71033 -229.061267) (xy 450.668659 -229.028036) (xy 450.632407 -228.988965) (xy 450.602383 -228.944928)
			(xy 450.579257 -228.896907) (xy 450.563547 -228.845977) (xy 450.555604 -228.793273) (xy 450.031915 -228.793273)
			(xy 450.029795 -228.820931) (xy 450.017408 -228.873984) (xy 449.997085 -228.924531) (xy 449.969301 -228.971394)
			(xy 449.934703 -229.013478) (xy 449.894099 -229.049801) (xy 449.848437 -229.079517) (xy 449.82384 -229.091236)
			(xy 449.793868 -229.104698) (xy 449.793868 -229.643411) (xy 450.555604 -229.643411) (xy 450.555604 -229.590113)
			(xy 450.563547 -229.537409) (xy 450.579257 -229.486479) (xy 450.602383 -229.438458) (xy 450.632407 -229.394421)
			(xy 450.668659 -229.35535) (xy 450.71033 -229.322119) (xy 450.756488 -229.29547) (xy 450.806102 -229.275998)
			(xy 450.858064 -229.264138) (xy 450.911214 -229.260155) (xy 450.964364 -229.264138) (xy 451.016326 -229.275998)
			(xy 451.06594 -229.29547) (xy 451.112098 -229.322119) (xy 451.153769 -229.35535) (xy 451.190021 -229.394421)
			(xy 451.220045 -229.438458) (xy 451.243171 -229.486479) (xy 451.258881 -229.537409) (xy 451.266824 -229.590113)
			(xy 451.267322 -229.616762) (xy 451.266824 -229.643411) (xy 452.765404 -229.643411) (xy 452.765404 -229.590113)
			(xy 452.773347 -229.537409) (xy 452.789057 -229.486479) (xy 452.812183 -229.438458) (xy 452.842207 -229.394421)
			(xy 452.878459 -229.35535) (xy 452.92013 -229.322119) (xy 452.966288 -229.29547) (xy 453.015902 -229.275998)
			(xy 453.067864 -229.264138) (xy 453.121014 -229.260155) (xy 453.174164 -229.264138) (xy 453.226126 -229.275998)
			(xy 453.27574 -229.29547) (xy 453.321898 -229.322119) (xy 453.363569 -229.35535) (xy 453.399821 -229.394421)
			(xy 453.429845 -229.438458) (xy 453.452971 -229.486479) (xy 453.468681 -229.537409) (xy 453.476624 -229.590113)
			(xy 453.477122 -229.616762) (xy 453.476624 -229.643411) (xy 454.655672 -229.643411) (xy 454.655672 -229.590113)
			(xy 454.663615 -229.537409) (xy 454.679325 -229.486479) (xy 454.702451 -229.438458) (xy 454.732475 -229.394421)
			(xy 454.768727 -229.35535) (xy 454.810398 -229.322119) (xy 454.856556 -229.29547) (xy 454.90617 -229.275998)
			(xy 454.958132 -229.264138) (xy 455.011282 -229.260155) (xy 455.064432 -229.264138) (xy 455.116394 -229.275998)
			(xy 455.166008 -229.29547) (xy 455.212166 -229.322119) (xy 455.253837 -229.35535) (xy 455.290089 -229.394421)
			(xy 455.320113 -229.438458) (xy 455.343239 -229.486479) (xy 455.358949 -229.537409) (xy 455.366892 -229.590113)
			(xy 455.36739 -229.616762) (xy 455.366892 -229.643411) (xy 458.099404 -229.643411) (xy 458.099404 -229.590113)
			(xy 458.107347 -229.537409) (xy 458.123057 -229.486479) (xy 458.146183 -229.438458) (xy 458.176207 -229.394421)
			(xy 458.212459 -229.35535) (xy 458.25413 -229.322119) (xy 458.300288 -229.29547) (xy 458.349902 -229.275998)
			(xy 458.401864 -229.264138) (xy 458.455014 -229.260155) (xy 458.508164 -229.264138) (xy 458.560126 -229.275998)
			(xy 458.60974 -229.29547) (xy 458.655898 -229.322119) (xy 458.697569 -229.35535) (xy 458.733821 -229.394421)
			(xy 458.763845 -229.438458) (xy 458.786971 -229.486479) (xy 458.802681 -229.537409) (xy 458.810624 -229.590113)
			(xy 458.811122 -229.616762) (xy 458.810624 -229.643411) (xy 458.802681 -229.696115) (xy 458.786971 -229.747045)
			(xy 458.763845 -229.795066) (xy 458.733821 -229.839103) (xy 458.697569 -229.878174) (xy 458.655898 -229.911405)
			(xy 458.60974 -229.938054) (xy 458.560126 -229.957526) (xy 458.508164 -229.969386) (xy 458.455014 -229.97337)
			(xy 458.401864 -229.969386) (xy 458.349902 -229.957526) (xy 458.300288 -229.938054) (xy 458.25413 -229.911405)
			(xy 458.212459 -229.878174) (xy 458.176207 -229.839103) (xy 458.146183 -229.795066) (xy 458.123057 -229.747045)
			(xy 458.107347 -229.696115) (xy 458.099404 -229.643411) (xy 455.366892 -229.643411) (xy 455.358949 -229.696115)
			(xy 455.343239 -229.747045) (xy 455.320113 -229.795066) (xy 455.290089 -229.839103) (xy 455.253837 -229.878174)
			(xy 455.212166 -229.911405) (xy 455.166008 -229.938054) (xy 455.116394 -229.957526) (xy 455.064432 -229.969386)
			(xy 455.011282 -229.97337) (xy 454.958132 -229.969386) (xy 454.90617 -229.957526) (xy 454.856556 -229.938054)
			(xy 454.810398 -229.911405) (xy 454.768727 -229.878174) (xy 454.732475 -229.839103) (xy 454.702451 -229.795066)
			(xy 454.679325 -229.747045) (xy 454.663615 -229.696115) (xy 454.655672 -229.643411) (xy 453.476624 -229.643411)
			(xy 453.468681 -229.696115) (xy 453.452971 -229.747045) (xy 453.429845 -229.795066) (xy 453.399821 -229.839103)
			(xy 453.363569 -229.878174) (xy 453.321898 -229.911405) (xy 453.27574 -229.938054) (xy 453.226126 -229.957526)
			(xy 453.174164 -229.969386) (xy 453.121014 -229.97337) (xy 453.067864 -229.969386) (xy 453.015902 -229.957526)
			(xy 452.966288 -229.938054) (xy 452.92013 -229.911405) (xy 452.878459 -229.878174) (xy 452.842207 -229.839103)
			(xy 452.812183 -229.795066) (xy 452.789057 -229.747045) (xy 452.773347 -229.696115) (xy 452.765404 -229.643411)
			(xy 451.266824 -229.643411) (xy 451.258881 -229.696115) (xy 451.243171 -229.747045) (xy 451.220045 -229.795066)
			(xy 451.190021 -229.839103) (xy 451.153769 -229.878174) (xy 451.112098 -229.911405) (xy 451.06594 -229.938054)
			(xy 451.016326 -229.957526) (xy 450.964364 -229.969386) (xy 450.911214 -229.97337) (xy 450.858064 -229.969386)
			(xy 450.806102 -229.957526) (xy 450.756488 -229.938054) (xy 450.71033 -229.911405) (xy 450.668659 -229.878174)
			(xy 450.632407 -229.839103) (xy 450.602383 -229.795066) (xy 450.579257 -229.747045) (xy 450.563547 -229.696115)
			(xy 450.555604 -229.643411) (xy 449.793868 -229.643411) (xy 449.793868 -230.128572) (xy 449.82384 -230.142034)
			(xy 449.848452 -230.153714) (xy 449.89411 -230.183432) (xy 449.934708 -230.219757) (xy 449.969301 -230.261841)
			(xy 449.99708 -230.308704) (xy 450.017398 -230.35925) (xy 450.02978 -230.412301) (xy 450.033938 -230.466619)
			(xy 450.031893 -230.493295) (xy 450.555604 -230.493295) (xy 450.555604 -230.439997) (xy 450.563547 -230.387293)
			(xy 450.579257 -230.336363) (xy 450.602383 -230.288342) (xy 450.632407 -230.244305) (xy 450.668659 -230.205234)
			(xy 450.71033 -230.172003) (xy 450.756488 -230.145354) (xy 450.806102 -230.125882) (xy 450.858064 -230.114022)
			(xy 450.911214 -230.110039) (xy 450.964364 -230.114022) (xy 451.016326 -230.125882) (xy 451.06594 -230.145354)
			(xy 451.112098 -230.172003) (xy 451.153769 -230.205234) (xy 451.190021 -230.244305) (xy 451.220045 -230.288342)
			(xy 451.243171 -230.336363) (xy 451.258881 -230.387293) (xy 451.266824 -230.439997) (xy 451.267322 -230.466646)
			(xy 451.266824 -230.493295) (xy 454.655672 -230.493295) (xy 454.655672 -230.439997) (xy 454.663615 -230.387293)
			(xy 454.679325 -230.336363) (xy 454.702451 -230.288342) (xy 454.732475 -230.244305) (xy 454.768727 -230.205234)
			(xy 454.810398 -230.172003) (xy 454.856556 -230.145354) (xy 454.90617 -230.125882) (xy 454.958132 -230.114022)
			(xy 455.011282 -230.110039) (xy 455.064432 -230.114022) (xy 455.116394 -230.125882) (xy 455.166008 -230.145354)
			(xy 455.212166 -230.172003) (xy 455.253837 -230.205234) (xy 455.290089 -230.244305) (xy 455.320113 -230.288342)
			(xy 455.343239 -230.336363) (xy 455.358949 -230.387293) (xy 455.366892 -230.439997) (xy 455.36739 -230.466646)
			(xy 455.366892 -230.493295) (xy 456.865472 -230.493295) (xy 456.865472 -230.439997) (xy 456.873415 -230.387293)
			(xy 456.889125 -230.336363) (xy 456.912251 -230.288342) (xy 456.942275 -230.244305) (xy 456.978527 -230.205234)
			(xy 457.020198 -230.172003) (xy 457.066356 -230.145354) (xy 457.11597 -230.125882) (xy 457.167932 -230.114022)
			(xy 457.221082 -230.110039) (xy 457.274232 -230.114022) (xy 457.326194 -230.125882) (xy 457.375808 -230.145354)
			(xy 457.421966 -230.172003) (xy 457.463637 -230.205234) (xy 457.499889 -230.244305) (xy 457.529913 -230.288342)
			(xy 457.553039 -230.336363) (xy 457.568749 -230.387293) (xy 457.576692 -230.439997) (xy 457.57719 -230.466646)
			(xy 457.576692 -230.493295) (xy 457.568749 -230.545999) (xy 457.553039 -230.596929) (xy 457.529913 -230.64495)
			(xy 457.499889 -230.688987) (xy 457.463637 -230.728058) (xy 457.421966 -230.761289) (xy 457.375808 -230.787938)
			(xy 457.326194 -230.80741) (xy 457.274232 -230.81927) (xy 457.221082 -230.823254) (xy 457.167932 -230.81927)
			(xy 457.11597 -230.80741) (xy 457.066356 -230.787938) (xy 457.020198 -230.761289) (xy 456.978527 -230.728058)
			(xy 456.942275 -230.688987) (xy 456.912251 -230.64495) (xy 456.889125 -230.596929) (xy 456.873415 -230.545999)
			(xy 456.865472 -230.493295) (xy 455.366892 -230.493295) (xy 455.358949 -230.545999) (xy 455.343239 -230.596929)
			(xy 455.320113 -230.64495) (xy 455.290089 -230.688987) (xy 455.253837 -230.728058) (xy 455.212166 -230.761289)
			(xy 455.166008 -230.787938) (xy 455.116394 -230.80741) (xy 455.064432 -230.81927) (xy 455.011282 -230.823254)
			(xy 454.958132 -230.81927) (xy 454.90617 -230.80741) (xy 454.856556 -230.787938) (xy 454.810398 -230.761289)
			(xy 454.768727 -230.728058) (xy 454.732475 -230.688987) (xy 454.702451 -230.64495) (xy 454.679325 -230.596929)
			(xy 454.663615 -230.545999) (xy 454.655672 -230.493295) (xy 451.266824 -230.493295) (xy 451.258881 -230.545999)
			(xy 451.243171 -230.596929) (xy 451.220045 -230.64495) (xy 451.190021 -230.688987) (xy 451.153769 -230.728058)
			(xy 451.112098 -230.761289) (xy 451.06594 -230.787938) (xy 451.016326 -230.80741) (xy 450.964364 -230.81927)
			(xy 450.911214 -230.823254) (xy 450.858064 -230.81927) (xy 450.806102 -230.80741) (xy 450.756488 -230.787938)
			(xy 450.71033 -230.761289) (xy 450.668659 -230.728058) (xy 450.632407 -230.688987) (xy 450.602383 -230.64495)
			(xy 450.579257 -230.596929) (xy 450.563547 -230.545999) (xy 450.555604 -230.493295) (xy 450.031893 -230.493295)
			(xy 450.029774 -230.520937) (xy 450.017386 -230.573986) (xy 449.997063 -230.62453) (xy 449.969279 -230.67139)
			(xy 449.934682 -230.71347) (xy 449.89408 -230.749791) (xy 449.848419 -230.779504) (xy 449.82384 -230.791258)
			(xy 449.793868 -230.80472) (xy 449.793868 -231.343433) (xy 450.555604 -231.343433) (xy 450.555604 -231.290135)
			(xy 450.563547 -231.237431) (xy 450.579257 -231.186501) (xy 450.602383 -231.13848) (xy 450.632407 -231.094443)
			(xy 450.668659 -231.055372) (xy 450.71033 -231.022141) (xy 450.756488 -230.995492) (xy 450.806102 -230.97602)
			(xy 450.858064 -230.96416) (xy 450.911214 -230.960177) (xy 450.964364 -230.96416) (xy 451.016326 -230.97602)
			(xy 451.06594 -230.995492) (xy 451.112098 -231.022141) (xy 451.153769 -231.055372) (xy 451.190021 -231.094443)
			(xy 451.220045 -231.13848) (xy 451.243171 -231.186501) (xy 451.258881 -231.237431) (xy 451.266824 -231.290135)
			(xy 451.267322 -231.316784) (xy 451.266824 -231.343433) (xy 452.765404 -231.343433) (xy 452.765404 -231.290135)
			(xy 452.773347 -231.237431) (xy 452.789057 -231.186501) (xy 452.812183 -231.13848) (xy 452.842207 -231.094443)
			(xy 452.878459 -231.055372) (xy 452.92013 -231.022141) (xy 452.966288 -230.995492) (xy 453.015902 -230.97602)
			(xy 453.067864 -230.96416) (xy 453.121014 -230.960177) (xy 453.174164 -230.96416) (xy 453.226126 -230.97602)
			(xy 453.27574 -230.995492) (xy 453.321898 -231.022141) (xy 453.363569 -231.055372) (xy 453.399821 -231.094443)
			(xy 453.429845 -231.13848) (xy 453.452971 -231.186501) (xy 453.468681 -231.237431) (xy 453.476624 -231.290135)
			(xy 453.477122 -231.316784) (xy 453.476624 -231.343433) (xy 454.655672 -231.343433) (xy 454.655672 -231.290135)
			(xy 454.663615 -231.237431) (xy 454.679325 -231.186501) (xy 454.702451 -231.13848) (xy 454.732475 -231.094443)
			(xy 454.768727 -231.055372) (xy 454.810398 -231.022141) (xy 454.856556 -230.995492) (xy 454.90617 -230.97602)
			(xy 454.958132 -230.96416) (xy 455.011282 -230.960177) (xy 455.064432 -230.96416) (xy 455.116394 -230.97602)
			(xy 455.166008 -230.995492) (xy 455.212166 -231.022141) (xy 455.253837 -231.055372) (xy 455.290089 -231.094443)
			(xy 455.320113 -231.13848) (xy 455.343239 -231.186501) (xy 455.358949 -231.237431) (xy 455.366892 -231.290135)
			(xy 455.36739 -231.316784) (xy 455.366892 -231.343433) (xy 458.099404 -231.343433) (xy 458.099404 -231.290135)
			(xy 458.107347 -231.237431) (xy 458.123057 -231.186501) (xy 458.146183 -231.13848) (xy 458.176207 -231.094443)
			(xy 458.212459 -231.055372) (xy 458.25413 -231.022141) (xy 458.300288 -230.995492) (xy 458.349902 -230.97602)
			(xy 458.401864 -230.96416) (xy 458.455014 -230.960177) (xy 458.508164 -230.96416) (xy 458.560126 -230.97602)
			(xy 458.60974 -230.995492) (xy 458.655898 -231.022141) (xy 458.697569 -231.055372) (xy 458.733821 -231.094443)
			(xy 458.763845 -231.13848) (xy 458.786971 -231.186501) (xy 458.802681 -231.237431) (xy 458.810624 -231.290135)
			(xy 458.811122 -231.316784) (xy 458.810624 -231.343433) (xy 458.802681 -231.396137) (xy 458.786971 -231.447067)
			(xy 458.763845 -231.495088) (xy 458.733821 -231.539125) (xy 458.697569 -231.578196) (xy 458.655898 -231.611427)
			(xy 458.60974 -231.638076) (xy 458.560126 -231.657548) (xy 458.508164 -231.669408) (xy 458.455014 -231.673392)
			(xy 458.401864 -231.669408) (xy 458.349902 -231.657548) (xy 458.300288 -231.638076) (xy 458.25413 -231.611427)
			(xy 458.212459 -231.578196) (xy 458.176207 -231.539125) (xy 458.146183 -231.495088) (xy 458.123057 -231.447067)
			(xy 458.107347 -231.396137) (xy 458.099404 -231.343433) (xy 455.366892 -231.343433) (xy 455.358949 -231.396137)
			(xy 455.343239 -231.447067) (xy 455.320113 -231.495088) (xy 455.290089 -231.539125) (xy 455.253837 -231.578196)
			(xy 455.212166 -231.611427) (xy 455.166008 -231.638076) (xy 455.116394 -231.657548) (xy 455.064432 -231.669408)
			(xy 455.011282 -231.673392) (xy 454.958132 -231.669408) (xy 454.90617 -231.657548) (xy 454.856556 -231.638076)
			(xy 454.810398 -231.611427) (xy 454.768727 -231.578196) (xy 454.732475 -231.539125) (xy 454.702451 -231.495088)
			(xy 454.679325 -231.447067) (xy 454.663615 -231.396137) (xy 454.655672 -231.343433) (xy 453.476624 -231.343433)
			(xy 453.468681 -231.396137) (xy 453.452971 -231.447067) (xy 453.429845 -231.495088) (xy 453.399821 -231.539125)
			(xy 453.363569 -231.578196) (xy 453.321898 -231.611427) (xy 453.27574 -231.638076) (xy 453.226126 -231.657548)
			(xy 453.174164 -231.669408) (xy 453.121014 -231.673392) (xy 453.067864 -231.669408) (xy 453.015902 -231.657548)
			(xy 452.966288 -231.638076) (xy 452.92013 -231.611427) (xy 452.878459 -231.578196) (xy 452.842207 -231.539125)
			(xy 452.812183 -231.495088) (xy 452.789057 -231.447067) (xy 452.773347 -231.396137) (xy 452.765404 -231.343433)
			(xy 451.266824 -231.343433) (xy 451.258881 -231.396137) (xy 451.243171 -231.447067) (xy 451.220045 -231.495088)
			(xy 451.190021 -231.539125) (xy 451.153769 -231.578196) (xy 451.112098 -231.611427) (xy 451.06594 -231.638076)
			(xy 451.016326 -231.657548) (xy 450.964364 -231.669408) (xy 450.911214 -231.673392) (xy 450.858064 -231.669408)
			(xy 450.806102 -231.657548) (xy 450.756488 -231.638076) (xy 450.71033 -231.611427) (xy 450.668659 -231.578196)
			(xy 450.632407 -231.539125) (xy 450.602383 -231.495088) (xy 450.579257 -231.447067) (xy 450.563547 -231.396137)
			(xy 450.555604 -231.343433) (xy 449.793868 -231.343433) (xy 449.793868 -231.828594) (xy 449.82384 -231.842056)
			(xy 449.848458 -231.853737) (xy 449.894127 -231.883456) (xy 449.934737 -231.919785) (xy 449.969341 -231.961874)
			(xy 449.99713 -232.008743) (xy 450.017456 -232.059298) (xy 450.029845 -232.112358) (xy 450.034009 -232.166687)
			(xy 450.03197 -232.193317) (xy 450.555604 -232.193317) (xy 450.555604 -232.140019) (xy 450.563547 -232.087315)
			(xy 450.579257 -232.036385) (xy 450.602383 -231.988364) (xy 450.632407 -231.944327) (xy 450.668659 -231.905256)
			(xy 450.71033 -231.872025) (xy 450.756488 -231.845376) (xy 450.806102 -231.825904) (xy 450.858064 -231.814044)
			(xy 450.911214 -231.810061) (xy 450.964364 -231.814044) (xy 451.016326 -231.825904) (xy 451.06594 -231.845376)
			(xy 451.112098 -231.872025) (xy 451.153769 -231.905256) (xy 451.190021 -231.944327) (xy 451.220045 -231.988364)
			(xy 451.243171 -232.036385) (xy 451.258881 -232.087315) (xy 451.266824 -232.140019) (xy 451.267322 -232.166668)
			(xy 451.266824 -232.193317) (xy 454.655672 -232.193317) (xy 454.655672 -232.140019) (xy 454.663615 -232.087315)
			(xy 454.679325 -232.036385) (xy 454.702451 -231.988364) (xy 454.732475 -231.944327) (xy 454.768727 -231.905256)
			(xy 454.810398 -231.872025) (xy 454.856556 -231.845376) (xy 454.90617 -231.825904) (xy 454.958132 -231.814044)
			(xy 455.011282 -231.810061) (xy 455.064432 -231.814044) (xy 455.116394 -231.825904) (xy 455.166008 -231.845376)
			(xy 455.212166 -231.872025) (xy 455.253837 -231.905256) (xy 455.290089 -231.944327) (xy 455.320113 -231.988364)
			(xy 455.343239 -232.036385) (xy 455.358949 -232.087315) (xy 455.366892 -232.140019) (xy 455.36739 -232.166668)
			(xy 455.366892 -232.193317) (xy 456.865472 -232.193317) (xy 456.865472 -232.140019) (xy 456.873415 -232.087315)
			(xy 456.889125 -232.036385) (xy 456.912251 -231.988364) (xy 456.942275 -231.944327) (xy 456.978527 -231.905256)
			(xy 457.020198 -231.872025) (xy 457.066356 -231.845376) (xy 457.11597 -231.825904) (xy 457.167932 -231.814044)
			(xy 457.221082 -231.810061) (xy 457.274232 -231.814044) (xy 457.326194 -231.825904) (xy 457.375808 -231.845376)
			(xy 457.421966 -231.872025) (xy 457.463637 -231.905256) (xy 457.499889 -231.944327) (xy 457.529913 -231.988364)
			(xy 457.553039 -232.036385) (xy 457.568749 -232.087315) (xy 457.576692 -232.140019) (xy 457.57719 -232.166668)
			(xy 457.576692 -232.193317) (xy 457.568749 -232.246021) (xy 457.553039 -232.296951) (xy 457.529913 -232.344972)
			(xy 457.499889 -232.389009) (xy 457.463637 -232.42808) (xy 457.421966 -232.461311) (xy 457.375808 -232.48796)
			(xy 457.326194 -232.507432) (xy 457.274232 -232.519292) (xy 457.221082 -232.523276) (xy 457.167932 -232.519292)
			(xy 457.11597 -232.507432) (xy 457.066356 -232.48796) (xy 457.020198 -232.461311) (xy 456.978527 -232.42808)
			(xy 456.942275 -232.389009) (xy 456.912251 -232.344972) (xy 456.889125 -232.296951) (xy 456.873415 -232.246021)
			(xy 456.865472 -232.193317) (xy 455.366892 -232.193317) (xy 455.358949 -232.246021) (xy 455.343239 -232.296951)
			(xy 455.320113 -232.344972) (xy 455.290089 -232.389009) (xy 455.253837 -232.42808) (xy 455.212166 -232.461311)
			(xy 455.166008 -232.48796) (xy 455.116394 -232.507432) (xy 455.064432 -232.519292) (xy 455.011282 -232.523276)
			(xy 454.958132 -232.519292) (xy 454.90617 -232.507432) (xy 454.856556 -232.48796) (xy 454.810398 -232.461311)
			(xy 454.768727 -232.42808) (xy 454.732475 -232.389009) (xy 454.702451 -232.344972) (xy 454.679325 -232.296951)
			(xy 454.663615 -232.246021) (xy 454.655672 -232.193317) (xy 451.266824 -232.193317) (xy 451.258881 -232.246021)
			(xy 451.243171 -232.296951) (xy 451.220045 -232.344972) (xy 451.190021 -232.389009) (xy 451.153769 -232.42808)
			(xy 451.112098 -232.461311) (xy 451.06594 -232.48796) (xy 451.016326 -232.507432) (xy 450.964364 -232.519292)
			(xy 450.911214 -232.523276) (xy 450.858064 -232.519292) (xy 450.806102 -232.507432) (xy 450.756488 -232.48796)
			(xy 450.71033 -232.461311) (xy 450.668659 -232.42808) (xy 450.632407 -232.389009) (xy 450.602383 -232.344972)
			(xy 450.579257 -232.296951) (xy 450.563547 -232.246021) (xy 450.555604 -232.193317) (xy 450.03197 -232.193317)
			(xy 450.029849 -232.221016) (xy 450.017464 -232.274077) (xy 449.997141 -232.324633) (xy 449.969356 -232.371504)
			(xy 449.934756 -232.413596) (xy 449.894148 -232.449928) (xy 449.848481 -232.479651) (xy 449.82384 -232.49128)
			(xy 449.793868 -232.504742) (xy 449.793868 -233.043455) (xy 450.555604 -233.043455) (xy 450.555604 -232.990157)
			(xy 450.563547 -232.937453) (xy 450.579257 -232.886523) (xy 450.602383 -232.838502) (xy 450.632407 -232.794465)
			(xy 450.668659 -232.755394) (xy 450.71033 -232.722163) (xy 450.756488 -232.695514) (xy 450.806102 -232.676042)
			(xy 450.858064 -232.664182) (xy 450.911214 -232.660199) (xy 450.964364 -232.664182) (xy 451.016326 -232.676042)
			(xy 451.06594 -232.695514) (xy 451.112098 -232.722163) (xy 451.153769 -232.755394) (xy 451.190021 -232.794465)
			(xy 451.220045 -232.838502) (xy 451.243171 -232.886523) (xy 451.258881 -232.937453) (xy 451.266824 -232.990157)
			(xy 451.267322 -233.016806) (xy 451.266824 -233.043455) (xy 452.765404 -233.043455) (xy 452.765404 -232.990157)
			(xy 452.773347 -232.937453) (xy 452.789057 -232.886523) (xy 452.812183 -232.838502) (xy 452.842207 -232.794465)
			(xy 452.878459 -232.755394) (xy 452.92013 -232.722163) (xy 452.966288 -232.695514) (xy 453.015902 -232.676042)
			(xy 453.067864 -232.664182) (xy 453.121014 -232.660199) (xy 453.174164 -232.664182) (xy 453.226126 -232.676042)
			(xy 453.27574 -232.695514) (xy 453.321898 -232.722163) (xy 453.363569 -232.755394) (xy 453.399821 -232.794465)
			(xy 453.429845 -232.838502) (xy 453.452971 -232.886523) (xy 453.468681 -232.937453) (xy 453.476624 -232.990157)
			(xy 453.477122 -233.016806) (xy 453.476624 -233.043455) (xy 454.655672 -233.043455) (xy 454.655672 -232.990157)
			(xy 454.663615 -232.937453) (xy 454.679325 -232.886523) (xy 454.702451 -232.838502) (xy 454.732475 -232.794465)
			(xy 454.768727 -232.755394) (xy 454.810398 -232.722163) (xy 454.856556 -232.695514) (xy 454.90617 -232.676042)
			(xy 454.958132 -232.664182) (xy 455.011282 -232.660199) (xy 455.064432 -232.664182) (xy 455.116394 -232.676042)
			(xy 455.166008 -232.695514) (xy 455.212166 -232.722163) (xy 455.253837 -232.755394) (xy 455.290089 -232.794465)
			(xy 455.320113 -232.838502) (xy 455.343239 -232.886523) (xy 455.358949 -232.937453) (xy 455.366892 -232.990157)
			(xy 455.36739 -233.016806) (xy 455.366892 -233.043455) (xy 458.099404 -233.043455) (xy 458.099404 -232.990157)
			(xy 458.107347 -232.937453) (xy 458.123057 -232.886523) (xy 458.146183 -232.838502) (xy 458.176207 -232.794465)
			(xy 458.212459 -232.755394) (xy 458.25413 -232.722163) (xy 458.300288 -232.695514) (xy 458.349902 -232.676042)
			(xy 458.401864 -232.664182) (xy 458.455014 -232.660199) (xy 458.508164 -232.664182) (xy 458.560126 -232.676042)
			(xy 458.60974 -232.695514) (xy 458.655898 -232.722163) (xy 458.697569 -232.755394) (xy 458.733821 -232.794465)
			(xy 458.763845 -232.838502) (xy 458.786971 -232.886523) (xy 458.802681 -232.937453) (xy 458.810624 -232.990157)
			(xy 458.811122 -233.016806) (xy 458.810624 -233.043455) (xy 458.802681 -233.096159) (xy 458.786971 -233.147089)
			(xy 458.763845 -233.19511) (xy 458.733821 -233.239147) (xy 458.697569 -233.278218) (xy 458.655898 -233.311449)
			(xy 458.60974 -233.338098) (xy 458.560126 -233.35757) (xy 458.508164 -233.36943) (xy 458.455014 -233.373414)
			(xy 458.401864 -233.36943) (xy 458.349902 -233.35757) (xy 458.300288 -233.338098) (xy 458.25413 -233.311449)
			(xy 458.212459 -233.278218) (xy 458.176207 -233.239147) (xy 458.146183 -233.19511) (xy 458.123057 -233.147089)
			(xy 458.107347 -233.096159) (xy 458.099404 -233.043455) (xy 455.366892 -233.043455) (xy 455.358949 -233.096159)
			(xy 455.343239 -233.147089) (xy 455.320113 -233.19511) (xy 455.290089 -233.239147) (xy 455.253837 -233.278218)
			(xy 455.212166 -233.311449) (xy 455.166008 -233.338098) (xy 455.116394 -233.35757) (xy 455.064432 -233.36943)
			(xy 455.011282 -233.373414) (xy 454.958132 -233.36943) (xy 454.90617 -233.35757) (xy 454.856556 -233.338098)
			(xy 454.810398 -233.311449) (xy 454.768727 -233.278218) (xy 454.732475 -233.239147) (xy 454.702451 -233.19511)
			(xy 454.679325 -233.147089) (xy 454.663615 -233.096159) (xy 454.655672 -233.043455) (xy 453.476624 -233.043455)
			(xy 453.468681 -233.096159) (xy 453.452971 -233.147089) (xy 453.429845 -233.19511) (xy 453.399821 -233.239147)
			(xy 453.363569 -233.278218) (xy 453.321898 -233.311449) (xy 453.27574 -233.338098) (xy 453.226126 -233.35757)
			(xy 453.174164 -233.36943) (xy 453.121014 -233.373414) (xy 453.067864 -233.36943) (xy 453.015902 -233.35757)
			(xy 452.966288 -233.338098) (xy 452.92013 -233.311449) (xy 452.878459 -233.278218) (xy 452.842207 -233.239147)
			(xy 452.812183 -233.19511) (xy 452.789057 -233.147089) (xy 452.773347 -233.096159) (xy 452.765404 -233.043455)
			(xy 451.266824 -233.043455) (xy 451.258881 -233.096159) (xy 451.243171 -233.147089) (xy 451.220045 -233.19511)
			(xy 451.190021 -233.239147) (xy 451.153769 -233.278218) (xy 451.112098 -233.311449) (xy 451.06594 -233.338098)
			(xy 451.016326 -233.35757) (xy 450.964364 -233.36943) (xy 450.911214 -233.373414) (xy 450.858064 -233.36943)
			(xy 450.806102 -233.35757) (xy 450.756488 -233.338098) (xy 450.71033 -233.311449) (xy 450.668659 -233.278218)
			(xy 450.632407 -233.239147) (xy 450.602383 -233.19511) (xy 450.579257 -233.147089) (xy 450.563547 -233.096159)
			(xy 450.555604 -233.043455) (xy 449.793868 -233.043455) (xy 449.793868 -233.528616) (xy 449.82384 -233.542078)
			(xy 449.848457 -233.553759) (xy 449.894123 -233.583478) (xy 449.934729 -233.619805) (xy 449.969329 -233.661893)
			(xy 449.997116 -233.70876) (xy 450.017439 -233.759312) (xy 450.029827 -233.81237) (xy 450.033989 -233.866696)
			(xy 450.031948 -233.893339) (xy 450.555604 -233.893339) (xy 450.555604 -233.840041) (xy 450.563547 -233.787337)
			(xy 450.579257 -233.736407) (xy 450.602383 -233.688386) (xy 450.632407 -233.644349) (xy 450.668659 -233.605278)
			(xy 450.71033 -233.572047) (xy 450.756488 -233.545398) (xy 450.806102 -233.525926) (xy 450.858064 -233.514066)
			(xy 450.911214 -233.510083) (xy 450.964364 -233.514066) (xy 451.016326 -233.525926) (xy 451.06594 -233.545398)
			(xy 451.112098 -233.572047) (xy 451.153769 -233.605278) (xy 451.190021 -233.644349) (xy 451.220045 -233.688386)
			(xy 451.243171 -233.736407) (xy 451.258881 -233.787337) (xy 451.266824 -233.840041) (xy 451.267322 -233.86669)
			(xy 451.266824 -233.893339) (xy 454.655672 -233.893339) (xy 454.655672 -233.840041) (xy 454.663615 -233.787337)
			(xy 454.679325 -233.736407) (xy 454.702451 -233.688386) (xy 454.732475 -233.644349) (xy 454.768727 -233.605278)
			(xy 454.810398 -233.572047) (xy 454.856556 -233.545398) (xy 454.90617 -233.525926) (xy 454.958132 -233.514066)
			(xy 455.011282 -233.510083) (xy 455.064432 -233.514066) (xy 455.116394 -233.525926) (xy 455.166008 -233.545398)
			(xy 455.212166 -233.572047) (xy 455.253837 -233.605278) (xy 455.290089 -233.644349) (xy 455.320113 -233.688386)
			(xy 455.343239 -233.736407) (xy 455.358949 -233.787337) (xy 455.366892 -233.840041) (xy 455.36739 -233.86669)
			(xy 455.366892 -233.893339) (xy 456.865472 -233.893339) (xy 456.865472 -233.840041) (xy 456.873415 -233.787337)
			(xy 456.889125 -233.736407) (xy 456.912251 -233.688386) (xy 456.942275 -233.644349) (xy 456.978527 -233.605278)
			(xy 457.020198 -233.572047) (xy 457.066356 -233.545398) (xy 457.11597 -233.525926) (xy 457.167932 -233.514066)
			(xy 457.221082 -233.510083) (xy 457.274232 -233.514066) (xy 457.326194 -233.525926) (xy 457.375808 -233.545398)
			(xy 457.421966 -233.572047) (xy 457.463637 -233.605278) (xy 457.499889 -233.644349) (xy 457.529913 -233.688386)
			(xy 457.553039 -233.736407) (xy 457.568749 -233.787337) (xy 457.576692 -233.840041) (xy 457.57719 -233.86669)
			(xy 457.576692 -233.893339) (xy 457.568749 -233.946043) (xy 457.553039 -233.996973) (xy 457.529913 -234.044994)
			(xy 457.499889 -234.089031) (xy 457.463637 -234.128102) (xy 457.421966 -234.161333) (xy 457.375808 -234.187982)
			(xy 457.326194 -234.207454) (xy 457.274232 -234.219314) (xy 457.221082 -234.223298) (xy 457.167932 -234.219314)
			(xy 457.11597 -234.207454) (xy 457.066356 -234.187982) (xy 457.020198 -234.161333) (xy 456.978527 -234.128102)
			(xy 456.942275 -234.089031) (xy 456.912251 -234.044994) (xy 456.889125 -233.996973) (xy 456.873415 -233.946043)
			(xy 456.865472 -233.893339) (xy 455.366892 -233.893339) (xy 455.358949 -233.946043) (xy 455.343239 -233.996973)
			(xy 455.320113 -234.044994) (xy 455.290089 -234.089031) (xy 455.253837 -234.128102) (xy 455.212166 -234.161333)
			(xy 455.166008 -234.187982) (xy 455.116394 -234.207454) (xy 455.064432 -234.219314) (xy 455.011282 -234.223298)
			(xy 454.958132 -234.219314) (xy 454.90617 -234.207454) (xy 454.856556 -234.187982) (xy 454.810398 -234.161333)
			(xy 454.768727 -234.128102) (xy 454.732475 -234.089031) (xy 454.702451 -234.044994) (xy 454.679325 -233.996973)
			(xy 454.663615 -233.946043) (xy 454.655672 -233.893339) (xy 451.266824 -233.893339) (xy 451.258881 -233.946043)
			(xy 451.243171 -233.996973) (xy 451.220045 -234.044994) (xy 451.190021 -234.089031) (xy 451.153769 -234.128102)
			(xy 451.112098 -234.161333) (xy 451.06594 -234.187982) (xy 451.016326 -234.207454) (xy 450.964364 -234.219314)
			(xy 450.911214 -234.223298) (xy 450.858064 -234.219314) (xy 450.806102 -234.207454) (xy 450.756488 -234.187982)
			(xy 450.71033 -234.161333) (xy 450.668659 -234.128102) (xy 450.632407 -234.089031) (xy 450.602383 -234.044994)
			(xy 450.579257 -233.996973) (xy 450.563547 -233.946043) (xy 450.555604 -233.893339) (xy 450.031948 -233.893339)
			(xy 450.029828 -233.921022) (xy 450.017442 -233.97408) (xy 449.997119 -234.024632) (xy 449.969334 -234.0715)
			(xy 449.934735 -234.113589) (xy 449.894129 -234.149917) (xy 449.848464 -234.179637) (xy 449.82384 -234.191302)
			(xy 449.793868 -234.204764) (xy 449.793868 -234.743223) (xy 450.555604 -234.743223) (xy 450.555604 -234.689925)
			(xy 450.563547 -234.637221) (xy 450.579257 -234.586291) (xy 450.602383 -234.53827) (xy 450.632407 -234.494233)
			(xy 450.668659 -234.455162) (xy 450.71033 -234.421931) (xy 450.756488 -234.395282) (xy 450.806102 -234.37581)
			(xy 450.858064 -234.36395) (xy 450.911214 -234.359967) (xy 450.964364 -234.36395) (xy 451.016326 -234.37581)
			(xy 451.06594 -234.395282) (xy 451.112098 -234.421931) (xy 451.153769 -234.455162) (xy 451.190021 -234.494233)
			(xy 451.220045 -234.53827) (xy 451.243171 -234.586291) (xy 451.258881 -234.637221) (xy 451.266824 -234.689925)
			(xy 451.267322 -234.716574) (xy 451.266824 -234.743223) (xy 452.765404 -234.743223) (xy 452.765404 -234.689925)
			(xy 452.773347 -234.637221) (xy 452.789057 -234.586291) (xy 452.812183 -234.53827) (xy 452.842207 -234.494233)
			(xy 452.878459 -234.455162) (xy 452.92013 -234.421931) (xy 452.966288 -234.395282) (xy 453.015902 -234.37581)
			(xy 453.067864 -234.36395) (xy 453.121014 -234.359967) (xy 453.174164 -234.36395) (xy 453.226126 -234.37581)
			(xy 453.27574 -234.395282) (xy 453.321898 -234.421931) (xy 453.363569 -234.455162) (xy 453.399821 -234.494233)
			(xy 453.429845 -234.53827) (xy 453.452971 -234.586291) (xy 453.468681 -234.637221) (xy 453.476624 -234.689925)
			(xy 453.477122 -234.716574) (xy 453.476624 -234.743223) (xy 454.655672 -234.743223) (xy 454.655672 -234.689925)
			(xy 454.663615 -234.637221) (xy 454.679325 -234.586291) (xy 454.702451 -234.53827) (xy 454.732475 -234.494233)
			(xy 454.768727 -234.455162) (xy 454.810398 -234.421931) (xy 454.856556 -234.395282) (xy 454.90617 -234.37581)
			(xy 454.958132 -234.36395) (xy 455.011282 -234.359967) (xy 455.064432 -234.36395) (xy 455.116394 -234.37581)
			(xy 455.166008 -234.395282) (xy 455.212166 -234.421931) (xy 455.253837 -234.455162) (xy 455.290089 -234.494233)
			(xy 455.320113 -234.53827) (xy 455.343239 -234.586291) (xy 455.358949 -234.637221) (xy 455.366892 -234.689925)
			(xy 455.36739 -234.716574) (xy 455.366892 -234.743223) (xy 458.099404 -234.743223) (xy 458.099404 -234.689925)
			(xy 458.107347 -234.637221) (xy 458.123057 -234.586291) (xy 458.146183 -234.53827) (xy 458.176207 -234.494233)
			(xy 458.212459 -234.455162) (xy 458.25413 -234.421931) (xy 458.300288 -234.395282) (xy 458.349902 -234.37581)
			(xy 458.401864 -234.36395) (xy 458.455014 -234.359967) (xy 458.508164 -234.36395) (xy 458.560126 -234.37581)
			(xy 458.60974 -234.395282) (xy 458.655898 -234.421931) (xy 458.697569 -234.455162) (xy 458.733821 -234.494233)
			(xy 458.763845 -234.53827) (xy 458.786971 -234.586291) (xy 458.802681 -234.637221) (xy 458.810624 -234.689925)
			(xy 458.811122 -234.716574) (xy 458.810624 -234.743223) (xy 458.802681 -234.795927) (xy 458.786971 -234.846857)
			(xy 458.763845 -234.894878) (xy 458.733821 -234.938915) (xy 458.697569 -234.977986) (xy 458.655898 -235.011217)
			(xy 458.60974 -235.037866) (xy 458.560126 -235.057338) (xy 458.508164 -235.069198) (xy 458.455014 -235.073182)
			(xy 458.401864 -235.069198) (xy 458.349902 -235.057338) (xy 458.300288 -235.037866) (xy 458.25413 -235.011217)
			(xy 458.212459 -234.977986) (xy 458.176207 -234.938915) (xy 458.146183 -234.894878) (xy 458.123057 -234.846857)
			(xy 458.107347 -234.795927) (xy 458.099404 -234.743223) (xy 455.366892 -234.743223) (xy 455.358949 -234.795927)
			(xy 455.343239 -234.846857) (xy 455.320113 -234.894878) (xy 455.290089 -234.938915) (xy 455.253837 -234.977986)
			(xy 455.212166 -235.011217) (xy 455.166008 -235.037866) (xy 455.116394 -235.057338) (xy 455.064432 -235.069198)
			(xy 455.011282 -235.073182) (xy 454.958132 -235.069198) (xy 454.90617 -235.057338) (xy 454.856556 -235.037866)
			(xy 454.810398 -235.011217) (xy 454.768727 -234.977986) (xy 454.732475 -234.938915) (xy 454.702451 -234.894878)
			(xy 454.679325 -234.846857) (xy 454.663615 -234.795927) (xy 454.655672 -234.743223) (xy 453.476624 -234.743223)
			(xy 453.468681 -234.795927) (xy 453.452971 -234.846857) (xy 453.429845 -234.894878) (xy 453.399821 -234.938915)
			(xy 453.363569 -234.977986) (xy 453.321898 -235.011217) (xy 453.27574 -235.037866) (xy 453.226126 -235.057338)
			(xy 453.174164 -235.069198) (xy 453.121014 -235.073182) (xy 453.067864 -235.069198) (xy 453.015902 -235.057338)
			(xy 452.966288 -235.037866) (xy 452.92013 -235.011217) (xy 452.878459 -234.977986) (xy 452.842207 -234.938915)
			(xy 452.812183 -234.894878) (xy 452.789057 -234.846857) (xy 452.773347 -234.795927) (xy 452.765404 -234.743223)
			(xy 451.266824 -234.743223) (xy 451.258881 -234.795927) (xy 451.243171 -234.846857) (xy 451.220045 -234.894878)
			(xy 451.190021 -234.938915) (xy 451.153769 -234.977986) (xy 451.112098 -235.011217) (xy 451.06594 -235.037866)
			(xy 451.016326 -235.057338) (xy 450.964364 -235.069198) (xy 450.911214 -235.073182) (xy 450.858064 -235.069198)
			(xy 450.806102 -235.057338) (xy 450.756488 -235.037866) (xy 450.71033 -235.011217) (xy 450.668659 -234.977986)
			(xy 450.632407 -234.938915) (xy 450.602383 -234.894878) (xy 450.579257 -234.846857) (xy 450.563547 -234.795927)
			(xy 450.555604 -234.743223) (xy 449.793868 -234.743223) (xy 449.793868 -235.228638) (xy 449.82384 -235.2421)
			(xy 449.848455 -235.25378) (xy 449.894118 -235.283499) (xy 449.934721 -235.319825) (xy 449.969318 -235.361912)
			(xy 449.997102 -235.408777) (xy 450.017423 -235.459327) (xy 450.029808 -235.512382) (xy 450.033969 -235.566705)
			(xy 450.031927 -235.593361) (xy 450.555604 -235.593361) (xy 450.555604 -235.540063) (xy 450.563547 -235.487359)
			(xy 450.579257 -235.436429) (xy 450.602383 -235.388408) (xy 450.632407 -235.344371) (xy 450.668659 -235.3053)
			(xy 450.71033 -235.272069) (xy 450.756488 -235.24542) (xy 450.806102 -235.225948) (xy 450.858064 -235.214088)
			(xy 450.911214 -235.210105) (xy 450.964364 -235.214088) (xy 451.016326 -235.225948) (xy 451.06594 -235.24542)
			(xy 451.112098 -235.272069) (xy 451.153769 -235.3053) (xy 451.190021 -235.344371) (xy 451.220045 -235.388408)
			(xy 451.243171 -235.436429) (xy 451.258881 -235.487359) (xy 451.266824 -235.540063) (xy 451.267322 -235.566712)
			(xy 451.266824 -235.593361) (xy 454.655672 -235.593361) (xy 454.655672 -235.540063) (xy 454.663615 -235.487359)
			(xy 454.679325 -235.436429) (xy 454.702451 -235.388408) (xy 454.732475 -235.344371) (xy 454.768727 -235.3053)
			(xy 454.810398 -235.272069) (xy 454.856556 -235.24542) (xy 454.90617 -235.225948) (xy 454.958132 -235.214088)
			(xy 455.011282 -235.210105) (xy 455.064432 -235.214088) (xy 455.116394 -235.225948) (xy 455.166008 -235.24542)
			(xy 455.212166 -235.272069) (xy 455.253837 -235.3053) (xy 455.290089 -235.344371) (xy 455.320113 -235.388408)
			(xy 455.343239 -235.436429) (xy 455.358949 -235.487359) (xy 455.366892 -235.540063) (xy 455.36739 -235.566712)
			(xy 455.366892 -235.593361) (xy 456.865472 -235.593361) (xy 456.865472 -235.540063) (xy 456.873415 -235.487359)
			(xy 456.889125 -235.436429) (xy 456.912251 -235.388408) (xy 456.942275 -235.344371) (xy 456.978527 -235.3053)
			(xy 457.020198 -235.272069) (xy 457.066356 -235.24542) (xy 457.11597 -235.225948) (xy 457.167932 -235.214088)
			(xy 457.221082 -235.210105) (xy 457.274232 -235.214088) (xy 457.326194 -235.225948) (xy 457.375808 -235.24542)
			(xy 457.421966 -235.272069) (xy 457.463637 -235.3053) (xy 457.499889 -235.344371) (xy 457.529913 -235.388408)
			(xy 457.553039 -235.436429) (xy 457.568749 -235.487359) (xy 457.576692 -235.540063) (xy 457.57719 -235.566712)
			(xy 457.576692 -235.593361) (xy 457.568749 -235.646065) (xy 457.553039 -235.696995) (xy 457.529913 -235.745016)
			(xy 457.499889 -235.789053) (xy 457.463637 -235.828124) (xy 457.421966 -235.861355) (xy 457.375808 -235.888004)
			(xy 457.326194 -235.907476) (xy 457.274232 -235.919336) (xy 457.221082 -235.92332) (xy 457.167932 -235.919336)
			(xy 457.11597 -235.907476) (xy 457.066356 -235.888004) (xy 457.020198 -235.861355) (xy 456.978527 -235.828124)
			(xy 456.942275 -235.789053) (xy 456.912251 -235.745016) (xy 456.889125 -235.696995) (xy 456.873415 -235.646065)
			(xy 456.865472 -235.593361) (xy 455.366892 -235.593361) (xy 455.358949 -235.646065) (xy 455.343239 -235.696995)
			(xy 455.320113 -235.745016) (xy 455.290089 -235.789053) (xy 455.253837 -235.828124) (xy 455.212166 -235.861355)
			(xy 455.166008 -235.888004) (xy 455.116394 -235.907476) (xy 455.064432 -235.919336) (xy 455.011282 -235.92332)
			(xy 454.958132 -235.919336) (xy 454.90617 -235.907476) (xy 454.856556 -235.888004) (xy 454.810398 -235.861355)
			(xy 454.768727 -235.828124) (xy 454.732475 -235.789053) (xy 454.702451 -235.745016) (xy 454.679325 -235.696995)
			(xy 454.663615 -235.646065) (xy 454.655672 -235.593361) (xy 451.266824 -235.593361) (xy 451.258881 -235.646065)
			(xy 451.243171 -235.696995) (xy 451.220045 -235.745016) (xy 451.190021 -235.789053) (xy 451.153769 -235.828124)
			(xy 451.112098 -235.861355) (xy 451.06594 -235.888004) (xy 451.016326 -235.907476) (xy 450.964364 -235.919336)
			(xy 450.911214 -235.92332) (xy 450.858064 -235.919336) (xy 450.806102 -235.907476) (xy 450.756488 -235.888004)
			(xy 450.71033 -235.861355) (xy 450.668659 -235.828124) (xy 450.632407 -235.789053) (xy 450.602383 -235.745016)
			(xy 450.579257 -235.696995) (xy 450.563547 -235.646065) (xy 450.555604 -235.593361) (xy 450.031927 -235.593361)
			(xy 450.029807 -235.621027) (xy 450.01742 -235.674082) (xy 449.997097 -235.724632) (xy 449.969312 -235.771496)
			(xy 449.934714 -235.813582) (xy 449.89411 -235.849907) (xy 449.848446 -235.879624) (xy 449.82384 -235.891324)
			(xy 449.793868 -235.904786) (xy 449.793868 -236.443245) (xy 450.555604 -236.443245) (xy 450.555604 -236.389947)
			(xy 450.563547 -236.337243) (xy 450.579257 -236.286313) (xy 450.602383 -236.238292) (xy 450.632407 -236.194255)
			(xy 450.668659 -236.155184) (xy 450.71033 -236.121953) (xy 450.756488 -236.095304) (xy 450.806102 -236.075832)
			(xy 450.858064 -236.063972) (xy 450.911214 -236.059989) (xy 450.964364 -236.063972) (xy 451.016326 -236.075832)
			(xy 451.06594 -236.095304) (xy 451.112098 -236.121953) (xy 451.153769 -236.155184) (xy 451.190021 -236.194255)
			(xy 451.220045 -236.238292) (xy 451.243171 -236.286313) (xy 451.258881 -236.337243) (xy 451.266824 -236.389947)
			(xy 451.267322 -236.416596) (xy 451.266824 -236.443245) (xy 452.765404 -236.443245) (xy 452.765404 -236.389947)
			(xy 452.773347 -236.337243) (xy 452.789057 -236.286313) (xy 452.812183 -236.238292) (xy 452.842207 -236.194255)
			(xy 452.878459 -236.155184) (xy 452.92013 -236.121953) (xy 452.966288 -236.095304) (xy 453.015902 -236.075832)
			(xy 453.067864 -236.063972) (xy 453.121014 -236.059989) (xy 453.174164 -236.063972) (xy 453.226126 -236.075832)
			(xy 453.27574 -236.095304) (xy 453.321898 -236.121953) (xy 453.363569 -236.155184) (xy 453.399821 -236.194255)
			(xy 453.429845 -236.238292) (xy 453.452971 -236.286313) (xy 453.468681 -236.337243) (xy 453.476624 -236.389947)
			(xy 453.477122 -236.416596) (xy 453.476624 -236.443245) (xy 454.655672 -236.443245) (xy 454.655672 -236.389947)
			(xy 454.663615 -236.337243) (xy 454.679325 -236.286313) (xy 454.702451 -236.238292) (xy 454.732475 -236.194255)
			(xy 454.768727 -236.155184) (xy 454.810398 -236.121953) (xy 454.856556 -236.095304) (xy 454.90617 -236.075832)
			(xy 454.958132 -236.063972) (xy 455.011282 -236.059989) (xy 455.064432 -236.063972) (xy 455.116394 -236.075832)
			(xy 455.166008 -236.095304) (xy 455.212166 -236.121953) (xy 455.253837 -236.155184) (xy 455.290089 -236.194255)
			(xy 455.320113 -236.238292) (xy 455.343239 -236.286313) (xy 455.358949 -236.337243) (xy 455.366892 -236.389947)
			(xy 455.36739 -236.416596) (xy 455.366892 -236.443245) (xy 458.099404 -236.443245) (xy 458.099404 -236.389947)
			(xy 458.107347 -236.337243) (xy 458.123057 -236.286313) (xy 458.146183 -236.238292) (xy 458.176207 -236.194255)
			(xy 458.212459 -236.155184) (xy 458.25413 -236.121953) (xy 458.300288 -236.095304) (xy 458.349902 -236.075832)
			(xy 458.401864 -236.063972) (xy 458.455014 -236.059989) (xy 458.508164 -236.063972) (xy 458.560126 -236.075832)
			(xy 458.60974 -236.095304) (xy 458.655898 -236.121953) (xy 458.697569 -236.155184) (xy 458.733821 -236.194255)
			(xy 458.763845 -236.238292) (xy 458.786971 -236.286313) (xy 458.802681 -236.337243) (xy 458.810624 -236.389947)
			(xy 458.811122 -236.416596) (xy 458.810624 -236.443245) (xy 458.802681 -236.495949) (xy 458.786971 -236.546879)
			(xy 458.763845 -236.5949) (xy 458.733821 -236.638937) (xy 458.697569 -236.678008) (xy 458.655898 -236.711239)
			(xy 458.60974 -236.737888) (xy 458.560126 -236.75736) (xy 458.508164 -236.76922) (xy 458.455014 -236.773204)
			(xy 458.401864 -236.76922) (xy 458.349902 -236.75736) (xy 458.300288 -236.737888) (xy 458.25413 -236.711239)
			(xy 458.212459 -236.678008) (xy 458.176207 -236.638937) (xy 458.146183 -236.5949) (xy 458.123057 -236.546879)
			(xy 458.107347 -236.495949) (xy 458.099404 -236.443245) (xy 455.366892 -236.443245) (xy 455.358949 -236.495949)
			(xy 455.343239 -236.546879) (xy 455.320113 -236.5949) (xy 455.290089 -236.638937) (xy 455.253837 -236.678008)
			(xy 455.212166 -236.711239) (xy 455.166008 -236.737888) (xy 455.116394 -236.75736) (xy 455.064432 -236.76922)
			(xy 455.011282 -236.773204) (xy 454.958132 -236.76922) (xy 454.90617 -236.75736) (xy 454.856556 -236.737888)
			(xy 454.810398 -236.711239) (xy 454.768727 -236.678008) (xy 454.732475 -236.638937) (xy 454.702451 -236.5949)
			(xy 454.679325 -236.546879) (xy 454.663615 -236.495949) (xy 454.655672 -236.443245) (xy 453.476624 -236.443245)
			(xy 453.468681 -236.495949) (xy 453.452971 -236.546879) (xy 453.429845 -236.5949) (xy 453.399821 -236.638937)
			(xy 453.363569 -236.678008) (xy 453.321898 -236.711239) (xy 453.27574 -236.737888) (xy 453.226126 -236.75736)
			(xy 453.174164 -236.76922) (xy 453.121014 -236.773204) (xy 453.067864 -236.76922) (xy 453.015902 -236.75736)
			(xy 452.966288 -236.737888) (xy 452.92013 -236.711239) (xy 452.878459 -236.678008) (xy 452.842207 -236.638937)
			(xy 452.812183 -236.5949) (xy 452.789057 -236.546879) (xy 452.773347 -236.495949) (xy 452.765404 -236.443245)
			(xy 451.266824 -236.443245) (xy 451.258881 -236.495949) (xy 451.243171 -236.546879) (xy 451.220045 -236.5949)
			(xy 451.190021 -236.638937) (xy 451.153769 -236.678008) (xy 451.112098 -236.711239) (xy 451.06594 -236.737888)
			(xy 451.016326 -236.75736) (xy 450.964364 -236.76922) (xy 450.911214 -236.773204) (xy 450.858064 -236.76922)
			(xy 450.806102 -236.75736) (xy 450.756488 -236.737888) (xy 450.71033 -236.711239) (xy 450.668659 -236.678008)
			(xy 450.632407 -236.638937) (xy 450.602383 -236.5949) (xy 450.579257 -236.546879) (xy 450.563547 -236.495949)
			(xy 450.555604 -236.443245) (xy 449.793868 -236.443245) (xy 449.793868 -237.293383) (xy 450.555604 -237.293383)
			(xy 450.555604 -237.240085) (xy 450.563547 -237.187381) (xy 450.579257 -237.136451) (xy 450.602383 -237.08843)
			(xy 450.632407 -237.044393) (xy 450.668659 -237.005322) (xy 450.71033 -236.972091) (xy 450.756488 -236.945442)
			(xy 450.806102 -236.92597) (xy 450.858064 -236.91411) (xy 450.911214 -236.910127) (xy 450.964364 -236.91411)
			(xy 451.016326 -236.92597) (xy 451.06594 -236.945442) (xy 451.112098 -236.972091) (xy 451.153769 -237.005322)
			(xy 451.190021 -237.044393) (xy 451.220045 -237.08843) (xy 451.243171 -237.136451) (xy 451.258881 -237.187381)
			(xy 451.266824 -237.240085) (xy 451.267322 -237.266734) (xy 451.266824 -237.293383) (xy 454.655672 -237.293383)
			(xy 454.655672 -237.240085) (xy 454.663615 -237.187381) (xy 454.679325 -237.136451) (xy 454.702451 -237.08843)
			(xy 454.732475 -237.044393) (xy 454.768727 -237.005322) (xy 454.810398 -236.972091) (xy 454.856556 -236.945442)
			(xy 454.90617 -236.92597) (xy 454.958132 -236.91411) (xy 455.011282 -236.910127) (xy 455.064432 -236.91411)
			(xy 455.116394 -236.92597) (xy 455.166008 -236.945442) (xy 455.212166 -236.972091) (xy 455.253837 -237.005322)
			(xy 455.290089 -237.044393) (xy 455.320113 -237.08843) (xy 455.343239 -237.136451) (xy 455.358949 -237.187381)
			(xy 455.366892 -237.240085) (xy 455.36739 -237.266734) (xy 455.366892 -237.293383) (xy 455.358949 -237.346087)
			(xy 455.343239 -237.397017) (xy 455.320113 -237.445038) (xy 455.290089 -237.489075) (xy 455.253837 -237.528146)
			(xy 455.212166 -237.561377) (xy 455.166008 -237.588026) (xy 455.116394 -237.607498) (xy 455.064432 -237.619358)
			(xy 455.011282 -237.623342) (xy 454.958132 -237.619358) (xy 454.90617 -237.607498) (xy 454.856556 -237.588026)
			(xy 454.810398 -237.561377) (xy 454.768727 -237.528146) (xy 454.732475 -237.489075) (xy 454.702451 -237.445038)
			(xy 454.679325 -237.397017) (xy 454.663615 -237.346087) (xy 454.655672 -237.293383) (xy 451.266824 -237.293383)
			(xy 451.258881 -237.346087) (xy 451.243171 -237.397017) (xy 451.220045 -237.445038) (xy 451.190021 -237.489075)
			(xy 451.153769 -237.528146) (xy 451.112098 -237.561377) (xy 451.06594 -237.588026) (xy 451.016326 -237.607498)
			(xy 450.964364 -237.619358) (xy 450.911214 -237.623342) (xy 450.858064 -237.619358) (xy 450.806102 -237.607498)
			(xy 450.756488 -237.588026) (xy 450.71033 -237.561377) (xy 450.668659 -237.528146) (xy 450.632407 -237.489075)
			(xy 450.602383 -237.445038) (xy 450.579257 -237.397017) (xy 450.563547 -237.346087) (xy 450.555604 -237.293383)
			(xy 449.793868 -237.293383) (xy 449.793868 -237.778544) (xy 449.82384 -237.792006) (xy 449.848455 -237.803686)
			(xy 449.894116 -237.833405) (xy 449.934719 -237.869731) (xy 449.969315 -237.911817) (xy 449.997098 -237.958682)
			(xy 450.017419 -238.009231) (xy 450.029803 -238.062286) (xy 450.033963 -238.116607) (xy 450.03192 -238.143267)
			(xy 450.555604 -238.143267) (xy 450.555604 -238.089969) (xy 450.563547 -238.037265) (xy 450.579257 -237.986335)
			(xy 450.602383 -237.938314) (xy 450.632407 -237.894277) (xy 450.668659 -237.855206) (xy 450.71033 -237.821975)
			(xy 450.756488 -237.795326) (xy 450.806102 -237.775854) (xy 450.858064 -237.763994) (xy 450.911214 -237.760011)
			(xy 450.964364 -237.763994) (xy 451.016326 -237.775854) (xy 451.06594 -237.795326) (xy 451.112098 -237.821975)
			(xy 451.153769 -237.855206) (xy 451.190021 -237.894277) (xy 451.220045 -237.938314) (xy 451.243171 -237.986335)
			(xy 451.258881 -238.037265) (xy 451.266824 -238.089969) (xy 451.267322 -238.116618) (xy 451.266824 -238.143267)
			(xy 454.655672 -238.143267) (xy 454.655672 -238.089969) (xy 454.663615 -238.037265) (xy 454.679325 -237.986335)
			(xy 454.702451 -237.938314) (xy 454.732475 -237.894277) (xy 454.768727 -237.855206) (xy 454.810398 -237.821975)
			(xy 454.856556 -237.795326) (xy 454.90617 -237.775854) (xy 454.958132 -237.763994) (xy 455.011282 -237.760011)
			(xy 455.064432 -237.763994) (xy 455.116394 -237.775854) (xy 455.166008 -237.795326) (xy 455.212166 -237.821975)
			(xy 455.253837 -237.855206) (xy 455.290089 -237.894277) (xy 455.320113 -237.938314) (xy 455.343239 -237.986335)
			(xy 455.358949 -238.037265) (xy 455.366892 -238.089969) (xy 455.36739 -238.116618) (xy 455.366892 -238.143267)
			(xy 456.865472 -238.143267) (xy 456.865472 -238.089969) (xy 456.873415 -238.037265) (xy 456.889125 -237.986335)
			(xy 456.912251 -237.938314) (xy 456.942275 -237.894277) (xy 456.978527 -237.855206) (xy 457.020198 -237.821975)
			(xy 457.066356 -237.795326) (xy 457.11597 -237.775854) (xy 457.167932 -237.763994) (xy 457.221082 -237.760011)
			(xy 457.274232 -237.763994) (xy 457.326194 -237.775854) (xy 457.375808 -237.795326) (xy 457.421966 -237.821975)
			(xy 457.463637 -237.855206) (xy 457.499889 -237.894277) (xy 457.529913 -237.938314) (xy 457.553039 -237.986335)
			(xy 457.568749 -238.037265) (xy 457.576692 -238.089969) (xy 457.57719 -238.116618) (xy 457.576692 -238.143267)
			(xy 457.568749 -238.195971) (xy 457.553039 -238.246901) (xy 457.529913 -238.294922) (xy 457.499889 -238.338959)
			(xy 457.463637 -238.37803) (xy 457.421966 -238.411261) (xy 457.375808 -238.43791) (xy 457.326194 -238.457382)
			(xy 457.274232 -238.469242) (xy 457.221082 -238.473226) (xy 457.167932 -238.469242) (xy 457.11597 -238.457382)
			(xy 457.066356 -238.43791) (xy 457.020198 -238.411261) (xy 456.978527 -238.37803) (xy 456.942275 -238.338959)
			(xy 456.912251 -238.294922) (xy 456.889125 -238.246901) (xy 456.873415 -238.195971) (xy 456.865472 -238.143267)
			(xy 455.366892 -238.143267) (xy 455.358949 -238.195971) (xy 455.343239 -238.246901) (xy 455.320113 -238.294922)
			(xy 455.290089 -238.338959) (xy 455.253837 -238.37803) (xy 455.212166 -238.411261) (xy 455.166008 -238.43791)
			(xy 455.116394 -238.457382) (xy 455.064432 -238.469242) (xy 455.011282 -238.473226) (xy 454.958132 -238.469242)
			(xy 454.90617 -238.457382) (xy 454.856556 -238.43791) (xy 454.810398 -238.411261) (xy 454.768727 -238.37803)
			(xy 454.732475 -238.338959) (xy 454.702451 -238.294922) (xy 454.679325 -238.246901) (xy 454.663615 -238.195971)
			(xy 454.655672 -238.143267) (xy 451.266824 -238.143267) (xy 451.258881 -238.195971) (xy 451.243171 -238.246901)
			(xy 451.220045 -238.294922) (xy 451.190021 -238.338959) (xy 451.153769 -238.37803) (xy 451.112098 -238.411261)
			(xy 451.06594 -238.43791) (xy 451.016326 -238.457382) (xy 450.964364 -238.469242) (xy 450.911214 -238.473226)
			(xy 450.858064 -238.469242) (xy 450.806102 -238.457382) (xy 450.756488 -238.43791) (xy 450.71033 -238.411261)
			(xy 450.668659 -238.37803) (xy 450.632407 -238.338959) (xy 450.602383 -238.294922) (xy 450.579257 -238.246901)
			(xy 450.563547 -238.195971) (xy 450.555604 -238.143267) (xy 450.03192 -238.143267) (xy 450.029801 -238.170929)
			(xy 450.017414 -238.223983) (xy 449.997091 -238.274531) (xy 449.969307 -238.321395) (xy 449.934709 -238.36348)
			(xy 449.894104 -238.399804) (xy 449.848442 -238.429521) (xy 449.82384 -238.44123) (xy 449.793868 -238.454692)
			(xy 449.793868 -238.993405) (xy 450.555604 -238.993405) (xy 450.555604 -238.940107) (xy 450.563547 -238.887403)
			(xy 450.579257 -238.836473) (xy 450.602383 -238.788452) (xy 450.632407 -238.744415) (xy 450.668659 -238.705344)
			(xy 450.71033 -238.672113) (xy 450.756488 -238.645464) (xy 450.806102 -238.625992) (xy 450.858064 -238.614132)
			(xy 450.911214 -238.610149) (xy 450.964364 -238.614132) (xy 451.016326 -238.625992) (xy 451.06594 -238.645464)
			(xy 451.112098 -238.672113) (xy 451.153769 -238.705344) (xy 451.190021 -238.744415) (xy 451.220045 -238.788452)
			(xy 451.243171 -238.836473) (xy 451.258881 -238.887403) (xy 451.266824 -238.940107) (xy 451.267322 -238.966756)
			(xy 451.266824 -238.993405) (xy 452.765404 -238.993405) (xy 452.765404 -238.940107) (xy 452.773347 -238.887403)
			(xy 452.789057 -238.836473) (xy 452.812183 -238.788452) (xy 452.842207 -238.744415) (xy 452.878459 -238.705344)
			(xy 452.92013 -238.672113) (xy 452.966288 -238.645464) (xy 453.015902 -238.625992) (xy 453.067864 -238.614132)
			(xy 453.121014 -238.610149) (xy 453.174164 -238.614132) (xy 453.226126 -238.625992) (xy 453.27574 -238.645464)
			(xy 453.321898 -238.672113) (xy 453.363569 -238.705344) (xy 453.399821 -238.744415) (xy 453.429845 -238.788452)
			(xy 453.452971 -238.836473) (xy 453.468681 -238.887403) (xy 453.476624 -238.940107) (xy 453.477122 -238.966756)
			(xy 453.476624 -238.993405) (xy 454.655672 -238.993405) (xy 454.655672 -238.940107) (xy 454.663615 -238.887403)
			(xy 454.679325 -238.836473) (xy 454.702451 -238.788452) (xy 454.732475 -238.744415) (xy 454.768727 -238.705344)
			(xy 454.810398 -238.672113) (xy 454.856556 -238.645464) (xy 454.90617 -238.625992) (xy 454.958132 -238.614132)
			(xy 455.011282 -238.610149) (xy 455.064432 -238.614132) (xy 455.116394 -238.625992) (xy 455.166008 -238.645464)
			(xy 455.212166 -238.672113) (xy 455.253837 -238.705344) (xy 455.290089 -238.744415) (xy 455.320113 -238.788452)
			(xy 455.343239 -238.836473) (xy 455.358949 -238.887403) (xy 455.366892 -238.940107) (xy 455.36739 -238.966756)
			(xy 455.366892 -238.993405) (xy 458.099404 -238.993405) (xy 458.099404 -238.940107) (xy 458.107347 -238.887403)
			(xy 458.123057 -238.836473) (xy 458.146183 -238.788452) (xy 458.176207 -238.744415) (xy 458.212459 -238.705344)
			(xy 458.25413 -238.672113) (xy 458.300288 -238.645464) (xy 458.349902 -238.625992) (xy 458.401864 -238.614132)
			(xy 458.455014 -238.610149) (xy 458.508164 -238.614132) (xy 458.560126 -238.625992) (xy 458.60974 -238.645464)
			(xy 458.655898 -238.672113) (xy 458.697569 -238.705344) (xy 458.733821 -238.744415) (xy 458.763845 -238.788452)
			(xy 458.786971 -238.836473) (xy 458.802681 -238.887403) (xy 458.810624 -238.940107) (xy 458.811122 -238.966756)
			(xy 458.810624 -238.993405) (xy 458.802681 -239.046109) (xy 458.786971 -239.097039) (xy 458.763845 -239.14506)
			(xy 458.733821 -239.189097) (xy 458.697569 -239.228168) (xy 458.655898 -239.261399) (xy 458.60974 -239.288048)
			(xy 458.560126 -239.30752) (xy 458.508164 -239.31938) (xy 458.455014 -239.323364) (xy 458.401864 -239.31938)
			(xy 458.349902 -239.30752) (xy 458.300288 -239.288048) (xy 458.25413 -239.261399) (xy 458.212459 -239.228168)
			(xy 458.176207 -239.189097) (xy 458.146183 -239.14506) (xy 458.123057 -239.097039) (xy 458.107347 -239.046109)
			(xy 458.099404 -238.993405) (xy 455.366892 -238.993405) (xy 455.358949 -239.046109) (xy 455.343239 -239.097039)
			(xy 455.320113 -239.14506) (xy 455.290089 -239.189097) (xy 455.253837 -239.228168) (xy 455.212166 -239.261399)
			(xy 455.166008 -239.288048) (xy 455.116394 -239.30752) (xy 455.064432 -239.31938) (xy 455.011282 -239.323364)
			(xy 454.958132 -239.31938) (xy 454.90617 -239.30752) (xy 454.856556 -239.288048) (xy 454.810398 -239.261399)
			(xy 454.768727 -239.228168) (xy 454.732475 -239.189097) (xy 454.702451 -239.14506) (xy 454.679325 -239.097039)
			(xy 454.663615 -239.046109) (xy 454.655672 -238.993405) (xy 453.476624 -238.993405) (xy 453.468681 -239.046109)
			(xy 453.452971 -239.097039) (xy 453.429845 -239.14506) (xy 453.399821 -239.189097) (xy 453.363569 -239.228168)
			(xy 453.321898 -239.261399) (xy 453.27574 -239.288048) (xy 453.226126 -239.30752) (xy 453.174164 -239.31938)
			(xy 453.121014 -239.323364) (xy 453.067864 -239.31938) (xy 453.015902 -239.30752) (xy 452.966288 -239.288048)
			(xy 452.92013 -239.261399) (xy 452.878459 -239.228168) (xy 452.842207 -239.189097) (xy 452.812183 -239.14506)
			(xy 452.789057 -239.097039) (xy 452.773347 -239.046109) (xy 452.765404 -238.993405) (xy 451.266824 -238.993405)
			(xy 451.258881 -239.046109) (xy 451.243171 -239.097039) (xy 451.220045 -239.14506) (xy 451.190021 -239.189097)
			(xy 451.153769 -239.228168) (xy 451.112098 -239.261399) (xy 451.06594 -239.288048) (xy 451.016326 -239.30752)
			(xy 450.964364 -239.31938) (xy 450.911214 -239.323364) (xy 450.858064 -239.31938) (xy 450.806102 -239.30752)
			(xy 450.756488 -239.288048) (xy 450.71033 -239.261399) (xy 450.668659 -239.228168) (xy 450.632407 -239.189097)
			(xy 450.602383 -239.14506) (xy 450.579257 -239.097039) (xy 450.563547 -239.046109) (xy 450.555604 -238.993405)
			(xy 449.793868 -238.993405) (xy 449.793868 -239.478566) (xy 449.82384 -239.492028) (xy 449.848453 -239.503708)
			(xy 449.894111 -239.533426) (xy 449.934711 -239.569751) (xy 449.969304 -239.611836) (xy 449.997084 -239.658699)
			(xy 450.017402 -239.709246) (xy 450.029785 -239.762298) (xy 450.033943 -239.816616) (xy 450.031899 -239.843289)
			(xy 450.555604 -239.843289) (xy 450.555604 -239.789991) (xy 450.563547 -239.737287) (xy 450.579257 -239.686357)
			(xy 450.602383 -239.638336) (xy 450.632407 -239.594299) (xy 450.668659 -239.555228) (xy 450.71033 -239.521997)
			(xy 450.756488 -239.495348) (xy 450.806102 -239.475876) (xy 450.858064 -239.464016) (xy 450.911214 -239.460033)
			(xy 450.964364 -239.464016) (xy 451.016326 -239.475876) (xy 451.06594 -239.495348) (xy 451.112098 -239.521997)
			(xy 451.153769 -239.555228) (xy 451.190021 -239.594299) (xy 451.220045 -239.638336) (xy 451.243171 -239.686357)
			(xy 451.258881 -239.737287) (xy 451.266824 -239.789991) (xy 451.267322 -239.81664) (xy 451.266824 -239.843289)
			(xy 454.655672 -239.843289) (xy 454.655672 -239.789991) (xy 454.663615 -239.737287) (xy 454.679325 -239.686357)
			(xy 454.702451 -239.638336) (xy 454.732475 -239.594299) (xy 454.768727 -239.555228) (xy 454.810398 -239.521997)
			(xy 454.856556 -239.495348) (xy 454.90617 -239.475876) (xy 454.958132 -239.464016) (xy 455.011282 -239.460033)
			(xy 455.064432 -239.464016) (xy 455.116394 -239.475876) (xy 455.166008 -239.495348) (xy 455.212166 -239.521997)
			(xy 455.253837 -239.555228) (xy 455.290089 -239.594299) (xy 455.320113 -239.638336) (xy 455.343239 -239.686357)
			(xy 455.358949 -239.737287) (xy 455.366892 -239.789991) (xy 455.36739 -239.81664) (xy 455.366892 -239.843289)
			(xy 456.865472 -239.843289) (xy 456.865472 -239.789991) (xy 456.873415 -239.737287) (xy 456.889125 -239.686357)
			(xy 456.912251 -239.638336) (xy 456.942275 -239.594299) (xy 456.978527 -239.555228) (xy 457.020198 -239.521997)
			(xy 457.066356 -239.495348) (xy 457.11597 -239.475876) (xy 457.167932 -239.464016) (xy 457.221082 -239.460033)
			(xy 457.274232 -239.464016) (xy 457.326194 -239.475876) (xy 457.375808 -239.495348) (xy 457.421966 -239.521997)
			(xy 457.463637 -239.555228) (xy 457.499889 -239.594299) (xy 457.529913 -239.638336) (xy 457.553039 -239.686357)
			(xy 457.568749 -239.737287) (xy 457.576692 -239.789991) (xy 457.57719 -239.81664) (xy 457.576692 -239.843289)
			(xy 457.568749 -239.895993) (xy 457.553039 -239.946923) (xy 457.529913 -239.994944) (xy 457.499889 -240.038981)
			(xy 457.463637 -240.078052) (xy 457.421966 -240.111283) (xy 457.375808 -240.137932) (xy 457.326194 -240.157404)
			(xy 457.274232 -240.169264) (xy 457.221082 -240.173248) (xy 457.167932 -240.169264) (xy 457.11597 -240.157404)
			(xy 457.066356 -240.137932) (xy 457.020198 -240.111283) (xy 456.978527 -240.078052) (xy 456.942275 -240.038981)
			(xy 456.912251 -239.994944) (xy 456.889125 -239.946923) (xy 456.873415 -239.895993) (xy 456.865472 -239.843289)
			(xy 455.366892 -239.843289) (xy 455.358949 -239.895993) (xy 455.343239 -239.946923) (xy 455.320113 -239.994944)
			(xy 455.290089 -240.038981) (xy 455.253837 -240.078052) (xy 455.212166 -240.111283) (xy 455.166008 -240.137932)
			(xy 455.116394 -240.157404) (xy 455.064432 -240.169264) (xy 455.011282 -240.173248) (xy 454.958132 -240.169264)
			(xy 454.90617 -240.157404) (xy 454.856556 -240.137932) (xy 454.810398 -240.111283) (xy 454.768727 -240.078052)
			(xy 454.732475 -240.038981) (xy 454.702451 -239.994944) (xy 454.679325 -239.946923) (xy 454.663615 -239.895993)
			(xy 454.655672 -239.843289) (xy 451.266824 -239.843289) (xy 451.258881 -239.895993) (xy 451.243171 -239.946923)
			(xy 451.220045 -239.994944) (xy 451.190021 -240.038981) (xy 451.153769 -240.078052) (xy 451.112098 -240.111283)
			(xy 451.06594 -240.137932) (xy 451.016326 -240.157404) (xy 450.964364 -240.169264) (xy 450.911214 -240.173248)
			(xy 450.858064 -240.169264) (xy 450.806102 -240.157404) (xy 450.756488 -240.137932) (xy 450.71033 -240.111283)
			(xy 450.668659 -240.078052) (xy 450.632407 -240.038981) (xy 450.602383 -239.994944) (xy 450.579257 -239.946923)
			(xy 450.563547 -239.895993) (xy 450.555604 -239.843289) (xy 450.031899 -239.843289) (xy 450.02978 -239.870935)
			(xy 450.017392 -239.923986) (xy 449.997069 -239.974531) (xy 449.969285 -240.021391) (xy 449.934688 -240.063472)
			(xy 449.894085 -240.099794) (xy 449.848424 -240.129507) (xy 449.82384 -240.141252) (xy 449.793868 -240.154714)
			(xy 449.793868 -240.693427) (xy 450.555604 -240.693427) (xy 450.555604 -240.640129) (xy 450.563547 -240.587425)
			(xy 450.579257 -240.536495) (xy 450.602383 -240.488474) (xy 450.632407 -240.444437) (xy 450.668659 -240.405366)
			(xy 450.71033 -240.372135) (xy 450.756488 -240.345486) (xy 450.806102 -240.326014) (xy 450.858064 -240.314154)
			(xy 450.911214 -240.310171) (xy 450.964364 -240.314154) (xy 451.016326 -240.326014) (xy 451.06594 -240.345486)
			(xy 451.112098 -240.372135) (xy 451.153769 -240.405366) (xy 451.190021 -240.444437) (xy 451.220045 -240.488474)
			(xy 451.243171 -240.536495) (xy 451.258881 -240.587425) (xy 451.266824 -240.640129) (xy 451.267322 -240.666778)
			(xy 451.266824 -240.693427) (xy 452.765404 -240.693427) (xy 452.765404 -240.640129) (xy 452.773347 -240.587425)
			(xy 452.789057 -240.536495) (xy 452.812183 -240.488474) (xy 452.842207 -240.444437) (xy 452.878459 -240.405366)
			(xy 452.92013 -240.372135) (xy 452.966288 -240.345486) (xy 453.015902 -240.326014) (xy 453.067864 -240.314154)
			(xy 453.121014 -240.310171) (xy 453.174164 -240.314154) (xy 453.226126 -240.326014) (xy 453.27574 -240.345486)
			(xy 453.321898 -240.372135) (xy 453.363569 -240.405366) (xy 453.399821 -240.444437) (xy 453.429845 -240.488474)
			(xy 453.452971 -240.536495) (xy 453.468681 -240.587425) (xy 453.476624 -240.640129) (xy 453.477122 -240.666778)
			(xy 453.476624 -240.693427) (xy 454.655672 -240.693427) (xy 454.655672 -240.640129) (xy 454.663615 -240.587425)
			(xy 454.679325 -240.536495) (xy 454.702451 -240.488474) (xy 454.732475 -240.444437) (xy 454.768727 -240.405366)
			(xy 454.810398 -240.372135) (xy 454.856556 -240.345486) (xy 454.90617 -240.326014) (xy 454.958132 -240.314154)
			(xy 455.011282 -240.310171) (xy 455.064432 -240.314154) (xy 455.116394 -240.326014) (xy 455.166008 -240.345486)
			(xy 455.212166 -240.372135) (xy 455.253837 -240.405366) (xy 455.290089 -240.444437) (xy 455.320113 -240.488474)
			(xy 455.343239 -240.536495) (xy 455.358949 -240.587425) (xy 455.366892 -240.640129) (xy 455.36739 -240.666778)
			(xy 455.366892 -240.693427) (xy 458.099404 -240.693427) (xy 458.099404 -240.640129) (xy 458.107347 -240.587425)
			(xy 458.123057 -240.536495) (xy 458.146183 -240.488474) (xy 458.176207 -240.444437) (xy 458.212459 -240.405366)
			(xy 458.25413 -240.372135) (xy 458.300288 -240.345486) (xy 458.349902 -240.326014) (xy 458.401864 -240.314154)
			(xy 458.455014 -240.310171) (xy 458.508164 -240.314154) (xy 458.560126 -240.326014) (xy 458.60974 -240.345486)
			(xy 458.655898 -240.372135) (xy 458.697569 -240.405366) (xy 458.733821 -240.444437) (xy 458.763845 -240.488474)
			(xy 458.786971 -240.536495) (xy 458.802681 -240.587425) (xy 458.810624 -240.640129) (xy 458.811122 -240.666778)
			(xy 458.810624 -240.693427) (xy 458.802681 -240.746131) (xy 458.786971 -240.797061) (xy 458.763845 -240.845082)
			(xy 458.733821 -240.889119) (xy 458.697569 -240.92819) (xy 458.655898 -240.961421) (xy 458.60974 -240.98807)
			(xy 458.560126 -241.007542) (xy 458.508164 -241.019402) (xy 458.455014 -241.023386) (xy 458.401864 -241.019402)
			(xy 458.349902 -241.007542) (xy 458.300288 -240.98807) (xy 458.25413 -240.961421) (xy 458.212459 -240.92819)
			(xy 458.176207 -240.889119) (xy 458.146183 -240.845082) (xy 458.123057 -240.797061) (xy 458.107347 -240.746131)
			(xy 458.099404 -240.693427) (xy 455.366892 -240.693427) (xy 455.358949 -240.746131) (xy 455.343239 -240.797061)
			(xy 455.320113 -240.845082) (xy 455.290089 -240.889119) (xy 455.253837 -240.92819) (xy 455.212166 -240.961421)
			(xy 455.166008 -240.98807) (xy 455.116394 -241.007542) (xy 455.064432 -241.019402) (xy 455.011282 -241.023386)
			(xy 454.958132 -241.019402) (xy 454.90617 -241.007542) (xy 454.856556 -240.98807) (xy 454.810398 -240.961421)
			(xy 454.768727 -240.92819) (xy 454.732475 -240.889119) (xy 454.702451 -240.845082) (xy 454.679325 -240.797061)
			(xy 454.663615 -240.746131) (xy 454.655672 -240.693427) (xy 453.476624 -240.693427) (xy 453.468681 -240.746131)
			(xy 453.452971 -240.797061) (xy 453.429845 -240.845082) (xy 453.399821 -240.889119) (xy 453.363569 -240.92819)
			(xy 453.321898 -240.961421) (xy 453.27574 -240.98807) (xy 453.226126 -241.007542) (xy 453.174164 -241.019402)
			(xy 453.121014 -241.023386) (xy 453.067864 -241.019402) (xy 453.015902 -241.007542) (xy 452.966288 -240.98807)
			(xy 452.92013 -240.961421) (xy 452.878459 -240.92819) (xy 452.842207 -240.889119) (xy 452.812183 -240.845082)
			(xy 452.789057 -240.797061) (xy 452.773347 -240.746131) (xy 452.765404 -240.693427) (xy 451.266824 -240.693427)
			(xy 451.258881 -240.746131) (xy 451.243171 -240.797061) (xy 451.220045 -240.845082) (xy 451.190021 -240.889119)
			(xy 451.153769 -240.92819) (xy 451.112098 -240.961421) (xy 451.06594 -240.98807) (xy 451.016326 -241.007542)
			(xy 450.964364 -241.019402) (xy 450.911214 -241.023386) (xy 450.858064 -241.019402) (xy 450.806102 -241.007542)
			(xy 450.756488 -240.98807) (xy 450.71033 -240.961421) (xy 450.668659 -240.92819) (xy 450.632407 -240.889119)
			(xy 450.602383 -240.845082) (xy 450.579257 -240.797061) (xy 450.563547 -240.746131) (xy 450.555604 -240.693427)
			(xy 449.793868 -240.693427) (xy 449.793868 -241.178588) (xy 449.82384 -241.19205) (xy 449.848459 -241.203731)
			(xy 449.894129 -241.23345) (xy 449.93474 -241.269779) (xy 449.969344 -241.311869) (xy 449.997133 -241.358739)
			(xy 450.01746 -241.409294) (xy 450.02985 -241.462355) (xy 450.034014 -241.516684) (xy 450.031976 -241.543311)
			(xy 450.555604 -241.543311) (xy 450.555604 -241.490013) (xy 450.563547 -241.437309) (xy 450.579257 -241.386379)
			(xy 450.602383 -241.338358) (xy 450.632407 -241.294321) (xy 450.668659 -241.25525) (xy 450.71033 -241.222019)
			(xy 450.756488 -241.19537) (xy 450.806102 -241.175898) (xy 450.858064 -241.164038) (xy 450.911214 -241.160055)
			(xy 450.964364 -241.164038) (xy 451.016326 -241.175898) (xy 451.06594 -241.19537) (xy 451.112098 -241.222019)
			(xy 451.153769 -241.25525) (xy 451.190021 -241.294321) (xy 451.220045 -241.338358) (xy 451.243171 -241.386379)
			(xy 451.258881 -241.437309) (xy 451.266824 -241.490013) (xy 451.267322 -241.516662) (xy 451.266824 -241.543311)
			(xy 454.655672 -241.543311) (xy 454.655672 -241.490013) (xy 454.663615 -241.437309) (xy 454.679325 -241.386379)
			(xy 454.702451 -241.338358) (xy 454.732475 -241.294321) (xy 454.768727 -241.25525) (xy 454.810398 -241.222019)
			(xy 454.856556 -241.19537) (xy 454.90617 -241.175898) (xy 454.958132 -241.164038) (xy 455.011282 -241.160055)
			(xy 455.064432 -241.164038) (xy 455.116394 -241.175898) (xy 455.166008 -241.19537) (xy 455.212166 -241.222019)
			(xy 455.253837 -241.25525) (xy 455.290089 -241.294321) (xy 455.320113 -241.338358) (xy 455.343239 -241.386379)
			(xy 455.358949 -241.437309) (xy 455.366892 -241.490013) (xy 455.36739 -241.516662) (xy 455.366892 -241.543311)
			(xy 456.865472 -241.543311) (xy 456.865472 -241.490013) (xy 456.873415 -241.437309) (xy 456.889125 -241.386379)
			(xy 456.912251 -241.338358) (xy 456.942275 -241.294321) (xy 456.978527 -241.25525) (xy 457.020198 -241.222019)
			(xy 457.066356 -241.19537) (xy 457.11597 -241.175898) (xy 457.167932 -241.164038) (xy 457.221082 -241.160055)
			(xy 457.274232 -241.164038) (xy 457.326194 -241.175898) (xy 457.375808 -241.19537) (xy 457.421966 -241.222019)
			(xy 457.463637 -241.25525) (xy 457.499889 -241.294321) (xy 457.529913 -241.338358) (xy 457.553039 -241.386379)
			(xy 457.568749 -241.437309) (xy 457.576692 -241.490013) (xy 457.57719 -241.516662) (xy 457.576692 -241.543311)
			(xy 457.568749 -241.596015) (xy 457.553039 -241.646945) (xy 457.529913 -241.694966) (xy 457.499889 -241.739003)
			(xy 457.463637 -241.778074) (xy 457.421966 -241.811305) (xy 457.375808 -241.837954) (xy 457.326194 -241.857426)
			(xy 457.274232 -241.869286) (xy 457.221082 -241.87327) (xy 457.167932 -241.869286) (xy 457.11597 -241.857426)
			(xy 457.066356 -241.837954) (xy 457.020198 -241.811305) (xy 456.978527 -241.778074) (xy 456.942275 -241.739003)
			(xy 456.912251 -241.694966) (xy 456.889125 -241.646945) (xy 456.873415 -241.596015) (xy 456.865472 -241.543311)
			(xy 455.366892 -241.543311) (xy 455.358949 -241.596015) (xy 455.343239 -241.646945) (xy 455.320113 -241.694966)
			(xy 455.290089 -241.739003) (xy 455.253837 -241.778074) (xy 455.212166 -241.811305) (xy 455.166008 -241.837954)
			(xy 455.116394 -241.857426) (xy 455.064432 -241.869286) (xy 455.011282 -241.87327) (xy 454.958132 -241.869286)
			(xy 454.90617 -241.857426) (xy 454.856556 -241.837954) (xy 454.810398 -241.811305) (xy 454.768727 -241.778074)
			(xy 454.732475 -241.739003) (xy 454.702451 -241.694966) (xy 454.679325 -241.646945) (xy 454.663615 -241.596015)
			(xy 454.655672 -241.543311) (xy 451.266824 -241.543311) (xy 451.258881 -241.596015) (xy 451.243171 -241.646945)
			(xy 451.220045 -241.694966) (xy 451.190021 -241.739003) (xy 451.153769 -241.778074) (xy 451.112098 -241.811305)
			(xy 451.06594 -241.837954) (xy 451.016326 -241.857426) (xy 450.964364 -241.869286) (xy 450.911214 -241.87327)
			(xy 450.858064 -241.869286) (xy 450.806102 -241.857426) (xy 450.756488 -241.837954) (xy 450.71033 -241.811305)
			(xy 450.668659 -241.778074) (xy 450.632407 -241.739003) (xy 450.602383 -241.694966) (xy 450.579257 -241.646945)
			(xy 450.563547 -241.596015) (xy 450.555604 -241.543311) (xy 450.031976 -241.543311) (xy 450.029855 -241.571014)
			(xy 450.01747 -241.624076) (xy 449.997147 -241.674633) (xy 449.969362 -241.721505) (xy 449.934761 -241.763598)
			(xy 449.894154 -241.799931) (xy 449.848486 -241.829654) (xy 449.82384 -241.841274) (xy 449.793868 -241.854736)
			(xy 449.793868 -242.393449) (xy 450.555604 -242.393449) (xy 450.555604 -242.340151) (xy 450.563547 -242.287447)
			(xy 450.579257 -242.236517) (xy 450.602383 -242.188496) (xy 450.632407 -242.144459) (xy 450.668659 -242.105388)
			(xy 450.71033 -242.072157) (xy 450.756488 -242.045508) (xy 450.806102 -242.026036) (xy 450.858064 -242.014176)
			(xy 450.911214 -242.010193) (xy 450.964364 -242.014176) (xy 451.016326 -242.026036) (xy 451.06594 -242.045508)
			(xy 451.112098 -242.072157) (xy 451.153769 -242.105388) (xy 451.190021 -242.144459) (xy 451.220045 -242.188496)
			(xy 451.243171 -242.236517) (xy 451.258881 -242.287447) (xy 451.266824 -242.340151) (xy 451.267322 -242.3668)
			(xy 451.266824 -242.393449) (xy 452.765404 -242.393449) (xy 452.765404 -242.340151) (xy 452.773347 -242.287447)
			(xy 452.789057 -242.236517) (xy 452.812183 -242.188496) (xy 452.842207 -242.144459) (xy 452.878459 -242.105388)
			(xy 452.92013 -242.072157) (xy 452.966288 -242.045508) (xy 453.015902 -242.026036) (xy 453.067864 -242.014176)
			(xy 453.121014 -242.010193) (xy 453.174164 -242.014176) (xy 453.226126 -242.026036) (xy 453.27574 -242.045508)
			(xy 453.321898 -242.072157) (xy 453.363569 -242.105388) (xy 453.399821 -242.144459) (xy 453.429845 -242.188496)
			(xy 453.452971 -242.236517) (xy 453.468681 -242.287447) (xy 453.476624 -242.340151) (xy 453.477122 -242.3668)
			(xy 453.476624 -242.393449) (xy 454.655672 -242.393449) (xy 454.655672 -242.340151) (xy 454.663615 -242.287447)
			(xy 454.679325 -242.236517) (xy 454.702451 -242.188496) (xy 454.732475 -242.144459) (xy 454.768727 -242.105388)
			(xy 454.810398 -242.072157) (xy 454.856556 -242.045508) (xy 454.90617 -242.026036) (xy 454.958132 -242.014176)
			(xy 455.011282 -242.010193) (xy 455.064432 -242.014176) (xy 455.116394 -242.026036) (xy 455.166008 -242.045508)
			(xy 455.212166 -242.072157) (xy 455.253837 -242.105388) (xy 455.290089 -242.144459) (xy 455.320113 -242.188496)
			(xy 455.343239 -242.236517) (xy 455.358949 -242.287447) (xy 455.366892 -242.340151) (xy 455.36739 -242.3668)
			(xy 455.366892 -242.393449) (xy 458.099404 -242.393449) (xy 458.099404 -242.340151) (xy 458.107347 -242.287447)
			(xy 458.123057 -242.236517) (xy 458.146183 -242.188496) (xy 458.176207 -242.144459) (xy 458.212459 -242.105388)
			(xy 458.25413 -242.072157) (xy 458.300288 -242.045508) (xy 458.349902 -242.026036) (xy 458.401864 -242.014176)
			(xy 458.455014 -242.010193) (xy 458.508164 -242.014176) (xy 458.560126 -242.026036) (xy 458.60974 -242.045508)
			(xy 458.655898 -242.072157) (xy 458.697569 -242.105388) (xy 458.733821 -242.144459) (xy 458.763845 -242.188496)
			(xy 458.786971 -242.236517) (xy 458.802681 -242.287447) (xy 458.810624 -242.340151) (xy 458.811122 -242.3668)
			(xy 458.810624 -242.393449) (xy 458.802681 -242.446153) (xy 458.786971 -242.497083) (xy 458.763845 -242.545104)
			(xy 458.733821 -242.589141) (xy 458.697569 -242.628212) (xy 458.655898 -242.661443) (xy 458.60974 -242.688092)
			(xy 458.560126 -242.707564) (xy 458.508164 -242.719424) (xy 458.455014 -242.723408) (xy 458.401864 -242.719424)
			(xy 458.349902 -242.707564) (xy 458.300288 -242.688092) (xy 458.25413 -242.661443) (xy 458.212459 -242.628212)
			(xy 458.176207 -242.589141) (xy 458.146183 -242.545104) (xy 458.123057 -242.497083) (xy 458.107347 -242.446153)
			(xy 458.099404 -242.393449) (xy 455.366892 -242.393449) (xy 455.358949 -242.446153) (xy 455.343239 -242.497083)
			(xy 455.320113 -242.545104) (xy 455.290089 -242.589141) (xy 455.253837 -242.628212) (xy 455.212166 -242.661443)
			(xy 455.166008 -242.688092) (xy 455.116394 -242.707564) (xy 455.064432 -242.719424) (xy 455.011282 -242.723408)
			(xy 454.958132 -242.719424) (xy 454.90617 -242.707564) (xy 454.856556 -242.688092) (xy 454.810398 -242.661443)
			(xy 454.768727 -242.628212) (xy 454.732475 -242.589141) (xy 454.702451 -242.545104) (xy 454.679325 -242.497083)
			(xy 454.663615 -242.446153) (xy 454.655672 -242.393449) (xy 453.476624 -242.393449) (xy 453.468681 -242.446153)
			(xy 453.452971 -242.497083) (xy 453.429845 -242.545104) (xy 453.399821 -242.589141) (xy 453.363569 -242.628212)
			(xy 453.321898 -242.661443) (xy 453.27574 -242.688092) (xy 453.226126 -242.707564) (xy 453.174164 -242.719424)
			(xy 453.121014 -242.723408) (xy 453.067864 -242.719424) (xy 453.015902 -242.707564) (xy 452.966288 -242.688092)
			(xy 452.92013 -242.661443) (xy 452.878459 -242.628212) (xy 452.842207 -242.589141) (xy 452.812183 -242.545104)
			(xy 452.789057 -242.497083) (xy 452.773347 -242.446153) (xy 452.765404 -242.393449) (xy 451.266824 -242.393449)
			(xy 451.258881 -242.446153) (xy 451.243171 -242.497083) (xy 451.220045 -242.545104) (xy 451.190021 -242.589141)
			(xy 451.153769 -242.628212) (xy 451.112098 -242.661443) (xy 451.06594 -242.688092) (xy 451.016326 -242.707564)
			(xy 450.964364 -242.719424) (xy 450.911214 -242.723408) (xy 450.858064 -242.719424) (xy 450.806102 -242.707564)
			(xy 450.756488 -242.688092) (xy 450.71033 -242.661443) (xy 450.668659 -242.628212) (xy 450.632407 -242.589141)
			(xy 450.602383 -242.545104) (xy 450.579257 -242.497083) (xy 450.563547 -242.446153) (xy 450.555604 -242.393449)
			(xy 449.793868 -242.393449) (xy 449.793868 -243.243333) (xy 450.555604 -243.243333) (xy 450.555604 -243.190035)
			(xy 450.563547 -243.137331) (xy 450.579257 -243.086401) (xy 450.602383 -243.03838) (xy 450.632407 -242.994343)
			(xy 450.668659 -242.955272) (xy 450.71033 -242.922041) (xy 450.756488 -242.895392) (xy 450.806102 -242.87592)
			(xy 450.858064 -242.86406) (xy 450.911214 -242.860077) (xy 450.964364 -242.86406) (xy 451.016326 -242.87592)
			(xy 451.06594 -242.895392) (xy 451.112098 -242.922041) (xy 451.153769 -242.955272) (xy 451.190021 -242.994343)
			(xy 451.220045 -243.03838) (xy 451.243171 -243.086401) (xy 451.258881 -243.137331) (xy 451.266824 -243.190035)
			(xy 451.267322 -243.216684) (xy 451.266824 -243.243333) (xy 454.655672 -243.243333) (xy 454.655672 -243.190035)
			(xy 454.663615 -243.137331) (xy 454.679325 -243.086401) (xy 454.702451 -243.03838) (xy 454.732475 -242.994343)
			(xy 454.768727 -242.955272) (xy 454.810398 -242.922041) (xy 454.856556 -242.895392) (xy 454.90617 -242.87592)
			(xy 454.958132 -242.86406) (xy 455.011282 -242.860077) (xy 455.064432 -242.86406) (xy 455.116394 -242.87592)
			(xy 455.166008 -242.895392) (xy 455.212166 -242.922041) (xy 455.253837 -242.955272) (xy 455.290089 -242.994343)
			(xy 455.320113 -243.03838) (xy 455.343239 -243.086401) (xy 455.358949 -243.137331) (xy 455.366892 -243.190035)
			(xy 455.36739 -243.216684) (xy 455.366892 -243.243333) (xy 458.099404 -243.243333) (xy 458.099404 -243.190035)
			(xy 458.107347 -243.137331) (xy 458.123057 -243.086401) (xy 458.146183 -243.03838) (xy 458.176207 -242.994343)
			(xy 458.212459 -242.955272) (xy 458.25413 -242.922041) (xy 458.300288 -242.895392) (xy 458.349902 -242.87592)
			(xy 458.401864 -242.86406) (xy 458.455014 -242.860077) (xy 458.508164 -242.86406) (xy 458.560126 -242.87592)
			(xy 458.60974 -242.895392) (xy 458.655898 -242.922041) (xy 458.697569 -242.955272) (xy 458.733821 -242.994343)
			(xy 458.763845 -243.03838) (xy 458.786971 -243.086401) (xy 458.802681 -243.137331) (xy 458.810624 -243.190035)
			(xy 458.811122 -243.216684) (xy 458.810624 -243.243333) (xy 458.802681 -243.296037) (xy 458.786971 -243.346967)
			(xy 458.763845 -243.394988) (xy 458.733821 -243.439025) (xy 458.697569 -243.478096) (xy 458.655898 -243.511327)
			(xy 458.60974 -243.537976) (xy 458.560126 -243.557448) (xy 458.508164 -243.569308) (xy 458.455014 -243.573292)
			(xy 458.401864 -243.569308) (xy 458.349902 -243.557448) (xy 458.300288 -243.537976) (xy 458.25413 -243.511327)
			(xy 458.212459 -243.478096) (xy 458.176207 -243.439025) (xy 458.146183 -243.394988) (xy 458.123057 -243.346967)
			(xy 458.107347 -243.296037) (xy 458.099404 -243.243333) (xy 455.366892 -243.243333) (xy 455.358949 -243.296037)
			(xy 455.343239 -243.346967) (xy 455.320113 -243.394988) (xy 455.290089 -243.439025) (xy 455.253837 -243.478096)
			(xy 455.212166 -243.511327) (xy 455.166008 -243.537976) (xy 455.116394 -243.557448) (xy 455.064432 -243.569308)
			(xy 455.011282 -243.573292) (xy 454.958132 -243.569308) (xy 454.90617 -243.557448) (xy 454.856556 -243.537976)
			(xy 454.810398 -243.511327) (xy 454.768727 -243.478096) (xy 454.732475 -243.439025) (xy 454.702451 -243.394988)
			(xy 454.679325 -243.346967) (xy 454.663615 -243.296037) (xy 454.655672 -243.243333) (xy 451.266824 -243.243333)
			(xy 451.258881 -243.296037) (xy 451.243171 -243.346967) (xy 451.220045 -243.394988) (xy 451.190021 -243.439025)
			(xy 451.153769 -243.478096) (xy 451.112098 -243.511327) (xy 451.06594 -243.537976) (xy 451.016326 -243.557448)
			(xy 450.964364 -243.569308) (xy 450.911214 -243.573292) (xy 450.858064 -243.569308) (xy 450.806102 -243.557448)
			(xy 450.756488 -243.537976) (xy 450.71033 -243.511327) (xy 450.668659 -243.478096) (xy 450.632407 -243.439025)
			(xy 450.602383 -243.394988) (xy 450.579257 -243.346967) (xy 450.563547 -243.296037) (xy 450.555604 -243.243333)
			(xy 449.793868 -243.243333) (xy 449.793868 -243.728494) (xy 449.82384 -243.741956) (xy 449.848458 -243.753637)
			(xy 449.894127 -243.783356) (xy 449.934737 -243.819685) (xy 449.969341 -243.861774) (xy 449.99713 -243.908643)
			(xy 450.017456 -243.959198) (xy 450.029845 -244.012258) (xy 450.034009 -244.066587) (xy 450.03197 -244.093217)
			(xy 450.555604 -244.093217) (xy 450.555604 -244.039919) (xy 450.563547 -243.987215) (xy 450.579257 -243.936285)
			(xy 450.602383 -243.888264) (xy 450.632407 -243.844227) (xy 450.668659 -243.805156) (xy 450.71033 -243.771925)
			(xy 450.756488 -243.745276) (xy 450.806102 -243.725804) (xy 450.858064 -243.713944) (xy 450.911214 -243.709961)
			(xy 450.964364 -243.713944) (xy 451.016326 -243.725804) (xy 451.06594 -243.745276) (xy 451.112098 -243.771925)
			(xy 451.153769 -243.805156) (xy 451.190021 -243.844227) (xy 451.220045 -243.888264) (xy 451.243171 -243.936285)
			(xy 451.258881 -243.987215) (xy 451.266824 -244.039919) (xy 451.267322 -244.066568) (xy 451.266824 -244.093217)
			(xy 454.655672 -244.093217) (xy 454.655672 -244.039919) (xy 454.663615 -243.987215) (xy 454.679325 -243.936285)
			(xy 454.702451 -243.888264) (xy 454.732475 -243.844227) (xy 454.768727 -243.805156) (xy 454.810398 -243.771925)
			(xy 454.856556 -243.745276) (xy 454.90617 -243.725804) (xy 454.958132 -243.713944) (xy 455.011282 -243.709961)
			(xy 455.064432 -243.713944) (xy 455.116394 -243.725804) (xy 455.166008 -243.745276) (xy 455.212166 -243.771925)
			(xy 455.253837 -243.805156) (xy 455.290089 -243.844227) (xy 455.320113 -243.888264) (xy 455.343239 -243.936285)
			(xy 455.358949 -243.987215) (xy 455.366892 -244.039919) (xy 455.36739 -244.066568) (xy 455.366892 -244.093217)
			(xy 456.865472 -244.093217) (xy 456.865472 -244.039919) (xy 456.873415 -243.987215) (xy 456.889125 -243.936285)
			(xy 456.912251 -243.888264) (xy 456.942275 -243.844227) (xy 456.978527 -243.805156) (xy 457.020198 -243.771925)
			(xy 457.066356 -243.745276) (xy 457.11597 -243.725804) (xy 457.167932 -243.713944) (xy 457.221082 -243.709961)
			(xy 457.274232 -243.713944) (xy 457.326194 -243.725804) (xy 457.375808 -243.745276) (xy 457.421966 -243.771925)
			(xy 457.463637 -243.805156) (xy 457.499889 -243.844227) (xy 457.529913 -243.888264) (xy 457.553039 -243.936285)
			(xy 457.568749 -243.987215) (xy 457.576692 -244.039919) (xy 457.57719 -244.066568) (xy 457.576692 -244.093217)
			(xy 458.099404 -244.093217) (xy 458.099404 -244.039919) (xy 458.107347 -243.987215) (xy 458.123057 -243.936285)
			(xy 458.146183 -243.888264) (xy 458.176207 -243.844227) (xy 458.212459 -243.805156) (xy 458.25413 -243.771925)
			(xy 458.300288 -243.745276) (xy 458.349902 -243.725804) (xy 458.401864 -243.713944) (xy 458.455014 -243.709961)
			(xy 458.508164 -243.713944) (xy 458.560126 -243.725804) (xy 458.60974 -243.745276) (xy 458.655898 -243.771925)
			(xy 458.697569 -243.805156) (xy 458.733821 -243.844227) (xy 458.763845 -243.888264) (xy 458.786971 -243.936285)
			(xy 458.802681 -243.987215) (xy 458.810624 -244.039919) (xy 458.811122 -244.066568) (xy 458.810624 -244.093217)
			(xy 458.802681 -244.145921) (xy 458.786971 -244.196851) (xy 458.763845 -244.244872) (xy 458.733821 -244.288909)
			(xy 458.697569 -244.32798) (xy 458.655898 -244.361211) (xy 458.60974 -244.38786) (xy 458.560126 -244.407332)
			(xy 458.508164 -244.419192) (xy 458.455014 -244.423176) (xy 458.401864 -244.419192) (xy 458.349902 -244.407332)
			(xy 458.300288 -244.38786) (xy 458.25413 -244.361211) (xy 458.212459 -244.32798) (xy 458.176207 -244.288909)
			(xy 458.146183 -244.244872) (xy 458.123057 -244.196851) (xy 458.107347 -244.145921) (xy 458.099404 -244.093217)
			(xy 457.576692 -244.093217) (xy 457.568749 -244.145921) (xy 457.553039 -244.196851) (xy 457.529913 -244.244872)
			(xy 457.499889 -244.288909) (xy 457.463637 -244.32798) (xy 457.421966 -244.361211) (xy 457.375808 -244.38786)
			(xy 457.326194 -244.407332) (xy 457.274232 -244.419192) (xy 457.221082 -244.423176) (xy 457.167932 -244.419192)
			(xy 457.11597 -244.407332) (xy 457.066356 -244.38786) (xy 457.020198 -244.361211) (xy 456.978527 -244.32798)
			(xy 456.942275 -244.288909) (xy 456.912251 -244.244872) (xy 456.889125 -244.196851) (xy 456.873415 -244.145921)
			(xy 456.865472 -244.093217) (xy 455.366892 -244.093217) (xy 455.358949 -244.145921) (xy 455.343239 -244.196851)
			(xy 455.320113 -244.244872) (xy 455.290089 -244.288909) (xy 455.253837 -244.32798) (xy 455.212166 -244.361211)
			(xy 455.166008 -244.38786) (xy 455.116394 -244.407332) (xy 455.064432 -244.419192) (xy 455.011282 -244.423176)
			(xy 454.958132 -244.419192) (xy 454.90617 -244.407332) (xy 454.856556 -244.38786) (xy 454.810398 -244.361211)
			(xy 454.768727 -244.32798) (xy 454.732475 -244.288909) (xy 454.702451 -244.244872) (xy 454.679325 -244.196851)
			(xy 454.663615 -244.145921) (xy 454.655672 -244.093217) (xy 451.266824 -244.093217) (xy 451.258881 -244.145921)
			(xy 451.243171 -244.196851) (xy 451.220045 -244.244872) (xy 451.190021 -244.288909) (xy 451.153769 -244.32798)
			(xy 451.112098 -244.361211) (xy 451.06594 -244.38786) (xy 451.016326 -244.407332) (xy 450.964364 -244.419192)
			(xy 450.911214 -244.423176) (xy 450.858064 -244.419192) (xy 450.806102 -244.407332) (xy 450.756488 -244.38786)
			(xy 450.71033 -244.361211) (xy 450.668659 -244.32798) (xy 450.632407 -244.288909) (xy 450.602383 -244.244872)
			(xy 450.579257 -244.196851) (xy 450.563547 -244.145921) (xy 450.555604 -244.093217) (xy 450.03197 -244.093217)
			(xy 450.029849 -244.120916) (xy 450.017464 -244.173977) (xy 449.997141 -244.224533) (xy 449.969356 -244.271404)
			(xy 449.934756 -244.313496) (xy 449.894148 -244.349828) (xy 449.848481 -244.379551) (xy 449.82384 -244.39118)
			(xy 449.793868 -244.404642) (xy 449.793868 -244.943355) (xy 450.555604 -244.943355) (xy 450.555604 -244.890057)
			(xy 450.563547 -244.837353) (xy 450.579257 -244.786423) (xy 450.602383 -244.738402) (xy 450.632407 -244.694365)
			(xy 450.668659 -244.655294) (xy 450.71033 -244.622063) (xy 450.756488 -244.595414) (xy 450.806102 -244.575942)
			(xy 450.858064 -244.564082) (xy 450.911214 -244.560099) (xy 450.964364 -244.564082) (xy 451.016326 -244.575942)
			(xy 451.06594 -244.595414) (xy 451.112098 -244.622063) (xy 451.153769 -244.655294) (xy 451.190021 -244.694365)
			(xy 451.220045 -244.738402) (xy 451.243171 -244.786423) (xy 451.258881 -244.837353) (xy 451.266824 -244.890057)
			(xy 451.267322 -244.916706) (xy 451.266824 -244.943355) (xy 452.765404 -244.943355) (xy 452.765404 -244.890057)
			(xy 452.773347 -244.837353) (xy 452.789057 -244.786423) (xy 452.812183 -244.738402) (xy 452.842207 -244.694365)
			(xy 452.878459 -244.655294) (xy 452.92013 -244.622063) (xy 452.966288 -244.595414) (xy 453.015902 -244.575942)
			(xy 453.067864 -244.564082) (xy 453.121014 -244.560099) (xy 453.174164 -244.564082) (xy 453.226126 -244.575942)
			(xy 453.27574 -244.595414) (xy 453.321898 -244.622063) (xy 453.363569 -244.655294) (xy 453.399821 -244.694365)
			(xy 453.429845 -244.738402) (xy 453.452971 -244.786423) (xy 453.468681 -244.837353) (xy 453.476624 -244.890057)
			(xy 453.477122 -244.916706) (xy 453.476624 -244.943355) (xy 454.655672 -244.943355) (xy 454.655672 -244.890057)
			(xy 454.663615 -244.837353) (xy 454.679325 -244.786423) (xy 454.702451 -244.738402) (xy 454.732475 -244.694365)
			(xy 454.768727 -244.655294) (xy 454.810398 -244.622063) (xy 454.856556 -244.595414) (xy 454.90617 -244.575942)
			(xy 454.958132 -244.564082) (xy 455.011282 -244.560099) (xy 455.064432 -244.564082) (xy 455.116394 -244.575942)
			(xy 455.166008 -244.595414) (xy 455.212166 -244.622063) (xy 455.253837 -244.655294) (xy 455.290089 -244.694365)
			(xy 455.320113 -244.738402) (xy 455.343239 -244.786423) (xy 455.358949 -244.837353) (xy 455.366892 -244.890057)
			(xy 455.36739 -244.916706) (xy 455.366892 -244.943355) (xy 458.099404 -244.943355) (xy 458.099404 -244.890057)
			(xy 458.107347 -244.837353) (xy 458.123057 -244.786423) (xy 458.146183 -244.738402) (xy 458.176207 -244.694365)
			(xy 458.212459 -244.655294) (xy 458.25413 -244.622063) (xy 458.300288 -244.595414) (xy 458.349902 -244.575942)
			(xy 458.401864 -244.564082) (xy 458.455014 -244.560099) (xy 458.508164 -244.564082) (xy 458.560126 -244.575942)
			(xy 458.60974 -244.595414) (xy 458.655898 -244.622063) (xy 458.697569 -244.655294) (xy 458.733821 -244.694365)
			(xy 458.763845 -244.738402) (xy 458.786971 -244.786423) (xy 458.802681 -244.837353) (xy 458.810624 -244.890057)
			(xy 458.811122 -244.916706) (xy 458.810624 -244.943355) (xy 458.802681 -244.996059) (xy 458.786971 -245.046989)
			(xy 458.763845 -245.09501) (xy 458.733821 -245.139047) (xy 458.697569 -245.178118) (xy 458.655898 -245.211349)
			(xy 458.60974 -245.237998) (xy 458.560126 -245.25747) (xy 458.508164 -245.26933) (xy 458.455014 -245.273314)
			(xy 458.401864 -245.26933) (xy 458.349902 -245.25747) (xy 458.300288 -245.237998) (xy 458.25413 -245.211349)
			(xy 458.212459 -245.178118) (xy 458.176207 -245.139047) (xy 458.146183 -245.09501) (xy 458.123057 -245.046989)
			(xy 458.107347 -244.996059) (xy 458.099404 -244.943355) (xy 455.366892 -244.943355) (xy 455.358949 -244.996059)
			(xy 455.343239 -245.046989) (xy 455.320113 -245.09501) (xy 455.290089 -245.139047) (xy 455.253837 -245.178118)
			(xy 455.212166 -245.211349) (xy 455.166008 -245.237998) (xy 455.116394 -245.25747) (xy 455.064432 -245.26933)
			(xy 455.011282 -245.273314) (xy 454.958132 -245.26933) (xy 454.90617 -245.25747) (xy 454.856556 -245.237998)
			(xy 454.810398 -245.211349) (xy 454.768727 -245.178118) (xy 454.732475 -245.139047) (xy 454.702451 -245.09501)
			(xy 454.679325 -245.046989) (xy 454.663615 -244.996059) (xy 454.655672 -244.943355) (xy 453.476624 -244.943355)
			(xy 453.468681 -244.996059) (xy 453.452971 -245.046989) (xy 453.429845 -245.09501) (xy 453.399821 -245.139047)
			(xy 453.363569 -245.178118) (xy 453.321898 -245.211349) (xy 453.27574 -245.237998) (xy 453.226126 -245.25747)
			(xy 453.174164 -245.26933) (xy 453.121014 -245.273314) (xy 453.067864 -245.26933) (xy 453.015902 -245.25747)
			(xy 452.966288 -245.237998) (xy 452.92013 -245.211349) (xy 452.878459 -245.178118) (xy 452.842207 -245.139047)
			(xy 452.812183 -245.09501) (xy 452.789057 -245.046989) (xy 452.773347 -244.996059) (xy 452.765404 -244.943355)
			(xy 451.266824 -244.943355) (xy 451.258881 -244.996059) (xy 451.243171 -245.046989) (xy 451.220045 -245.09501)
			(xy 451.190021 -245.139047) (xy 451.153769 -245.178118) (xy 451.112098 -245.211349) (xy 451.06594 -245.237998)
			(xy 451.016326 -245.25747) (xy 450.964364 -245.26933) (xy 450.911214 -245.273314) (xy 450.858064 -245.26933)
			(xy 450.806102 -245.25747) (xy 450.756488 -245.237998) (xy 450.71033 -245.211349) (xy 450.668659 -245.178118)
			(xy 450.632407 -245.139047) (xy 450.602383 -245.09501) (xy 450.579257 -245.046989) (xy 450.563547 -244.996059)
			(xy 450.555604 -244.943355) (xy 449.793868 -244.943355) (xy 449.793868 -245.428516) (xy 449.82384 -245.441978)
			(xy 449.848457 -245.453659) (xy 449.894123 -245.483378) (xy 449.934729 -245.519705) (xy 449.969329 -245.561793)
			(xy 449.997116 -245.60866) (xy 450.017439 -245.659212) (xy 450.029827 -245.71227) (xy 450.033989 -245.766596)
			(xy 450.031948 -245.793239) (xy 450.555604 -245.793239) (xy 450.555604 -245.739941) (xy 450.563547 -245.687237)
			(xy 450.579257 -245.636307) (xy 450.602383 -245.588286) (xy 450.632407 -245.544249) (xy 450.668659 -245.505178)
			(xy 450.71033 -245.471947) (xy 450.756488 -245.445298) (xy 450.806102 -245.425826) (xy 450.858064 -245.413966)
			(xy 450.911214 -245.409983) (xy 450.964364 -245.413966) (xy 451.016326 -245.425826) (xy 451.06594 -245.445298)
			(xy 451.112098 -245.471947) (xy 451.153769 -245.505178) (xy 451.190021 -245.544249) (xy 451.220045 -245.588286)
			(xy 451.243171 -245.636307) (xy 451.258881 -245.687237) (xy 451.266824 -245.739941) (xy 451.267322 -245.76659)
			(xy 451.266824 -245.793239) (xy 454.655672 -245.793239) (xy 454.655672 -245.739941) (xy 454.663615 -245.687237)
			(xy 454.679325 -245.636307) (xy 454.702451 -245.588286) (xy 454.732475 -245.544249) (xy 454.768727 -245.505178)
			(xy 454.810398 -245.471947) (xy 454.856556 -245.445298) (xy 454.90617 -245.425826) (xy 454.958132 -245.413966)
			(xy 455.011282 -245.409983) (xy 455.064432 -245.413966) (xy 455.116394 -245.425826) (xy 455.166008 -245.445298)
			(xy 455.212166 -245.471947) (xy 455.253837 -245.505178) (xy 455.290089 -245.544249) (xy 455.320113 -245.588286)
			(xy 455.343239 -245.636307) (xy 455.358949 -245.687237) (xy 455.366892 -245.739941) (xy 455.36739 -245.76659)
			(xy 455.366892 -245.793239) (xy 456.865472 -245.793239) (xy 456.865472 -245.739941) (xy 456.873415 -245.687237)
			(xy 456.889125 -245.636307) (xy 456.912251 -245.588286) (xy 456.942275 -245.544249) (xy 456.978527 -245.505178)
			(xy 457.020198 -245.471947) (xy 457.066356 -245.445298) (xy 457.11597 -245.425826) (xy 457.167932 -245.413966)
			(xy 457.221082 -245.409983) (xy 457.274232 -245.413966) (xy 457.326194 -245.425826) (xy 457.375808 -245.445298)
			(xy 457.421966 -245.471947) (xy 457.463637 -245.505178) (xy 457.499889 -245.544249) (xy 457.529913 -245.588286)
			(xy 457.553039 -245.636307) (xy 457.568749 -245.687237) (xy 457.576692 -245.739941) (xy 457.57719 -245.76659)
			(xy 457.576692 -245.793239) (xy 458.099404 -245.793239) (xy 458.099404 -245.739941) (xy 458.107347 -245.687237)
			(xy 458.123057 -245.636307) (xy 458.146183 -245.588286) (xy 458.176207 -245.544249) (xy 458.212459 -245.505178)
			(xy 458.25413 -245.471947) (xy 458.300288 -245.445298) (xy 458.349902 -245.425826) (xy 458.401864 -245.413966)
			(xy 458.455014 -245.409983) (xy 458.508164 -245.413966) (xy 458.560126 -245.425826) (xy 458.60974 -245.445298)
			(xy 458.655898 -245.471947) (xy 458.697569 -245.505178) (xy 458.733821 -245.544249) (xy 458.763845 -245.588286)
			(xy 458.786971 -245.636307) (xy 458.802681 -245.687237) (xy 458.810624 -245.739941) (xy 458.811122 -245.76659)
			(xy 458.810624 -245.793239) (xy 458.802681 -245.845943) (xy 458.786971 -245.896873) (xy 458.763845 -245.944894)
			(xy 458.733821 -245.988931) (xy 458.697569 -246.028002) (xy 458.655898 -246.061233) (xy 458.60974 -246.087882)
			(xy 458.560126 -246.107354) (xy 458.508164 -246.119214) (xy 458.455014 -246.123198) (xy 458.401864 -246.119214)
			(xy 458.349902 -246.107354) (xy 458.300288 -246.087882) (xy 458.25413 -246.061233) (xy 458.212459 -246.028002)
			(xy 458.176207 -245.988931) (xy 458.146183 -245.944894) (xy 458.123057 -245.896873) (xy 458.107347 -245.845943)
			(xy 458.099404 -245.793239) (xy 457.576692 -245.793239) (xy 457.568749 -245.845943) (xy 457.553039 -245.896873)
			(xy 457.529913 -245.944894) (xy 457.499889 -245.988931) (xy 457.463637 -246.028002) (xy 457.421966 -246.061233)
			(xy 457.375808 -246.087882) (xy 457.326194 -246.107354) (xy 457.274232 -246.119214) (xy 457.221082 -246.123198)
			(xy 457.167932 -246.119214) (xy 457.11597 -246.107354) (xy 457.066356 -246.087882) (xy 457.020198 -246.061233)
			(xy 456.978527 -246.028002) (xy 456.942275 -245.988931) (xy 456.912251 -245.944894) (xy 456.889125 -245.896873)
			(xy 456.873415 -245.845943) (xy 456.865472 -245.793239) (xy 455.366892 -245.793239) (xy 455.358949 -245.845943)
			(xy 455.343239 -245.896873) (xy 455.320113 -245.944894) (xy 455.290089 -245.988931) (xy 455.253837 -246.028002)
			(xy 455.212166 -246.061233) (xy 455.166008 -246.087882) (xy 455.116394 -246.107354) (xy 455.064432 -246.119214)
			(xy 455.011282 -246.123198) (xy 454.958132 -246.119214) (xy 454.90617 -246.107354) (xy 454.856556 -246.087882)
			(xy 454.810398 -246.061233) (xy 454.768727 -246.028002) (xy 454.732475 -245.988931) (xy 454.702451 -245.944894)
			(xy 454.679325 -245.896873) (xy 454.663615 -245.845943) (xy 454.655672 -245.793239) (xy 451.266824 -245.793239)
			(xy 451.258881 -245.845943) (xy 451.243171 -245.896873) (xy 451.220045 -245.944894) (xy 451.190021 -245.988931)
			(xy 451.153769 -246.028002) (xy 451.112098 -246.061233) (xy 451.06594 -246.087882) (xy 451.016326 -246.107354)
			(xy 450.964364 -246.119214) (xy 450.911214 -246.123198) (xy 450.858064 -246.119214) (xy 450.806102 -246.107354)
			(xy 450.756488 -246.087882) (xy 450.71033 -246.061233) (xy 450.668659 -246.028002) (xy 450.632407 -245.988931)
			(xy 450.602383 -245.944894) (xy 450.579257 -245.896873) (xy 450.563547 -245.845943) (xy 450.555604 -245.793239)
			(xy 450.031948 -245.793239) (xy 450.029828 -245.820922) (xy 450.017442 -245.87398) (xy 449.997119 -245.924532)
			(xy 449.969334 -245.9714) (xy 449.934735 -246.013489) (xy 449.894129 -246.049817) (xy 449.848464 -246.079537)
			(xy 449.82384 -246.091202) (xy 449.793868 -246.104664) (xy 449.793868 -246.643377) (xy 450.555604 -246.643377)
			(xy 450.555604 -246.590079) (xy 450.563547 -246.537375) (xy 450.579257 -246.486445) (xy 450.602383 -246.438424)
			(xy 450.632407 -246.394387) (xy 450.668659 -246.355316) (xy 450.71033 -246.322085) (xy 450.756488 -246.295436)
			(xy 450.806102 -246.275964) (xy 450.858064 -246.264104) (xy 450.911214 -246.260121) (xy 450.964364 -246.264104)
			(xy 451.016326 -246.275964) (xy 451.06594 -246.295436) (xy 451.112098 -246.322085) (xy 451.153769 -246.355316)
			(xy 451.190021 -246.394387) (xy 451.220045 -246.438424) (xy 451.243171 -246.486445) (xy 451.258881 -246.537375)
			(xy 451.266824 -246.590079) (xy 451.267322 -246.616728) (xy 451.266824 -246.643377) (xy 452.765404 -246.643377)
			(xy 452.765404 -246.590079) (xy 452.773347 -246.537375) (xy 452.789057 -246.486445) (xy 452.812183 -246.438424)
			(xy 452.842207 -246.394387) (xy 452.878459 -246.355316) (xy 452.92013 -246.322085) (xy 452.966288 -246.295436)
			(xy 453.015902 -246.275964) (xy 453.067864 -246.264104) (xy 453.121014 -246.260121) (xy 453.174164 -246.264104)
			(xy 453.226126 -246.275964) (xy 453.27574 -246.295436) (xy 453.321898 -246.322085) (xy 453.363569 -246.355316)
			(xy 453.399821 -246.394387) (xy 453.429845 -246.438424) (xy 453.452971 -246.486445) (xy 453.468681 -246.537375)
			(xy 453.476624 -246.590079) (xy 453.477122 -246.616728) (xy 453.476624 -246.643377) (xy 454.655672 -246.643377)
			(xy 454.655672 -246.590079) (xy 454.663615 -246.537375) (xy 454.679325 -246.486445) (xy 454.702451 -246.438424)
			(xy 454.732475 -246.394387) (xy 454.768727 -246.355316) (xy 454.810398 -246.322085) (xy 454.856556 -246.295436)
			(xy 454.90617 -246.275964) (xy 454.958132 -246.264104) (xy 455.011282 -246.260121) (xy 455.064432 -246.264104)
			(xy 455.116394 -246.275964) (xy 455.166008 -246.295436) (xy 455.212166 -246.322085) (xy 455.253837 -246.355316)
			(xy 455.290089 -246.394387) (xy 455.320113 -246.438424) (xy 455.343239 -246.486445) (xy 455.358949 -246.537375)
			(xy 455.366892 -246.590079) (xy 455.36739 -246.616728) (xy 455.366892 -246.643377) (xy 458.099404 -246.643377)
			(xy 458.099404 -246.590079) (xy 458.107347 -246.537375) (xy 458.123057 -246.486445) (xy 458.146183 -246.438424)
			(xy 458.176207 -246.394387) (xy 458.212459 -246.355316) (xy 458.25413 -246.322085) (xy 458.300288 -246.295436)
			(xy 458.349902 -246.275964) (xy 458.401864 -246.264104) (xy 458.455014 -246.260121) (xy 458.508164 -246.264104)
			(xy 458.560126 -246.275964) (xy 458.60974 -246.295436) (xy 458.655898 -246.322085) (xy 458.697569 -246.355316)
			(xy 458.733821 -246.394387) (xy 458.763845 -246.438424) (xy 458.786971 -246.486445) (xy 458.802681 -246.537375)
			(xy 458.810624 -246.590079) (xy 458.811122 -246.616728) (xy 458.810624 -246.643377) (xy 458.802681 -246.696081)
			(xy 458.786971 -246.747011) (xy 458.763845 -246.795032) (xy 458.733821 -246.839069) (xy 458.697569 -246.87814)
			(xy 458.655898 -246.911371) (xy 458.60974 -246.93802) (xy 458.560126 -246.957492) (xy 458.508164 -246.969352)
			(xy 458.455014 -246.973336) (xy 458.401864 -246.969352) (xy 458.349902 -246.957492) (xy 458.300288 -246.93802)
			(xy 458.25413 -246.911371) (xy 458.212459 -246.87814) (xy 458.176207 -246.839069) (xy 458.146183 -246.795032)
			(xy 458.123057 -246.747011) (xy 458.107347 -246.696081) (xy 458.099404 -246.643377) (xy 455.366892 -246.643377)
			(xy 455.358949 -246.696081) (xy 455.343239 -246.747011) (xy 455.320113 -246.795032) (xy 455.290089 -246.839069)
			(xy 455.253837 -246.87814) (xy 455.212166 -246.911371) (xy 455.166008 -246.93802) (xy 455.116394 -246.957492)
			(xy 455.064432 -246.969352) (xy 455.011282 -246.973336) (xy 454.958132 -246.969352) (xy 454.90617 -246.957492)
			(xy 454.856556 -246.93802) (xy 454.810398 -246.911371) (xy 454.768727 -246.87814) (xy 454.732475 -246.839069)
			(xy 454.702451 -246.795032) (xy 454.679325 -246.747011) (xy 454.663615 -246.696081) (xy 454.655672 -246.643377)
			(xy 453.476624 -246.643377) (xy 453.468681 -246.696081) (xy 453.452971 -246.747011) (xy 453.429845 -246.795032)
			(xy 453.399821 -246.839069) (xy 453.363569 -246.87814) (xy 453.321898 -246.911371) (xy 453.27574 -246.93802)
			(xy 453.226126 -246.957492) (xy 453.174164 -246.969352) (xy 453.121014 -246.973336) (xy 453.067864 -246.969352)
			(xy 453.015902 -246.957492) (xy 452.966288 -246.93802) (xy 452.92013 -246.911371) (xy 452.878459 -246.87814)
			(xy 452.842207 -246.839069) (xy 452.812183 -246.795032) (xy 452.789057 -246.747011) (xy 452.773347 -246.696081)
			(xy 452.765404 -246.643377) (xy 451.266824 -246.643377) (xy 451.258881 -246.696081) (xy 451.243171 -246.747011)
			(xy 451.220045 -246.795032) (xy 451.190021 -246.839069) (xy 451.153769 -246.87814) (xy 451.112098 -246.911371)
			(xy 451.06594 -246.93802) (xy 451.016326 -246.957492) (xy 450.964364 -246.969352) (xy 450.911214 -246.973336)
			(xy 450.858064 -246.969352) (xy 450.806102 -246.957492) (xy 450.756488 -246.93802) (xy 450.71033 -246.911371)
			(xy 450.668659 -246.87814) (xy 450.632407 -246.839069) (xy 450.602383 -246.795032) (xy 450.579257 -246.747011)
			(xy 450.563547 -246.696081) (xy 450.555604 -246.643377) (xy 449.793868 -246.643377) (xy 449.793868 -247.128538)
			(xy 449.82384 -247.142) (xy 449.848455 -247.15368) (xy 449.894118 -247.183399) (xy 449.934721 -247.219725)
			(xy 449.969318 -247.261812) (xy 449.997102 -247.308677) (xy 450.017423 -247.359227) (xy 450.029808 -247.412282)
			(xy 450.033969 -247.466605) (xy 450.031927 -247.493261) (xy 450.555604 -247.493261) (xy 450.555604 -247.439963)
			(xy 450.563547 -247.387259) (xy 450.579257 -247.336329) (xy 450.602383 -247.288308) (xy 450.632407 -247.244271)
			(xy 450.668659 -247.2052) (xy 450.71033 -247.171969) (xy 450.756488 -247.14532) (xy 450.806102 -247.125848)
			(xy 450.858064 -247.113988) (xy 450.911214 -247.110005) (xy 450.964364 -247.113988) (xy 451.016326 -247.125848)
			(xy 451.06594 -247.14532) (xy 451.112098 -247.171969) (xy 451.153769 -247.2052) (xy 451.190021 -247.244271)
			(xy 451.220045 -247.288308) (xy 451.243171 -247.336329) (xy 451.258881 -247.387259) (xy 451.266824 -247.439963)
			(xy 451.267322 -247.466612) (xy 451.266824 -247.493261) (xy 454.655672 -247.493261) (xy 454.655672 -247.439963)
			(xy 454.663615 -247.387259) (xy 454.679325 -247.336329) (xy 454.702451 -247.288308) (xy 454.732475 -247.244271)
			(xy 454.768727 -247.2052) (xy 454.810398 -247.171969) (xy 454.856556 -247.14532) (xy 454.90617 -247.125848)
			(xy 454.958132 -247.113988) (xy 455.011282 -247.110005) (xy 455.064432 -247.113988) (xy 455.116394 -247.125848)
			(xy 455.166008 -247.14532) (xy 455.212166 -247.171969) (xy 455.253837 -247.2052) (xy 455.290089 -247.244271)
			(xy 455.320113 -247.288308) (xy 455.343239 -247.336329) (xy 455.358949 -247.387259) (xy 455.366892 -247.439963)
			(xy 455.36739 -247.466612) (xy 455.366892 -247.493261) (xy 456.865472 -247.493261) (xy 456.865472 -247.439963)
			(xy 456.873415 -247.387259) (xy 456.889125 -247.336329) (xy 456.912251 -247.288308) (xy 456.942275 -247.244271)
			(xy 456.978527 -247.2052) (xy 457.020198 -247.171969) (xy 457.066356 -247.14532) (xy 457.11597 -247.125848)
			(xy 457.167932 -247.113988) (xy 457.221082 -247.110005) (xy 457.274232 -247.113988) (xy 457.326194 -247.125848)
			(xy 457.375808 -247.14532) (xy 457.421966 -247.171969) (xy 457.463637 -247.2052) (xy 457.499889 -247.244271)
			(xy 457.529913 -247.288308) (xy 457.553039 -247.336329) (xy 457.568749 -247.387259) (xy 457.576692 -247.439963)
			(xy 457.57719 -247.466612) (xy 457.576692 -247.493261) (xy 457.568749 -247.545965) (xy 457.553039 -247.596895)
			(xy 457.529913 -247.644916) (xy 457.499889 -247.688953) (xy 457.463637 -247.728024) (xy 457.421966 -247.761255)
			(xy 457.375808 -247.787904) (xy 457.326194 -247.807376) (xy 457.274232 -247.819236) (xy 457.221082 -247.82322)
			(xy 457.167932 -247.819236) (xy 457.11597 -247.807376) (xy 457.066356 -247.787904) (xy 457.020198 -247.761255)
			(xy 456.978527 -247.728024) (xy 456.942275 -247.688953) (xy 456.912251 -247.644916) (xy 456.889125 -247.596895)
			(xy 456.873415 -247.545965) (xy 456.865472 -247.493261) (xy 455.366892 -247.493261) (xy 455.358949 -247.545965)
			(xy 455.343239 -247.596895) (xy 455.320113 -247.644916) (xy 455.290089 -247.688953) (xy 455.253837 -247.728024)
			(xy 455.212166 -247.761255) (xy 455.166008 -247.787904) (xy 455.116394 -247.807376) (xy 455.064432 -247.819236)
			(xy 455.011282 -247.82322) (xy 454.958132 -247.819236) (xy 454.90617 -247.807376) (xy 454.856556 -247.787904)
			(xy 454.810398 -247.761255) (xy 454.768727 -247.728024) (xy 454.732475 -247.688953) (xy 454.702451 -247.644916)
			(xy 454.679325 -247.596895) (xy 454.663615 -247.545965) (xy 454.655672 -247.493261) (xy 451.266824 -247.493261)
			(xy 451.258881 -247.545965) (xy 451.243171 -247.596895) (xy 451.220045 -247.644916) (xy 451.190021 -247.688953)
			(xy 451.153769 -247.728024) (xy 451.112098 -247.761255) (xy 451.06594 -247.787904) (xy 451.016326 -247.807376)
			(xy 450.964364 -247.819236) (xy 450.911214 -247.82322) (xy 450.858064 -247.819236) (xy 450.806102 -247.807376)
			(xy 450.756488 -247.787904) (xy 450.71033 -247.761255) (xy 450.668659 -247.728024) (xy 450.632407 -247.688953)
			(xy 450.602383 -247.644916) (xy 450.579257 -247.596895) (xy 450.563547 -247.545965) (xy 450.555604 -247.493261)
			(xy 450.031927 -247.493261) (xy 450.029807 -247.520927) (xy 450.01742 -247.573982) (xy 449.997097 -247.624532)
			(xy 449.969312 -247.671396) (xy 449.934714 -247.713482) (xy 449.89411 -247.749807) (xy 449.848446 -247.779524)
			(xy 449.82384 -247.791224) (xy 449.793868 -247.804686) (xy 449.793868 -248.343399) (xy 450.555604 -248.343399)
			(xy 450.555604 -248.290101) (xy 450.563547 -248.237397) (xy 450.579257 -248.186467) (xy 450.602383 -248.138446)
			(xy 450.632407 -248.094409) (xy 450.668659 -248.055338) (xy 450.71033 -248.022107) (xy 450.756488 -247.995458)
			(xy 450.806102 -247.975986) (xy 450.858064 -247.964126) (xy 450.911214 -247.960143) (xy 450.964364 -247.964126)
			(xy 451.016326 -247.975986) (xy 451.06594 -247.995458) (xy 451.112098 -248.022107) (xy 451.153769 -248.055338)
			(xy 451.190021 -248.094409) (xy 451.220045 -248.138446) (xy 451.243171 -248.186467) (xy 451.258881 -248.237397)
			(xy 451.266824 -248.290101) (xy 451.267322 -248.31675) (xy 451.266824 -248.343399) (xy 452.765404 -248.343399)
			(xy 452.765404 -248.290101) (xy 452.773347 -248.237397) (xy 452.789057 -248.186467) (xy 452.812183 -248.138446)
			(xy 452.842207 -248.094409) (xy 452.878459 -248.055338) (xy 452.92013 -248.022107) (xy 452.966288 -247.995458)
			(xy 453.015902 -247.975986) (xy 453.067864 -247.964126) (xy 453.121014 -247.960143) (xy 453.174164 -247.964126)
			(xy 453.226126 -247.975986) (xy 453.27574 -247.995458) (xy 453.321898 -248.022107) (xy 453.363569 -248.055338)
			(xy 453.399821 -248.094409) (xy 453.429845 -248.138446) (xy 453.452971 -248.186467) (xy 453.468681 -248.237397)
			(xy 453.476624 -248.290101) (xy 453.477122 -248.31675) (xy 453.476624 -248.343399) (xy 454.655672 -248.343399)
			(xy 454.655672 -248.290101) (xy 454.663615 -248.237397) (xy 454.679325 -248.186467) (xy 454.702451 -248.138446)
			(xy 454.732475 -248.094409) (xy 454.768727 -248.055338) (xy 454.810398 -248.022107) (xy 454.856556 -247.995458)
			(xy 454.90617 -247.975986) (xy 454.958132 -247.964126) (xy 455.011282 -247.960143) (xy 455.064432 -247.964126)
			(xy 455.116394 -247.975986) (xy 455.166008 -247.995458) (xy 455.212166 -248.022107) (xy 455.253837 -248.055338)
			(xy 455.290089 -248.094409) (xy 455.320113 -248.138446) (xy 455.343239 -248.186467) (xy 455.358949 -248.237397)
			(xy 455.366892 -248.290101) (xy 455.36739 -248.31675) (xy 455.366892 -248.343399) (xy 458.099404 -248.343399)
			(xy 458.099404 -248.290101) (xy 458.107347 -248.237397) (xy 458.123057 -248.186467) (xy 458.146183 -248.138446)
			(xy 458.176207 -248.094409) (xy 458.212459 -248.055338) (xy 458.25413 -248.022107) (xy 458.300288 -247.995458)
			(xy 458.349902 -247.975986) (xy 458.401864 -247.964126) (xy 458.455014 -247.960143) (xy 458.508164 -247.964126)
			(xy 458.560126 -247.975986) (xy 458.60974 -247.995458) (xy 458.655898 -248.022107) (xy 458.697569 -248.055338)
			(xy 458.733821 -248.094409) (xy 458.763845 -248.138446) (xy 458.786971 -248.186467) (xy 458.802681 -248.237397)
			(xy 458.810624 -248.290101) (xy 458.811122 -248.31675) (xy 458.810624 -248.343399) (xy 458.802681 -248.396103)
			(xy 458.786971 -248.447033) (xy 458.763845 -248.495054) (xy 458.733821 -248.539091) (xy 458.697569 -248.578162)
			(xy 458.655898 -248.611393) (xy 458.60974 -248.638042) (xy 458.560126 -248.657514) (xy 458.508164 -248.669374)
			(xy 458.455014 -248.673358) (xy 458.401864 -248.669374) (xy 458.349902 -248.657514) (xy 458.300288 -248.638042)
			(xy 458.25413 -248.611393) (xy 458.212459 -248.578162) (xy 458.176207 -248.539091) (xy 458.146183 -248.495054)
			(xy 458.123057 -248.447033) (xy 458.107347 -248.396103) (xy 458.099404 -248.343399) (xy 455.366892 -248.343399)
			(xy 455.358949 -248.396103) (xy 455.343239 -248.447033) (xy 455.320113 -248.495054) (xy 455.290089 -248.539091)
			(xy 455.253837 -248.578162) (xy 455.212166 -248.611393) (xy 455.166008 -248.638042) (xy 455.116394 -248.657514)
			(xy 455.064432 -248.669374) (xy 455.011282 -248.673358) (xy 454.958132 -248.669374) (xy 454.90617 -248.657514)
			(xy 454.856556 -248.638042) (xy 454.810398 -248.611393) (xy 454.768727 -248.578162) (xy 454.732475 -248.539091)
			(xy 454.702451 -248.495054) (xy 454.679325 -248.447033) (xy 454.663615 -248.396103) (xy 454.655672 -248.343399)
			(xy 453.476624 -248.343399) (xy 453.468681 -248.396103) (xy 453.452971 -248.447033) (xy 453.429845 -248.495054)
			(xy 453.399821 -248.539091) (xy 453.363569 -248.578162) (xy 453.321898 -248.611393) (xy 453.27574 -248.638042)
			(xy 453.226126 -248.657514) (xy 453.174164 -248.669374) (xy 453.121014 -248.673358) (xy 453.067864 -248.669374)
			(xy 453.015902 -248.657514) (xy 452.966288 -248.638042) (xy 452.92013 -248.611393) (xy 452.878459 -248.578162)
			(xy 452.842207 -248.539091) (xy 452.812183 -248.495054) (xy 452.789057 -248.447033) (xy 452.773347 -248.396103)
			(xy 452.765404 -248.343399) (xy 451.266824 -248.343399) (xy 451.258881 -248.396103) (xy 451.243171 -248.447033)
			(xy 451.220045 -248.495054) (xy 451.190021 -248.539091) (xy 451.153769 -248.578162) (xy 451.112098 -248.611393)
			(xy 451.06594 -248.638042) (xy 451.016326 -248.657514) (xy 450.964364 -248.669374) (xy 450.911214 -248.673358)
			(xy 450.858064 -248.669374) (xy 450.806102 -248.657514) (xy 450.756488 -248.638042) (xy 450.71033 -248.611393)
			(xy 450.668659 -248.578162) (xy 450.632407 -248.539091) (xy 450.602383 -248.495054) (xy 450.579257 -248.447033)
			(xy 450.563547 -248.396103) (xy 450.555604 -248.343399) (xy 449.793868 -248.343399) (xy 449.793868 -248.82856)
			(xy 449.82384 -248.842022) (xy 449.848453 -248.853702) (xy 449.894113 -248.88342) (xy 449.934713 -248.919746)
			(xy 449.969307 -248.961831) (xy 449.997088 -249.008694) (xy 450.017407 -249.059242) (xy 450.02979 -249.112294)
			(xy 450.033949 -249.166614) (xy 450.031905 -249.193283) (xy 450.555604 -249.193283) (xy 450.555604 -249.139985)
			(xy 450.563547 -249.087281) (xy 450.579257 -249.036351) (xy 450.602383 -248.98833) (xy 450.632407 -248.944293)
			(xy 450.668659 -248.905222) (xy 450.71033 -248.871991) (xy 450.756488 -248.845342) (xy 450.806102 -248.82587)
			(xy 450.858064 -248.81401) (xy 450.911214 -248.810027) (xy 450.964364 -248.81401) (xy 451.016326 -248.82587)
			(xy 451.06594 -248.845342) (xy 451.112098 -248.871991) (xy 451.153769 -248.905222) (xy 451.190021 -248.944293)
			(xy 451.220045 -248.98833) (xy 451.243171 -249.036351) (xy 451.258881 -249.087281) (xy 451.266824 -249.139985)
			(xy 451.267322 -249.166634) (xy 451.266824 -249.193283) (xy 454.655672 -249.193283) (xy 454.655672 -249.139985)
			(xy 454.663615 -249.087281) (xy 454.679325 -249.036351) (xy 454.702451 -248.98833) (xy 454.732475 -248.944293)
			(xy 454.768727 -248.905222) (xy 454.810398 -248.871991) (xy 454.856556 -248.845342) (xy 454.90617 -248.82587)
			(xy 454.958132 -248.81401) (xy 455.011282 -248.810027) (xy 455.064432 -248.81401) (xy 455.116394 -248.82587)
			(xy 455.166008 -248.845342) (xy 455.212166 -248.871991) (xy 455.253837 -248.905222) (xy 455.290089 -248.944293)
			(xy 455.320113 -248.98833) (xy 455.343239 -249.036351) (xy 455.358949 -249.087281) (xy 455.366892 -249.139985)
			(xy 455.36739 -249.166634) (xy 455.366892 -249.193283) (xy 456.865472 -249.193283) (xy 456.865472 -249.139985)
			(xy 456.873415 -249.087281) (xy 456.889125 -249.036351) (xy 456.912251 -248.98833) (xy 456.942275 -248.944293)
			(xy 456.978527 -248.905222) (xy 457.020198 -248.871991) (xy 457.066356 -248.845342) (xy 457.11597 -248.82587)
			(xy 457.167932 -248.81401) (xy 457.221082 -248.810027) (xy 457.274232 -248.81401) (xy 457.326194 -248.82587)
			(xy 457.375808 -248.845342) (xy 457.421966 -248.871991) (xy 457.463637 -248.905222) (xy 457.499889 -248.944293)
			(xy 457.529913 -248.98833) (xy 457.553039 -249.036351) (xy 457.568749 -249.087281) (xy 457.576692 -249.139985)
			(xy 457.57719 -249.166634) (xy 457.576692 -249.193283) (xy 457.568749 -249.245987) (xy 457.553039 -249.296917)
			(xy 457.529913 -249.344938) (xy 457.499889 -249.388975) (xy 457.463637 -249.428046) (xy 457.421966 -249.461277)
			(xy 457.375808 -249.487926) (xy 457.326194 -249.507398) (xy 457.274232 -249.519258) (xy 457.221082 -249.523242)
			(xy 457.167932 -249.519258) (xy 457.11597 -249.507398) (xy 457.066356 -249.487926) (xy 457.020198 -249.461277)
			(xy 456.978527 -249.428046) (xy 456.942275 -249.388975) (xy 456.912251 -249.344938) (xy 456.889125 -249.296917)
			(xy 456.873415 -249.245987) (xy 456.865472 -249.193283) (xy 455.366892 -249.193283) (xy 455.358949 -249.245987)
			(xy 455.343239 -249.296917) (xy 455.320113 -249.344938) (xy 455.290089 -249.388975) (xy 455.253837 -249.428046)
			(xy 455.212166 -249.461277) (xy 455.166008 -249.487926) (xy 455.116394 -249.507398) (xy 455.064432 -249.519258)
			(xy 455.011282 -249.523242) (xy 454.958132 -249.519258) (xy 454.90617 -249.507398) (xy 454.856556 -249.487926)
			(xy 454.810398 -249.461277) (xy 454.768727 -249.428046) (xy 454.732475 -249.388975) (xy 454.702451 -249.344938)
			(xy 454.679325 -249.296917) (xy 454.663615 -249.245987) (xy 454.655672 -249.193283) (xy 451.266824 -249.193283)
			(xy 451.258881 -249.245987) (xy 451.243171 -249.296917) (xy 451.220045 -249.344938) (xy 451.190021 -249.388975)
			(xy 451.153769 -249.428046) (xy 451.112098 -249.461277) (xy 451.06594 -249.487926) (xy 451.016326 -249.507398)
			(xy 450.964364 -249.519258) (xy 450.911214 -249.523242) (xy 450.858064 -249.519258) (xy 450.806102 -249.507398)
			(xy 450.756488 -249.487926) (xy 450.71033 -249.461277) (xy 450.668659 -249.428046) (xy 450.632407 -249.388975)
			(xy 450.602383 -249.344938) (xy 450.579257 -249.296917) (xy 450.563547 -249.245987) (xy 450.555604 -249.193283)
			(xy 450.031905 -249.193283) (xy 450.029786 -249.220933) (xy 450.017398 -249.273985) (xy 449.997075 -249.324531)
			(xy 449.969291 -249.371392) (xy 449.934693 -249.413474) (xy 449.89409 -249.449797) (xy 449.848429 -249.479511)
			(xy 449.82384 -249.491246) (xy 449.793868 -249.504708) (xy 449.793868 -250.043421) (xy 450.555604 -250.043421)
			(xy 450.555604 -249.990123) (xy 450.563547 -249.937419) (xy 450.579257 -249.886489) (xy 450.602383 -249.838468)
			(xy 450.632407 -249.794431) (xy 450.668659 -249.75536) (xy 450.71033 -249.722129) (xy 450.756488 -249.69548)
			(xy 450.806102 -249.676008) (xy 450.858064 -249.664148) (xy 450.911214 -249.660165) (xy 450.964364 -249.664148)
			(xy 451.016326 -249.676008) (xy 451.06594 -249.69548) (xy 451.112098 -249.722129) (xy 451.153769 -249.75536)
			(xy 451.190021 -249.794431) (xy 451.220045 -249.838468) (xy 451.243171 -249.886489) (xy 451.258881 -249.937419)
			(xy 451.266824 -249.990123) (xy 451.267322 -250.016772) (xy 451.266824 -250.043421) (xy 452.765404 -250.043421)
			(xy 452.765404 -249.990123) (xy 452.773347 -249.937419) (xy 452.789057 -249.886489) (xy 452.812183 -249.838468)
			(xy 452.842207 -249.794431) (xy 452.878459 -249.75536) (xy 452.92013 -249.722129) (xy 452.966288 -249.69548)
			(xy 453.015902 -249.676008) (xy 453.067864 -249.664148) (xy 453.121014 -249.660165) (xy 453.174164 -249.664148)
			(xy 453.226126 -249.676008) (xy 453.27574 -249.69548) (xy 453.321898 -249.722129) (xy 453.363569 -249.75536)
			(xy 453.399821 -249.794431) (xy 453.429845 -249.838468) (xy 453.452971 -249.886489) (xy 453.468681 -249.937419)
			(xy 453.476624 -249.990123) (xy 453.477122 -250.016772) (xy 453.476624 -250.043421) (xy 454.655672 -250.043421)
			(xy 454.655672 -249.990123) (xy 454.663615 -249.937419) (xy 454.679325 -249.886489) (xy 454.702451 -249.838468)
			(xy 454.732475 -249.794431) (xy 454.768727 -249.75536) (xy 454.810398 -249.722129) (xy 454.856556 -249.69548)
			(xy 454.90617 -249.676008) (xy 454.958132 -249.664148) (xy 455.011282 -249.660165) (xy 455.064432 -249.664148)
			(xy 455.116394 -249.676008) (xy 455.166008 -249.69548) (xy 455.212166 -249.722129) (xy 455.253837 -249.75536)
			(xy 455.290089 -249.794431) (xy 455.320113 -249.838468) (xy 455.343239 -249.886489) (xy 455.358949 -249.937419)
			(xy 455.366892 -249.990123) (xy 455.36739 -250.016772) (xy 455.366892 -250.043421) (xy 458.099404 -250.043421)
			(xy 458.099404 -249.990123) (xy 458.107347 -249.937419) (xy 458.123057 -249.886489) (xy 458.146183 -249.838468)
			(xy 458.176207 -249.794431) (xy 458.212459 -249.75536) (xy 458.25413 -249.722129) (xy 458.300288 -249.69548)
			(xy 458.349902 -249.676008) (xy 458.401864 -249.664148) (xy 458.455014 -249.660165) (xy 458.508164 -249.664148)
			(xy 458.560126 -249.676008) (xy 458.60974 -249.69548) (xy 458.655898 -249.722129) (xy 458.697569 -249.75536)
			(xy 458.733821 -249.794431) (xy 458.763845 -249.838468) (xy 458.786971 -249.886489) (xy 458.802681 -249.937419)
			(xy 458.810624 -249.990123) (xy 458.811122 -250.016772) (xy 458.810624 -250.043421) (xy 458.802681 -250.096125)
			(xy 458.786971 -250.147055) (xy 458.763845 -250.195076) (xy 458.733821 -250.239113) (xy 458.697569 -250.278184)
			(xy 458.655898 -250.311415) (xy 458.60974 -250.338064) (xy 458.560126 -250.357536) (xy 458.508164 -250.369396)
			(xy 458.455014 -250.37338) (xy 458.401864 -250.369396) (xy 458.349902 -250.357536) (xy 458.300288 -250.338064)
			(xy 458.25413 -250.311415) (xy 458.212459 -250.278184) (xy 458.176207 -250.239113) (xy 458.146183 -250.195076)
			(xy 458.123057 -250.147055) (xy 458.107347 -250.096125) (xy 458.099404 -250.043421) (xy 455.366892 -250.043421)
			(xy 455.358949 -250.096125) (xy 455.343239 -250.147055) (xy 455.320113 -250.195076) (xy 455.290089 -250.239113)
			(xy 455.253837 -250.278184) (xy 455.212166 -250.311415) (xy 455.166008 -250.338064) (xy 455.116394 -250.357536)
			(xy 455.064432 -250.369396) (xy 455.011282 -250.37338) (xy 454.958132 -250.369396) (xy 454.90617 -250.357536)
			(xy 454.856556 -250.338064) (xy 454.810398 -250.311415) (xy 454.768727 -250.278184) (xy 454.732475 -250.239113)
			(xy 454.702451 -250.195076) (xy 454.679325 -250.147055) (xy 454.663615 -250.096125) (xy 454.655672 -250.043421)
			(xy 453.476624 -250.043421) (xy 453.468681 -250.096125) (xy 453.452971 -250.147055) (xy 453.429845 -250.195076)
			(xy 453.399821 -250.239113) (xy 453.363569 -250.278184) (xy 453.321898 -250.311415) (xy 453.27574 -250.338064)
			(xy 453.226126 -250.357536) (xy 453.174164 -250.369396) (xy 453.121014 -250.37338) (xy 453.067864 -250.369396)
			(xy 453.015902 -250.357536) (xy 452.966288 -250.338064) (xy 452.92013 -250.311415) (xy 452.878459 -250.278184)
			(xy 452.842207 -250.239113) (xy 452.812183 -250.195076) (xy 452.789057 -250.147055) (xy 452.773347 -250.096125)
			(xy 452.765404 -250.043421) (xy 451.266824 -250.043421) (xy 451.258881 -250.096125) (xy 451.243171 -250.147055)
			(xy 451.220045 -250.195076) (xy 451.190021 -250.239113) (xy 451.153769 -250.278184) (xy 451.112098 -250.311415)
			(xy 451.06594 -250.338064) (xy 451.016326 -250.357536) (xy 450.964364 -250.369396) (xy 450.911214 -250.37338)
			(xy 450.858064 -250.369396) (xy 450.806102 -250.357536) (xy 450.756488 -250.338064) (xy 450.71033 -250.311415)
			(xy 450.668659 -250.278184) (xy 450.632407 -250.239113) (xy 450.602383 -250.195076) (xy 450.579257 -250.147055)
			(xy 450.563547 -250.096125) (xy 450.555604 -250.043421) (xy 449.793868 -250.043421) (xy 449.793868 -250.528582)
			(xy 449.82384 -250.542044) (xy 449.848459 -250.553725) (xy 449.89413 -250.583444) (xy 449.934742 -250.619773)
			(xy 449.969347 -250.661864) (xy 449.997137 -250.708734) (xy 450.017465 -250.75929) (xy 450.029855 -250.812352)
			(xy 450.03402 -250.866682) (xy 450.031982 -250.893305) (xy 450.555604 -250.893305) (xy 450.555604 -250.840007)
			(xy 450.563547 -250.787303) (xy 450.579257 -250.736373) (xy 450.602383 -250.688352) (xy 450.632407 -250.644315)
			(xy 450.668659 -250.605244) (xy 450.71033 -250.572013) (xy 450.756488 -250.545364) (xy 450.806102 -250.525892)
			(xy 450.858064 -250.514032) (xy 450.911214 -250.510049) (xy 450.964364 -250.514032) (xy 451.016326 -250.525892)
			(xy 451.06594 -250.545364) (xy 451.112098 -250.572013) (xy 451.153769 -250.605244) (xy 451.190021 -250.644315)
			(xy 451.220045 -250.688352) (xy 451.243171 -250.736373) (xy 451.258881 -250.787303) (xy 451.266824 -250.840007)
			(xy 451.267322 -250.866656) (xy 451.266824 -250.893305) (xy 454.655672 -250.893305) (xy 454.655672 -250.840007)
			(xy 454.663615 -250.787303) (xy 454.679325 -250.736373) (xy 454.702451 -250.688352) (xy 454.732475 -250.644315)
			(xy 454.768727 -250.605244) (xy 454.810398 -250.572013) (xy 454.856556 -250.545364) (xy 454.90617 -250.525892)
			(xy 454.958132 -250.514032) (xy 455.011282 -250.510049) (xy 455.064432 -250.514032) (xy 455.116394 -250.525892)
			(xy 455.166008 -250.545364) (xy 455.212166 -250.572013) (xy 455.253837 -250.605244) (xy 455.290089 -250.644315)
			(xy 455.320113 -250.688352) (xy 455.343239 -250.736373) (xy 455.358949 -250.787303) (xy 455.366892 -250.840007)
			(xy 455.36739 -250.866656) (xy 455.366892 -250.893305) (xy 456.865472 -250.893305) (xy 456.865472 -250.840007)
			(xy 456.873415 -250.787303) (xy 456.889125 -250.736373) (xy 456.912251 -250.688352) (xy 456.942275 -250.644315)
			(xy 456.978527 -250.605244) (xy 457.020198 -250.572013) (xy 457.066356 -250.545364) (xy 457.11597 -250.525892)
			(xy 457.167932 -250.514032) (xy 457.221082 -250.510049) (xy 457.274232 -250.514032) (xy 457.326194 -250.525892)
			(xy 457.375808 -250.545364) (xy 457.421966 -250.572013) (xy 457.463637 -250.605244) (xy 457.499889 -250.644315)
			(xy 457.529913 -250.688352) (xy 457.553039 -250.736373) (xy 457.568749 -250.787303) (xy 457.576692 -250.840007)
			(xy 457.57719 -250.866656) (xy 457.576692 -250.893305) (xy 457.568749 -250.946009) (xy 457.553039 -250.996939)
			(xy 457.529913 -251.04496) (xy 457.499889 -251.088997) (xy 457.463637 -251.128068) (xy 457.421966 -251.161299)
			(xy 457.375808 -251.187948) (xy 457.326194 -251.20742) (xy 457.274232 -251.21928) (xy 457.221082 -251.223264)
			(xy 457.167932 -251.21928) (xy 457.11597 -251.20742) (xy 457.066356 -251.187948) (xy 457.020198 -251.161299)
			(xy 456.978527 -251.128068) (xy 456.942275 -251.088997) (xy 456.912251 -251.04496) (xy 456.889125 -250.996939)
			(xy 456.873415 -250.946009) (xy 456.865472 -250.893305) (xy 455.366892 -250.893305) (xy 455.358949 -250.946009)
			(xy 455.343239 -250.996939) (xy 455.320113 -251.04496) (xy 455.290089 -251.088997) (xy 455.253837 -251.128068)
			(xy 455.212166 -251.161299) (xy 455.166008 -251.187948) (xy 455.116394 -251.20742) (xy 455.064432 -251.21928)
			(xy 455.011282 -251.223264) (xy 454.958132 -251.21928) (xy 454.90617 -251.20742) (xy 454.856556 -251.187948)
			(xy 454.810398 -251.161299) (xy 454.768727 -251.128068) (xy 454.732475 -251.088997) (xy 454.702451 -251.04496)
			(xy 454.679325 -250.996939) (xy 454.663615 -250.946009) (xy 454.655672 -250.893305) (xy 451.266824 -250.893305)
			(xy 451.258881 -250.946009) (xy 451.243171 -250.996939) (xy 451.220045 -251.04496) (xy 451.190021 -251.088997)
			(xy 451.153769 -251.128068) (xy 451.112098 -251.161299) (xy 451.06594 -251.187948) (xy 451.016326 -251.20742)
			(xy 450.964364 -251.21928) (xy 450.911214 -251.223264) (xy 450.858064 -251.21928) (xy 450.806102 -251.20742)
			(xy 450.756488 -251.187948) (xy 450.71033 -251.161299) (xy 450.668659 -251.128068) (xy 450.632407 -251.088997)
			(xy 450.602383 -251.04496) (xy 450.579257 -250.996939) (xy 450.563547 -250.946009) (xy 450.555604 -250.893305)
			(xy 450.031982 -250.893305) (xy 450.029861 -250.921012) (xy 450.017476 -250.974076) (xy 449.997153 -251.024634)
			(xy 449.969367 -251.071506) (xy 449.934767 -251.1136) (xy 449.894159 -251.149934) (xy 449.848491 -251.179658)
			(xy 449.82384 -251.191268) (xy 449.793868 -251.20473) (xy 449.793868 -251.743443) (xy 450.555604 -251.743443)
			(xy 450.555604 -251.690145) (xy 450.563547 -251.637441) (xy 450.579257 -251.586511) (xy 450.602383 -251.53849)
			(xy 450.632407 -251.494453) (xy 450.668659 -251.455382) (xy 450.71033 -251.422151) (xy 450.756488 -251.395502)
			(xy 450.806102 -251.37603) (xy 450.858064 -251.36417) (xy 450.911214 -251.360187) (xy 450.964364 -251.36417)
			(xy 451.016326 -251.37603) (xy 451.06594 -251.395502) (xy 451.112098 -251.422151) (xy 451.153769 -251.455382)
			(xy 451.190021 -251.494453) (xy 451.220045 -251.53849) (xy 451.243171 -251.586511) (xy 451.258881 -251.637441)
			(xy 451.266824 -251.690145) (xy 451.267322 -251.716794) (xy 451.266824 -251.743443) (xy 452.765404 -251.743443)
			(xy 452.765404 -251.690145) (xy 452.773347 -251.637441) (xy 452.789057 -251.586511) (xy 452.812183 -251.53849)
			(xy 452.842207 -251.494453) (xy 452.878459 -251.455382) (xy 452.92013 -251.422151) (xy 452.966288 -251.395502)
			(xy 453.015902 -251.37603) (xy 453.067864 -251.36417) (xy 453.121014 -251.360187) (xy 453.174164 -251.36417)
			(xy 453.226126 -251.37603) (xy 453.27574 -251.395502) (xy 453.321898 -251.422151) (xy 453.363569 -251.455382)
			(xy 453.399821 -251.494453) (xy 453.429845 -251.53849) (xy 453.452971 -251.586511) (xy 453.468681 -251.637441)
			(xy 453.476624 -251.690145) (xy 453.477122 -251.716794) (xy 453.476624 -251.743443) (xy 454.655672 -251.743443)
			(xy 454.655672 -251.690145) (xy 454.663615 -251.637441) (xy 454.679325 -251.586511) (xy 454.702451 -251.53849)
			(xy 454.732475 -251.494453) (xy 454.768727 -251.455382) (xy 454.810398 -251.422151) (xy 454.856556 -251.395502)
			(xy 454.90617 -251.37603) (xy 454.958132 -251.36417) (xy 455.011282 -251.360187) (xy 455.064432 -251.36417)
			(xy 455.116394 -251.37603) (xy 455.166008 -251.395502) (xy 455.212166 -251.422151) (xy 455.253837 -251.455382)
			(xy 455.290089 -251.494453) (xy 455.320113 -251.53849) (xy 455.343239 -251.586511) (xy 455.358949 -251.637441)
			(xy 455.366892 -251.690145) (xy 455.36739 -251.716794) (xy 455.366892 -251.743443) (xy 458.099404 -251.743443)
			(xy 458.099404 -251.690145) (xy 458.107347 -251.637441) (xy 458.123057 -251.586511) (xy 458.146183 -251.53849)
			(xy 458.176207 -251.494453) (xy 458.212459 -251.455382) (xy 458.25413 -251.422151) (xy 458.300288 -251.395502)
			(xy 458.349902 -251.37603) (xy 458.401864 -251.36417) (xy 458.455014 -251.360187) (xy 458.508164 -251.36417)
			(xy 458.560126 -251.37603) (xy 458.60974 -251.395502) (xy 458.655898 -251.422151) (xy 458.697569 -251.455382)
			(xy 458.733821 -251.494453) (xy 458.763845 -251.53849) (xy 458.786971 -251.586511) (xy 458.802681 -251.637441)
			(xy 458.810624 -251.690145) (xy 458.811122 -251.716794) (xy 458.810624 -251.743443) (xy 458.802681 -251.796147)
			(xy 458.786971 -251.847077) (xy 458.763845 -251.895098) (xy 458.733821 -251.939135) (xy 458.697569 -251.978206)
			(xy 458.655898 -252.011437) (xy 458.60974 -252.038086) (xy 458.560126 -252.057558) (xy 458.508164 -252.069418)
			(xy 458.455014 -252.073402) (xy 458.401864 -252.069418) (xy 458.349902 -252.057558) (xy 458.300288 -252.038086)
			(xy 458.25413 -252.011437) (xy 458.212459 -251.978206) (xy 458.176207 -251.939135) (xy 458.146183 -251.895098)
			(xy 458.123057 -251.847077) (xy 458.107347 -251.796147) (xy 458.099404 -251.743443) (xy 455.366892 -251.743443)
			(xy 455.358949 -251.796147) (xy 455.343239 -251.847077) (xy 455.320113 -251.895098) (xy 455.290089 -251.939135)
			(xy 455.253837 -251.978206) (xy 455.212166 -252.011437) (xy 455.166008 -252.038086) (xy 455.116394 -252.057558)
			(xy 455.064432 -252.069418) (xy 455.011282 -252.073402) (xy 454.958132 -252.069418) (xy 454.90617 -252.057558)
			(xy 454.856556 -252.038086) (xy 454.810398 -252.011437) (xy 454.768727 -251.978206) (xy 454.732475 -251.939135)
			(xy 454.702451 -251.895098) (xy 454.679325 -251.847077) (xy 454.663615 -251.796147) (xy 454.655672 -251.743443)
			(xy 453.476624 -251.743443) (xy 453.468681 -251.796147) (xy 453.452971 -251.847077) (xy 453.429845 -251.895098)
			(xy 453.399821 -251.939135) (xy 453.363569 -251.978206) (xy 453.321898 -252.011437) (xy 453.27574 -252.038086)
			(xy 453.226126 -252.057558) (xy 453.174164 -252.069418) (xy 453.121014 -252.073402) (xy 453.067864 -252.069418)
			(xy 453.015902 -252.057558) (xy 452.966288 -252.038086) (xy 452.92013 -252.011437) (xy 452.878459 -251.978206)
			(xy 452.842207 -251.939135) (xy 452.812183 -251.895098) (xy 452.789057 -251.847077) (xy 452.773347 -251.796147)
			(xy 452.765404 -251.743443) (xy 451.266824 -251.743443) (xy 451.258881 -251.796147) (xy 451.243171 -251.847077)
			(xy 451.220045 -251.895098) (xy 451.190021 -251.939135) (xy 451.153769 -251.978206) (xy 451.112098 -252.011437)
			(xy 451.06594 -252.038086) (xy 451.016326 -252.057558) (xy 450.964364 -252.069418) (xy 450.911214 -252.073402)
			(xy 450.858064 -252.069418) (xy 450.806102 -252.057558) (xy 450.756488 -252.038086) (xy 450.71033 -252.011437)
			(xy 450.668659 -251.978206) (xy 450.632407 -251.939135) (xy 450.602383 -251.895098) (xy 450.579257 -251.847077)
			(xy 450.563547 -251.796147) (xy 450.555604 -251.743443) (xy 449.793868 -251.743443) (xy 449.793868 -252.593327)
			(xy 450.555604 -252.593327) (xy 450.555604 -252.540029) (xy 450.563547 -252.487325) (xy 450.579257 -252.436395)
			(xy 450.602383 -252.388374) (xy 450.632407 -252.344337) (xy 450.668659 -252.305266) (xy 450.71033 -252.272035)
			(xy 450.756488 -252.245386) (xy 450.806102 -252.225914) (xy 450.858064 -252.214054) (xy 450.911214 -252.210071)
			(xy 450.964364 -252.214054) (xy 451.016326 -252.225914) (xy 451.06594 -252.245386) (xy 451.112098 -252.272035)
			(xy 451.153769 -252.305266) (xy 451.190021 -252.344337) (xy 451.220045 -252.388374) (xy 451.243171 -252.436395)
			(xy 451.258881 -252.487325) (xy 451.266824 -252.540029) (xy 451.267322 -252.566678) (xy 451.266824 -252.593327)
			(xy 454.655672 -252.593327) (xy 454.655672 -252.540029) (xy 454.663615 -252.487325) (xy 454.679325 -252.436395)
			(xy 454.702451 -252.388374) (xy 454.732475 -252.344337) (xy 454.768727 -252.305266) (xy 454.810398 -252.272035)
			(xy 454.856556 -252.245386) (xy 454.90617 -252.225914) (xy 454.958132 -252.214054) (xy 455.011282 -252.210071)
			(xy 455.064432 -252.214054) (xy 455.116394 -252.225914) (xy 455.166008 -252.245386) (xy 455.212166 -252.272035)
			(xy 455.253837 -252.305266) (xy 455.290089 -252.344337) (xy 455.320113 -252.388374) (xy 455.343239 -252.436395)
			(xy 455.358949 -252.487325) (xy 455.366892 -252.540029) (xy 455.36739 -252.566678) (xy 455.366892 -252.593327)
			(xy 455.358949 -252.646031) (xy 455.343239 -252.696961) (xy 455.320113 -252.744982) (xy 455.290089 -252.789019)
			(xy 455.253837 -252.82809) (xy 455.212166 -252.861321) (xy 455.166008 -252.88797) (xy 455.116394 -252.907442)
			(xy 455.064432 -252.919302) (xy 455.011282 -252.923286) (xy 454.958132 -252.919302) (xy 454.90617 -252.907442)
			(xy 454.856556 -252.88797) (xy 454.810398 -252.861321) (xy 454.768727 -252.82809) (xy 454.732475 -252.789019)
			(xy 454.702451 -252.744982) (xy 454.679325 -252.696961) (xy 454.663615 -252.646031) (xy 454.655672 -252.593327)
			(xy 451.266824 -252.593327) (xy 451.258881 -252.646031) (xy 451.243171 -252.696961) (xy 451.220045 -252.744982)
			(xy 451.190021 -252.789019) (xy 451.153769 -252.82809) (xy 451.112098 -252.861321) (xy 451.06594 -252.88797)
			(xy 451.016326 -252.907442) (xy 450.964364 -252.919302) (xy 450.911214 -252.923286) (xy 450.858064 -252.919302)
			(xy 450.806102 -252.907442) (xy 450.756488 -252.88797) (xy 450.71033 -252.861321) (xy 450.668659 -252.82809)
			(xy 450.632407 -252.789019) (xy 450.602383 -252.744982) (xy 450.579257 -252.696961) (xy 450.563547 -252.646031)
			(xy 450.555604 -252.593327) (xy 449.793868 -252.593327) (xy 449.793868 -254.258968) (xy 452.529582 -254.258968)
			(xy 452.529582 -254.174432) (xy 452.537382 -254.090256) (xy 452.552916 -254.007159) (xy 452.576051 -253.92585)
			(xy 452.60659 -253.847022) (xy 452.644273 -253.771348) (xy 452.688777 -253.699475) (xy 452.739723 -253.632014)
			(xy 452.796676 -253.569542) (xy 452.859151 -253.512592) (xy 452.926614 -253.46165) (xy 452.99849 -253.417149)
			(xy 453.074166 -253.379471) (xy 453.152995 -253.348936) (xy 453.234305 -253.325805) (xy 453.317403 -253.310275)
			(xy 453.40158 -253.302479) (xy 453.443848 -253.302008) (xy 454.688448 -253.302008) (xy 454.730709 -253.302574)
			(xy 454.814871 -253.310377) (xy 454.897954 -253.325912) (xy 454.979249 -253.349046) (xy 455.058062 -253.379582)
			(xy 455.133722 -253.41726) (xy 455.205583 -253.461758) (xy 455.273032 -253.512696) (xy 455.335494 -253.56964)
			(xy 455.392435 -253.632105) (xy 455.443369 -253.699556) (xy 455.487863 -253.77142) (xy 455.525537 -253.847082)
			(xy 455.556069 -253.925897) (xy 455.579199 -254.007193) (xy 455.59473 -254.090277) (xy 455.602528 -254.174439)
			(xy 455.602528 -254.258961) (xy 455.59473 -254.343123) (xy 455.579199 -254.426207) (xy 455.556069 -254.507503)
			(xy 455.525537 -254.586318) (xy 455.487863 -254.66198) (xy 455.443369 -254.733844) (xy 455.392435 -254.801295)
			(xy 455.335494 -254.86376) (xy 455.273032 -254.920704) (xy 455.205583 -254.971642) (xy 455.133722 -255.01614)
			(xy 455.058062 -255.053818) (xy 454.979249 -255.084354) (xy 454.897954 -255.107488) (xy 454.814871 -255.123023)
			(xy 454.730709 -255.130826) (xy 454.688448 -255.131316) (xy 453.443848 -255.131316) (xy 453.40158 -255.130921)
			(xy 453.317403 -255.123125) (xy 453.234305 -255.107595) (xy 453.152995 -255.084464) (xy 453.074166 -255.053929)
			(xy 452.99849 -255.016251) (xy 452.926614 -254.97175) (xy 452.859151 -254.920808) (xy 452.796676 -254.863858)
			(xy 452.739723 -254.801386) (xy 452.688777 -254.733925) (xy 452.644273 -254.662052) (xy 452.60659 -254.586378)
			(xy 452.576051 -254.50755) (xy 452.552916 -254.426241) (xy 452.537382 -254.343144) (xy 452.529582 -254.258968)
			(xy 449.793868 -254.258968) (xy 449.793868 -258.178554) (xy 449.82384 -258.192016) (xy 449.848454 -258.203696)
			(xy 449.894114 -258.233415) (xy 449.934715 -258.26974) (xy 449.96931 -258.311826) (xy 449.997091 -258.35869)
			(xy 450.017411 -258.409238) (xy 450.029795 -258.462291) (xy 450.033954 -258.516612) (xy 450.031911 -258.543277)
			(xy 450.555604 -258.543277) (xy 450.555604 -258.489979) (xy 450.563547 -258.437275) (xy 450.579257 -258.386345)
			(xy 450.602383 -258.338324) (xy 450.632407 -258.294287) (xy 450.668659 -258.255216) (xy 450.71033 -258.221985)
			(xy 450.756488 -258.195336) (xy 450.806102 -258.175864) (xy 450.858064 -258.164004) (xy 450.911214 -258.160021)
			(xy 450.964364 -258.164004) (xy 451.016326 -258.175864) (xy 451.06594 -258.195336) (xy 451.112098 -258.221985)
			(xy 451.153769 -258.255216) (xy 451.190021 -258.294287) (xy 451.220045 -258.338324) (xy 451.243171 -258.386345)
			(xy 451.258881 -258.437275) (xy 451.266824 -258.489979) (xy 451.267322 -258.516628) (xy 451.266824 -258.543277)
			(xy 452.765404 -258.543277) (xy 452.765404 -258.489979) (xy 452.773347 -258.437275) (xy 452.789057 -258.386345)
			(xy 452.812183 -258.338324) (xy 452.842207 -258.294287) (xy 452.878459 -258.255216) (xy 452.92013 -258.221985)
			(xy 452.966288 -258.195336) (xy 453.015902 -258.175864) (xy 453.067864 -258.164004) (xy 453.121014 -258.160021)
			(xy 453.174164 -258.164004) (xy 453.226126 -258.175864) (xy 453.27574 -258.195336) (xy 453.321898 -258.221985)
			(xy 453.363569 -258.255216) (xy 453.399821 -258.294287) (xy 453.429845 -258.338324) (xy 453.452971 -258.386345)
			(xy 453.468681 -258.437275) (xy 453.476624 -258.489979) (xy 453.477122 -258.516628) (xy 453.476624 -258.543277)
			(xy 454.655672 -258.543277) (xy 454.655672 -258.489979) (xy 454.663615 -258.437275) (xy 454.679325 -258.386345)
			(xy 454.702451 -258.338324) (xy 454.732475 -258.294287) (xy 454.768727 -258.255216) (xy 454.810398 -258.221985)
			(xy 454.856556 -258.195336) (xy 454.90617 -258.175864) (xy 454.958132 -258.164004) (xy 455.011282 -258.160021)
			(xy 455.064432 -258.164004) (xy 455.116394 -258.175864) (xy 455.166008 -258.195336) (xy 455.212166 -258.221985)
			(xy 455.253837 -258.255216) (xy 455.290089 -258.294287) (xy 455.320113 -258.338324) (xy 455.343239 -258.386345)
			(xy 455.358949 -258.437275) (xy 455.366892 -258.489979) (xy 455.36739 -258.516628) (xy 455.366892 -258.543277)
			(xy 456.865472 -258.543277) (xy 456.865472 -258.489979) (xy 456.873415 -258.437275) (xy 456.889125 -258.386345)
			(xy 456.912251 -258.338324) (xy 456.942275 -258.294287) (xy 456.978527 -258.255216) (xy 457.020198 -258.221985)
			(xy 457.066356 -258.195336) (xy 457.11597 -258.175864) (xy 457.167932 -258.164004) (xy 457.221082 -258.160021)
			(xy 457.274232 -258.164004) (xy 457.326194 -258.175864) (xy 457.375808 -258.195336) (xy 457.421966 -258.221985)
			(xy 457.463637 -258.255216) (xy 457.499889 -258.294287) (xy 457.529913 -258.338324) (xy 457.553039 -258.386345)
			(xy 457.568749 -258.437275) (xy 457.576692 -258.489979) (xy 457.57719 -258.516628) (xy 457.576692 -258.543277)
			(xy 458.099404 -258.543277) (xy 458.099404 -258.489979) (xy 458.107347 -258.437275) (xy 458.123057 -258.386345)
			(xy 458.146183 -258.338324) (xy 458.176207 -258.294287) (xy 458.212459 -258.255216) (xy 458.25413 -258.221985)
			(xy 458.300288 -258.195336) (xy 458.349902 -258.175864) (xy 458.401864 -258.164004) (xy 458.455014 -258.160021)
			(xy 458.508164 -258.164004) (xy 458.560126 -258.175864) (xy 458.60974 -258.195336) (xy 458.655898 -258.221985)
			(xy 458.697569 -258.255216) (xy 458.733821 -258.294287) (xy 458.763845 -258.338324) (xy 458.786971 -258.386345)
			(xy 458.802681 -258.437275) (xy 458.810624 -258.489979) (xy 458.811122 -258.516628) (xy 458.810624 -258.543277)
			(xy 458.802681 -258.595981) (xy 458.786971 -258.646911) (xy 458.763845 -258.694932) (xy 458.733821 -258.738969)
			(xy 458.697569 -258.77804) (xy 458.655898 -258.811271) (xy 458.60974 -258.83792) (xy 458.560126 -258.857392)
			(xy 458.508164 -258.869252) (xy 458.455014 -258.873236) (xy 458.401864 -258.869252) (xy 458.349902 -258.857392)
			(xy 458.300288 -258.83792) (xy 458.25413 -258.811271) (xy 458.212459 -258.77804) (xy 458.176207 -258.738969)
			(xy 458.146183 -258.694932) (xy 458.123057 -258.646911) (xy 458.107347 -258.595981) (xy 458.099404 -258.543277)
			(xy 457.576692 -258.543277) (xy 457.568749 -258.595981) (xy 457.553039 -258.646911) (xy 457.529913 -258.694932)
			(xy 457.499889 -258.738969) (xy 457.463637 -258.77804) (xy 457.421966 -258.811271) (xy 457.375808 -258.83792)
			(xy 457.326194 -258.857392) (xy 457.274232 -258.869252) (xy 457.221082 -258.873236) (xy 457.167932 -258.869252)
			(xy 457.11597 -258.857392) (xy 457.066356 -258.83792) (xy 457.020198 -258.811271) (xy 456.978527 -258.77804)
			(xy 456.942275 -258.738969) (xy 456.912251 -258.694932) (xy 456.889125 -258.646911) (xy 456.873415 -258.595981)
			(xy 456.865472 -258.543277) (xy 455.366892 -258.543277) (xy 455.358949 -258.595981) (xy 455.343239 -258.646911)
			(xy 455.320113 -258.694932) (xy 455.290089 -258.738969) (xy 455.253837 -258.77804) (xy 455.212166 -258.811271)
			(xy 455.166008 -258.83792) (xy 455.116394 -258.857392) (xy 455.064432 -258.869252) (xy 455.011282 -258.873236)
			(xy 454.958132 -258.869252) (xy 454.90617 -258.857392) (xy 454.856556 -258.83792) (xy 454.810398 -258.811271)
			(xy 454.768727 -258.77804) (xy 454.732475 -258.738969) (xy 454.702451 -258.694932) (xy 454.679325 -258.646911)
			(xy 454.663615 -258.595981) (xy 454.655672 -258.543277) (xy 453.476624 -258.543277) (xy 453.468681 -258.595981)
			(xy 453.452971 -258.646911) (xy 453.429845 -258.694932) (xy 453.399821 -258.738969) (xy 453.363569 -258.77804)
			(xy 453.321898 -258.811271) (xy 453.27574 -258.83792) (xy 453.226126 -258.857392) (xy 453.174164 -258.869252)
			(xy 453.121014 -258.873236) (xy 453.067864 -258.869252) (xy 453.015902 -258.857392) (xy 452.966288 -258.83792)
			(xy 452.92013 -258.811271) (xy 452.878459 -258.77804) (xy 452.842207 -258.738969) (xy 452.812183 -258.694932)
			(xy 452.789057 -258.646911) (xy 452.773347 -258.595981) (xy 452.765404 -258.543277) (xy 451.266824 -258.543277)
			(xy 451.258881 -258.595981) (xy 451.243171 -258.646911) (xy 451.220045 -258.694932) (xy 451.190021 -258.738969)
			(xy 451.153769 -258.77804) (xy 451.112098 -258.811271) (xy 451.06594 -258.83792) (xy 451.016326 -258.857392)
			(xy 450.964364 -258.869252) (xy 450.911214 -258.873236) (xy 450.858064 -258.869252) (xy 450.806102 -258.857392)
			(xy 450.756488 -258.83792) (xy 450.71033 -258.811271) (xy 450.668659 -258.77804) (xy 450.632407 -258.738969)
			(xy 450.602383 -258.694932) (xy 450.579257 -258.646911) (xy 450.563547 -258.595981) (xy 450.555604 -258.543277)
			(xy 450.031911 -258.543277) (xy 450.029792 -258.570932) (xy 450.017404 -258.623984) (xy 449.997081 -258.674531)
			(xy 449.969297 -258.721393) (xy 449.934699 -258.763476) (xy 449.894096 -258.799799) (xy 449.848434 -258.829515)
			(xy 449.82384 -258.84124) (xy 449.793868 -258.854702) (xy 449.793868 -259.393415) (xy 450.555604 -259.393415)
			(xy 450.555604 -259.340117) (xy 450.563547 -259.287413) (xy 450.579257 -259.236483) (xy 450.602383 -259.188462)
			(xy 450.632407 -259.144425) (xy 450.668659 -259.105354) (xy 450.71033 -259.072123) (xy 450.756488 -259.045474)
			(xy 450.806102 -259.026002) (xy 450.858064 -259.014142) (xy 450.911214 -259.010159) (xy 450.964364 -259.014142)
			(xy 451.016326 -259.026002) (xy 451.06594 -259.045474) (xy 451.112098 -259.072123) (xy 451.153769 -259.105354)
			(xy 451.190021 -259.144425) (xy 451.220045 -259.188462) (xy 451.243171 -259.236483) (xy 451.258881 -259.287413)
			(xy 451.266824 -259.340117) (xy 451.267322 -259.366766) (xy 451.266824 -259.393415) (xy 454.655672 -259.393415)
			(xy 454.655672 -259.340117) (xy 454.663615 -259.287413) (xy 454.679325 -259.236483) (xy 454.702451 -259.188462)
			(xy 454.732475 -259.144425) (xy 454.768727 -259.105354) (xy 454.810398 -259.072123) (xy 454.856556 -259.045474)
			(xy 454.90617 -259.026002) (xy 454.958132 -259.014142) (xy 455.011282 -259.010159) (xy 455.064432 -259.014142)
			(xy 455.116394 -259.026002) (xy 455.166008 -259.045474) (xy 455.212166 -259.072123) (xy 455.253837 -259.105354)
			(xy 455.290089 -259.144425) (xy 455.320113 -259.188462) (xy 455.343239 -259.236483) (xy 455.358949 -259.287413)
			(xy 455.366892 -259.340117) (xy 455.36739 -259.366766) (xy 455.366892 -259.393415) (xy 455.358949 -259.446119)
			(xy 455.343239 -259.497049) (xy 455.320113 -259.54507) (xy 455.290089 -259.589107) (xy 455.253837 -259.628178)
			(xy 455.212166 -259.661409) (xy 455.166008 -259.688058) (xy 455.116394 -259.70753) (xy 455.064432 -259.71939)
			(xy 455.011282 -259.723374) (xy 454.958132 -259.71939) (xy 454.90617 -259.70753) (xy 454.856556 -259.688058)
			(xy 454.810398 -259.661409) (xy 454.768727 -259.628178) (xy 454.732475 -259.589107) (xy 454.702451 -259.54507)
			(xy 454.679325 -259.497049) (xy 454.663615 -259.446119) (xy 454.655672 -259.393415) (xy 451.266824 -259.393415)
			(xy 451.258881 -259.446119) (xy 451.243171 -259.497049) (xy 451.220045 -259.54507) (xy 451.190021 -259.589107)
			(xy 451.153769 -259.628178) (xy 451.112098 -259.661409) (xy 451.06594 -259.688058) (xy 451.016326 -259.70753)
			(xy 450.964364 -259.71939) (xy 450.911214 -259.723374) (xy 450.858064 -259.71939) (xy 450.806102 -259.70753)
			(xy 450.756488 -259.688058) (xy 450.71033 -259.661409) (xy 450.668659 -259.628178) (xy 450.632407 -259.589107)
			(xy 450.602383 -259.54507) (xy 450.579257 -259.497049) (xy 450.563547 -259.446119) (xy 450.555604 -259.393415)
			(xy 449.793868 -259.393415) (xy 449.793868 -260.243299) (xy 450.555604 -260.243299) (xy 450.555604 -260.190001)
			(xy 450.563547 -260.137297) (xy 450.579257 -260.086367) (xy 450.602383 -260.038346) (xy 450.632407 -259.994309)
			(xy 450.668659 -259.955238) (xy 450.71033 -259.922007) (xy 450.756488 -259.895358) (xy 450.806102 -259.875886)
			(xy 450.858064 -259.864026) (xy 450.911214 -259.860043) (xy 450.964364 -259.864026) (xy 451.016326 -259.875886)
			(xy 451.06594 -259.895358) (xy 451.112098 -259.922007) (xy 451.153769 -259.955238) (xy 451.190021 -259.994309)
			(xy 451.220045 -260.038346) (xy 451.243171 -260.086367) (xy 451.258881 -260.137297) (xy 451.266824 -260.190001)
			(xy 451.267322 -260.21665) (xy 451.266824 -260.243299) (xy 452.765404 -260.243299) (xy 452.765404 -260.190001)
			(xy 452.773347 -260.137297) (xy 452.789057 -260.086367) (xy 452.812183 -260.038346) (xy 452.842207 -259.994309)
			(xy 452.878459 -259.955238) (xy 452.92013 -259.922007) (xy 452.966288 -259.895358) (xy 453.015902 -259.875886)
			(xy 453.067864 -259.864026) (xy 453.121014 -259.860043) (xy 453.174164 -259.864026) (xy 453.226126 -259.875886)
			(xy 453.27574 -259.895358) (xy 453.321898 -259.922007) (xy 453.363569 -259.955238) (xy 453.399821 -259.994309)
			(xy 453.429845 -260.038346) (xy 453.452971 -260.086367) (xy 453.468681 -260.137297) (xy 453.476624 -260.190001)
			(xy 453.477122 -260.21665) (xy 453.476624 -260.243299) (xy 454.655672 -260.243299) (xy 454.655672 -260.190001)
			(xy 454.663615 -260.137297) (xy 454.679325 -260.086367) (xy 454.702451 -260.038346) (xy 454.732475 -259.994309)
			(xy 454.768727 -259.955238) (xy 454.810398 -259.922007) (xy 454.856556 -259.895358) (xy 454.90617 -259.875886)
			(xy 454.958132 -259.864026) (xy 455.011282 -259.860043) (xy 455.064432 -259.864026) (xy 455.116394 -259.875886)
			(xy 455.166008 -259.895358) (xy 455.212166 -259.922007) (xy 455.253837 -259.955238) (xy 455.290089 -259.994309)
			(xy 455.320113 -260.038346) (xy 455.343239 -260.086367) (xy 455.358949 -260.137297) (xy 455.366892 -260.190001)
			(xy 455.36739 -260.21665) (xy 455.366892 -260.243299) (xy 458.099404 -260.243299) (xy 458.099404 -260.190001)
			(xy 458.107347 -260.137297) (xy 458.123057 -260.086367) (xy 458.146183 -260.038346) (xy 458.176207 -259.994309)
			(xy 458.212459 -259.955238) (xy 458.25413 -259.922007) (xy 458.300288 -259.895358) (xy 458.349902 -259.875886)
			(xy 458.401864 -259.864026) (xy 458.455014 -259.860043) (xy 458.508164 -259.864026) (xy 458.560126 -259.875886)
			(xy 458.60974 -259.895358) (xy 458.655898 -259.922007) (xy 458.697569 -259.955238) (xy 458.733821 -259.994309)
			(xy 458.763845 -260.038346) (xy 458.786971 -260.086367) (xy 458.802681 -260.137297) (xy 458.810624 -260.190001)
			(xy 458.811122 -260.21665) (xy 458.810624 -260.243299) (xy 458.802681 -260.296003) (xy 458.786971 -260.346933)
			(xy 458.763845 -260.394954) (xy 458.733821 -260.438991) (xy 458.697569 -260.478062) (xy 458.655898 -260.511293)
			(xy 458.60974 -260.537942) (xy 458.560126 -260.557414) (xy 458.508164 -260.569274) (xy 458.455014 -260.573258)
			(xy 458.401864 -260.569274) (xy 458.349902 -260.557414) (xy 458.300288 -260.537942) (xy 458.25413 -260.511293)
			(xy 458.212459 -260.478062) (xy 458.176207 -260.438991) (xy 458.146183 -260.394954) (xy 458.123057 -260.346933)
			(xy 458.107347 -260.296003) (xy 458.099404 -260.243299) (xy 455.366892 -260.243299) (xy 455.358949 -260.296003)
			(xy 455.343239 -260.346933) (xy 455.320113 -260.394954) (xy 455.290089 -260.438991) (xy 455.253837 -260.478062)
			(xy 455.212166 -260.511293) (xy 455.166008 -260.537942) (xy 455.116394 -260.557414) (xy 455.064432 -260.569274)
			(xy 455.011282 -260.573258) (xy 454.958132 -260.569274) (xy 454.90617 -260.557414) (xy 454.856556 -260.537942)
			(xy 454.810398 -260.511293) (xy 454.768727 -260.478062) (xy 454.732475 -260.438991) (xy 454.702451 -260.394954)
			(xy 454.679325 -260.346933) (xy 454.663615 -260.296003) (xy 454.655672 -260.243299) (xy 453.476624 -260.243299)
			(xy 453.468681 -260.296003) (xy 453.452971 -260.346933) (xy 453.429845 -260.394954) (xy 453.399821 -260.438991)
			(xy 453.363569 -260.478062) (xy 453.321898 -260.511293) (xy 453.27574 -260.537942) (xy 453.226126 -260.557414)
			(xy 453.174164 -260.569274) (xy 453.121014 -260.573258) (xy 453.067864 -260.569274) (xy 453.015902 -260.557414)
			(xy 452.966288 -260.537942) (xy 452.92013 -260.511293) (xy 452.878459 -260.478062) (xy 452.842207 -260.438991)
			(xy 452.812183 -260.394954) (xy 452.789057 -260.346933) (xy 452.773347 -260.296003) (xy 452.765404 -260.243299)
			(xy 451.266824 -260.243299) (xy 451.258881 -260.296003) (xy 451.243171 -260.346933) (xy 451.220045 -260.394954)
			(xy 451.190021 -260.438991) (xy 451.153769 -260.478062) (xy 451.112098 -260.511293) (xy 451.06594 -260.537942)
			(xy 451.016326 -260.557414) (xy 450.964364 -260.569274) (xy 450.911214 -260.573258) (xy 450.858064 -260.569274)
			(xy 450.806102 -260.557414) (xy 450.756488 -260.537942) (xy 450.71033 -260.511293) (xy 450.668659 -260.478062)
			(xy 450.632407 -260.438991) (xy 450.602383 -260.394954) (xy 450.579257 -260.346933) (xy 450.563547 -260.296003)
			(xy 450.555604 -260.243299) (xy 449.793868 -260.243299) (xy 449.793868 -260.728714) (xy 449.82384 -260.742176)
			(xy 449.848457 -260.753857) (xy 449.894123 -260.783576) (xy 449.93473 -260.819903) (xy 449.96933 -260.861992)
			(xy 449.997117 -260.908859) (xy 450.017441 -260.959411) (xy 450.029829 -261.012469) (xy 450.033991 -261.066795)
			(xy 450.03195 -261.093437) (xy 450.555604 -261.093437) (xy 450.555604 -261.040139) (xy 450.563547 -260.987435)
			(xy 450.579257 -260.936505) (xy 450.602383 -260.888484) (xy 450.632407 -260.844447) (xy 450.668659 -260.805376)
			(xy 450.71033 -260.772145) (xy 450.756488 -260.745496) (xy 450.806102 -260.726024) (xy 450.858064 -260.714164)
			(xy 450.911214 -260.710181) (xy 450.964364 -260.714164) (xy 451.016326 -260.726024) (xy 451.06594 -260.745496)
			(xy 451.112098 -260.772145) (xy 451.153769 -260.805376) (xy 451.190021 -260.844447) (xy 451.220045 -260.888484)
			(xy 451.243171 -260.936505) (xy 451.258881 -260.987435) (xy 451.266824 -261.040139) (xy 451.267322 -261.066788)
			(xy 451.266824 -261.093437) (xy 454.655672 -261.093437) (xy 454.655672 -261.040139) (xy 454.663615 -260.987435)
			(xy 454.679325 -260.936505) (xy 454.702451 -260.888484) (xy 454.732475 -260.844447) (xy 454.768727 -260.805376)
			(xy 454.810398 -260.772145) (xy 454.856556 -260.745496) (xy 454.90617 -260.726024) (xy 454.958132 -260.714164)
			(xy 455.011282 -260.710181) (xy 455.064432 -260.714164) (xy 455.116394 -260.726024) (xy 455.166008 -260.745496)
			(xy 455.212166 -260.772145) (xy 455.253837 -260.805376) (xy 455.290089 -260.844447) (xy 455.320113 -260.888484)
			(xy 455.343239 -260.936505) (xy 455.358949 -260.987435) (xy 455.366892 -261.040139) (xy 455.36739 -261.066788)
			(xy 455.366892 -261.093437) (xy 456.865472 -261.093437) (xy 456.865472 -261.040139) (xy 456.873415 -260.987435)
			(xy 456.889125 -260.936505) (xy 456.912251 -260.888484) (xy 456.942275 -260.844447) (xy 456.978527 -260.805376)
			(xy 457.020198 -260.772145) (xy 457.066356 -260.745496) (xy 457.11597 -260.726024) (xy 457.167932 -260.714164)
			(xy 457.221082 -260.710181) (xy 457.274232 -260.714164) (xy 457.326194 -260.726024) (xy 457.375808 -260.745496)
			(xy 457.421966 -260.772145) (xy 457.463637 -260.805376) (xy 457.499889 -260.844447) (xy 457.529913 -260.888484)
			(xy 457.553039 -260.936505) (xy 457.568749 -260.987435) (xy 457.576692 -261.040139) (xy 457.57719 -261.066788)
			(xy 457.576692 -261.093437) (xy 457.568749 -261.146141) (xy 457.553039 -261.197071) (xy 457.529913 -261.245092)
			(xy 457.499889 -261.289129) (xy 457.463637 -261.3282) (xy 457.421966 -261.361431) (xy 457.375808 -261.38808)
			(xy 457.326194 -261.407552) (xy 457.274232 -261.419412) (xy 457.221082 -261.423396) (xy 457.167932 -261.419412)
			(xy 457.11597 -261.407552) (xy 457.066356 -261.38808) (xy 457.020198 -261.361431) (xy 456.978527 -261.3282)
			(xy 456.942275 -261.289129) (xy 456.912251 -261.245092) (xy 456.889125 -261.197071) (xy 456.873415 -261.146141)
			(xy 456.865472 -261.093437) (xy 455.366892 -261.093437) (xy 455.358949 -261.146141) (xy 455.343239 -261.197071)
			(xy 455.320113 -261.245092) (xy 455.290089 -261.289129) (xy 455.253837 -261.3282) (xy 455.212166 -261.361431)
			(xy 455.166008 -261.38808) (xy 455.116394 -261.407552) (xy 455.064432 -261.419412) (xy 455.011282 -261.423396)
			(xy 454.958132 -261.419412) (xy 454.90617 -261.407552) (xy 454.856556 -261.38808) (xy 454.810398 -261.361431)
			(xy 454.768727 -261.3282) (xy 454.732475 -261.289129) (xy 454.702451 -261.245092) (xy 454.679325 -261.197071)
			(xy 454.663615 -261.146141) (xy 454.655672 -261.093437) (xy 451.266824 -261.093437) (xy 451.258881 -261.146141)
			(xy 451.243171 -261.197071) (xy 451.220045 -261.245092) (xy 451.190021 -261.289129) (xy 451.153769 -261.3282)
			(xy 451.112098 -261.361431) (xy 451.06594 -261.38808) (xy 451.016326 -261.407552) (xy 450.964364 -261.419412)
			(xy 450.911214 -261.423396) (xy 450.858064 -261.419412) (xy 450.806102 -261.407552) (xy 450.756488 -261.38808)
			(xy 450.71033 -261.361431) (xy 450.668659 -261.3282) (xy 450.632407 -261.289129) (xy 450.602383 -261.245092)
			(xy 450.579257 -261.197071) (xy 450.563547 -261.146141) (xy 450.555604 -261.093437) (xy 450.03195 -261.093437)
			(xy 450.02983 -261.121121) (xy 450.017444 -261.174179) (xy 449.997121 -261.224732) (xy 449.969336 -261.2716)
			(xy 449.934737 -261.31369) (xy 449.894131 -261.350018) (xy 449.848465 -261.379739) (xy 449.82384 -261.3914)
			(xy 449.793868 -261.404862) (xy 449.793868 -261.943321) (xy 450.555604 -261.943321) (xy 450.555604 -261.890023)
			(xy 450.563547 -261.837319) (xy 450.579257 -261.786389) (xy 450.602383 -261.738368) (xy 450.632407 -261.694331)
			(xy 450.668659 -261.65526) (xy 450.71033 -261.622029) (xy 450.756488 -261.59538) (xy 450.806102 -261.575908)
			(xy 450.858064 -261.564048) (xy 450.911214 -261.560065) (xy 450.964364 -261.564048) (xy 451.016326 -261.575908)
			(xy 451.06594 -261.59538) (xy 451.112098 -261.622029) (xy 451.153769 -261.65526) (xy 451.190021 -261.694331)
			(xy 451.220045 -261.738368) (xy 451.243171 -261.786389) (xy 451.258881 -261.837319) (xy 451.266824 -261.890023)
			(xy 451.267322 -261.916672) (xy 451.266824 -261.943321) (xy 452.765404 -261.943321) (xy 452.765404 -261.890023)
			(xy 452.773347 -261.837319) (xy 452.789057 -261.786389) (xy 452.812183 -261.738368) (xy 452.842207 -261.694331)
			(xy 452.878459 -261.65526) (xy 452.92013 -261.622029) (xy 452.966288 -261.59538) (xy 453.015902 -261.575908)
			(xy 453.067864 -261.564048) (xy 453.121014 -261.560065) (xy 453.174164 -261.564048) (xy 453.226126 -261.575908)
			(xy 453.27574 -261.59538) (xy 453.321898 -261.622029) (xy 453.363569 -261.65526) (xy 453.399821 -261.694331)
			(xy 453.429845 -261.738368) (xy 453.452971 -261.786389) (xy 453.468681 -261.837319) (xy 453.476624 -261.890023)
			(xy 453.477122 -261.916672) (xy 453.476624 -261.943321) (xy 454.655672 -261.943321) (xy 454.655672 -261.890023)
			(xy 454.663615 -261.837319) (xy 454.679325 -261.786389) (xy 454.702451 -261.738368) (xy 454.732475 -261.694331)
			(xy 454.768727 -261.65526) (xy 454.810398 -261.622029) (xy 454.856556 -261.59538) (xy 454.90617 -261.575908)
			(xy 454.958132 -261.564048) (xy 455.011282 -261.560065) (xy 455.064432 -261.564048) (xy 455.116394 -261.575908)
			(xy 455.166008 -261.59538) (xy 455.212166 -261.622029) (xy 455.253837 -261.65526) (xy 455.290089 -261.694331)
			(xy 455.320113 -261.738368) (xy 455.343239 -261.786389) (xy 455.358949 -261.837319) (xy 455.366892 -261.890023)
			(xy 455.36739 -261.916672) (xy 455.366892 -261.943321) (xy 458.099404 -261.943321) (xy 458.099404 -261.890023)
			(xy 458.107347 -261.837319) (xy 458.123057 -261.786389) (xy 458.146183 -261.738368) (xy 458.176207 -261.694331)
			(xy 458.212459 -261.65526) (xy 458.25413 -261.622029) (xy 458.300288 -261.59538) (xy 458.349902 -261.575908)
			(xy 458.401864 -261.564048) (xy 458.455014 -261.560065) (xy 458.508164 -261.564048) (xy 458.560126 -261.575908)
			(xy 458.60974 -261.59538) (xy 458.655898 -261.622029) (xy 458.697569 -261.65526) (xy 458.733821 -261.694331)
			(xy 458.763845 -261.738368) (xy 458.786971 -261.786389) (xy 458.802681 -261.837319) (xy 458.810624 -261.890023)
			(xy 458.811122 -261.916672) (xy 458.810624 -261.943321) (xy 458.802681 -261.996025) (xy 458.786971 -262.046955)
			(xy 458.763845 -262.094976) (xy 458.733821 -262.139013) (xy 458.697569 -262.178084) (xy 458.655898 -262.211315)
			(xy 458.60974 -262.237964) (xy 458.560126 -262.257436) (xy 458.508164 -262.269296) (xy 458.455014 -262.27328)
			(xy 458.401864 -262.269296) (xy 458.349902 -262.257436) (xy 458.300288 -262.237964) (xy 458.25413 -262.211315)
			(xy 458.212459 -262.178084) (xy 458.176207 -262.139013) (xy 458.146183 -262.094976) (xy 458.123057 -262.046955)
			(xy 458.107347 -261.996025) (xy 458.099404 -261.943321) (xy 455.366892 -261.943321) (xy 455.358949 -261.996025)
			(xy 455.343239 -262.046955) (xy 455.320113 -262.094976) (xy 455.290089 -262.139013) (xy 455.253837 -262.178084)
			(xy 455.212166 -262.211315) (xy 455.166008 -262.237964) (xy 455.116394 -262.257436) (xy 455.064432 -262.269296)
			(xy 455.011282 -262.27328) (xy 454.958132 -262.269296) (xy 454.90617 -262.257436) (xy 454.856556 -262.237964)
			(xy 454.810398 -262.211315) (xy 454.768727 -262.178084) (xy 454.732475 -262.139013) (xy 454.702451 -262.094976)
			(xy 454.679325 -262.046955) (xy 454.663615 -261.996025) (xy 454.655672 -261.943321) (xy 453.476624 -261.943321)
			(xy 453.468681 -261.996025) (xy 453.452971 -262.046955) (xy 453.429845 -262.094976) (xy 453.399821 -262.139013)
			(xy 453.363569 -262.178084) (xy 453.321898 -262.211315) (xy 453.27574 -262.237964) (xy 453.226126 -262.257436)
			(xy 453.174164 -262.269296) (xy 453.121014 -262.27328) (xy 453.067864 -262.269296) (xy 453.015902 -262.257436)
			(xy 452.966288 -262.237964) (xy 452.92013 -262.211315) (xy 452.878459 -262.178084) (xy 452.842207 -262.139013)
			(xy 452.812183 -262.094976) (xy 452.789057 -262.046955) (xy 452.773347 -261.996025) (xy 452.765404 -261.943321)
			(xy 451.266824 -261.943321) (xy 451.258881 -261.996025) (xy 451.243171 -262.046955) (xy 451.220045 -262.094976)
			(xy 451.190021 -262.139013) (xy 451.153769 -262.178084) (xy 451.112098 -262.211315) (xy 451.06594 -262.237964)
			(xy 451.016326 -262.257436) (xy 450.964364 -262.269296) (xy 450.911214 -262.27328) (xy 450.858064 -262.269296)
			(xy 450.806102 -262.257436) (xy 450.756488 -262.237964) (xy 450.71033 -262.211315) (xy 450.668659 -262.178084)
			(xy 450.632407 -262.139013) (xy 450.602383 -262.094976) (xy 450.579257 -262.046955) (xy 450.563547 -261.996025)
			(xy 450.555604 -261.943321) (xy 449.793868 -261.943321) (xy 449.793868 -262.428736) (xy 449.82384 -262.442198)
			(xy 449.848455 -262.453879) (xy 449.894118 -262.483597) (xy 449.934722 -262.519924) (xy 449.969319 -262.56201)
			(xy 449.997103 -262.608876) (xy 450.017425 -262.659426) (xy 450.02981 -262.712481) (xy 450.033971 -262.766804)
			(xy 450.031929 -262.793459) (xy 450.555604 -262.793459) (xy 450.555604 -262.740161) (xy 450.563547 -262.687457)
			(xy 450.579257 -262.636527) (xy 450.602383 -262.588506) (xy 450.632407 -262.544469) (xy 450.668659 -262.505398)
			(xy 450.71033 -262.472167) (xy 450.756488 -262.445518) (xy 450.806102 -262.426046) (xy 450.858064 -262.414186)
			(xy 450.911214 -262.410203) (xy 450.964364 -262.414186) (xy 451.016326 -262.426046) (xy 451.06594 -262.445518)
			(xy 451.112098 -262.472167) (xy 451.153769 -262.505398) (xy 451.190021 -262.544469) (xy 451.220045 -262.588506)
			(xy 451.243171 -262.636527) (xy 451.258881 -262.687457) (xy 451.266824 -262.740161) (xy 451.267322 -262.76681)
			(xy 451.266824 -262.793459) (xy 454.655672 -262.793459) (xy 454.655672 -262.740161) (xy 454.663615 -262.687457)
			(xy 454.679325 -262.636527) (xy 454.702451 -262.588506) (xy 454.732475 -262.544469) (xy 454.768727 -262.505398)
			(xy 454.810398 -262.472167) (xy 454.856556 -262.445518) (xy 454.90617 -262.426046) (xy 454.958132 -262.414186)
			(xy 455.011282 -262.410203) (xy 455.064432 -262.414186) (xy 455.116394 -262.426046) (xy 455.166008 -262.445518)
			(xy 455.212166 -262.472167) (xy 455.253837 -262.505398) (xy 455.290089 -262.544469) (xy 455.320113 -262.588506)
			(xy 455.343239 -262.636527) (xy 455.358949 -262.687457) (xy 455.366892 -262.740161) (xy 455.36739 -262.76681)
			(xy 455.366892 -262.793459) (xy 456.865472 -262.793459) (xy 456.865472 -262.740161) (xy 456.873415 -262.687457)
			(xy 456.889125 -262.636527) (xy 456.912251 -262.588506) (xy 456.942275 -262.544469) (xy 456.978527 -262.505398)
			(xy 457.020198 -262.472167) (xy 457.066356 -262.445518) (xy 457.11597 -262.426046) (xy 457.167932 -262.414186)
			(xy 457.221082 -262.410203) (xy 457.274232 -262.414186) (xy 457.326194 -262.426046) (xy 457.375808 -262.445518)
			(xy 457.421966 -262.472167) (xy 457.463637 -262.505398) (xy 457.499889 -262.544469) (xy 457.529913 -262.588506)
			(xy 457.553039 -262.636527) (xy 457.568749 -262.687457) (xy 457.576692 -262.740161) (xy 457.57719 -262.76681)
			(xy 457.576692 -262.793459) (xy 457.568749 -262.846163) (xy 457.553039 -262.897093) (xy 457.529913 -262.945114)
			(xy 457.499889 -262.989151) (xy 457.463637 -263.028222) (xy 457.421966 -263.061453) (xy 457.375808 -263.088102)
			(xy 457.326194 -263.107574) (xy 457.274232 -263.119434) (xy 457.221082 -263.123418) (xy 457.167932 -263.119434)
			(xy 457.11597 -263.107574) (xy 457.066356 -263.088102) (xy 457.020198 -263.061453) (xy 456.978527 -263.028222)
			(xy 456.942275 -262.989151) (xy 456.912251 -262.945114) (xy 456.889125 -262.897093) (xy 456.873415 -262.846163)
			(xy 456.865472 -262.793459) (xy 455.366892 -262.793459) (xy 455.358949 -262.846163) (xy 455.343239 -262.897093)
			(xy 455.320113 -262.945114) (xy 455.290089 -262.989151) (xy 455.253837 -263.028222) (xy 455.212166 -263.061453)
			(xy 455.166008 -263.088102) (xy 455.116394 -263.107574) (xy 455.064432 -263.119434) (xy 455.011282 -263.123418)
			(xy 454.958132 -263.119434) (xy 454.90617 -263.107574) (xy 454.856556 -263.088102) (xy 454.810398 -263.061453)
			(xy 454.768727 -263.028222) (xy 454.732475 -262.989151) (xy 454.702451 -262.945114) (xy 454.679325 -262.897093)
			(xy 454.663615 -262.846163) (xy 454.655672 -262.793459) (xy 451.266824 -262.793459) (xy 451.258881 -262.846163)
			(xy 451.243171 -262.897093) (xy 451.220045 -262.945114) (xy 451.190021 -262.989151) (xy 451.153769 -263.028222)
			(xy 451.112098 -263.061453) (xy 451.06594 -263.088102) (xy 451.016326 -263.107574) (xy 450.964364 -263.119434)
			(xy 450.911214 -263.123418) (xy 450.858064 -263.119434) (xy 450.806102 -263.107574) (xy 450.756488 -263.088102)
			(xy 450.71033 -263.061453) (xy 450.668659 -263.028222) (xy 450.632407 -262.989151) (xy 450.602383 -262.945114)
			(xy 450.579257 -262.897093) (xy 450.563547 -262.846163) (xy 450.555604 -262.793459) (xy 450.031929 -262.793459)
			(xy 450.029809 -262.821127) (xy 450.017422 -262.874182) (xy 449.997099 -262.924732) (xy 449.969314 -262.971596)
			(xy 449.934716 -263.013682) (xy 449.894111 -263.050008) (xy 449.848448 -263.079725) (xy 449.82384 -263.091422)
			(xy 449.793868 -263.104884) (xy 449.793868 -263.643343) (xy 450.555604 -263.643343) (xy 450.555604 -263.590045)
			(xy 450.563547 -263.537341) (xy 450.579257 -263.486411) (xy 450.602383 -263.43839) (xy 450.632407 -263.394353)
			(xy 450.668659 -263.355282) (xy 450.71033 -263.322051) (xy 450.756488 -263.295402) (xy 450.806102 -263.27593)
			(xy 450.858064 -263.26407) (xy 450.911214 -263.260087) (xy 450.964364 -263.26407) (xy 451.016326 -263.27593)
			(xy 451.06594 -263.295402) (xy 451.112098 -263.322051) (xy 451.153769 -263.355282) (xy 451.190021 -263.394353)
			(xy 451.220045 -263.43839) (xy 451.243171 -263.486411) (xy 451.258881 -263.537341) (xy 451.266824 -263.590045)
			(xy 451.267322 -263.616694) (xy 451.266824 -263.643343) (xy 452.765404 -263.643343) (xy 452.765404 -263.590045)
			(xy 452.773347 -263.537341) (xy 452.789057 -263.486411) (xy 452.812183 -263.43839) (xy 452.842207 -263.394353)
			(xy 452.878459 -263.355282) (xy 452.92013 -263.322051) (xy 452.966288 -263.295402) (xy 453.015902 -263.27593)
			(xy 453.067864 -263.26407) (xy 453.121014 -263.260087) (xy 453.174164 -263.26407) (xy 453.226126 -263.27593)
			(xy 453.27574 -263.295402) (xy 453.321898 -263.322051) (xy 453.363569 -263.355282) (xy 453.399821 -263.394353)
			(xy 453.429845 -263.43839) (xy 453.452971 -263.486411) (xy 453.468681 -263.537341) (xy 453.476624 -263.590045)
			(xy 453.477122 -263.616694) (xy 453.476624 -263.643343) (xy 454.655672 -263.643343) (xy 454.655672 -263.590045)
			(xy 454.663615 -263.537341) (xy 454.679325 -263.486411) (xy 454.702451 -263.43839) (xy 454.732475 -263.394353)
			(xy 454.768727 -263.355282) (xy 454.810398 -263.322051) (xy 454.856556 -263.295402) (xy 454.90617 -263.27593)
			(xy 454.958132 -263.26407) (xy 455.011282 -263.260087) (xy 455.064432 -263.26407) (xy 455.116394 -263.27593)
			(xy 455.166008 -263.295402) (xy 455.212166 -263.322051) (xy 455.253837 -263.355282) (xy 455.290089 -263.394353)
			(xy 455.320113 -263.43839) (xy 455.343239 -263.486411) (xy 455.358949 -263.537341) (xy 455.366892 -263.590045)
			(xy 455.36739 -263.616694) (xy 455.366892 -263.643343) (xy 458.099404 -263.643343) (xy 458.099404 -263.590045)
			(xy 458.107347 -263.537341) (xy 458.123057 -263.486411) (xy 458.146183 -263.43839) (xy 458.176207 -263.394353)
			(xy 458.212459 -263.355282) (xy 458.25413 -263.322051) (xy 458.300288 -263.295402) (xy 458.349902 -263.27593)
			(xy 458.401864 -263.26407) (xy 458.455014 -263.260087) (xy 458.508164 -263.26407) (xy 458.560126 -263.27593)
			(xy 458.60974 -263.295402) (xy 458.655898 -263.322051) (xy 458.697569 -263.355282) (xy 458.733821 -263.394353)
			(xy 458.763845 -263.43839) (xy 458.786971 -263.486411) (xy 458.802681 -263.537341) (xy 458.810624 -263.590045)
			(xy 458.811122 -263.616694) (xy 458.810624 -263.643343) (xy 458.802681 -263.696047) (xy 458.786971 -263.746977)
			(xy 458.763845 -263.794998) (xy 458.733821 -263.839035) (xy 458.697569 -263.878106) (xy 458.655898 -263.911337)
			(xy 458.60974 -263.937986) (xy 458.560126 -263.957458) (xy 458.508164 -263.969318) (xy 458.455014 -263.973302)
			(xy 458.401864 -263.969318) (xy 458.349902 -263.957458) (xy 458.300288 -263.937986) (xy 458.25413 -263.911337)
			(xy 458.212459 -263.878106) (xy 458.176207 -263.839035) (xy 458.146183 -263.794998) (xy 458.123057 -263.746977)
			(xy 458.107347 -263.696047) (xy 458.099404 -263.643343) (xy 455.366892 -263.643343) (xy 455.358949 -263.696047)
			(xy 455.343239 -263.746977) (xy 455.320113 -263.794998) (xy 455.290089 -263.839035) (xy 455.253837 -263.878106)
			(xy 455.212166 -263.911337) (xy 455.166008 -263.937986) (xy 455.116394 -263.957458) (xy 455.064432 -263.969318)
			(xy 455.011282 -263.973302) (xy 454.958132 -263.969318) (xy 454.90617 -263.957458) (xy 454.856556 -263.937986)
			(xy 454.810398 -263.911337) (xy 454.768727 -263.878106) (xy 454.732475 -263.839035) (xy 454.702451 -263.794998)
			(xy 454.679325 -263.746977) (xy 454.663615 -263.696047) (xy 454.655672 -263.643343) (xy 453.476624 -263.643343)
			(xy 453.468681 -263.696047) (xy 453.452971 -263.746977) (xy 453.429845 -263.794998) (xy 453.399821 -263.839035)
			(xy 453.363569 -263.878106) (xy 453.321898 -263.911337) (xy 453.27574 -263.937986) (xy 453.226126 -263.957458)
			(xy 453.174164 -263.969318) (xy 453.121014 -263.973302) (xy 453.067864 -263.969318) (xy 453.015902 -263.957458)
			(xy 452.966288 -263.937986) (xy 452.92013 -263.911337) (xy 452.878459 -263.878106) (xy 452.842207 -263.839035)
			(xy 452.812183 -263.794998) (xy 452.789057 -263.746977) (xy 452.773347 -263.696047) (xy 452.765404 -263.643343)
			(xy 451.266824 -263.643343) (xy 451.258881 -263.696047) (xy 451.243171 -263.746977) (xy 451.220045 -263.794998)
			(xy 451.190021 -263.839035) (xy 451.153769 -263.878106) (xy 451.112098 -263.911337) (xy 451.06594 -263.937986)
			(xy 451.016326 -263.957458) (xy 450.964364 -263.969318) (xy 450.911214 -263.973302) (xy 450.858064 -263.969318)
			(xy 450.806102 -263.957458) (xy 450.756488 -263.937986) (xy 450.71033 -263.911337) (xy 450.668659 -263.878106)
			(xy 450.632407 -263.839035) (xy 450.602383 -263.794998) (xy 450.579257 -263.746977) (xy 450.563547 -263.696047)
			(xy 450.555604 -263.643343) (xy 449.793868 -263.643343) (xy 449.793868 -264.128504) (xy 449.82384 -264.141966)
			(xy 449.848458 -264.153647) (xy 449.894125 -264.183366) (xy 449.934734 -264.219694) (xy 449.969335 -264.261783)
			(xy 449.997123 -264.308651) (xy 450.017448 -264.359204) (xy 450.029837 -264.412264) (xy 450.034 -264.466591)
			(xy 450.03196 -264.493227) (xy 450.555604 -264.493227) (xy 450.555604 -264.439929) (xy 450.563547 -264.387225)
			(xy 450.579257 -264.336295) (xy 450.602383 -264.288274) (xy 450.632407 -264.244237) (xy 450.668659 -264.205166)
			(xy 450.71033 -264.171935) (xy 450.756488 -264.145286) (xy 450.806102 -264.125814) (xy 450.858064 -264.113954)
			(xy 450.911214 -264.109971) (xy 450.964364 -264.113954) (xy 451.016326 -264.125814) (xy 451.06594 -264.145286)
			(xy 451.112098 -264.171935) (xy 451.153769 -264.205166) (xy 451.190021 -264.244237) (xy 451.220045 -264.288274)
			(xy 451.243171 -264.336295) (xy 451.258881 -264.387225) (xy 451.266824 -264.439929) (xy 451.267322 -264.466578)
			(xy 451.266824 -264.493227) (xy 454.655672 -264.493227) (xy 454.655672 -264.439929) (xy 454.663615 -264.387225)
			(xy 454.679325 -264.336295) (xy 454.702451 -264.288274) (xy 454.732475 -264.244237) (xy 454.768727 -264.205166)
			(xy 454.810398 -264.171935) (xy 454.856556 -264.145286) (xy 454.90617 -264.125814) (xy 454.958132 -264.113954)
			(xy 455.011282 -264.109971) (xy 455.064432 -264.113954) (xy 455.116394 -264.125814) (xy 455.166008 -264.145286)
			(xy 455.212166 -264.171935) (xy 455.253837 -264.205166) (xy 455.290089 -264.244237) (xy 455.320113 -264.288274)
			(xy 455.343239 -264.336295) (xy 455.358949 -264.387225) (xy 455.366892 -264.439929) (xy 455.36739 -264.466578)
			(xy 455.366892 -264.493227) (xy 456.865472 -264.493227) (xy 456.865472 -264.439929) (xy 456.873415 -264.387225)
			(xy 456.889125 -264.336295) (xy 456.912251 -264.288274) (xy 456.942275 -264.244237) (xy 456.978527 -264.205166)
			(xy 457.020198 -264.171935) (xy 457.066356 -264.145286) (xy 457.11597 -264.125814) (xy 457.167932 -264.113954)
			(xy 457.221082 -264.109971) (xy 457.274232 -264.113954) (xy 457.326194 -264.125814) (xy 457.375808 -264.145286)
			(xy 457.421966 -264.171935) (xy 457.463637 -264.205166) (xy 457.499889 -264.244237) (xy 457.529913 -264.288274)
			(xy 457.553039 -264.336295) (xy 457.568749 -264.387225) (xy 457.576692 -264.439929) (xy 457.57719 -264.466578)
			(xy 457.576692 -264.493227) (xy 457.568749 -264.545931) (xy 457.553039 -264.596861) (xy 457.529913 -264.644882)
			(xy 457.499889 -264.688919) (xy 457.463637 -264.72799) (xy 457.421966 -264.761221) (xy 457.375808 -264.78787)
			(xy 457.326194 -264.807342) (xy 457.274232 -264.819202) (xy 457.221082 -264.823186) (xy 457.167932 -264.819202)
			(xy 457.11597 -264.807342) (xy 457.066356 -264.78787) (xy 457.020198 -264.761221) (xy 456.978527 -264.72799)
			(xy 456.942275 -264.688919) (xy 456.912251 -264.644882) (xy 456.889125 -264.596861) (xy 456.873415 -264.545931)
			(xy 456.865472 -264.493227) (xy 455.366892 -264.493227) (xy 455.358949 -264.545931) (xy 455.343239 -264.596861)
			(xy 455.320113 -264.644882) (xy 455.290089 -264.688919) (xy 455.253837 -264.72799) (xy 455.212166 -264.761221)
			(xy 455.166008 -264.78787) (xy 455.116394 -264.807342) (xy 455.064432 -264.819202) (xy 455.011282 -264.823186)
			(xy 454.958132 -264.819202) (xy 454.90617 -264.807342) (xy 454.856556 -264.78787) (xy 454.810398 -264.761221)
			(xy 454.768727 -264.72799) (xy 454.732475 -264.688919) (xy 454.702451 -264.644882) (xy 454.679325 -264.596861)
			(xy 454.663615 -264.545931) (xy 454.655672 -264.493227) (xy 451.266824 -264.493227) (xy 451.258881 -264.545931)
			(xy 451.243171 -264.596861) (xy 451.220045 -264.644882) (xy 451.190021 -264.688919) (xy 451.153769 -264.72799)
			(xy 451.112098 -264.761221) (xy 451.06594 -264.78787) (xy 451.016326 -264.807342) (xy 450.964364 -264.819202)
			(xy 450.911214 -264.823186) (xy 450.858064 -264.819202) (xy 450.806102 -264.807342) (xy 450.756488 -264.78787)
			(xy 450.71033 -264.761221) (xy 450.668659 -264.72799) (xy 450.632407 -264.688919) (xy 450.602383 -264.644882)
			(xy 450.579257 -264.596861) (xy 450.563547 -264.545931) (xy 450.555604 -264.493227) (xy 450.03196 -264.493227)
			(xy 450.02984 -264.520918) (xy 450.017454 -264.573978) (xy 449.997131 -264.624533) (xy 449.969346 -264.671402)
			(xy 449.934746 -264.713493) (xy 449.89414 -264.749823) (xy 449.848473 -264.779545) (xy 449.82384 -264.79119)
			(xy 449.793868 -264.804652) (xy 449.793868 -265.343365) (xy 450.555604 -265.343365) (xy 450.555604 -265.290067)
			(xy 450.563547 -265.237363) (xy 450.579257 -265.186433) (xy 450.602383 -265.138412) (xy 450.632407 -265.094375)
			(xy 450.668659 -265.055304) (xy 450.71033 -265.022073) (xy 450.756488 -264.995424) (xy 450.806102 -264.975952)
			(xy 450.858064 -264.964092) (xy 450.911214 -264.960109) (xy 450.964364 -264.964092) (xy 451.016326 -264.975952)
			(xy 451.06594 -264.995424) (xy 451.112098 -265.022073) (xy 451.153769 -265.055304) (xy 451.190021 -265.094375)
			(xy 451.220045 -265.138412) (xy 451.243171 -265.186433) (xy 451.258881 -265.237363) (xy 451.266824 -265.290067)
			(xy 451.267322 -265.316716) (xy 451.266824 -265.343365) (xy 452.765404 -265.343365) (xy 452.765404 -265.290067)
			(xy 452.773347 -265.237363) (xy 452.789057 -265.186433) (xy 452.812183 -265.138412) (xy 452.842207 -265.094375)
			(xy 452.878459 -265.055304) (xy 452.92013 -265.022073) (xy 452.966288 -264.995424) (xy 453.015902 -264.975952)
			(xy 453.067864 -264.964092) (xy 453.121014 -264.960109) (xy 453.174164 -264.964092) (xy 453.226126 -264.975952)
			(xy 453.27574 -264.995424) (xy 453.321898 -265.022073) (xy 453.363569 -265.055304) (xy 453.399821 -265.094375)
			(xy 453.429845 -265.138412) (xy 453.452971 -265.186433) (xy 453.468681 -265.237363) (xy 453.476624 -265.290067)
			(xy 453.477122 -265.316716) (xy 453.476624 -265.343365) (xy 454.655672 -265.343365) (xy 454.655672 -265.290067)
			(xy 454.663615 -265.237363) (xy 454.679325 -265.186433) (xy 454.702451 -265.138412) (xy 454.732475 -265.094375)
			(xy 454.768727 -265.055304) (xy 454.810398 -265.022073) (xy 454.856556 -264.995424) (xy 454.90617 -264.975952)
			(xy 454.958132 -264.964092) (xy 455.011282 -264.960109) (xy 455.064432 -264.964092) (xy 455.116394 -264.975952)
			(xy 455.166008 -264.995424) (xy 455.212166 -265.022073) (xy 455.253837 -265.055304) (xy 455.290089 -265.094375)
			(xy 455.320113 -265.138412) (xy 455.343239 -265.186433) (xy 455.358949 -265.237363) (xy 455.366892 -265.290067)
			(xy 455.36739 -265.316716) (xy 455.366892 -265.343365) (xy 458.099404 -265.343365) (xy 458.099404 -265.290067)
			(xy 458.107347 -265.237363) (xy 458.123057 -265.186433) (xy 458.146183 -265.138412) (xy 458.176207 -265.094375)
			(xy 458.212459 -265.055304) (xy 458.25413 -265.022073) (xy 458.300288 -264.995424) (xy 458.349902 -264.975952)
			(xy 458.401864 -264.964092) (xy 458.455014 -264.960109) (xy 458.508164 -264.964092) (xy 458.560126 -264.975952)
			(xy 458.60974 -264.995424) (xy 458.655898 -265.022073) (xy 458.697569 -265.055304) (xy 458.733821 -265.094375)
			(xy 458.763845 -265.138412) (xy 458.786971 -265.186433) (xy 458.802681 -265.237363) (xy 458.810624 -265.290067)
			(xy 458.811122 -265.316716) (xy 458.810624 -265.343365) (xy 458.802681 -265.396069) (xy 458.786971 -265.446999)
			(xy 458.763845 -265.49502) (xy 458.733821 -265.539057) (xy 458.697569 -265.578128) (xy 458.655898 -265.611359)
			(xy 458.60974 -265.638008) (xy 458.560126 -265.65748) (xy 458.508164 -265.66934) (xy 458.455014 -265.673324)
			(xy 458.401864 -265.66934) (xy 458.349902 -265.65748) (xy 458.300288 -265.638008) (xy 458.25413 -265.611359)
			(xy 458.212459 -265.578128) (xy 458.176207 -265.539057) (xy 458.146183 -265.49502) (xy 458.123057 -265.446999)
			(xy 458.107347 -265.396069) (xy 458.099404 -265.343365) (xy 455.366892 -265.343365) (xy 455.358949 -265.396069)
			(xy 455.343239 -265.446999) (xy 455.320113 -265.49502) (xy 455.290089 -265.539057) (xy 455.253837 -265.578128)
			(xy 455.212166 -265.611359) (xy 455.166008 -265.638008) (xy 455.116394 -265.65748) (xy 455.064432 -265.66934)
			(xy 455.011282 -265.673324) (xy 454.958132 -265.66934) (xy 454.90617 -265.65748) (xy 454.856556 -265.638008)
			(xy 454.810398 -265.611359) (xy 454.768727 -265.578128) (xy 454.732475 -265.539057) (xy 454.702451 -265.49502)
			(xy 454.679325 -265.446999) (xy 454.663615 -265.396069) (xy 454.655672 -265.343365) (xy 453.476624 -265.343365)
			(xy 453.468681 -265.396069) (xy 453.452971 -265.446999) (xy 453.429845 -265.49502) (xy 453.399821 -265.539057)
			(xy 453.363569 -265.578128) (xy 453.321898 -265.611359) (xy 453.27574 -265.638008) (xy 453.226126 -265.65748)
			(xy 453.174164 -265.66934) (xy 453.121014 -265.673324) (xy 453.067864 -265.66934) (xy 453.015902 -265.65748)
			(xy 452.966288 -265.638008) (xy 452.92013 -265.611359) (xy 452.878459 -265.578128) (xy 452.842207 -265.539057)
			(xy 452.812183 -265.49502) (xy 452.789057 -265.446999) (xy 452.773347 -265.396069) (xy 452.765404 -265.343365)
			(xy 451.266824 -265.343365) (xy 451.258881 -265.396069) (xy 451.243171 -265.446999) (xy 451.220045 -265.49502)
			(xy 451.190021 -265.539057) (xy 451.153769 -265.578128) (xy 451.112098 -265.611359) (xy 451.06594 -265.638008)
			(xy 451.016326 -265.65748) (xy 450.964364 -265.66934) (xy 450.911214 -265.673324) (xy 450.858064 -265.66934)
			(xy 450.806102 -265.65748) (xy 450.756488 -265.638008) (xy 450.71033 -265.611359) (xy 450.668659 -265.578128)
			(xy 450.632407 -265.539057) (xy 450.602383 -265.49502) (xy 450.579257 -265.446999) (xy 450.563547 -265.396069)
			(xy 450.555604 -265.343365) (xy 449.793868 -265.343365) (xy 449.793868 -265.828526) (xy 449.82384 -265.841988)
			(xy 449.848456 -265.853669) (xy 449.89412 -265.883387) (xy 449.934725 -265.919714) (xy 449.969324 -265.961802)
			(xy 449.997109 -266.008668) (xy 450.017432 -266.059219) (xy 450.029819 -266.112276) (xy 450.03398 -266.1666)
			(xy 450.031939 -266.193249) (xy 450.555604 -266.193249) (xy 450.555604 -266.139951) (xy 450.563547 -266.087247)
			(xy 450.579257 -266.036317) (xy 450.602383 -265.988296) (xy 450.632407 -265.944259) (xy 450.668659 -265.905188)
			(xy 450.71033 -265.871957) (xy 450.756488 -265.845308) (xy 450.806102 -265.825836) (xy 450.858064 -265.813976)
			(xy 450.911214 -265.809993) (xy 450.964364 -265.813976) (xy 451.016326 -265.825836) (xy 451.06594 -265.845308)
			(xy 451.112098 -265.871957) (xy 451.153769 -265.905188) (xy 451.190021 -265.944259) (xy 451.220045 -265.988296)
			(xy 451.243171 -266.036317) (xy 451.258881 -266.087247) (xy 451.266824 -266.139951) (xy 451.267322 -266.1666)
			(xy 451.266824 -266.193249) (xy 454.655672 -266.193249) (xy 454.655672 -266.139951) (xy 454.663615 -266.087247)
			(xy 454.679325 -266.036317) (xy 454.702451 -265.988296) (xy 454.732475 -265.944259) (xy 454.768727 -265.905188)
			(xy 454.810398 -265.871957) (xy 454.856556 -265.845308) (xy 454.90617 -265.825836) (xy 454.958132 -265.813976)
			(xy 455.011282 -265.809993) (xy 455.064432 -265.813976) (xy 455.116394 -265.825836) (xy 455.166008 -265.845308)
			(xy 455.212166 -265.871957) (xy 455.253837 -265.905188) (xy 455.290089 -265.944259) (xy 455.320113 -265.988296)
			(xy 455.343239 -266.036317) (xy 455.358949 -266.087247) (xy 455.366892 -266.139951) (xy 455.36739 -266.1666)
			(xy 455.366892 -266.193249) (xy 456.865472 -266.193249) (xy 456.865472 -266.139951) (xy 456.873415 -266.087247)
			(xy 456.889125 -266.036317) (xy 456.912251 -265.988296) (xy 456.942275 -265.944259) (xy 456.978527 -265.905188)
			(xy 457.020198 -265.871957) (xy 457.066356 -265.845308) (xy 457.11597 -265.825836) (xy 457.167932 -265.813976)
			(xy 457.221082 -265.809993) (xy 457.274232 -265.813976) (xy 457.326194 -265.825836) (xy 457.375808 -265.845308)
			(xy 457.421966 -265.871957) (xy 457.463637 -265.905188) (xy 457.499889 -265.944259) (xy 457.529913 -265.988296)
			(xy 457.553039 -266.036317) (xy 457.568749 -266.087247) (xy 457.576692 -266.139951) (xy 457.57719 -266.1666)
			(xy 457.576692 -266.193249) (xy 457.568749 -266.245953) (xy 457.553039 -266.296883) (xy 457.529913 -266.344904)
			(xy 457.499889 -266.388941) (xy 457.463637 -266.428012) (xy 457.421966 -266.461243) (xy 457.375808 -266.487892)
			(xy 457.326194 -266.507364) (xy 457.274232 -266.519224) (xy 457.221082 -266.523208) (xy 457.167932 -266.519224)
			(xy 457.11597 -266.507364) (xy 457.066356 -266.487892) (xy 457.020198 -266.461243) (xy 456.978527 -266.428012)
			(xy 456.942275 -266.388941) (xy 456.912251 -266.344904) (xy 456.889125 -266.296883) (xy 456.873415 -266.245953)
			(xy 456.865472 -266.193249) (xy 455.366892 -266.193249) (xy 455.358949 -266.245953) (xy 455.343239 -266.296883)
			(xy 455.320113 -266.344904) (xy 455.290089 -266.388941) (xy 455.253837 -266.428012) (xy 455.212166 -266.461243)
			(xy 455.166008 -266.487892) (xy 455.116394 -266.507364) (xy 455.064432 -266.519224) (xy 455.011282 -266.523208)
			(xy 454.958132 -266.519224) (xy 454.90617 -266.507364) (xy 454.856556 -266.487892) (xy 454.810398 -266.461243)
			(xy 454.768727 -266.428012) (xy 454.732475 -266.388941) (xy 454.702451 -266.344904) (xy 454.679325 -266.296883)
			(xy 454.663615 -266.245953) (xy 454.655672 -266.193249) (xy 451.266824 -266.193249) (xy 451.258881 -266.245953)
			(xy 451.243171 -266.296883) (xy 451.220045 -266.344904) (xy 451.190021 -266.388941) (xy 451.153769 -266.428012)
			(xy 451.112098 -266.461243) (xy 451.06594 -266.487892) (xy 451.016326 -266.507364) (xy 450.964364 -266.519224)
			(xy 450.911214 -266.523208) (xy 450.858064 -266.519224) (xy 450.806102 -266.507364) (xy 450.756488 -266.487892)
			(xy 450.71033 -266.461243) (xy 450.668659 -266.428012) (xy 450.632407 -266.388941) (xy 450.602383 -266.344904)
			(xy 450.579257 -266.296883) (xy 450.563547 -266.245953) (xy 450.555604 -266.193249) (xy 450.031939 -266.193249)
			(xy 450.029819 -266.220924) (xy 450.017432 -266.273981) (xy 449.997109 -266.324532) (xy 449.969324 -266.371398)
			(xy 449.934725 -266.413486) (xy 449.89412 -266.449813) (xy 449.848456 -266.479531) (xy 449.82384 -266.491212)
			(xy 449.793868 -266.504674) (xy 449.793868 -267.043387) (xy 450.555604 -267.043387) (xy 450.555604 -266.990089)
			(xy 450.563547 -266.937385) (xy 450.579257 -266.886455) (xy 450.602383 -266.838434) (xy 450.632407 -266.794397)
			(xy 450.668659 -266.755326) (xy 450.71033 -266.722095) (xy 450.756488 -266.695446) (xy 450.806102 -266.675974)
			(xy 450.858064 -266.664114) (xy 450.911214 -266.660131) (xy 450.964364 -266.664114) (xy 451.016326 -266.675974)
			(xy 451.06594 -266.695446) (xy 451.112098 -266.722095) (xy 451.153769 -266.755326) (xy 451.190021 -266.794397)
			(xy 451.220045 -266.838434) (xy 451.243171 -266.886455) (xy 451.258881 -266.937385) (xy 451.266824 -266.990089)
			(xy 451.267322 -267.016738) (xy 451.266824 -267.043387) (xy 452.765404 -267.043387) (xy 452.765404 -266.990089)
			(xy 452.773347 -266.937385) (xy 452.789057 -266.886455) (xy 452.812183 -266.838434) (xy 452.842207 -266.794397)
			(xy 452.878459 -266.755326) (xy 452.92013 -266.722095) (xy 452.966288 -266.695446) (xy 453.015902 -266.675974)
			(xy 453.067864 -266.664114) (xy 453.121014 -266.660131) (xy 453.174164 -266.664114) (xy 453.226126 -266.675974)
			(xy 453.27574 -266.695446) (xy 453.321898 -266.722095) (xy 453.363569 -266.755326) (xy 453.399821 -266.794397)
			(xy 453.429845 -266.838434) (xy 453.452971 -266.886455) (xy 453.468681 -266.937385) (xy 453.476624 -266.990089)
			(xy 453.477122 -267.016738) (xy 453.476624 -267.043387) (xy 454.579472 -267.043387) (xy 454.579472 -266.990089)
			(xy 454.587415 -266.937385) (xy 454.603125 -266.886455) (xy 454.626251 -266.838434) (xy 454.656275 -266.794397)
			(xy 454.692527 -266.755326) (xy 454.734198 -266.722095) (xy 454.780356 -266.695446) (xy 454.82997 -266.675974)
			(xy 454.881932 -266.664114) (xy 454.935082 -266.660131) (xy 454.988232 -266.664114) (xy 455.040194 -266.675974)
			(xy 455.089808 -266.695446) (xy 455.135966 -266.722095) (xy 455.177637 -266.755326) (xy 455.213889 -266.794397)
			(xy 455.243913 -266.838434) (xy 455.267039 -266.886455) (xy 455.282749 -266.937385) (xy 455.290692 -266.990089)
			(xy 455.29119 -267.016738) (xy 455.290692 -267.043387) (xy 458.099404 -267.043387) (xy 458.099404 -266.990089)
			(xy 458.107347 -266.937385) (xy 458.123057 -266.886455) (xy 458.146183 -266.838434) (xy 458.176207 -266.794397)
			(xy 458.212459 -266.755326) (xy 458.25413 -266.722095) (xy 458.300288 -266.695446) (xy 458.349902 -266.675974)
			(xy 458.401864 -266.664114) (xy 458.455014 -266.660131) (xy 458.508164 -266.664114) (xy 458.560126 -266.675974)
			(xy 458.60974 -266.695446) (xy 458.655898 -266.722095) (xy 458.697569 -266.755326) (xy 458.733821 -266.794397)
			(xy 458.763845 -266.838434) (xy 458.786971 -266.886455) (xy 458.802681 -266.937385) (xy 458.810624 -266.990089)
			(xy 458.811122 -267.016738) (xy 458.810624 -267.043387) (xy 458.802681 -267.096091) (xy 458.786971 -267.147021)
			(xy 458.763845 -267.195042) (xy 458.733821 -267.239079) (xy 458.697569 -267.27815) (xy 458.655898 -267.311381)
			(xy 458.60974 -267.33803) (xy 458.560126 -267.357502) (xy 458.508164 -267.369362) (xy 458.455014 -267.373346)
			(xy 458.401864 -267.369362) (xy 458.349902 -267.357502) (xy 458.300288 -267.33803) (xy 458.25413 -267.311381)
			(xy 458.212459 -267.27815) (xy 458.176207 -267.239079) (xy 458.146183 -267.195042) (xy 458.123057 -267.147021)
			(xy 458.107347 -267.096091) (xy 458.099404 -267.043387) (xy 455.290692 -267.043387) (xy 455.282749 -267.096091)
			(xy 455.267039 -267.147021) (xy 455.243913 -267.195042) (xy 455.213889 -267.239079) (xy 455.177637 -267.27815)
			(xy 455.135966 -267.311381) (xy 455.089808 -267.33803) (xy 455.040194 -267.357502) (xy 454.988232 -267.369362)
			(xy 454.935082 -267.373346) (xy 454.881932 -267.369362) (xy 454.82997 -267.357502) (xy 454.780356 -267.33803)
			(xy 454.734198 -267.311381) (xy 454.692527 -267.27815) (xy 454.656275 -267.239079) (xy 454.626251 -267.195042)
			(xy 454.603125 -267.147021) (xy 454.587415 -267.096091) (xy 454.579472 -267.043387) (xy 453.476624 -267.043387)
			(xy 453.468681 -267.096091) (xy 453.452971 -267.147021) (xy 453.429845 -267.195042) (xy 453.399821 -267.239079)
			(xy 453.363569 -267.27815) (xy 453.321898 -267.311381) (xy 453.27574 -267.33803) (xy 453.226126 -267.357502)
			(xy 453.174164 -267.369362) (xy 453.121014 -267.373346) (xy 453.067864 -267.369362) (xy 453.015902 -267.357502)
			(xy 452.966288 -267.33803) (xy 452.92013 -267.311381) (xy 452.878459 -267.27815) (xy 452.842207 -267.239079)
			(xy 452.812183 -267.195042) (xy 452.789057 -267.147021) (xy 452.773347 -267.096091) (xy 452.765404 -267.043387)
			(xy 451.266824 -267.043387) (xy 451.258881 -267.096091) (xy 451.243171 -267.147021) (xy 451.220045 -267.195042)
			(xy 451.190021 -267.239079) (xy 451.153769 -267.27815) (xy 451.112098 -267.311381) (xy 451.06594 -267.33803)
			(xy 451.016326 -267.357502) (xy 450.964364 -267.369362) (xy 450.911214 -267.373346) (xy 450.858064 -267.369362)
			(xy 450.806102 -267.357502) (xy 450.756488 -267.33803) (xy 450.71033 -267.311381) (xy 450.668659 -267.27815)
			(xy 450.632407 -267.239079) (xy 450.602383 -267.195042) (xy 450.579257 -267.147021) (xy 450.563547 -267.096091)
			(xy 450.555604 -267.043387) (xy 449.793868 -267.043387) (xy 449.793868 -267.528548) (xy 449.82384 -267.54201)
			(xy 449.848454 -267.55369) (xy 449.894115 -267.583409) (xy 449.934717 -267.619735) (xy 449.969313 -267.661821)
			(xy 449.997095 -267.708685) (xy 450.017416 -267.759234) (xy 450.0298 -267.812288) (xy 450.03396 -267.866609)
			(xy 450.031917 -267.893271) (xy 450.555604 -267.893271) (xy 450.555604 -267.839973) (xy 450.563547 -267.787269)
			(xy 450.579257 -267.736339) (xy 450.602383 -267.688318) (xy 450.632407 -267.644281) (xy 450.668659 -267.60521)
			(xy 450.71033 -267.571979) (xy 450.756488 -267.54533) (xy 450.806102 -267.525858) (xy 450.858064 -267.513998)
			(xy 450.911214 -267.510015) (xy 450.964364 -267.513998) (xy 451.016326 -267.525858) (xy 451.06594 -267.54533)
			(xy 451.112098 -267.571979) (xy 451.153769 -267.60521) (xy 451.190021 -267.644281) (xy 451.220045 -267.688318)
			(xy 451.243171 -267.736339) (xy 451.258881 -267.787269) (xy 451.266824 -267.839973) (xy 451.267322 -267.866622)
			(xy 451.266824 -267.893271) (xy 454.655672 -267.893271) (xy 454.655672 -267.839973) (xy 454.663615 -267.787269)
			(xy 454.679325 -267.736339) (xy 454.702451 -267.688318) (xy 454.732475 -267.644281) (xy 454.768727 -267.60521)
			(xy 454.810398 -267.571979) (xy 454.856556 -267.54533) (xy 454.90617 -267.525858) (xy 454.958132 -267.513998)
			(xy 455.011282 -267.510015) (xy 455.064432 -267.513998) (xy 455.116394 -267.525858) (xy 455.166008 -267.54533)
			(xy 455.212166 -267.571979) (xy 455.253837 -267.60521) (xy 455.290089 -267.644281) (xy 455.320113 -267.688318)
			(xy 455.343239 -267.736339) (xy 455.358949 -267.787269) (xy 455.366892 -267.839973) (xy 455.36739 -267.866622)
			(xy 455.366892 -267.893271) (xy 456.865472 -267.893271) (xy 456.865472 -267.839973) (xy 456.873415 -267.787269)
			(xy 456.889125 -267.736339) (xy 456.912251 -267.688318) (xy 456.942275 -267.644281) (xy 456.978527 -267.60521)
			(xy 457.020198 -267.571979) (xy 457.066356 -267.54533) (xy 457.11597 -267.525858) (xy 457.167932 -267.513998)
			(xy 457.221082 -267.510015) (xy 457.274232 -267.513998) (xy 457.326194 -267.525858) (xy 457.375808 -267.54533)
			(xy 457.421966 -267.571979) (xy 457.463637 -267.60521) (xy 457.499889 -267.644281) (xy 457.529913 -267.688318)
			(xy 457.553039 -267.736339) (xy 457.568749 -267.787269) (xy 457.576692 -267.839973) (xy 457.57719 -267.866622)
			(xy 457.576692 -267.893271) (xy 458.099404 -267.893271) (xy 458.099404 -267.839973) (xy 458.107347 -267.787269)
			(xy 458.123057 -267.736339) (xy 458.146183 -267.688318) (xy 458.176207 -267.644281) (xy 458.212459 -267.60521)
			(xy 458.25413 -267.571979) (xy 458.300288 -267.54533) (xy 458.349902 -267.525858) (xy 458.401864 -267.513998)
			(xy 458.455014 -267.510015) (xy 458.508164 -267.513998) (xy 458.560126 -267.525858) (xy 458.60974 -267.54533)
			(xy 458.655898 -267.571979) (xy 458.697569 -267.60521) (xy 458.733821 -267.644281) (xy 458.763845 -267.688318)
			(xy 458.786971 -267.736339) (xy 458.802681 -267.787269) (xy 458.810624 -267.839973) (xy 458.811122 -267.866622)
			(xy 458.810624 -267.893271) (xy 458.802681 -267.945975) (xy 458.786971 -267.996905) (xy 458.763845 -268.044926)
			(xy 458.733821 -268.088963) (xy 458.697569 -268.128034) (xy 458.655898 -268.161265) (xy 458.60974 -268.187914)
			(xy 458.560126 -268.207386) (xy 458.508164 -268.219246) (xy 458.455014 -268.22323) (xy 458.401864 -268.219246)
			(xy 458.349902 -268.207386) (xy 458.300288 -268.187914) (xy 458.25413 -268.161265) (xy 458.212459 -268.128034)
			(xy 458.176207 -268.088963) (xy 458.146183 -268.044926) (xy 458.123057 -267.996905) (xy 458.107347 -267.945975)
			(xy 458.099404 -267.893271) (xy 457.576692 -267.893271) (xy 457.568749 -267.945975) (xy 457.553039 -267.996905)
			(xy 457.529913 -268.044926) (xy 457.499889 -268.088963) (xy 457.463637 -268.128034) (xy 457.421966 -268.161265)
			(xy 457.375808 -268.187914) (xy 457.326194 -268.207386) (xy 457.274232 -268.219246) (xy 457.221082 -268.22323)
			(xy 457.167932 -268.219246) (xy 457.11597 -268.207386) (xy 457.066356 -268.187914) (xy 457.020198 -268.161265)
			(xy 456.978527 -268.128034) (xy 456.942275 -268.088963) (xy 456.912251 -268.044926) (xy 456.889125 -267.996905)
			(xy 456.873415 -267.945975) (xy 456.865472 -267.893271) (xy 455.366892 -267.893271) (xy 455.358949 -267.945975)
			(xy 455.343239 -267.996905) (xy 455.320113 -268.044926) (xy 455.290089 -268.088963) (xy 455.253837 -268.128034)
			(xy 455.212166 -268.161265) (xy 455.166008 -268.187914) (xy 455.116394 -268.207386) (xy 455.064432 -268.219246)
			(xy 455.011282 -268.22323) (xy 454.958132 -268.219246) (xy 454.90617 -268.207386) (xy 454.856556 -268.187914)
			(xy 454.810398 -268.161265) (xy 454.768727 -268.128034) (xy 454.732475 -268.088963) (xy 454.702451 -268.044926)
			(xy 454.679325 -267.996905) (xy 454.663615 -267.945975) (xy 454.655672 -267.893271) (xy 451.266824 -267.893271)
			(xy 451.258881 -267.945975) (xy 451.243171 -267.996905) (xy 451.220045 -268.044926) (xy 451.190021 -268.088963)
			(xy 451.153769 -268.128034) (xy 451.112098 -268.161265) (xy 451.06594 -268.187914) (xy 451.016326 -268.207386)
			(xy 450.964364 -268.219246) (xy 450.911214 -268.22323) (xy 450.858064 -268.219246) (xy 450.806102 -268.207386)
			(xy 450.756488 -268.187914) (xy 450.71033 -268.161265) (xy 450.668659 -268.128034) (xy 450.632407 -268.088963)
			(xy 450.602383 -268.044926) (xy 450.579257 -267.996905) (xy 450.563547 -267.945975) (xy 450.555604 -267.893271)
			(xy 450.031917 -267.893271) (xy 450.029797 -267.92093) (xy 450.01741 -267.973983) (xy 449.997087 -268.024531)
			(xy 449.969303 -268.071394) (xy 449.934705 -268.113478) (xy 449.894101 -268.149802) (xy 449.848438 -268.179518)
			(xy 449.82384 -268.191234) (xy 449.793868 -268.204696) (xy 449.793868 -268.743409) (xy 450.555604 -268.743409)
			(xy 450.555604 -268.690111) (xy 450.563547 -268.637407) (xy 450.579257 -268.586477) (xy 450.602383 -268.538456)
			(xy 450.632407 -268.494419) (xy 450.668659 -268.455348) (xy 450.71033 -268.422117) (xy 450.756488 -268.395468)
			(xy 450.806102 -268.375996) (xy 450.858064 -268.364136) (xy 450.911214 -268.360153) (xy 450.964364 -268.364136)
			(xy 451.016326 -268.375996) (xy 451.06594 -268.395468) (xy 451.112098 -268.422117) (xy 451.153769 -268.455348)
			(xy 451.190021 -268.494419) (xy 451.220045 -268.538456) (xy 451.243171 -268.586477) (xy 451.258881 -268.637407)
			(xy 451.266824 -268.690111) (xy 451.267322 -268.71676) (xy 451.266824 -268.743409) (xy 452.765404 -268.743409)
			(xy 452.765404 -268.690111) (xy 452.773347 -268.637407) (xy 452.789057 -268.586477) (xy 452.812183 -268.538456)
			(xy 452.842207 -268.494419) (xy 452.878459 -268.455348) (xy 452.92013 -268.422117) (xy 452.966288 -268.395468)
			(xy 453.015902 -268.375996) (xy 453.067864 -268.364136) (xy 453.121014 -268.360153) (xy 453.174164 -268.364136)
			(xy 453.226126 -268.375996) (xy 453.27574 -268.395468) (xy 453.321898 -268.422117) (xy 453.363569 -268.455348)
			(xy 453.399821 -268.494419) (xy 453.429845 -268.538456) (xy 453.452971 -268.586477) (xy 453.468681 -268.637407)
			(xy 453.476624 -268.690111) (xy 453.477122 -268.71676) (xy 453.476624 -268.743409) (xy 458.099404 -268.743409)
			(xy 458.099404 -268.690111) (xy 458.107347 -268.637407) (xy 458.123057 -268.586477) (xy 458.146183 -268.538456)
			(xy 458.176207 -268.494419) (xy 458.212459 -268.455348) (xy 458.25413 -268.422117) (xy 458.300288 -268.395468)
			(xy 458.349902 -268.375996) (xy 458.401864 -268.364136) (xy 458.455014 -268.360153) (xy 458.508164 -268.364136)
			(xy 458.560126 -268.375996) (xy 458.60974 -268.395468) (xy 458.655898 -268.422117) (xy 458.697569 -268.455348)
			(xy 458.733821 -268.494419) (xy 458.763845 -268.538456) (xy 458.786971 -268.586477) (xy 458.802681 -268.637407)
			(xy 458.810624 -268.690111) (xy 458.811122 -268.71676) (xy 458.810624 -268.743409) (xy 458.802681 -268.796113)
			(xy 458.786971 -268.847043) (xy 458.763845 -268.895064) (xy 458.733821 -268.939101) (xy 458.697569 -268.978172)
			(xy 458.655898 -269.011403) (xy 458.60974 -269.038052) (xy 458.560126 -269.057524) (xy 458.508164 -269.069384)
			(xy 458.455014 -269.073368) (xy 458.401864 -269.069384) (xy 458.349902 -269.057524) (xy 458.300288 -269.038052)
			(xy 458.25413 -269.011403) (xy 458.212459 -268.978172) (xy 458.176207 -268.939101) (xy 458.146183 -268.895064)
			(xy 458.123057 -268.847043) (xy 458.107347 -268.796113) (xy 458.099404 -268.743409) (xy 453.476624 -268.743409)
			(xy 453.468681 -268.796113) (xy 453.452971 -268.847043) (xy 453.429845 -268.895064) (xy 453.399821 -268.939101)
			(xy 453.363569 -268.978172) (xy 453.321898 -269.011403) (xy 453.27574 -269.038052) (xy 453.226126 -269.057524)
			(xy 453.174164 -269.069384) (xy 453.121014 -269.073368) (xy 453.067864 -269.069384) (xy 453.015902 -269.057524)
			(xy 452.966288 -269.038052) (xy 452.92013 -269.011403) (xy 452.878459 -268.978172) (xy 452.842207 -268.939101)
			(xy 452.812183 -268.895064) (xy 452.789057 -268.847043) (xy 452.773347 -268.796113) (xy 452.765404 -268.743409)
			(xy 451.266824 -268.743409) (xy 451.258881 -268.796113) (xy 451.243171 -268.847043) (xy 451.220045 -268.895064)
			(xy 451.190021 -268.939101) (xy 451.153769 -268.978172) (xy 451.112098 -269.011403) (xy 451.06594 -269.038052)
			(xy 451.016326 -269.057524) (xy 450.964364 -269.069384) (xy 450.911214 -269.073368) (xy 450.858064 -269.069384)
			(xy 450.806102 -269.057524) (xy 450.756488 -269.038052) (xy 450.71033 -269.011403) (xy 450.668659 -268.978172)
			(xy 450.632407 -268.939101) (xy 450.602383 -268.895064) (xy 450.579257 -268.847043) (xy 450.563547 -268.796113)
			(xy 450.555604 -268.743409) (xy 449.793868 -268.743409) (xy 449.793868 -269.22857) (xy 449.82384 -269.242032)
			(xy 449.848453 -269.253712) (xy 449.89411 -269.28343) (xy 449.934709 -269.319755) (xy 449.969302 -269.36184)
			(xy 449.997081 -269.408702) (xy 450.017399 -269.459248) (xy 450.029782 -269.5123) (xy 450.03394 -269.566618)
			(xy 450.031895 -269.593293) (xy 450.555604 -269.593293) (xy 450.555604 -269.539995) (xy 450.563547 -269.487291)
			(xy 450.579257 -269.436361) (xy 450.602383 -269.38834) (xy 450.632407 -269.344303) (xy 450.668659 -269.305232)
			(xy 450.71033 -269.272001) (xy 450.756488 -269.245352) (xy 450.806102 -269.22588) (xy 450.858064 -269.21402)
			(xy 450.911214 -269.210037) (xy 450.964364 -269.21402) (xy 451.016326 -269.22588) (xy 451.06594 -269.245352)
			(xy 451.112098 -269.272001) (xy 451.153769 -269.305232) (xy 451.190021 -269.344303) (xy 451.220045 -269.38834)
			(xy 451.243171 -269.436361) (xy 451.258881 -269.487291) (xy 451.266824 -269.539995) (xy 451.267322 -269.566644)
			(xy 451.266824 -269.593293) (xy 454.655672 -269.593293) (xy 454.655672 -269.539995) (xy 454.663615 -269.487291)
			(xy 454.679325 -269.436361) (xy 454.702451 -269.38834) (xy 454.732475 -269.344303) (xy 454.768727 -269.305232)
			(xy 454.810398 -269.272001) (xy 454.856556 -269.245352) (xy 454.90617 -269.22588) (xy 454.958132 -269.21402)
			(xy 455.011282 -269.210037) (xy 455.064432 -269.21402) (xy 455.116394 -269.22588) (xy 455.166008 -269.245352)
			(xy 455.212166 -269.272001) (xy 455.253837 -269.305232) (xy 455.290089 -269.344303) (xy 455.320113 -269.38834)
			(xy 455.343239 -269.436361) (xy 455.358949 -269.487291) (xy 455.366892 -269.539995) (xy 455.36739 -269.566644)
			(xy 455.366892 -269.593293) (xy 456.865472 -269.593293) (xy 456.865472 -269.539995) (xy 456.873415 -269.487291)
			(xy 456.889125 -269.436361) (xy 456.912251 -269.38834) (xy 456.942275 -269.344303) (xy 456.978527 -269.305232)
			(xy 457.020198 -269.272001) (xy 457.066356 -269.245352) (xy 457.11597 -269.22588) (xy 457.167932 -269.21402)
			(xy 457.221082 -269.210037) (xy 457.274232 -269.21402) (xy 457.326194 -269.22588) (xy 457.375808 -269.245352)
			(xy 457.421966 -269.272001) (xy 457.463637 -269.305232) (xy 457.499889 -269.344303) (xy 457.529913 -269.38834)
			(xy 457.553039 -269.436361) (xy 457.568749 -269.487291) (xy 457.576692 -269.539995) (xy 457.57719 -269.566644)
			(xy 457.576692 -269.593293) (xy 457.568749 -269.645997) (xy 457.553039 -269.696927) (xy 457.529913 -269.744948)
			(xy 457.499889 -269.788985) (xy 457.463637 -269.828056) (xy 457.421966 -269.861287) (xy 457.375808 -269.887936)
			(xy 457.326194 -269.907408) (xy 457.274232 -269.919268) (xy 457.221082 -269.923252) (xy 457.167932 -269.919268)
			(xy 457.11597 -269.907408) (xy 457.066356 -269.887936) (xy 457.020198 -269.861287) (xy 456.978527 -269.828056)
			(xy 456.942275 -269.788985) (xy 456.912251 -269.744948) (xy 456.889125 -269.696927) (xy 456.873415 -269.645997)
			(xy 456.865472 -269.593293) (xy 455.366892 -269.593293) (xy 455.358949 -269.645997) (xy 455.343239 -269.696927)
			(xy 455.320113 -269.744948) (xy 455.290089 -269.788985) (xy 455.253837 -269.828056) (xy 455.212166 -269.861287)
			(xy 455.166008 -269.887936) (xy 455.116394 -269.907408) (xy 455.064432 -269.919268) (xy 455.011282 -269.923252)
			(xy 454.958132 -269.919268) (xy 454.90617 -269.907408) (xy 454.856556 -269.887936) (xy 454.810398 -269.861287)
			(xy 454.768727 -269.828056) (xy 454.732475 -269.788985) (xy 454.702451 -269.744948) (xy 454.679325 -269.696927)
			(xy 454.663615 -269.645997) (xy 454.655672 -269.593293) (xy 451.266824 -269.593293) (xy 451.258881 -269.645997)
			(xy 451.243171 -269.696927) (xy 451.220045 -269.744948) (xy 451.190021 -269.788985) (xy 451.153769 -269.828056)
			(xy 451.112098 -269.861287) (xy 451.06594 -269.887936) (xy 451.016326 -269.907408) (xy 450.964364 -269.919268)
			(xy 450.911214 -269.923252) (xy 450.858064 -269.919268) (xy 450.806102 -269.907408) (xy 450.756488 -269.887936)
			(xy 450.71033 -269.861287) (xy 450.668659 -269.828056) (xy 450.632407 -269.788985) (xy 450.602383 -269.744948)
			(xy 450.579257 -269.696927) (xy 450.563547 -269.645997) (xy 450.555604 -269.593293) (xy 450.031895 -269.593293)
			(xy 450.029776 -269.620936) (xy 450.017388 -269.673986) (xy 449.997065 -269.724531) (xy 449.969281 -269.77139)
			(xy 449.934684 -269.813471) (xy 449.894081 -269.849792) (xy 449.848421 -269.879505) (xy 449.82384 -269.891256)
			(xy 449.793868 -269.904718) (xy 449.793868 -270.443431) (xy 450.555604 -270.443431) (xy 450.555604 -270.390133)
			(xy 450.563547 -270.337429) (xy 450.579257 -270.286499) (xy 450.602383 -270.238478) (xy 450.632407 -270.194441)
			(xy 450.668659 -270.15537) (xy 450.71033 -270.122139) (xy 450.756488 -270.09549) (xy 450.806102 -270.076018)
			(xy 450.858064 -270.064158) (xy 450.911214 -270.060175) (xy 450.964364 -270.064158) (xy 451.016326 -270.076018)
			(xy 451.06594 -270.09549) (xy 451.112098 -270.122139) (xy 451.153769 -270.15537) (xy 451.190021 -270.194441)
			(xy 451.220045 -270.238478) (xy 451.243171 -270.286499) (xy 451.258881 -270.337429) (xy 451.266824 -270.390133)
			(xy 451.267322 -270.416782) (xy 451.266824 -270.443431) (xy 452.765404 -270.443431) (xy 452.765404 -270.390133)
			(xy 452.773347 -270.337429) (xy 452.789057 -270.286499) (xy 452.812183 -270.238478) (xy 452.842207 -270.194441)
			(xy 452.878459 -270.15537) (xy 452.92013 -270.122139) (xy 452.966288 -270.09549) (xy 453.015902 -270.076018)
			(xy 453.067864 -270.064158) (xy 453.121014 -270.060175) (xy 453.174164 -270.064158) (xy 453.226126 -270.076018)
			(xy 453.27574 -270.09549) (xy 453.321898 -270.122139) (xy 453.363569 -270.15537) (xy 453.399821 -270.194441)
			(xy 453.429845 -270.238478) (xy 453.452971 -270.286499) (xy 453.468681 -270.337429) (xy 453.476624 -270.390133)
			(xy 453.477122 -270.416782) (xy 453.476624 -270.443431) (xy 454.655672 -270.443431) (xy 454.655672 -270.390133)
			(xy 454.663615 -270.337429) (xy 454.679325 -270.286499) (xy 454.702451 -270.238478) (xy 454.732475 -270.194441)
			(xy 454.768727 -270.15537) (xy 454.810398 -270.122139) (xy 454.856556 -270.09549) (xy 454.90617 -270.076018)
			(xy 454.958132 -270.064158) (xy 455.011282 -270.060175) (xy 455.064432 -270.064158) (xy 455.116394 -270.076018)
			(xy 455.166008 -270.09549) (xy 455.212166 -270.122139) (xy 455.253837 -270.15537) (xy 455.290089 -270.194441)
			(xy 455.320113 -270.238478) (xy 455.343239 -270.286499) (xy 455.358949 -270.337429) (xy 455.366892 -270.390133)
			(xy 455.36739 -270.416782) (xy 455.366892 -270.443431) (xy 458.099404 -270.443431) (xy 458.099404 -270.390133)
			(xy 458.107347 -270.337429) (xy 458.123057 -270.286499) (xy 458.146183 -270.238478) (xy 458.176207 -270.194441)
			(xy 458.212459 -270.15537) (xy 458.25413 -270.122139) (xy 458.300288 -270.09549) (xy 458.349902 -270.076018)
			(xy 458.401864 -270.064158) (xy 458.455014 -270.060175) (xy 458.508164 -270.064158) (xy 458.560126 -270.076018)
			(xy 458.60974 -270.09549) (xy 458.655898 -270.122139) (xy 458.697569 -270.15537) (xy 458.733821 -270.194441)
			(xy 458.763845 -270.238478) (xy 458.786971 -270.286499) (xy 458.802681 -270.337429) (xy 458.810624 -270.390133)
			(xy 458.811122 -270.416782) (xy 458.810624 -270.443431) (xy 458.802681 -270.496135) (xy 458.786971 -270.547065)
			(xy 458.763845 -270.595086) (xy 458.733821 -270.639123) (xy 458.697569 -270.678194) (xy 458.655898 -270.711425)
			(xy 458.60974 -270.738074) (xy 458.560126 -270.757546) (xy 458.508164 -270.769406) (xy 458.455014 -270.77339)
			(xy 458.401864 -270.769406) (xy 458.349902 -270.757546) (xy 458.300288 -270.738074) (xy 458.25413 -270.711425)
			(xy 458.212459 -270.678194) (xy 458.176207 -270.639123) (xy 458.146183 -270.595086) (xy 458.123057 -270.547065)
			(xy 458.107347 -270.496135) (xy 458.099404 -270.443431) (xy 455.366892 -270.443431) (xy 455.358949 -270.496135)
			(xy 455.343239 -270.547065) (xy 455.320113 -270.595086) (xy 455.290089 -270.639123) (xy 455.253837 -270.678194)
			(xy 455.212166 -270.711425) (xy 455.166008 -270.738074) (xy 455.116394 -270.757546) (xy 455.064432 -270.769406)
			(xy 455.011282 -270.77339) (xy 454.958132 -270.769406) (xy 454.90617 -270.757546) (xy 454.856556 -270.738074)
			(xy 454.810398 -270.711425) (xy 454.768727 -270.678194) (xy 454.732475 -270.639123) (xy 454.702451 -270.595086)
			(xy 454.679325 -270.547065) (xy 454.663615 -270.496135) (xy 454.655672 -270.443431) (xy 453.476624 -270.443431)
			(xy 453.468681 -270.496135) (xy 453.452971 -270.547065) (xy 453.429845 -270.595086) (xy 453.399821 -270.639123)
			(xy 453.363569 -270.678194) (xy 453.321898 -270.711425) (xy 453.27574 -270.738074) (xy 453.226126 -270.757546)
			(xy 453.174164 -270.769406) (xy 453.121014 -270.77339) (xy 453.067864 -270.769406) (xy 453.015902 -270.757546)
			(xy 452.966288 -270.738074) (xy 452.92013 -270.711425) (xy 452.878459 -270.678194) (xy 452.842207 -270.639123)
			(xy 452.812183 -270.595086) (xy 452.789057 -270.547065) (xy 452.773347 -270.496135) (xy 452.765404 -270.443431)
			(xy 451.266824 -270.443431) (xy 451.258881 -270.496135) (xy 451.243171 -270.547065) (xy 451.220045 -270.595086)
			(xy 451.190021 -270.639123) (xy 451.153769 -270.678194) (xy 451.112098 -270.711425) (xy 451.06594 -270.738074)
			(xy 451.016326 -270.757546) (xy 450.964364 -270.769406) (xy 450.911214 -270.77339) (xy 450.858064 -270.769406)
			(xy 450.806102 -270.757546) (xy 450.756488 -270.738074) (xy 450.71033 -270.711425) (xy 450.668659 -270.678194)
			(xy 450.632407 -270.639123) (xy 450.602383 -270.595086) (xy 450.579257 -270.547065) (xy 450.563547 -270.496135)
			(xy 450.555604 -270.443431) (xy 449.793868 -270.443431) (xy 449.793868 -270.928592) (xy 449.82384 -270.942054)
			(xy 449.848458 -270.953735) (xy 449.894128 -270.983454) (xy 449.934738 -271.019783) (xy 449.969342 -271.061873)
			(xy 449.997131 -271.108742) (xy 450.017457 -271.159296) (xy 450.029847 -271.212357) (xy 450.034011 -271.266686)
			(xy 450.031972 -271.293315) (xy 450.555604 -271.293315) (xy 450.555604 -271.240017) (xy 450.563547 -271.187313)
			(xy 450.579257 -271.136383) (xy 450.602383 -271.088362) (xy 450.632407 -271.044325) (xy 450.668659 -271.005254)
			(xy 450.71033 -270.972023) (xy 450.756488 -270.945374) (xy 450.806102 -270.925902) (xy 450.858064 -270.914042)
			(xy 450.911214 -270.910059) (xy 450.964364 -270.914042) (xy 451.016326 -270.925902) (xy 451.06594 -270.945374)
			(xy 451.112098 -270.972023) (xy 451.153769 -271.005254) (xy 451.190021 -271.044325) (xy 451.220045 -271.088362)
			(xy 451.243171 -271.136383) (xy 451.258881 -271.187313) (xy 451.266824 -271.240017) (xy 451.267322 -271.266666)
			(xy 451.266824 -271.293315) (xy 454.655672 -271.293315) (xy 454.655672 -271.240017) (xy 454.663615 -271.187313)
			(xy 454.679325 -271.136383) (xy 454.702451 -271.088362) (xy 454.732475 -271.044325) (xy 454.768727 -271.005254)
			(xy 454.810398 -270.972023) (xy 454.856556 -270.945374) (xy 454.90617 -270.925902) (xy 454.958132 -270.914042)
			(xy 455.011282 -270.910059) (xy 455.064432 -270.914042) (xy 455.116394 -270.925902) (xy 455.166008 -270.945374)
			(xy 455.212166 -270.972023) (xy 455.253837 -271.005254) (xy 455.290089 -271.044325) (xy 455.320113 -271.088362)
			(xy 455.343239 -271.136383) (xy 455.358949 -271.187313) (xy 455.366892 -271.240017) (xy 455.36739 -271.266666)
			(xy 455.366892 -271.293315) (xy 456.865472 -271.293315) (xy 456.865472 -271.240017) (xy 456.873415 -271.187313)
			(xy 456.889125 -271.136383) (xy 456.912251 -271.088362) (xy 456.942275 -271.044325) (xy 456.978527 -271.005254)
			(xy 457.020198 -270.972023) (xy 457.066356 -270.945374) (xy 457.11597 -270.925902) (xy 457.167932 -270.914042)
			(xy 457.221082 -270.910059) (xy 457.274232 -270.914042) (xy 457.326194 -270.925902) (xy 457.375808 -270.945374)
			(xy 457.421966 -270.972023) (xy 457.463637 -271.005254) (xy 457.499889 -271.044325) (xy 457.529913 -271.088362)
			(xy 457.553039 -271.136383) (xy 457.568749 -271.187313) (xy 457.576692 -271.240017) (xy 457.57719 -271.266666)
			(xy 457.576692 -271.293315) (xy 457.568749 -271.346019) (xy 457.553039 -271.396949) (xy 457.529913 -271.44497)
			(xy 457.499889 -271.489007) (xy 457.463637 -271.528078) (xy 457.421966 -271.561309) (xy 457.375808 -271.587958)
			(xy 457.326194 -271.60743) (xy 457.274232 -271.61929) (xy 457.221082 -271.623274) (xy 457.167932 -271.61929)
			(xy 457.11597 -271.60743) (xy 457.066356 -271.587958) (xy 457.020198 -271.561309) (xy 456.978527 -271.528078)
			(xy 456.942275 -271.489007) (xy 456.912251 -271.44497) (xy 456.889125 -271.396949) (xy 456.873415 -271.346019)
			(xy 456.865472 -271.293315) (xy 455.366892 -271.293315) (xy 455.358949 -271.346019) (xy 455.343239 -271.396949)
			(xy 455.320113 -271.44497) (xy 455.290089 -271.489007) (xy 455.253837 -271.528078) (xy 455.212166 -271.561309)
			(xy 455.166008 -271.587958) (xy 455.116394 -271.60743) (xy 455.064432 -271.61929) (xy 455.011282 -271.623274)
			(xy 454.958132 -271.61929) (xy 454.90617 -271.60743) (xy 454.856556 -271.587958) (xy 454.810398 -271.561309)
			(xy 454.768727 -271.528078) (xy 454.732475 -271.489007) (xy 454.702451 -271.44497) (xy 454.679325 -271.396949)
			(xy 454.663615 -271.346019) (xy 454.655672 -271.293315) (xy 451.266824 -271.293315) (xy 451.258881 -271.346019)
			(xy 451.243171 -271.396949) (xy 451.220045 -271.44497) (xy 451.190021 -271.489007) (xy 451.153769 -271.528078)
			(xy 451.112098 -271.561309) (xy 451.06594 -271.587958) (xy 451.016326 -271.60743) (xy 450.964364 -271.61929)
			(xy 450.911214 -271.623274) (xy 450.858064 -271.61929) (xy 450.806102 -271.60743) (xy 450.756488 -271.587958)
			(xy 450.71033 -271.561309) (xy 450.668659 -271.528078) (xy 450.632407 -271.489007) (xy 450.602383 -271.44497)
			(xy 450.579257 -271.396949) (xy 450.563547 -271.346019) (xy 450.555604 -271.293315) (xy 450.031972 -271.293315)
			(xy 450.029851 -271.321015) (xy 450.017466 -271.374077) (xy 449.997143 -271.424633) (xy 449.969358 -271.471504)
			(xy 449.934758 -271.513597) (xy 449.89415 -271.549929) (xy 449.848483 -271.579652) (xy 449.82384 -271.591278)
			(xy 449.793868 -271.60474) (xy 449.793868 -272.143453) (xy 450.555604 -272.143453) (xy 450.555604 -272.090155)
			(xy 450.563547 -272.037451) (xy 450.579257 -271.986521) (xy 450.602383 -271.9385) (xy 450.632407 -271.894463)
			(xy 450.668659 -271.855392) (xy 450.71033 -271.822161) (xy 450.756488 -271.795512) (xy 450.806102 -271.77604)
			(xy 450.858064 -271.76418) (xy 450.911214 -271.760197) (xy 450.964364 -271.76418) (xy 451.016326 -271.77604)
			(xy 451.06594 -271.795512) (xy 451.112098 -271.822161) (xy 451.153769 -271.855392) (xy 451.190021 -271.894463)
			(xy 451.220045 -271.9385) (xy 451.243171 -271.986521) (xy 451.258881 -272.037451) (xy 451.266824 -272.090155)
			(xy 451.267322 -272.116804) (xy 451.266824 -272.143453) (xy 452.765404 -272.143453) (xy 452.765404 -272.090155)
			(xy 452.773347 -272.037451) (xy 452.789057 -271.986521) (xy 452.812183 -271.9385) (xy 452.842207 -271.894463)
			(xy 452.878459 -271.855392) (xy 452.92013 -271.822161) (xy 452.966288 -271.795512) (xy 453.015902 -271.77604)
			(xy 453.067864 -271.76418) (xy 453.121014 -271.760197) (xy 453.174164 -271.76418) (xy 453.226126 -271.77604)
			(xy 453.27574 -271.795512) (xy 453.321898 -271.822161) (xy 453.363569 -271.855392) (xy 453.399821 -271.894463)
			(xy 453.429845 -271.9385) (xy 453.452971 -271.986521) (xy 453.468681 -272.037451) (xy 453.476624 -272.090155)
			(xy 453.477122 -272.116804) (xy 453.476629 -272.143199) (xy 454.655672 -272.143199) (xy 454.655672 -272.089901)
			(xy 454.663615 -272.037197) (xy 454.679325 -271.986267) (xy 454.702451 -271.938246) (xy 454.732475 -271.894209)
			(xy 454.768727 -271.855138) (xy 454.810398 -271.821907) (xy 454.856556 -271.795258) (xy 454.90617 -271.775786)
			(xy 454.958132 -271.763926) (xy 455.011282 -271.759943) (xy 455.064432 -271.763926) (xy 455.116394 -271.775786)
			(xy 455.166008 -271.795258) (xy 455.212166 -271.821907) (xy 455.253837 -271.855138) (xy 455.290089 -271.894209)
			(xy 455.320113 -271.938246) (xy 455.343239 -271.986267) (xy 455.358949 -272.037197) (xy 455.366892 -272.089901)
			(xy 455.36739 -272.11655) (xy 455.366892 -272.143199) (xy 455.366854 -272.143453) (xy 458.099404 -272.143453)
			(xy 458.099404 -272.090155) (xy 458.107347 -272.037451) (xy 458.123057 -271.986521) (xy 458.146183 -271.9385)
			(xy 458.176207 -271.894463) (xy 458.212459 -271.855392) (xy 458.25413 -271.822161) (xy 458.300288 -271.795512)
			(xy 458.349902 -271.77604) (xy 458.401864 -271.76418) (xy 458.455014 -271.760197) (xy 458.508164 -271.76418)
			(xy 458.560126 -271.77604) (xy 458.60974 -271.795512) (xy 458.655898 -271.822161) (xy 458.697569 -271.855392)
			(xy 458.733821 -271.894463) (xy 458.763845 -271.9385) (xy 458.786971 -271.986521) (xy 458.802681 -272.037451)
			(xy 458.810624 -272.090155) (xy 458.811122 -272.116804) (xy 458.810624 -272.143453) (xy 458.802681 -272.196157)
			(xy 458.786971 -272.247087) (xy 458.763845 -272.295108) (xy 458.733821 -272.339145) (xy 458.697569 -272.378216)
			(xy 458.655898 -272.411447) (xy 458.60974 -272.438096) (xy 458.560126 -272.457568) (xy 458.508164 -272.469428)
			(xy 458.455014 -272.473412) (xy 458.401864 -272.469428) (xy 458.349902 -272.457568) (xy 458.300288 -272.438096)
			(xy 458.25413 -272.411447) (xy 458.212459 -272.378216) (xy 458.176207 -272.339145) (xy 458.146183 -272.295108)
			(xy 458.123057 -272.247087) (xy 458.107347 -272.196157) (xy 458.099404 -272.143453) (xy 455.366854 -272.143453)
			(xy 455.358949 -272.195903) (xy 455.343239 -272.246833) (xy 455.320113 -272.294854) (xy 455.290089 -272.338891)
			(xy 455.253837 -272.377962) (xy 455.212166 -272.411193) (xy 455.166008 -272.437842) (xy 455.116394 -272.457314)
			(xy 455.064432 -272.469174) (xy 455.011282 -272.473158) (xy 454.958132 -272.469174) (xy 454.90617 -272.457314)
			(xy 454.856556 -272.437842) (xy 454.810398 -272.411193) (xy 454.768727 -272.377962) (xy 454.732475 -272.338891)
			(xy 454.702451 -272.294854) (xy 454.679325 -272.246833) (xy 454.663615 -272.195903) (xy 454.655672 -272.143199)
			(xy 453.476629 -272.143199) (xy 453.476624 -272.143453) (xy 453.468681 -272.196157) (xy 453.452971 -272.247087)
			(xy 453.429845 -272.295108) (xy 453.399821 -272.339145) (xy 453.363569 -272.378216) (xy 453.321898 -272.411447)
			(xy 453.27574 -272.438096) (xy 453.226126 -272.457568) (xy 453.174164 -272.469428) (xy 453.121014 -272.473412)
			(xy 453.067864 -272.469428) (xy 453.015902 -272.457568) (xy 452.966288 -272.438096) (xy 452.92013 -272.411447)
			(xy 452.878459 -272.378216) (xy 452.842207 -272.339145) (xy 452.812183 -272.295108) (xy 452.789057 -272.247087)
			(xy 452.773347 -272.196157) (xy 452.765404 -272.143453) (xy 451.266824 -272.143453) (xy 451.258881 -272.196157)
			(xy 451.243171 -272.247087) (xy 451.220045 -272.295108) (xy 451.190021 -272.339145) (xy 451.153769 -272.378216)
			(xy 451.112098 -272.411447) (xy 451.06594 -272.438096) (xy 451.016326 -272.457568) (xy 450.964364 -272.469428)
			(xy 450.911214 -272.473412) (xy 450.858064 -272.469428) (xy 450.806102 -272.457568) (xy 450.756488 -272.438096)
			(xy 450.71033 -272.411447) (xy 450.668659 -272.378216) (xy 450.632407 -272.339145) (xy 450.602383 -272.295108)
			(xy 450.579257 -272.247087) (xy 450.563547 -272.196157) (xy 450.555604 -272.143453) (xy 449.793868 -272.143453)
			(xy 449.793868 -272.628614) (xy 449.82384 -272.642076) (xy 449.848457 -272.653757) (xy 449.894123 -272.683476)
			(xy 449.93473 -272.719803) (xy 449.96933 -272.761892) (xy 449.997117 -272.808759) (xy 450.017441 -272.859311)
			(xy 450.029829 -272.912369) (xy 450.033991 -272.966695) (xy 450.03195 -272.993337) (xy 450.555604 -272.993337)
			(xy 450.555604 -272.940039) (xy 450.563547 -272.887335) (xy 450.579257 -272.836405) (xy 450.602383 -272.788384)
			(xy 450.632407 -272.744347) (xy 450.668659 -272.705276) (xy 450.71033 -272.672045) (xy 450.756488 -272.645396)
			(xy 450.806102 -272.625924) (xy 450.858064 -272.614064) (xy 450.911214 -272.610081) (xy 450.964364 -272.614064)
			(xy 451.016326 -272.625924) (xy 451.06594 -272.645396) (xy 451.112098 -272.672045) (xy 451.153769 -272.705276)
			(xy 451.190021 -272.744347) (xy 451.220045 -272.788384) (xy 451.243171 -272.836405) (xy 451.258881 -272.887335)
			(xy 451.266824 -272.940039) (xy 451.267322 -272.966688) (xy 451.266824 -272.993337) (xy 454.655672 -272.993337)
			(xy 454.655672 -272.940039) (xy 454.663615 -272.887335) (xy 454.679325 -272.836405) (xy 454.702451 -272.788384)
			(xy 454.732475 -272.744347) (xy 454.768727 -272.705276) (xy 454.810398 -272.672045) (xy 454.856556 -272.645396)
			(xy 454.90617 -272.625924) (xy 454.958132 -272.614064) (xy 455.011282 -272.610081) (xy 455.064432 -272.614064)
			(xy 455.116394 -272.625924) (xy 455.166008 -272.645396) (xy 455.212166 -272.672045) (xy 455.253837 -272.705276)
			(xy 455.290089 -272.744347) (xy 455.320113 -272.788384) (xy 455.343239 -272.836405) (xy 455.358949 -272.887335)
			(xy 455.366892 -272.940039) (xy 455.36739 -272.966688) (xy 455.366892 -272.993337) (xy 456.865472 -272.993337)
			(xy 456.865472 -272.940039) (xy 456.873415 -272.887335) (xy 456.889125 -272.836405) (xy 456.912251 -272.788384)
			(xy 456.942275 -272.744347) (xy 456.978527 -272.705276) (xy 457.020198 -272.672045) (xy 457.066356 -272.645396)
			(xy 457.11597 -272.625924) (xy 457.167932 -272.614064) (xy 457.221082 -272.610081) (xy 457.274232 -272.614064)
			(xy 457.326194 -272.625924) (xy 457.375808 -272.645396) (xy 457.421966 -272.672045) (xy 457.463637 -272.705276)
			(xy 457.499889 -272.744347) (xy 457.529913 -272.788384) (xy 457.553039 -272.836405) (xy 457.568749 -272.887335)
			(xy 457.576692 -272.940039) (xy 457.57719 -272.966688) (xy 457.576692 -272.993337) (xy 457.568749 -273.046041)
			(xy 457.553039 -273.096971) (xy 457.529913 -273.144992) (xy 457.499889 -273.189029) (xy 457.463637 -273.2281)
			(xy 457.421966 -273.261331) (xy 457.375808 -273.28798) (xy 457.326194 -273.307452) (xy 457.274232 -273.319312)
			(xy 457.221082 -273.323296) (xy 457.167932 -273.319312) (xy 457.11597 -273.307452) (xy 457.066356 -273.28798)
			(xy 457.020198 -273.261331) (xy 456.978527 -273.2281) (xy 456.942275 -273.189029) (xy 456.912251 -273.144992)
			(xy 456.889125 -273.096971) (xy 456.873415 -273.046041) (xy 456.865472 -272.993337) (xy 455.366892 -272.993337)
			(xy 455.358949 -273.046041) (xy 455.343239 -273.096971) (xy 455.320113 -273.144992) (xy 455.290089 -273.189029)
			(xy 455.253837 -273.2281) (xy 455.212166 -273.261331) (xy 455.166008 -273.28798) (xy 455.116394 -273.307452)
			(xy 455.064432 -273.319312) (xy 455.011282 -273.323296) (xy 454.958132 -273.319312) (xy 454.90617 -273.307452)
			(xy 454.856556 -273.28798) (xy 454.810398 -273.261331) (xy 454.768727 -273.2281) (xy 454.732475 -273.189029)
			(xy 454.702451 -273.144992) (xy 454.679325 -273.096971) (xy 454.663615 -273.046041) (xy 454.655672 -272.993337)
			(xy 451.266824 -272.993337) (xy 451.258881 -273.046041) (xy 451.243171 -273.096971) (xy 451.220045 -273.144992)
			(xy 451.190021 -273.189029) (xy 451.153769 -273.2281) (xy 451.112098 -273.261331) (xy 451.06594 -273.28798)
			(xy 451.016326 -273.307452) (xy 450.964364 -273.319312) (xy 450.911214 -273.323296) (xy 450.858064 -273.319312)
			(xy 450.806102 -273.307452) (xy 450.756488 -273.28798) (xy 450.71033 -273.261331) (xy 450.668659 -273.2281)
			(xy 450.632407 -273.189029) (xy 450.602383 -273.144992) (xy 450.579257 -273.096971) (xy 450.563547 -273.046041)
			(xy 450.555604 -272.993337) (xy 450.03195 -272.993337) (xy 450.02983 -273.021021) (xy 450.017444 -273.074079)
			(xy 449.997121 -273.124632) (xy 449.969336 -273.1715) (xy 449.934737 -273.21359) (xy 449.894131 -273.249918)
			(xy 449.848465 -273.279639) (xy 449.82384 -273.2913) (xy 449.793868 -273.304762) (xy 449.793868 -273.843221)
			(xy 450.555604 -273.843221) (xy 450.555604 -273.789923) (xy 450.563547 -273.737219) (xy 450.579257 -273.686289)
			(xy 450.602383 -273.638268) (xy 450.632407 -273.594231) (xy 450.668659 -273.55516) (xy 450.71033 -273.521929)
			(xy 450.756488 -273.49528) (xy 450.806102 -273.475808) (xy 450.858064 -273.463948) (xy 450.911214 -273.459965)
			(xy 450.964364 -273.463948) (xy 451.016326 -273.475808) (xy 451.06594 -273.49528) (xy 451.112098 -273.521929)
			(xy 451.153769 -273.55516) (xy 451.190021 -273.594231) (xy 451.220045 -273.638268) (xy 451.243171 -273.686289)
			(xy 451.258881 -273.737219) (xy 451.266824 -273.789923) (xy 451.267322 -273.816572) (xy 451.266824 -273.843221)
			(xy 452.765404 -273.843221) (xy 452.765404 -273.789923) (xy 452.773347 -273.737219) (xy 452.789057 -273.686289)
			(xy 452.812183 -273.638268) (xy 452.842207 -273.594231) (xy 452.878459 -273.55516) (xy 452.92013 -273.521929)
			(xy 452.966288 -273.49528) (xy 453.015902 -273.475808) (xy 453.067864 -273.463948) (xy 453.121014 -273.459965)
			(xy 453.174164 -273.463948) (xy 453.226126 -273.475808) (xy 453.27574 -273.49528) (xy 453.321898 -273.521929)
			(xy 453.363569 -273.55516) (xy 453.399821 -273.594231) (xy 453.429845 -273.638268) (xy 453.452971 -273.686289)
			(xy 453.468681 -273.737219) (xy 453.476624 -273.789923) (xy 453.477122 -273.816572) (xy 453.476624 -273.843221)
			(xy 454.655672 -273.843221) (xy 454.655672 -273.789923) (xy 454.663615 -273.737219) (xy 454.679325 -273.686289)
			(xy 454.702451 -273.638268) (xy 454.732475 -273.594231) (xy 454.768727 -273.55516) (xy 454.810398 -273.521929)
			(xy 454.856556 -273.49528) (xy 454.90617 -273.475808) (xy 454.958132 -273.463948) (xy 455.011282 -273.459965)
			(xy 455.064432 -273.463948) (xy 455.116394 -273.475808) (xy 455.166008 -273.49528) (xy 455.212166 -273.521929)
			(xy 455.253837 -273.55516) (xy 455.290089 -273.594231) (xy 455.320113 -273.638268) (xy 455.343239 -273.686289)
			(xy 455.358949 -273.737219) (xy 455.366892 -273.789923) (xy 455.36739 -273.816572) (xy 455.366892 -273.843221)
			(xy 458.099404 -273.843221) (xy 458.099404 -273.789923) (xy 458.107347 -273.737219) (xy 458.123057 -273.686289)
			(xy 458.146183 -273.638268) (xy 458.176207 -273.594231) (xy 458.212459 -273.55516) (xy 458.25413 -273.521929)
			(xy 458.300288 -273.49528) (xy 458.349902 -273.475808) (xy 458.401864 -273.463948) (xy 458.455014 -273.459965)
			(xy 458.508164 -273.463948) (xy 458.560126 -273.475808) (xy 458.60974 -273.49528) (xy 458.655898 -273.521929)
			(xy 458.697569 -273.55516) (xy 458.733821 -273.594231) (xy 458.763845 -273.638268) (xy 458.786971 -273.686289)
			(xy 458.802681 -273.737219) (xy 458.810624 -273.789923) (xy 458.811122 -273.816572) (xy 458.810624 -273.843221)
			(xy 458.802681 -273.895925) (xy 458.786971 -273.946855) (xy 458.763845 -273.994876) (xy 458.733821 -274.038913)
			(xy 458.697569 -274.077984) (xy 458.655898 -274.111215) (xy 458.60974 -274.137864) (xy 458.560126 -274.157336)
			(xy 458.508164 -274.169196) (xy 458.455014 -274.17318) (xy 458.401864 -274.169196) (xy 458.349902 -274.157336)
			(xy 458.300288 -274.137864) (xy 458.25413 -274.111215) (xy 458.212459 -274.077984) (xy 458.176207 -274.038913)
			(xy 458.146183 -273.994876) (xy 458.123057 -273.946855) (xy 458.107347 -273.895925) (xy 458.099404 -273.843221)
			(xy 455.366892 -273.843221) (xy 455.358949 -273.895925) (xy 455.343239 -273.946855) (xy 455.320113 -273.994876)
			(xy 455.290089 -274.038913) (xy 455.253837 -274.077984) (xy 455.212166 -274.111215) (xy 455.166008 -274.137864)
			(xy 455.116394 -274.157336) (xy 455.064432 -274.169196) (xy 455.011282 -274.17318) (xy 454.958132 -274.169196)
			(xy 454.90617 -274.157336) (xy 454.856556 -274.137864) (xy 454.810398 -274.111215) (xy 454.768727 -274.077984)
			(xy 454.732475 -274.038913) (xy 454.702451 -273.994876) (xy 454.679325 -273.946855) (xy 454.663615 -273.895925)
			(xy 454.655672 -273.843221) (xy 453.476624 -273.843221) (xy 453.468681 -273.895925) (xy 453.452971 -273.946855)
			(xy 453.429845 -273.994876) (xy 453.399821 -274.038913) (xy 453.363569 -274.077984) (xy 453.321898 -274.111215)
			(xy 453.27574 -274.137864) (xy 453.226126 -274.157336) (xy 453.174164 -274.169196) (xy 453.121014 -274.17318)
			(xy 453.067864 -274.169196) (xy 453.015902 -274.157336) (xy 452.966288 -274.137864) (xy 452.92013 -274.111215)
			(xy 452.878459 -274.077984) (xy 452.842207 -274.038913) (xy 452.812183 -273.994876) (xy 452.789057 -273.946855)
			(xy 452.773347 -273.895925) (xy 452.765404 -273.843221) (xy 451.266824 -273.843221) (xy 451.258881 -273.895925)
			(xy 451.243171 -273.946855) (xy 451.220045 -273.994876) (xy 451.190021 -274.038913) (xy 451.153769 -274.077984)
			(xy 451.112098 -274.111215) (xy 451.06594 -274.137864) (xy 451.016326 -274.157336) (xy 450.964364 -274.169196)
			(xy 450.911214 -274.17318) (xy 450.858064 -274.169196) (xy 450.806102 -274.157336) (xy 450.756488 -274.137864)
			(xy 450.71033 -274.111215) (xy 450.668659 -274.077984) (xy 450.632407 -274.038913) (xy 450.602383 -273.994876)
			(xy 450.579257 -273.946855) (xy 450.563547 -273.895925) (xy 450.555604 -273.843221) (xy 449.793868 -273.843221)
			(xy 449.793868 -274.693359) (xy 450.555604 -274.693359) (xy 450.555604 -274.640061) (xy 450.563547 -274.587357)
			(xy 450.579257 -274.536427) (xy 450.602383 -274.488406) (xy 450.632407 -274.444369) (xy 450.668659 -274.405298)
			(xy 450.71033 -274.372067) (xy 450.756488 -274.345418) (xy 450.806102 -274.325946) (xy 450.858064 -274.314086)
			(xy 450.911214 -274.310103) (xy 450.964364 -274.314086) (xy 451.016326 -274.325946) (xy 451.06594 -274.345418)
			(xy 451.112098 -274.372067) (xy 451.153769 -274.405298) (xy 451.190021 -274.444369) (xy 451.220045 -274.488406)
			(xy 451.243171 -274.536427) (xy 451.258881 -274.587357) (xy 451.266824 -274.640061) (xy 451.267322 -274.66671)
			(xy 451.266824 -274.693359) (xy 454.655672 -274.693359) (xy 454.655672 -274.640061) (xy 454.663615 -274.587357)
			(xy 454.679325 -274.536427) (xy 454.702451 -274.488406) (xy 454.732475 -274.444369) (xy 454.768727 -274.405298)
			(xy 454.810398 -274.372067) (xy 454.856556 -274.345418) (xy 454.90617 -274.325946) (xy 454.958132 -274.314086)
			(xy 455.011282 -274.310103) (xy 455.064432 -274.314086) (xy 455.116394 -274.325946) (xy 455.166008 -274.345418)
			(xy 455.212166 -274.372067) (xy 455.253837 -274.405298) (xy 455.290089 -274.444369) (xy 455.320113 -274.488406)
			(xy 455.343239 -274.536427) (xy 455.358949 -274.587357) (xy 455.366892 -274.640061) (xy 455.36739 -274.66671)
			(xy 455.366892 -274.693359) (xy 455.358949 -274.746063) (xy 455.343239 -274.796993) (xy 455.320113 -274.845014)
			(xy 455.290089 -274.889051) (xy 455.253837 -274.928122) (xy 455.212166 -274.961353) (xy 455.166008 -274.988002)
			(xy 455.116394 -275.007474) (xy 455.064432 -275.019334) (xy 455.011282 -275.023318) (xy 454.958132 -275.019334)
			(xy 454.90617 -275.007474) (xy 454.856556 -274.988002) (xy 454.810398 -274.961353) (xy 454.768727 -274.928122)
			(xy 454.732475 -274.889051) (xy 454.702451 -274.845014) (xy 454.679325 -274.796993) (xy 454.663615 -274.746063)
			(xy 454.655672 -274.693359) (xy 451.266824 -274.693359) (xy 451.258881 -274.746063) (xy 451.243171 -274.796993)
			(xy 451.220045 -274.845014) (xy 451.190021 -274.889051) (xy 451.153769 -274.928122) (xy 451.112098 -274.961353)
			(xy 451.06594 -274.988002) (xy 451.016326 -275.007474) (xy 450.964364 -275.019334) (xy 450.911214 -275.023318)
			(xy 450.858064 -275.019334) (xy 450.806102 -275.007474) (xy 450.756488 -274.988002) (xy 450.71033 -274.961353)
			(xy 450.668659 -274.928122) (xy 450.632407 -274.889051) (xy 450.602383 -274.845014) (xy 450.579257 -274.796993)
			(xy 450.563547 -274.746063) (xy 450.555604 -274.693359) (xy 449.793868 -274.693359) (xy 449.793868 -275.17852)
			(xy 449.82384 -275.191982) (xy 449.848456 -275.203663) (xy 449.894122 -275.233381) (xy 449.934728 -275.269709)
			(xy 449.969327 -275.311797) (xy 449.997113 -275.358663) (xy 450.017436 -275.409215) (xy 450.029824 -275.462273)
			(xy 450.033985 -275.516598) (xy 450.031944 -275.543243) (xy 450.555604 -275.543243) (xy 450.555604 -275.489945)
			(xy 450.563547 -275.437241) (xy 450.579257 -275.386311) (xy 450.602383 -275.33829) (xy 450.632407 -275.294253)
			(xy 450.668659 -275.255182) (xy 450.71033 -275.221951) (xy 450.756488 -275.195302) (xy 450.806102 -275.17583)
			(xy 450.858064 -275.16397) (xy 450.911214 -275.159987) (xy 450.964364 -275.16397) (xy 451.016326 -275.17583)
			(xy 451.06594 -275.195302) (xy 451.112098 -275.221951) (xy 451.153769 -275.255182) (xy 451.190021 -275.294253)
			(xy 451.220045 -275.33829) (xy 451.243171 -275.386311) (xy 451.258881 -275.437241) (xy 451.266824 -275.489945)
			(xy 451.267322 -275.516594) (xy 451.266824 -275.543243) (xy 454.655672 -275.543243) (xy 454.655672 -275.489945)
			(xy 454.663615 -275.437241) (xy 454.679325 -275.386311) (xy 454.702451 -275.33829) (xy 454.732475 -275.294253)
			(xy 454.768727 -275.255182) (xy 454.810398 -275.221951) (xy 454.856556 -275.195302) (xy 454.90617 -275.17583)
			(xy 454.958132 -275.16397) (xy 455.011282 -275.159987) (xy 455.064432 -275.16397) (xy 455.116394 -275.17583)
			(xy 455.166008 -275.195302) (xy 455.212166 -275.221951) (xy 455.253837 -275.255182) (xy 455.290089 -275.294253)
			(xy 455.320113 -275.33829) (xy 455.343239 -275.386311) (xy 455.358949 -275.437241) (xy 455.366892 -275.489945)
			(xy 455.36739 -275.516594) (xy 455.366892 -275.543243) (xy 456.865472 -275.543243) (xy 456.865472 -275.489945)
			(xy 456.873415 -275.437241) (xy 456.889125 -275.386311) (xy 456.912251 -275.33829) (xy 456.942275 -275.294253)
			(xy 456.978527 -275.255182) (xy 457.020198 -275.221951) (xy 457.066356 -275.195302) (xy 457.11597 -275.17583)
			(xy 457.167932 -275.16397) (xy 457.221082 -275.159987) (xy 457.274232 -275.16397) (xy 457.326194 -275.17583)
			(xy 457.375808 -275.195302) (xy 457.421966 -275.221951) (xy 457.463637 -275.255182) (xy 457.499889 -275.294253)
			(xy 457.529913 -275.33829) (xy 457.553039 -275.386311) (xy 457.568749 -275.437241) (xy 457.576692 -275.489945)
			(xy 457.57719 -275.516594) (xy 457.576692 -275.543243) (xy 457.568749 -275.595947) (xy 457.553039 -275.646877)
			(xy 457.529913 -275.694898) (xy 457.499889 -275.738935) (xy 457.463637 -275.778006) (xy 457.421966 -275.811237)
			(xy 457.375808 -275.837886) (xy 457.326194 -275.857358) (xy 457.274232 -275.869218) (xy 457.221082 -275.873202)
			(xy 457.167932 -275.869218) (xy 457.11597 -275.857358) (xy 457.066356 -275.837886) (xy 457.020198 -275.811237)
			(xy 456.978527 -275.778006) (xy 456.942275 -275.738935) (xy 456.912251 -275.694898) (xy 456.889125 -275.646877)
			(xy 456.873415 -275.595947) (xy 456.865472 -275.543243) (xy 455.366892 -275.543243) (xy 455.358949 -275.595947)
			(xy 455.343239 -275.646877) (xy 455.320113 -275.694898) (xy 455.290089 -275.738935) (xy 455.253837 -275.778006)
			(xy 455.212166 -275.811237) (xy 455.166008 -275.837886) (xy 455.116394 -275.857358) (xy 455.064432 -275.869218)
			(xy 455.011282 -275.873202) (xy 454.958132 -275.869218) (xy 454.90617 -275.857358) (xy 454.856556 -275.837886)
			(xy 454.810398 -275.811237) (xy 454.768727 -275.778006) (xy 454.732475 -275.738935) (xy 454.702451 -275.694898)
			(xy 454.679325 -275.646877) (xy 454.663615 -275.595947) (xy 454.655672 -275.543243) (xy 451.266824 -275.543243)
			(xy 451.258881 -275.595947) (xy 451.243171 -275.646877) (xy 451.220045 -275.694898) (xy 451.190021 -275.738935)
			(xy 451.153769 -275.778006) (xy 451.112098 -275.811237) (xy 451.06594 -275.837886) (xy 451.016326 -275.857358)
			(xy 450.964364 -275.869218) (xy 450.911214 -275.873202) (xy 450.858064 -275.869218) (xy 450.806102 -275.857358)
			(xy 450.756488 -275.837886) (xy 450.71033 -275.811237) (xy 450.668659 -275.778006) (xy 450.632407 -275.738935)
			(xy 450.602383 -275.694898) (xy 450.579257 -275.646877) (xy 450.563547 -275.595947) (xy 450.555604 -275.543243)
			(xy 450.031944 -275.543243) (xy 450.029824 -275.570923) (xy 450.017438 -275.62398) (xy 449.997115 -275.674532)
			(xy 449.96933 -275.721399) (xy 449.934731 -275.763488) (xy 449.894126 -275.799816) (xy 449.848461 -275.829535)
			(xy 449.82384 -275.841206) (xy 449.793868 -275.854668) (xy 449.793868 -276.393381) (xy 450.555604 -276.393381)
			(xy 450.555604 -276.340083) (xy 450.563547 -276.287379) (xy 450.579257 -276.236449) (xy 450.602383 -276.188428)
			(xy 450.632407 -276.144391) (xy 450.668659 -276.10532) (xy 450.71033 -276.072089) (xy 450.756488 -276.04544)
			(xy 450.806102 -276.025968) (xy 450.858064 -276.014108) (xy 450.911214 -276.010125) (xy 450.964364 -276.014108)
			(xy 451.016326 -276.025968) (xy 451.06594 -276.04544) (xy 451.112098 -276.072089) (xy 451.153769 -276.10532)
			(xy 451.190021 -276.144391) (xy 451.220045 -276.188428) (xy 451.243171 -276.236449) (xy 451.258881 -276.287379)
			(xy 451.266824 -276.340083) (xy 451.267322 -276.366732) (xy 451.266824 -276.393381) (xy 452.765404 -276.393381)
			(xy 452.765404 -276.340083) (xy 452.773347 -276.287379) (xy 452.789057 -276.236449) (xy 452.812183 -276.188428)
			(xy 452.842207 -276.144391) (xy 452.878459 -276.10532) (xy 452.92013 -276.072089) (xy 452.966288 -276.04544)
			(xy 453.015902 -276.025968) (xy 453.067864 -276.014108) (xy 453.121014 -276.010125) (xy 453.174164 -276.014108)
			(xy 453.226126 -276.025968) (xy 453.27574 -276.04544) (xy 453.321898 -276.072089) (xy 453.363569 -276.10532)
			(xy 453.399821 -276.144391) (xy 453.429845 -276.188428) (xy 453.452971 -276.236449) (xy 453.468681 -276.287379)
			(xy 453.476624 -276.340083) (xy 453.477122 -276.366732) (xy 453.476624 -276.393381) (xy 454.655672 -276.393381)
			(xy 454.655672 -276.340083) (xy 454.663615 -276.287379) (xy 454.679325 -276.236449) (xy 454.702451 -276.188428)
			(xy 454.732475 -276.144391) (xy 454.768727 -276.10532) (xy 454.810398 -276.072089) (xy 454.856556 -276.04544)
			(xy 454.90617 -276.025968) (xy 454.958132 -276.014108) (xy 455.011282 -276.010125) (xy 455.064432 -276.014108)
			(xy 455.116394 -276.025968) (xy 455.166008 -276.04544) (xy 455.212166 -276.072089) (xy 455.253837 -276.10532)
			(xy 455.290089 -276.144391) (xy 455.320113 -276.188428) (xy 455.343239 -276.236449) (xy 455.358949 -276.287379)
			(xy 455.366892 -276.340083) (xy 455.36739 -276.366732) (xy 455.366892 -276.393381) (xy 458.099404 -276.393381)
			(xy 458.099404 -276.340083) (xy 458.107347 -276.287379) (xy 458.123057 -276.236449) (xy 458.146183 -276.188428)
			(xy 458.176207 -276.144391) (xy 458.212459 -276.10532) (xy 458.25413 -276.072089) (xy 458.300288 -276.04544)
			(xy 458.349902 -276.025968) (xy 458.401864 -276.014108) (xy 458.455014 -276.010125) (xy 458.508164 -276.014108)
			(xy 458.560126 -276.025968) (xy 458.60974 -276.04544) (xy 458.655898 -276.072089) (xy 458.697569 -276.10532)
			(xy 458.733821 -276.144391) (xy 458.763845 -276.188428) (xy 458.786971 -276.236449) (xy 458.802681 -276.287379)
			(xy 458.810624 -276.340083) (xy 458.811122 -276.366732) (xy 458.810624 -276.393381) (xy 458.802681 -276.446085)
			(xy 458.786971 -276.497015) (xy 458.763845 -276.545036) (xy 458.733821 -276.589073) (xy 458.697569 -276.628144)
			(xy 458.655898 -276.661375) (xy 458.60974 -276.688024) (xy 458.560126 -276.707496) (xy 458.508164 -276.719356)
			(xy 458.455014 -276.72334) (xy 458.401864 -276.719356) (xy 458.349902 -276.707496) (xy 458.300288 -276.688024)
			(xy 458.25413 -276.661375) (xy 458.212459 -276.628144) (xy 458.176207 -276.589073) (xy 458.146183 -276.545036)
			(xy 458.123057 -276.497015) (xy 458.107347 -276.446085) (xy 458.099404 -276.393381) (xy 455.366892 -276.393381)
			(xy 455.358949 -276.446085) (xy 455.343239 -276.497015) (xy 455.320113 -276.545036) (xy 455.290089 -276.589073)
			(xy 455.253837 -276.628144) (xy 455.212166 -276.661375) (xy 455.166008 -276.688024) (xy 455.116394 -276.707496)
			(xy 455.064432 -276.719356) (xy 455.011282 -276.72334) (xy 454.958132 -276.719356) (xy 454.90617 -276.707496)
			(xy 454.856556 -276.688024) (xy 454.810398 -276.661375) (xy 454.768727 -276.628144) (xy 454.732475 -276.589073)
			(xy 454.702451 -276.545036) (xy 454.679325 -276.497015) (xy 454.663615 -276.446085) (xy 454.655672 -276.393381)
			(xy 453.476624 -276.393381) (xy 453.468681 -276.446085) (xy 453.452971 -276.497015) (xy 453.429845 -276.545036)
			(xy 453.399821 -276.589073) (xy 453.363569 -276.628144) (xy 453.321898 -276.661375) (xy 453.27574 -276.688024)
			(xy 453.226126 -276.707496) (xy 453.174164 -276.719356) (xy 453.121014 -276.72334) (xy 453.067864 -276.719356)
			(xy 453.015902 -276.707496) (xy 452.966288 -276.688024) (xy 452.92013 -276.661375) (xy 452.878459 -276.628144)
			(xy 452.842207 -276.589073) (xy 452.812183 -276.545036) (xy 452.789057 -276.497015) (xy 452.773347 -276.446085)
			(xy 452.765404 -276.393381) (xy 451.266824 -276.393381) (xy 451.258881 -276.446085) (xy 451.243171 -276.497015)
			(xy 451.220045 -276.545036) (xy 451.190021 -276.589073) (xy 451.153769 -276.628144) (xy 451.112098 -276.661375)
			(xy 451.06594 -276.688024) (xy 451.016326 -276.707496) (xy 450.964364 -276.719356) (xy 450.911214 -276.72334)
			(xy 450.858064 -276.719356) (xy 450.806102 -276.707496) (xy 450.756488 -276.688024) (xy 450.71033 -276.661375)
			(xy 450.668659 -276.628144) (xy 450.632407 -276.589073) (xy 450.602383 -276.545036) (xy 450.579257 -276.497015)
			(xy 450.563547 -276.446085) (xy 450.555604 -276.393381) (xy 449.793868 -276.393381) (xy 449.793868 -276.878542)
			(xy 449.82384 -276.892004) (xy 449.848455 -276.903684) (xy 449.894117 -276.933403) (xy 449.93472 -276.969729)
			(xy 449.969316 -277.011816) (xy 449.997099 -277.05868) (xy 450.01742 -277.10923) (xy 450.029805 -277.162285)
			(xy 450.033965 -277.216607) (xy 450.031923 -277.243265) (xy 450.555604 -277.243265) (xy 450.555604 -277.189967)
			(xy 450.563547 -277.137263) (xy 450.579257 -277.086333) (xy 450.602383 -277.038312) (xy 450.632407 -276.994275)
			(xy 450.668659 -276.955204) (xy 450.71033 -276.921973) (xy 450.756488 -276.895324) (xy 450.806102 -276.875852)
			(xy 450.858064 -276.863992) (xy 450.911214 -276.860009) (xy 450.964364 -276.863992) (xy 451.016326 -276.875852)
			(xy 451.06594 -276.895324) (xy 451.112098 -276.921973) (xy 451.153769 -276.955204) (xy 451.190021 -276.994275)
			(xy 451.220045 -277.038312) (xy 451.243171 -277.086333) (xy 451.258881 -277.137263) (xy 451.266824 -277.189967)
			(xy 451.267322 -277.216616) (xy 451.266824 -277.243265) (xy 454.655672 -277.243265) (xy 454.655672 -277.189967)
			(xy 454.663615 -277.137263) (xy 454.679325 -277.086333) (xy 454.702451 -277.038312) (xy 454.732475 -276.994275)
			(xy 454.768727 -276.955204) (xy 454.810398 -276.921973) (xy 454.856556 -276.895324) (xy 454.90617 -276.875852)
			(xy 454.958132 -276.863992) (xy 455.011282 -276.860009) (xy 455.064432 -276.863992) (xy 455.116394 -276.875852)
			(xy 455.166008 -276.895324) (xy 455.212166 -276.921973) (xy 455.253837 -276.955204) (xy 455.290089 -276.994275)
			(xy 455.320113 -277.038312) (xy 455.343239 -277.086333) (xy 455.358949 -277.137263) (xy 455.366892 -277.189967)
			(xy 455.36739 -277.216616) (xy 455.366892 -277.243265) (xy 456.865472 -277.243265) (xy 456.865472 -277.189967)
			(xy 456.873415 -277.137263) (xy 456.889125 -277.086333) (xy 456.912251 -277.038312) (xy 456.942275 -276.994275)
			(xy 456.978527 -276.955204) (xy 457.020198 -276.921973) (xy 457.066356 -276.895324) (xy 457.11597 -276.875852)
			(xy 457.167932 -276.863992) (xy 457.221082 -276.860009) (xy 457.274232 -276.863992) (xy 457.326194 -276.875852)
			(xy 457.375808 -276.895324) (xy 457.421966 -276.921973) (xy 457.463637 -276.955204) (xy 457.499889 -276.994275)
			(xy 457.529913 -277.038312) (xy 457.553039 -277.086333) (xy 457.568749 -277.137263) (xy 457.576692 -277.189967)
			(xy 457.57719 -277.216616) (xy 457.576692 -277.243265) (xy 457.568749 -277.295969) (xy 457.553039 -277.346899)
			(xy 457.529913 -277.39492) (xy 457.499889 -277.438957) (xy 457.463637 -277.478028) (xy 457.421966 -277.511259)
			(xy 457.375808 -277.537908) (xy 457.326194 -277.55738) (xy 457.274232 -277.56924) (xy 457.221082 -277.573224)
			(xy 457.167932 -277.56924) (xy 457.11597 -277.55738) (xy 457.066356 -277.537908) (xy 457.020198 -277.511259)
			(xy 456.978527 -277.478028) (xy 456.942275 -277.438957) (xy 456.912251 -277.39492) (xy 456.889125 -277.346899)
			(xy 456.873415 -277.295969) (xy 456.865472 -277.243265) (xy 455.366892 -277.243265) (xy 455.358949 -277.295969)
			(xy 455.343239 -277.346899) (xy 455.320113 -277.39492) (xy 455.290089 -277.438957) (xy 455.253837 -277.478028)
			(xy 455.212166 -277.511259) (xy 455.166008 -277.537908) (xy 455.116394 -277.55738) (xy 455.064432 -277.56924)
			(xy 455.011282 -277.573224) (xy 454.958132 -277.56924) (xy 454.90617 -277.55738) (xy 454.856556 -277.537908)
			(xy 454.810398 -277.511259) (xy 454.768727 -277.478028) (xy 454.732475 -277.438957) (xy 454.702451 -277.39492)
			(xy 454.679325 -277.346899) (xy 454.663615 -277.295969) (xy 454.655672 -277.243265) (xy 451.266824 -277.243265)
			(xy 451.258881 -277.295969) (xy 451.243171 -277.346899) (xy 451.220045 -277.39492) (xy 451.190021 -277.438957)
			(xy 451.153769 -277.478028) (xy 451.112098 -277.511259) (xy 451.06594 -277.537908) (xy 451.016326 -277.55738)
			(xy 450.964364 -277.56924) (xy 450.911214 -277.573224) (xy 450.858064 -277.56924) (xy 450.806102 -277.55738)
			(xy 450.756488 -277.537908) (xy 450.71033 -277.511259) (xy 450.668659 -277.478028) (xy 450.632407 -277.438957)
			(xy 450.602383 -277.39492) (xy 450.579257 -277.346899) (xy 450.563547 -277.295969) (xy 450.555604 -277.243265)
			(xy 450.031923 -277.243265) (xy 450.029803 -277.270929) (xy 450.017416 -277.323983) (xy 449.997093 -277.374531)
			(xy 449.969309 -277.421395) (xy 449.93471 -277.46348) (xy 449.894106 -277.499805) (xy 449.848443 -277.529522)
			(xy 449.82384 -277.541228) (xy 449.793868 -277.55469) (xy 449.793868 -278.093403) (xy 450.555604 -278.093403)
			(xy 450.555604 -278.040105) (xy 450.563547 -277.987401) (xy 450.579257 -277.936471) (xy 450.602383 -277.88845)
			(xy 450.632407 -277.844413) (xy 450.668659 -277.805342) (xy 450.71033 -277.772111) (xy 450.756488 -277.745462)
			(xy 450.806102 -277.72599) (xy 450.858064 -277.71413) (xy 450.911214 -277.710147) (xy 450.964364 -277.71413)
			(xy 451.016326 -277.72599) (xy 451.06594 -277.745462) (xy 451.112098 -277.772111) (xy 451.153769 -277.805342)
			(xy 451.190021 -277.844413) (xy 451.220045 -277.88845) (xy 451.243171 -277.936471) (xy 451.258881 -277.987401)
			(xy 451.266824 -278.040105) (xy 451.267322 -278.066754) (xy 451.266824 -278.093403) (xy 452.765404 -278.093403)
			(xy 452.765404 -278.040105) (xy 452.773347 -277.987401) (xy 452.789057 -277.936471) (xy 452.812183 -277.88845)
			(xy 452.842207 -277.844413) (xy 452.878459 -277.805342) (xy 452.92013 -277.772111) (xy 452.966288 -277.745462)
			(xy 453.015902 -277.72599) (xy 453.067864 -277.71413) (xy 453.121014 -277.710147) (xy 453.174164 -277.71413)
			(xy 453.226126 -277.72599) (xy 453.27574 -277.745462) (xy 453.321898 -277.772111) (xy 453.363569 -277.805342)
			(xy 453.399821 -277.844413) (xy 453.429845 -277.88845) (xy 453.452971 -277.936471) (xy 453.468681 -277.987401)
			(xy 453.476624 -278.040105) (xy 453.477122 -278.066754) (xy 453.476624 -278.093403) (xy 454.655672 -278.093403)
			(xy 454.655672 -278.040105) (xy 454.663615 -277.987401) (xy 454.679325 -277.936471) (xy 454.702451 -277.88845)
			(xy 454.732475 -277.844413) (xy 454.768727 -277.805342) (xy 454.810398 -277.772111) (xy 454.856556 -277.745462)
			(xy 454.90617 -277.72599) (xy 454.958132 -277.71413) (xy 455.011282 -277.710147) (xy 455.064432 -277.71413)
			(xy 455.116394 -277.72599) (xy 455.166008 -277.745462) (xy 455.212166 -277.772111) (xy 455.253837 -277.805342)
			(xy 455.290089 -277.844413) (xy 455.320113 -277.88845) (xy 455.343239 -277.936471) (xy 455.358949 -277.987401)
			(xy 455.366892 -278.040105) (xy 455.36739 -278.066754) (xy 455.366892 -278.093403) (xy 458.099404 -278.093403)
			(xy 458.099404 -278.040105) (xy 458.107347 -277.987401) (xy 458.123057 -277.936471) (xy 458.146183 -277.88845)
			(xy 458.176207 -277.844413) (xy 458.212459 -277.805342) (xy 458.25413 -277.772111) (xy 458.300288 -277.745462)
			(xy 458.349902 -277.72599) (xy 458.401864 -277.71413) (xy 458.455014 -277.710147) (xy 458.508164 -277.71413)
			(xy 458.560126 -277.72599) (xy 458.60974 -277.745462) (xy 458.655898 -277.772111) (xy 458.697569 -277.805342)
			(xy 458.733821 -277.844413) (xy 458.763845 -277.88845) (xy 458.786971 -277.936471) (xy 458.802681 -277.987401)
			(xy 458.810624 -278.040105) (xy 458.811122 -278.066754) (xy 458.810624 -278.093403) (xy 458.802681 -278.146107)
			(xy 458.786971 -278.197037) (xy 458.763845 -278.245058) (xy 458.733821 -278.289095) (xy 458.697569 -278.328166)
			(xy 458.655898 -278.361397) (xy 458.60974 -278.388046) (xy 458.560126 -278.407518) (xy 458.508164 -278.419378)
			(xy 458.455014 -278.423362) (xy 458.401864 -278.419378) (xy 458.349902 -278.407518) (xy 458.300288 -278.388046)
			(xy 458.25413 -278.361397) (xy 458.212459 -278.328166) (xy 458.176207 -278.289095) (xy 458.146183 -278.245058)
			(xy 458.123057 -278.197037) (xy 458.107347 -278.146107) (xy 458.099404 -278.093403) (xy 455.366892 -278.093403)
			(xy 455.358949 -278.146107) (xy 455.343239 -278.197037) (xy 455.320113 -278.245058) (xy 455.290089 -278.289095)
			(xy 455.253837 -278.328166) (xy 455.212166 -278.361397) (xy 455.166008 -278.388046) (xy 455.116394 -278.407518)
			(xy 455.064432 -278.419378) (xy 455.011282 -278.423362) (xy 454.958132 -278.419378) (xy 454.90617 -278.407518)
			(xy 454.856556 -278.388046) (xy 454.810398 -278.361397) (xy 454.768727 -278.328166) (xy 454.732475 -278.289095)
			(xy 454.702451 -278.245058) (xy 454.679325 -278.197037) (xy 454.663615 -278.146107) (xy 454.655672 -278.093403)
			(xy 453.476624 -278.093403) (xy 453.468681 -278.146107) (xy 453.452971 -278.197037) (xy 453.429845 -278.245058)
			(xy 453.399821 -278.289095) (xy 453.363569 -278.328166) (xy 453.321898 -278.361397) (xy 453.27574 -278.388046)
			(xy 453.226126 -278.407518) (xy 453.174164 -278.419378) (xy 453.121014 -278.423362) (xy 453.067864 -278.419378)
			(xy 453.015902 -278.407518) (xy 452.966288 -278.388046) (xy 452.92013 -278.361397) (xy 452.878459 -278.328166)
			(xy 452.842207 -278.289095) (xy 452.812183 -278.245058) (xy 452.789057 -278.197037) (xy 452.773347 -278.146107)
			(xy 452.765404 -278.093403) (xy 451.266824 -278.093403) (xy 451.258881 -278.146107) (xy 451.243171 -278.197037)
			(xy 451.220045 -278.245058) (xy 451.190021 -278.289095) (xy 451.153769 -278.328166) (xy 451.112098 -278.361397)
			(xy 451.06594 -278.388046) (xy 451.016326 -278.407518) (xy 450.964364 -278.419378) (xy 450.911214 -278.423362)
			(xy 450.858064 -278.419378) (xy 450.806102 -278.407518) (xy 450.756488 -278.388046) (xy 450.71033 -278.361397)
			(xy 450.668659 -278.328166) (xy 450.632407 -278.289095) (xy 450.602383 -278.245058) (xy 450.579257 -278.197037)
			(xy 450.563547 -278.146107) (xy 450.555604 -278.093403) (xy 449.793868 -278.093403) (xy 449.793868 -278.578564)
			(xy 449.82384 -278.592026) (xy 449.848453 -278.603706) (xy 449.894112 -278.633424) (xy 449.934711 -278.66975)
			(xy 449.969305 -278.711835) (xy 449.997085 -278.758697) (xy 450.017404 -278.809244) (xy 450.029787 -278.862297)
			(xy 450.033945 -278.916616) (xy 450.031901 -278.943287) (xy 450.555604 -278.943287) (xy 450.555604 -278.889989)
			(xy 450.563547 -278.837285) (xy 450.579257 -278.786355) (xy 450.602383 -278.738334) (xy 450.632407 -278.694297)
			(xy 450.668659 -278.655226) (xy 450.71033 -278.621995) (xy 450.756488 -278.595346) (xy 450.806102 -278.575874)
			(xy 450.858064 -278.564014) (xy 450.911214 -278.560031) (xy 450.964364 -278.564014) (xy 451.016326 -278.575874)
			(xy 451.06594 -278.595346) (xy 451.112098 -278.621995) (xy 451.153769 -278.655226) (xy 451.190021 -278.694297)
			(xy 451.220045 -278.738334) (xy 451.243171 -278.786355) (xy 451.258881 -278.837285) (xy 451.266824 -278.889989)
			(xy 451.267322 -278.916638) (xy 451.266824 -278.943287) (xy 454.655672 -278.943287) (xy 454.655672 -278.889989)
			(xy 454.663615 -278.837285) (xy 454.679325 -278.786355) (xy 454.702451 -278.738334) (xy 454.732475 -278.694297)
			(xy 454.768727 -278.655226) (xy 454.810398 -278.621995) (xy 454.856556 -278.595346) (xy 454.90617 -278.575874)
			(xy 454.958132 -278.564014) (xy 455.011282 -278.560031) (xy 455.064432 -278.564014) (xy 455.116394 -278.575874)
			(xy 455.166008 -278.595346) (xy 455.212166 -278.621995) (xy 455.253837 -278.655226) (xy 455.290089 -278.694297)
			(xy 455.320113 -278.738334) (xy 455.343239 -278.786355) (xy 455.358949 -278.837285) (xy 455.366892 -278.889989)
			(xy 455.36739 -278.916638) (xy 455.366892 -278.943287) (xy 456.865472 -278.943287) (xy 456.865472 -278.889989)
			(xy 456.873415 -278.837285) (xy 456.889125 -278.786355) (xy 456.912251 -278.738334) (xy 456.942275 -278.694297)
			(xy 456.978527 -278.655226) (xy 457.020198 -278.621995) (xy 457.066356 -278.595346) (xy 457.11597 -278.575874)
			(xy 457.167932 -278.564014) (xy 457.221082 -278.560031) (xy 457.274232 -278.564014) (xy 457.326194 -278.575874)
			(xy 457.375808 -278.595346) (xy 457.421966 -278.621995) (xy 457.463637 -278.655226) (xy 457.499889 -278.694297)
			(xy 457.529913 -278.738334) (xy 457.553039 -278.786355) (xy 457.568749 -278.837285) (xy 457.576692 -278.889989)
			(xy 457.57719 -278.916638) (xy 457.576692 -278.943287) (xy 457.568749 -278.995991) (xy 457.553039 -279.046921)
			(xy 457.529913 -279.094942) (xy 457.499889 -279.138979) (xy 457.463637 -279.17805) (xy 457.421966 -279.211281)
			(xy 457.375808 -279.23793) (xy 457.326194 -279.257402) (xy 457.274232 -279.269262) (xy 457.221082 -279.273246)
			(xy 457.167932 -279.269262) (xy 457.11597 -279.257402) (xy 457.066356 -279.23793) (xy 457.020198 -279.211281)
			(xy 456.978527 -279.17805) (xy 456.942275 -279.138979) (xy 456.912251 -279.094942) (xy 456.889125 -279.046921)
			(xy 456.873415 -278.995991) (xy 456.865472 -278.943287) (xy 455.366892 -278.943287) (xy 455.358949 -278.995991)
			(xy 455.343239 -279.046921) (xy 455.320113 -279.094942) (xy 455.290089 -279.138979) (xy 455.253837 -279.17805)
			(xy 455.212166 -279.211281) (xy 455.166008 -279.23793) (xy 455.116394 -279.257402) (xy 455.064432 -279.269262)
			(xy 455.011282 -279.273246) (xy 454.958132 -279.269262) (xy 454.90617 -279.257402) (xy 454.856556 -279.23793)
			(xy 454.810398 -279.211281) (xy 454.768727 -279.17805) (xy 454.732475 -279.138979) (xy 454.702451 -279.094942)
			(xy 454.679325 -279.046921) (xy 454.663615 -278.995991) (xy 454.655672 -278.943287) (xy 451.266824 -278.943287)
			(xy 451.258881 -278.995991) (xy 451.243171 -279.046921) (xy 451.220045 -279.094942) (xy 451.190021 -279.138979)
			(xy 451.153769 -279.17805) (xy 451.112098 -279.211281) (xy 451.06594 -279.23793) (xy 451.016326 -279.257402)
			(xy 450.964364 -279.269262) (xy 450.911214 -279.273246) (xy 450.858064 -279.269262) (xy 450.806102 -279.257402)
			(xy 450.756488 -279.23793) (xy 450.71033 -279.211281) (xy 450.668659 -279.17805) (xy 450.632407 -279.138979)
			(xy 450.602383 -279.094942) (xy 450.579257 -279.046921) (xy 450.563547 -278.995991) (xy 450.555604 -278.943287)
			(xy 450.031901 -278.943287) (xy 450.029782 -278.970934) (xy 450.017394 -279.023985) (xy 449.997071 -279.074531)
			(xy 449.969287 -279.121391) (xy 449.93469 -279.163473) (xy 449.894087 -279.199795) (xy 449.848426 -279.229509)
			(xy 449.82384 -279.24125) (xy 449.793868 -279.254712) (xy 449.793868 -279.793425) (xy 450.555604 -279.793425)
			(xy 450.555604 -279.740127) (xy 450.563547 -279.687423) (xy 450.579257 -279.636493) (xy 450.602383 -279.588472)
			(xy 450.632407 -279.544435) (xy 450.668659 -279.505364) (xy 450.71033 -279.472133) (xy 450.756488 -279.445484)
			(xy 450.806102 -279.426012) (xy 450.858064 -279.414152) (xy 450.911214 -279.410169) (xy 450.964364 -279.414152)
			(xy 451.016326 -279.426012) (xy 451.06594 -279.445484) (xy 451.112098 -279.472133) (xy 451.153769 -279.505364)
			(xy 451.190021 -279.544435) (xy 451.220045 -279.588472) (xy 451.243171 -279.636493) (xy 451.258881 -279.687423)
			(xy 451.266824 -279.740127) (xy 451.267322 -279.766776) (xy 451.266824 -279.793425) (xy 452.765404 -279.793425)
			(xy 452.765404 -279.740127) (xy 452.773347 -279.687423) (xy 452.789057 -279.636493) (xy 452.812183 -279.588472)
			(xy 452.842207 -279.544435) (xy 452.878459 -279.505364) (xy 452.92013 -279.472133) (xy 452.966288 -279.445484)
			(xy 453.015902 -279.426012) (xy 453.067864 -279.414152) (xy 453.121014 -279.410169) (xy 453.174164 -279.414152)
			(xy 453.226126 -279.426012) (xy 453.27574 -279.445484) (xy 453.321898 -279.472133) (xy 453.363569 -279.505364)
			(xy 453.399821 -279.544435) (xy 453.429845 -279.588472) (xy 453.452971 -279.636493) (xy 453.468681 -279.687423)
			(xy 453.476624 -279.740127) (xy 453.477122 -279.766776) (xy 453.476624 -279.793425) (xy 454.655672 -279.793425)
			(xy 454.655672 -279.740127) (xy 454.663615 -279.687423) (xy 454.679325 -279.636493) (xy 454.702451 -279.588472)
			(xy 454.732475 -279.544435) (xy 454.768727 -279.505364) (xy 454.810398 -279.472133) (xy 454.856556 -279.445484)
			(xy 454.90617 -279.426012) (xy 454.958132 -279.414152) (xy 455.011282 -279.410169) (xy 455.064432 -279.414152)
			(xy 455.116394 -279.426012) (xy 455.166008 -279.445484) (xy 455.212166 -279.472133) (xy 455.253837 -279.505364)
			(xy 455.290089 -279.544435) (xy 455.320113 -279.588472) (xy 455.343239 -279.636493) (xy 455.358949 -279.687423)
			(xy 455.366892 -279.740127) (xy 455.36739 -279.766776) (xy 455.366892 -279.793425) (xy 458.099404 -279.793425)
			(xy 458.099404 -279.740127) (xy 458.107347 -279.687423) (xy 458.123057 -279.636493) (xy 458.146183 -279.588472)
			(xy 458.176207 -279.544435) (xy 458.212459 -279.505364) (xy 458.25413 -279.472133) (xy 458.300288 -279.445484)
			(xy 458.349902 -279.426012) (xy 458.401864 -279.414152) (xy 458.455014 -279.410169) (xy 458.508164 -279.414152)
			(xy 458.560126 -279.426012) (xy 458.60974 -279.445484) (xy 458.655898 -279.472133) (xy 458.697569 -279.505364)
			(xy 458.733821 -279.544435) (xy 458.763845 -279.588472) (xy 458.786971 -279.636493) (xy 458.802681 -279.687423)
			(xy 458.810624 -279.740127) (xy 458.811122 -279.766776) (xy 458.810624 -279.793425) (xy 458.802681 -279.846129)
			(xy 458.786971 -279.897059) (xy 458.763845 -279.94508) (xy 458.733821 -279.989117) (xy 458.697569 -280.028188)
			(xy 458.655898 -280.061419) (xy 458.60974 -280.088068) (xy 458.560126 -280.10754) (xy 458.508164 -280.1194)
			(xy 458.455014 -280.123384) (xy 458.401864 -280.1194) (xy 458.349902 -280.10754) (xy 458.300288 -280.088068)
			(xy 458.25413 -280.061419) (xy 458.212459 -280.028188) (xy 458.176207 -279.989117) (xy 458.146183 -279.94508)
			(xy 458.123057 -279.897059) (xy 458.107347 -279.846129) (xy 458.099404 -279.793425) (xy 455.366892 -279.793425)
			(xy 455.358949 -279.846129) (xy 455.343239 -279.897059) (xy 455.320113 -279.94508) (xy 455.290089 -279.989117)
			(xy 455.253837 -280.028188) (xy 455.212166 -280.061419) (xy 455.166008 -280.088068) (xy 455.116394 -280.10754)
			(xy 455.064432 -280.1194) (xy 455.011282 -280.123384) (xy 454.958132 -280.1194) (xy 454.90617 -280.10754)
			(xy 454.856556 -280.088068) (xy 454.810398 -280.061419) (xy 454.768727 -280.028188) (xy 454.732475 -279.989117)
			(xy 454.702451 -279.94508) (xy 454.679325 -279.897059) (xy 454.663615 -279.846129) (xy 454.655672 -279.793425)
			(xy 453.476624 -279.793425) (xy 453.468681 -279.846129) (xy 453.452971 -279.897059) (xy 453.429845 -279.94508)
			(xy 453.399821 -279.989117) (xy 453.363569 -280.028188) (xy 453.321898 -280.061419) (xy 453.27574 -280.088068)
			(xy 453.226126 -280.10754) (xy 453.174164 -280.1194) (xy 453.121014 -280.123384) (xy 453.067864 -280.1194)
			(xy 453.015902 -280.10754) (xy 452.966288 -280.088068) (xy 452.92013 -280.061419) (xy 452.878459 -280.028188)
			(xy 452.842207 -279.989117) (xy 452.812183 -279.94508) (xy 452.789057 -279.897059) (xy 452.773347 -279.846129)
			(xy 452.765404 -279.793425) (xy 451.266824 -279.793425) (xy 451.258881 -279.846129) (xy 451.243171 -279.897059)
			(xy 451.220045 -279.94508) (xy 451.190021 -279.989117) (xy 451.153769 -280.028188) (xy 451.112098 -280.061419)
			(xy 451.06594 -280.088068) (xy 451.016326 -280.10754) (xy 450.964364 -280.1194) (xy 450.911214 -280.123384)
			(xy 450.858064 -280.1194) (xy 450.806102 -280.10754) (xy 450.756488 -280.088068) (xy 450.71033 -280.061419)
			(xy 450.668659 -280.028188) (xy 450.632407 -279.989117) (xy 450.602383 -279.94508) (xy 450.579257 -279.897059)
			(xy 450.563547 -279.846129) (xy 450.555604 -279.793425) (xy 449.793868 -279.793425) (xy 449.793868 -280.278586)
			(xy 449.82384 -280.292048) (xy 449.848459 -280.303729) (xy 449.894129 -280.333448) (xy 449.93474 -280.369777)
			(xy 449.969345 -280.411867) (xy 449.997135 -280.458737) (xy 450.017462 -280.509292) (xy 450.029852 -280.562354)
			(xy 450.034016 -280.616684) (xy 450.031978 -280.643309) (xy 450.555604 -280.643309) (xy 450.555604 -280.590011)
			(xy 450.563547 -280.537307) (xy 450.579257 -280.486377) (xy 450.602383 -280.438356) (xy 450.632407 -280.394319)
			(xy 450.668659 -280.355248) (xy 450.71033 -280.322017) (xy 450.756488 -280.295368) (xy 450.806102 -280.275896)
			(xy 450.858064 -280.264036) (xy 450.911214 -280.260053) (xy 450.964364 -280.264036) (xy 451.016326 -280.275896)
			(xy 451.06594 -280.295368) (xy 451.112098 -280.322017) (xy 451.153769 -280.355248) (xy 451.190021 -280.394319)
			(xy 451.220045 -280.438356) (xy 451.243171 -280.486377) (xy 451.258881 -280.537307) (xy 451.266824 -280.590011)
			(xy 451.267322 -280.61666) (xy 451.266824 -280.643309) (xy 454.655672 -280.643309) (xy 454.655672 -280.590011)
			(xy 454.663615 -280.537307) (xy 454.679325 -280.486377) (xy 454.702451 -280.438356) (xy 454.732475 -280.394319)
			(xy 454.768727 -280.355248) (xy 454.810398 -280.322017) (xy 454.856556 -280.295368) (xy 454.90617 -280.275896)
			(xy 454.958132 -280.264036) (xy 455.011282 -280.260053) (xy 455.064432 -280.264036) (xy 455.116394 -280.275896)
			(xy 455.166008 -280.295368) (xy 455.212166 -280.322017) (xy 455.253837 -280.355248) (xy 455.290089 -280.394319)
			(xy 455.320113 -280.438356) (xy 455.343239 -280.486377) (xy 455.358949 -280.537307) (xy 455.366892 -280.590011)
			(xy 455.36739 -280.61666) (xy 455.366892 -280.643309) (xy 456.865472 -280.643309) (xy 456.865472 -280.590011)
			(xy 456.873415 -280.537307) (xy 456.889125 -280.486377) (xy 456.912251 -280.438356) (xy 456.942275 -280.394319)
			(xy 456.978527 -280.355248) (xy 457.020198 -280.322017) (xy 457.066356 -280.295368) (xy 457.11597 -280.275896)
			(xy 457.167932 -280.264036) (xy 457.221082 -280.260053) (xy 457.274232 -280.264036) (xy 457.326194 -280.275896)
			(xy 457.375808 -280.295368) (xy 457.421966 -280.322017) (xy 457.463637 -280.355248) (xy 457.499889 -280.394319)
			(xy 457.529913 -280.438356) (xy 457.553039 -280.486377) (xy 457.568749 -280.537307) (xy 457.576692 -280.590011)
			(xy 457.57719 -280.61666) (xy 457.576692 -280.643309) (xy 457.568749 -280.696013) (xy 457.553039 -280.746943)
			(xy 457.529913 -280.794964) (xy 457.499889 -280.839001) (xy 457.463637 -280.878072) (xy 457.421966 -280.911303)
			(xy 457.375808 -280.937952) (xy 457.326194 -280.957424) (xy 457.274232 -280.969284) (xy 457.221082 -280.973268)
			(xy 457.167932 -280.969284) (xy 457.11597 -280.957424) (xy 457.066356 -280.937952) (xy 457.020198 -280.911303)
			(xy 456.978527 -280.878072) (xy 456.942275 -280.839001) (xy 456.912251 -280.794964) (xy 456.889125 -280.746943)
			(xy 456.873415 -280.696013) (xy 456.865472 -280.643309) (xy 455.366892 -280.643309) (xy 455.358949 -280.696013)
			(xy 455.343239 -280.746943) (xy 455.320113 -280.794964) (xy 455.290089 -280.839001) (xy 455.253837 -280.878072)
			(xy 455.212166 -280.911303) (xy 455.166008 -280.937952) (xy 455.116394 -280.957424) (xy 455.064432 -280.969284)
			(xy 455.011282 -280.973268) (xy 454.958132 -280.969284) (xy 454.90617 -280.957424) (xy 454.856556 -280.937952)
			(xy 454.810398 -280.911303) (xy 454.768727 -280.878072) (xy 454.732475 -280.839001) (xy 454.702451 -280.794964)
			(xy 454.679325 -280.746943) (xy 454.663615 -280.696013) (xy 454.655672 -280.643309) (xy 451.266824 -280.643309)
			(xy 451.258881 -280.696013) (xy 451.243171 -280.746943) (xy 451.220045 -280.794964) (xy 451.190021 -280.839001)
			(xy 451.153769 -280.878072) (xy 451.112098 -280.911303) (xy 451.06594 -280.937952) (xy 451.016326 -280.957424)
			(xy 450.964364 -280.969284) (xy 450.911214 -280.973268) (xy 450.858064 -280.969284) (xy 450.806102 -280.957424)
			(xy 450.756488 -280.937952) (xy 450.71033 -280.911303) (xy 450.668659 -280.878072) (xy 450.632407 -280.839001)
			(xy 450.602383 -280.794964) (xy 450.579257 -280.746943) (xy 450.563547 -280.696013) (xy 450.555604 -280.643309)
			(xy 450.031978 -280.643309) (xy 450.029857 -280.671013) (xy 450.017472 -280.724076) (xy 449.997149 -280.774633)
			(xy 449.969364 -280.821506) (xy 449.934763 -280.863599) (xy 449.894155 -280.899932) (xy 449.848488 -280.929656)
			(xy 449.82384 -280.941272) (xy 449.793868 -280.954734) (xy 449.793868 -281.493447) (xy 450.555604 -281.493447)
			(xy 450.555604 -281.440149) (xy 450.563547 -281.387445) (xy 450.579257 -281.336515) (xy 450.602383 -281.288494)
			(xy 450.632407 -281.244457) (xy 450.668659 -281.205386) (xy 450.71033 -281.172155) (xy 450.756488 -281.145506)
			(xy 450.806102 -281.126034) (xy 450.858064 -281.114174) (xy 450.911214 -281.110191) (xy 450.964364 -281.114174)
			(xy 451.016326 -281.126034) (xy 451.06594 -281.145506) (xy 451.112098 -281.172155) (xy 451.153769 -281.205386)
			(xy 451.190021 -281.244457) (xy 451.220045 -281.288494) (xy 451.243171 -281.336515) (xy 451.258881 -281.387445)
			(xy 451.266824 -281.440149) (xy 451.267322 -281.466798) (xy 451.266824 -281.493447) (xy 452.765404 -281.493447)
			(xy 452.765404 -281.440149) (xy 452.773347 -281.387445) (xy 452.789057 -281.336515) (xy 452.812183 -281.288494)
			(xy 452.842207 -281.244457) (xy 452.878459 -281.205386) (xy 452.92013 -281.172155) (xy 452.966288 -281.145506)
			(xy 453.015902 -281.126034) (xy 453.067864 -281.114174) (xy 453.121014 -281.110191) (xy 453.174164 -281.114174)
			(xy 453.226126 -281.126034) (xy 453.27574 -281.145506) (xy 453.321898 -281.172155) (xy 453.363569 -281.205386)
			(xy 453.399821 -281.244457) (xy 453.429845 -281.288494) (xy 453.452971 -281.336515) (xy 453.468681 -281.387445)
			(xy 453.476624 -281.440149) (xy 453.477122 -281.466798) (xy 453.476629 -281.493193) (xy 454.655672 -281.493193)
			(xy 454.655672 -281.439895) (xy 454.663615 -281.387191) (xy 454.679325 -281.336261) (xy 454.702451 -281.28824)
			(xy 454.732475 -281.244203) (xy 454.768727 -281.205132) (xy 454.810398 -281.171901) (xy 454.856556 -281.145252)
			(xy 454.90617 -281.12578) (xy 454.958132 -281.11392) (xy 455.011282 -281.109937) (xy 455.064432 -281.11392)
			(xy 455.116394 -281.12578) (xy 455.166008 -281.145252) (xy 455.212166 -281.171901) (xy 455.253837 -281.205132)
			(xy 455.290089 -281.244203) (xy 455.320113 -281.28824) (xy 455.343239 -281.336261) (xy 455.358949 -281.387191)
			(xy 455.366892 -281.439895) (xy 455.36739 -281.466544) (xy 455.366892 -281.493193) (xy 455.366854 -281.493447)
			(xy 458.099404 -281.493447) (xy 458.099404 -281.440149) (xy 458.107347 -281.387445) (xy 458.123057 -281.336515)
			(xy 458.146183 -281.288494) (xy 458.176207 -281.244457) (xy 458.212459 -281.205386) (xy 458.25413 -281.172155)
			(xy 458.300288 -281.145506) (xy 458.349902 -281.126034) (xy 458.401864 -281.114174) (xy 458.455014 -281.110191)
			(xy 458.508164 -281.114174) (xy 458.560126 -281.126034) (xy 458.60974 -281.145506) (xy 458.655898 -281.172155)
			(xy 458.697569 -281.205386) (xy 458.733821 -281.244457) (xy 458.763845 -281.288494) (xy 458.786971 -281.336515)
			(xy 458.802681 -281.387445) (xy 458.810624 -281.440149) (xy 458.811122 -281.466798) (xy 458.810624 -281.493447)
			(xy 458.802681 -281.546151) (xy 458.786971 -281.597081) (xy 458.763845 -281.645102) (xy 458.733821 -281.689139)
			(xy 458.697569 -281.72821) (xy 458.655898 -281.761441) (xy 458.60974 -281.78809) (xy 458.560126 -281.807562)
			(xy 458.508164 -281.819422) (xy 458.455014 -281.823406) (xy 458.401864 -281.819422) (xy 458.349902 -281.807562)
			(xy 458.300288 -281.78809) (xy 458.25413 -281.761441) (xy 458.212459 -281.72821) (xy 458.176207 -281.689139)
			(xy 458.146183 -281.645102) (xy 458.123057 -281.597081) (xy 458.107347 -281.546151) (xy 458.099404 -281.493447)
			(xy 455.366854 -281.493447) (xy 455.358949 -281.545897) (xy 455.343239 -281.596827) (xy 455.320113 -281.644848)
			(xy 455.290089 -281.688885) (xy 455.253837 -281.727956) (xy 455.212166 -281.761187) (xy 455.166008 -281.787836)
			(xy 455.116394 -281.807308) (xy 455.064432 -281.819168) (xy 455.011282 -281.823152) (xy 454.958132 -281.819168)
			(xy 454.90617 -281.807308) (xy 454.856556 -281.787836) (xy 454.810398 -281.761187) (xy 454.768727 -281.727956)
			(xy 454.732475 -281.688885) (xy 454.702451 -281.644848) (xy 454.679325 -281.596827) (xy 454.663615 -281.545897)
			(xy 454.655672 -281.493193) (xy 453.476629 -281.493193) (xy 453.476624 -281.493447) (xy 453.468681 -281.546151)
			(xy 453.452971 -281.597081) (xy 453.429845 -281.645102) (xy 453.399821 -281.689139) (xy 453.363569 -281.72821)
			(xy 453.321898 -281.761441) (xy 453.27574 -281.78809) (xy 453.226126 -281.807562) (xy 453.174164 -281.819422)
			(xy 453.121014 -281.823406) (xy 453.067864 -281.819422) (xy 453.015902 -281.807562) (xy 452.966288 -281.78809)
			(xy 452.92013 -281.761441) (xy 452.878459 -281.72821) (xy 452.842207 -281.689139) (xy 452.812183 -281.645102)
			(xy 452.789057 -281.597081) (xy 452.773347 -281.546151) (xy 452.765404 -281.493447) (xy 451.266824 -281.493447)
			(xy 451.258881 -281.546151) (xy 451.243171 -281.597081) (xy 451.220045 -281.645102) (xy 451.190021 -281.689139)
			(xy 451.153769 -281.72821) (xy 451.112098 -281.761441) (xy 451.06594 -281.78809) (xy 451.016326 -281.807562)
			(xy 450.964364 -281.819422) (xy 450.911214 -281.823406) (xy 450.858064 -281.819422) (xy 450.806102 -281.807562)
			(xy 450.756488 -281.78809) (xy 450.71033 -281.761441) (xy 450.668659 -281.72821) (xy 450.632407 -281.689139)
			(xy 450.602383 -281.645102) (xy 450.579257 -281.597081) (xy 450.563547 -281.546151) (xy 450.555604 -281.493447)
			(xy 449.793868 -281.493447) (xy 449.793868 -281.978608) (xy 449.82384 -281.99207) (xy 449.848457 -282.003751)
			(xy 449.894124 -282.03347) (xy 449.934732 -282.069798) (xy 449.969333 -282.111886) (xy 449.997121 -282.158754)
			(xy 450.017445 -282.209307) (xy 450.029834 -282.262366) (xy 450.033996 -282.316693) (xy 450.031956 -282.343331)
			(xy 450.555604 -282.343331) (xy 450.555604 -282.290033) (xy 450.563547 -282.237329) (xy 450.579257 -282.186399)
			(xy 450.602383 -282.138378) (xy 450.632407 -282.094341) (xy 450.668659 -282.05527) (xy 450.71033 -282.022039)
			(xy 450.756488 -281.99539) (xy 450.806102 -281.975918) (xy 450.858064 -281.964058) (xy 450.911214 -281.960075)
			(xy 450.964364 -281.964058) (xy 451.016326 -281.975918) (xy 451.06594 -281.99539) (xy 451.112098 -282.022039)
			(xy 451.153769 -282.05527) (xy 451.190021 -282.094341) (xy 451.220045 -282.138378) (xy 451.243171 -282.186399)
			(xy 451.258881 -282.237329) (xy 451.266824 -282.290033) (xy 451.267322 -282.316682) (xy 451.266824 -282.343331)
			(xy 454.655672 -282.343331) (xy 454.655672 -282.290033) (xy 454.663615 -282.237329) (xy 454.679325 -282.186399)
			(xy 454.702451 -282.138378) (xy 454.732475 -282.094341) (xy 454.768727 -282.05527) (xy 454.810398 -282.022039)
			(xy 454.856556 -281.99539) (xy 454.90617 -281.975918) (xy 454.958132 -281.964058) (xy 455.011282 -281.960075)
			(xy 455.064432 -281.964058) (xy 455.116394 -281.975918) (xy 455.166008 -281.99539) (xy 455.212166 -282.022039)
			(xy 455.253837 -282.05527) (xy 455.290089 -282.094341) (xy 455.320113 -282.138378) (xy 455.343239 -282.186399)
			(xy 455.358949 -282.237329) (xy 455.366892 -282.290033) (xy 455.36739 -282.316682) (xy 455.366892 -282.343331)
			(xy 456.865472 -282.343331) (xy 456.865472 -282.290033) (xy 456.873415 -282.237329) (xy 456.889125 -282.186399)
			(xy 456.912251 -282.138378) (xy 456.942275 -282.094341) (xy 456.978527 -282.05527) (xy 457.020198 -282.022039)
			(xy 457.066356 -281.99539) (xy 457.11597 -281.975918) (xy 457.167932 -281.964058) (xy 457.221082 -281.960075)
			(xy 457.274232 -281.964058) (xy 457.326194 -281.975918) (xy 457.375808 -281.99539) (xy 457.421966 -282.022039)
			(xy 457.463637 -282.05527) (xy 457.499889 -282.094341) (xy 457.529913 -282.138378) (xy 457.553039 -282.186399)
			(xy 457.568749 -282.237329) (xy 457.576692 -282.290033) (xy 457.57719 -282.316682) (xy 457.576692 -282.343331)
			(xy 457.568749 -282.396035) (xy 457.553039 -282.446965) (xy 457.529913 -282.494986) (xy 457.499889 -282.539023)
			(xy 457.463637 -282.578094) (xy 457.421966 -282.611325) (xy 457.375808 -282.637974) (xy 457.326194 -282.657446)
			(xy 457.274232 -282.669306) (xy 457.221082 -282.67329) (xy 457.167932 -282.669306) (xy 457.11597 -282.657446)
			(xy 457.066356 -282.637974) (xy 457.020198 -282.611325) (xy 456.978527 -282.578094) (xy 456.942275 -282.539023)
			(xy 456.912251 -282.494986) (xy 456.889125 -282.446965) (xy 456.873415 -282.396035) (xy 456.865472 -282.343331)
			(xy 455.366892 -282.343331) (xy 455.358949 -282.396035) (xy 455.343239 -282.446965) (xy 455.320113 -282.494986)
			(xy 455.290089 -282.539023) (xy 455.253837 -282.578094) (xy 455.212166 -282.611325) (xy 455.166008 -282.637974)
			(xy 455.116394 -282.657446) (xy 455.064432 -282.669306) (xy 455.011282 -282.67329) (xy 454.958132 -282.669306)
			(xy 454.90617 -282.657446) (xy 454.856556 -282.637974) (xy 454.810398 -282.611325) (xy 454.768727 -282.578094)
			(xy 454.732475 -282.539023) (xy 454.702451 -282.494986) (xy 454.679325 -282.446965) (xy 454.663615 -282.396035)
			(xy 454.655672 -282.343331) (xy 451.266824 -282.343331) (xy 451.258881 -282.396035) (xy 451.243171 -282.446965)
			(xy 451.220045 -282.494986) (xy 451.190021 -282.539023) (xy 451.153769 -282.578094) (xy 451.112098 -282.611325)
			(xy 451.06594 -282.637974) (xy 451.016326 -282.657446) (xy 450.964364 -282.669306) (xy 450.911214 -282.67329)
			(xy 450.858064 -282.669306) (xy 450.806102 -282.657446) (xy 450.756488 -282.637974) (xy 450.71033 -282.611325)
			(xy 450.668659 -282.578094) (xy 450.632407 -282.539023) (xy 450.602383 -282.494986) (xy 450.579257 -282.446965)
			(xy 450.563547 -282.396035) (xy 450.555604 -282.343331) (xy 450.031956 -282.343331) (xy 450.029836 -282.371019)
			(xy 450.01745 -282.424079) (xy 449.997127 -282.474633) (xy 449.969342 -282.521502) (xy 449.934742 -282.563592)
			(xy 449.894136 -282.599921) (xy 449.84847 -282.629642) (xy 449.82384 -282.641294) (xy 449.793868 -282.654756)
			(xy 449.793868 -283.193215) (xy 450.555604 -283.193215) (xy 450.555604 -283.139917) (xy 450.563547 -283.087213)
			(xy 450.579257 -283.036283) (xy 450.602383 -282.988262) (xy 450.632407 -282.944225) (xy 450.668659 -282.905154)
			(xy 450.71033 -282.871923) (xy 450.756488 -282.845274) (xy 450.806102 -282.825802) (xy 450.858064 -282.813942)
			(xy 450.911214 -282.809959) (xy 450.964364 -282.813942) (xy 451.016326 -282.825802) (xy 451.06594 -282.845274)
			(xy 451.112098 -282.871923) (xy 451.153769 -282.905154) (xy 451.190021 -282.944225) (xy 451.220045 -282.988262)
			(xy 451.243171 -283.036283) (xy 451.258881 -283.087213) (xy 451.266824 -283.139917) (xy 451.267322 -283.166566)
			(xy 451.266824 -283.193215) (xy 452.765404 -283.193215) (xy 452.765404 -283.139917) (xy 452.773347 -283.087213)
			(xy 452.789057 -283.036283) (xy 452.812183 -282.988262) (xy 452.842207 -282.944225) (xy 452.878459 -282.905154)
			(xy 452.92013 -282.871923) (xy 452.966288 -282.845274) (xy 453.015902 -282.825802) (xy 453.067864 -282.813942)
			(xy 453.121014 -282.809959) (xy 453.174164 -282.813942) (xy 453.226126 -282.825802) (xy 453.27574 -282.845274)
			(xy 453.321898 -282.871923) (xy 453.363569 -282.905154) (xy 453.399821 -282.944225) (xy 453.429845 -282.988262)
			(xy 453.452971 -283.036283) (xy 453.468681 -283.087213) (xy 453.476624 -283.139917) (xy 453.477122 -283.166566)
			(xy 453.476624 -283.193215) (xy 454.655672 -283.193215) (xy 454.655672 -283.139917) (xy 454.663615 -283.087213)
			(xy 454.679325 -283.036283) (xy 454.702451 -282.988262) (xy 454.732475 -282.944225) (xy 454.768727 -282.905154)
			(xy 454.810398 -282.871923) (xy 454.856556 -282.845274) (xy 454.90617 -282.825802) (xy 454.958132 -282.813942)
			(xy 455.011282 -282.809959) (xy 455.064432 -282.813942) (xy 455.116394 -282.825802) (xy 455.166008 -282.845274)
			(xy 455.212166 -282.871923) (xy 455.253837 -282.905154) (xy 455.290089 -282.944225) (xy 455.320113 -282.988262)
			(xy 455.343239 -283.036283) (xy 455.358949 -283.087213) (xy 455.366892 -283.139917) (xy 455.36739 -283.166566)
			(xy 455.366892 -283.193215) (xy 458.099404 -283.193215) (xy 458.099404 -283.139917) (xy 458.107347 -283.087213)
			(xy 458.123057 -283.036283) (xy 458.146183 -282.988262) (xy 458.176207 -282.944225) (xy 458.212459 -282.905154)
			(xy 458.25413 -282.871923) (xy 458.300288 -282.845274) (xy 458.349902 -282.825802) (xy 458.401864 -282.813942)
			(xy 458.455014 -282.809959) (xy 458.508164 -282.813942) (xy 458.560126 -282.825802) (xy 458.60974 -282.845274)
			(xy 458.655898 -282.871923) (xy 458.697569 -282.905154) (xy 458.733821 -282.944225) (xy 458.763845 -282.988262)
			(xy 458.786971 -283.036283) (xy 458.802681 -283.087213) (xy 458.810624 -283.139917) (xy 458.811122 -283.166566)
			(xy 458.810624 -283.193215) (xy 458.802681 -283.245919) (xy 458.786971 -283.296849) (xy 458.763845 -283.34487)
			(xy 458.733821 -283.388907) (xy 458.697569 -283.427978) (xy 458.655898 -283.461209) (xy 458.60974 -283.487858)
			(xy 458.560126 -283.50733) (xy 458.508164 -283.51919) (xy 458.455014 -283.523174) (xy 458.401864 -283.51919)
			(xy 458.349902 -283.50733) (xy 458.300288 -283.487858) (xy 458.25413 -283.461209) (xy 458.212459 -283.427978)
			(xy 458.176207 -283.388907) (xy 458.146183 -283.34487) (xy 458.123057 -283.296849) (xy 458.107347 -283.245919)
			(xy 458.099404 -283.193215) (xy 455.366892 -283.193215) (xy 455.358949 -283.245919) (xy 455.343239 -283.296849)
			(xy 455.320113 -283.34487) (xy 455.290089 -283.388907) (xy 455.253837 -283.427978) (xy 455.212166 -283.461209)
			(xy 455.166008 -283.487858) (xy 455.116394 -283.50733) (xy 455.064432 -283.51919) (xy 455.011282 -283.523174)
			(xy 454.958132 -283.51919) (xy 454.90617 -283.50733) (xy 454.856556 -283.487858) (xy 454.810398 -283.461209)
			(xy 454.768727 -283.427978) (xy 454.732475 -283.388907) (xy 454.702451 -283.34487) (xy 454.679325 -283.296849)
			(xy 454.663615 -283.245919) (xy 454.655672 -283.193215) (xy 453.476624 -283.193215) (xy 453.468681 -283.245919)
			(xy 453.452971 -283.296849) (xy 453.429845 -283.34487) (xy 453.399821 -283.388907) (xy 453.363569 -283.427978)
			(xy 453.321898 -283.461209) (xy 453.27574 -283.487858) (xy 453.226126 -283.50733) (xy 453.174164 -283.51919)
			(xy 453.121014 -283.523174) (xy 453.067864 -283.51919) (xy 453.015902 -283.50733) (xy 452.966288 -283.487858)
			(xy 452.92013 -283.461209) (xy 452.878459 -283.427978) (xy 452.842207 -283.388907) (xy 452.812183 -283.34487)
			(xy 452.789057 -283.296849) (xy 452.773347 -283.245919) (xy 452.765404 -283.193215) (xy 451.266824 -283.193215)
			(xy 451.258881 -283.245919) (xy 451.243171 -283.296849) (xy 451.220045 -283.34487) (xy 451.190021 -283.388907)
			(xy 451.153769 -283.427978) (xy 451.112098 -283.461209) (xy 451.06594 -283.487858) (xy 451.016326 -283.50733)
			(xy 450.964364 -283.51919) (xy 450.911214 -283.523174) (xy 450.858064 -283.51919) (xy 450.806102 -283.50733)
			(xy 450.756488 -283.487858) (xy 450.71033 -283.461209) (xy 450.668659 -283.427978) (xy 450.632407 -283.388907)
			(xy 450.602383 -283.34487) (xy 450.579257 -283.296849) (xy 450.563547 -283.245919) (xy 450.555604 -283.193215)
			(xy 449.793868 -283.193215) (xy 449.793868 -284.043353) (xy 450.555604 -284.043353) (xy 450.555604 -283.990055)
			(xy 450.563547 -283.937351) (xy 450.579257 -283.886421) (xy 450.602383 -283.8384) (xy 450.632407 -283.794363)
			(xy 450.668659 -283.755292) (xy 450.71033 -283.722061) (xy 450.756488 -283.695412) (xy 450.806102 -283.67594)
			(xy 450.858064 -283.66408) (xy 450.911214 -283.660097) (xy 450.964364 -283.66408) (xy 451.016326 -283.67594)
			(xy 451.06594 -283.695412) (xy 451.112098 -283.722061) (xy 451.153769 -283.755292) (xy 451.190021 -283.794363)
			(xy 451.220045 -283.8384) (xy 451.243171 -283.886421) (xy 451.258881 -283.937351) (xy 451.266824 -283.990055)
			(xy 451.267322 -284.016704) (xy 451.266824 -284.043353) (xy 454.655672 -284.043353) (xy 454.655672 -283.990055)
			(xy 454.663615 -283.937351) (xy 454.679325 -283.886421) (xy 454.702451 -283.8384) (xy 454.732475 -283.794363)
			(xy 454.768727 -283.755292) (xy 454.810398 -283.722061) (xy 454.856556 -283.695412) (xy 454.90617 -283.67594)
			(xy 454.958132 -283.66408) (xy 455.011282 -283.660097) (xy 455.064432 -283.66408) (xy 455.116394 -283.67594)
			(xy 455.166008 -283.695412) (xy 455.212166 -283.722061) (xy 455.253837 -283.755292) (xy 455.290089 -283.794363)
			(xy 455.320113 -283.8384) (xy 455.343239 -283.886421) (xy 455.358949 -283.937351) (xy 455.366892 -283.990055)
			(xy 455.36739 -284.016704) (xy 455.366892 -284.043353) (xy 455.358949 -284.096057) (xy 455.343239 -284.146987)
			(xy 455.320113 -284.195008) (xy 455.290089 -284.239045) (xy 455.253837 -284.278116) (xy 455.212166 -284.311347)
			(xy 455.166008 -284.337996) (xy 455.116394 -284.357468) (xy 455.064432 -284.369328) (xy 455.011282 -284.373312)
			(xy 454.958132 -284.369328) (xy 454.90617 -284.357468) (xy 454.856556 -284.337996) (xy 454.810398 -284.311347)
			(xy 454.768727 -284.278116) (xy 454.732475 -284.239045) (xy 454.702451 -284.195008) (xy 454.679325 -284.146987)
			(xy 454.663615 -284.096057) (xy 454.655672 -284.043353) (xy 451.266824 -284.043353) (xy 451.258881 -284.096057)
			(xy 451.243171 -284.146987) (xy 451.220045 -284.195008) (xy 451.190021 -284.239045) (xy 451.153769 -284.278116)
			(xy 451.112098 -284.311347) (xy 451.06594 -284.337996) (xy 451.016326 -284.357468) (xy 450.964364 -284.369328)
			(xy 450.911214 -284.373312) (xy 450.858064 -284.369328) (xy 450.806102 -284.357468) (xy 450.756488 -284.337996)
			(xy 450.71033 -284.311347) (xy 450.668659 -284.278116) (xy 450.632407 -284.239045) (xy 450.602383 -284.195008)
			(xy 450.579257 -284.146987) (xy 450.563547 -284.096057) (xy 450.555604 -284.043353) (xy 449.793868 -284.043353)
			(xy 449.793868 -284.528514) (xy 449.82384 -284.541976) (xy 449.848457 -284.553657) (xy 449.894123 -284.583376)
			(xy 449.93473 -284.619703) (xy 449.96933 -284.661792) (xy 449.997117 -284.708659) (xy 450.017441 -284.759211)
			(xy 450.029829 -284.812269) (xy 450.033991 -284.866595) (xy 450.03195 -284.893237) (xy 450.555604 -284.893237)
			(xy 450.555604 -284.839939) (xy 450.563547 -284.787235) (xy 450.579257 -284.736305) (xy 450.602383 -284.688284)
			(xy 450.632407 -284.644247) (xy 450.668659 -284.605176) (xy 450.71033 -284.571945) (xy 450.756488 -284.545296)
			(xy 450.806102 -284.525824) (xy 450.858064 -284.513964) (xy 450.911214 -284.509981) (xy 450.964364 -284.513964)
			(xy 451.016326 -284.525824) (xy 451.06594 -284.545296) (xy 451.112098 -284.571945) (xy 451.153769 -284.605176)
			(xy 451.190021 -284.644247) (xy 451.220045 -284.688284) (xy 451.243171 -284.736305) (xy 451.258881 -284.787235)
			(xy 451.266824 -284.839939) (xy 451.267322 -284.866588) (xy 451.266824 -284.893237) (xy 454.655672 -284.893237)
			(xy 454.655672 -284.839939) (xy 454.663615 -284.787235) (xy 454.679325 -284.736305) (xy 454.702451 -284.688284)
			(xy 454.732475 -284.644247) (xy 454.768727 -284.605176) (xy 454.810398 -284.571945) (xy 454.856556 -284.545296)
			(xy 454.90617 -284.525824) (xy 454.958132 -284.513964) (xy 455.011282 -284.509981) (xy 455.064432 -284.513964)
			(xy 455.116394 -284.525824) (xy 455.166008 -284.545296) (xy 455.212166 -284.571945) (xy 455.253837 -284.605176)
			(xy 455.290089 -284.644247) (xy 455.320113 -284.688284) (xy 455.343239 -284.736305) (xy 455.358949 -284.787235)
			(xy 455.366892 -284.839939) (xy 455.36739 -284.866588) (xy 455.366892 -284.893237) (xy 456.865472 -284.893237)
			(xy 456.865472 -284.839939) (xy 456.873415 -284.787235) (xy 456.889125 -284.736305) (xy 456.912251 -284.688284)
			(xy 456.942275 -284.644247) (xy 456.978527 -284.605176) (xy 457.020198 -284.571945) (xy 457.066356 -284.545296)
			(xy 457.11597 -284.525824) (xy 457.167932 -284.513964) (xy 457.221082 -284.509981) (xy 457.274232 -284.513964)
			(xy 457.326194 -284.525824) (xy 457.375808 -284.545296) (xy 457.421966 -284.571945) (xy 457.463637 -284.605176)
			(xy 457.499889 -284.644247) (xy 457.529913 -284.688284) (xy 457.553039 -284.736305) (xy 457.568749 -284.787235)
			(xy 457.576692 -284.839939) (xy 457.57719 -284.866588) (xy 457.576692 -284.893237) (xy 457.568749 -284.945941)
			(xy 457.553039 -284.996871) (xy 457.529913 -285.044892) (xy 457.499889 -285.088929) (xy 457.463637 -285.128)
			(xy 457.421966 -285.161231) (xy 457.375808 -285.18788) (xy 457.326194 -285.207352) (xy 457.274232 -285.219212)
			(xy 457.221082 -285.223196) (xy 457.167932 -285.219212) (xy 457.11597 -285.207352) (xy 457.066356 -285.18788)
			(xy 457.020198 -285.161231) (xy 456.978527 -285.128) (xy 456.942275 -285.088929) (xy 456.912251 -285.044892)
			(xy 456.889125 -284.996871) (xy 456.873415 -284.945941) (xy 456.865472 -284.893237) (xy 455.366892 -284.893237)
			(xy 455.358949 -284.945941) (xy 455.343239 -284.996871) (xy 455.320113 -285.044892) (xy 455.290089 -285.088929)
			(xy 455.253837 -285.128) (xy 455.212166 -285.161231) (xy 455.166008 -285.18788) (xy 455.116394 -285.207352)
			(xy 455.064432 -285.219212) (xy 455.011282 -285.223196) (xy 454.958132 -285.219212) (xy 454.90617 -285.207352)
			(xy 454.856556 -285.18788) (xy 454.810398 -285.161231) (xy 454.768727 -285.128) (xy 454.732475 -285.088929)
			(xy 454.702451 -285.044892) (xy 454.679325 -284.996871) (xy 454.663615 -284.945941) (xy 454.655672 -284.893237)
			(xy 451.266824 -284.893237) (xy 451.258881 -284.945941) (xy 451.243171 -284.996871) (xy 451.220045 -285.044892)
			(xy 451.190021 -285.088929) (xy 451.153769 -285.128) (xy 451.112098 -285.161231) (xy 451.06594 -285.18788)
			(xy 451.016326 -285.207352) (xy 450.964364 -285.219212) (xy 450.911214 -285.223196) (xy 450.858064 -285.219212)
			(xy 450.806102 -285.207352) (xy 450.756488 -285.18788) (xy 450.71033 -285.161231) (xy 450.668659 -285.128)
			(xy 450.632407 -285.088929) (xy 450.602383 -285.044892) (xy 450.579257 -284.996871) (xy 450.563547 -284.945941)
			(xy 450.555604 -284.893237) (xy 450.03195 -284.893237) (xy 450.02983 -284.920921) (xy 450.017444 -284.973979)
			(xy 449.997121 -285.024532) (xy 449.969336 -285.0714) (xy 449.934737 -285.11349) (xy 449.894131 -285.149818)
			(xy 449.848465 -285.179539) (xy 449.82384 -285.1912) (xy 449.793868 -285.204662) (xy 449.793868 -285.743375)
			(xy 450.555604 -285.743375) (xy 450.555604 -285.690077) (xy 450.563547 -285.637373) (xy 450.579257 -285.586443)
			(xy 450.602383 -285.538422) (xy 450.632407 -285.494385) (xy 450.668659 -285.455314) (xy 450.71033 -285.422083)
			(xy 450.756488 -285.395434) (xy 450.806102 -285.375962) (xy 450.858064 -285.364102) (xy 450.911214 -285.360119)
			(xy 450.964364 -285.364102) (xy 451.016326 -285.375962) (xy 451.06594 -285.395434) (xy 451.112098 -285.422083)
			(xy 451.153769 -285.455314) (xy 451.190021 -285.494385) (xy 451.220045 -285.538422) (xy 451.243171 -285.586443)
			(xy 451.258881 -285.637373) (xy 451.266824 -285.690077) (xy 451.267322 -285.716726) (xy 451.266824 -285.743375)
			(xy 452.765404 -285.743375) (xy 452.765404 -285.690077) (xy 452.773347 -285.637373) (xy 452.789057 -285.586443)
			(xy 452.812183 -285.538422) (xy 452.842207 -285.494385) (xy 452.878459 -285.455314) (xy 452.92013 -285.422083)
			(xy 452.966288 -285.395434) (xy 453.015902 -285.375962) (xy 453.067864 -285.364102) (xy 453.121014 -285.360119)
			(xy 453.174164 -285.364102) (xy 453.226126 -285.375962) (xy 453.27574 -285.395434) (xy 453.321898 -285.422083)
			(xy 453.363569 -285.455314) (xy 453.399821 -285.494385) (xy 453.429845 -285.538422) (xy 453.452971 -285.586443)
			(xy 453.468681 -285.637373) (xy 453.476624 -285.690077) (xy 453.477122 -285.716726) (xy 453.476624 -285.743375)
			(xy 454.655672 -285.743375) (xy 454.655672 -285.690077) (xy 454.663615 -285.637373) (xy 454.679325 -285.586443)
			(xy 454.702451 -285.538422) (xy 454.732475 -285.494385) (xy 454.768727 -285.455314) (xy 454.810398 -285.422083)
			(xy 454.856556 -285.395434) (xy 454.90617 -285.375962) (xy 454.958132 -285.364102) (xy 455.011282 -285.360119)
			(xy 455.064432 -285.364102) (xy 455.116394 -285.375962) (xy 455.166008 -285.395434) (xy 455.212166 -285.422083)
			(xy 455.253837 -285.455314) (xy 455.290089 -285.494385) (xy 455.320113 -285.538422) (xy 455.343239 -285.586443)
			(xy 455.358949 -285.637373) (xy 455.366892 -285.690077) (xy 455.36739 -285.716726) (xy 455.366892 -285.743375)
			(xy 458.099404 -285.743375) (xy 458.099404 -285.690077) (xy 458.107347 -285.637373) (xy 458.123057 -285.586443)
			(xy 458.146183 -285.538422) (xy 458.176207 -285.494385) (xy 458.212459 -285.455314) (xy 458.25413 -285.422083)
			(xy 458.300288 -285.395434) (xy 458.349902 -285.375962) (xy 458.401864 -285.364102) (xy 458.455014 -285.360119)
			(xy 458.508164 -285.364102) (xy 458.560126 -285.375962) (xy 458.60974 -285.395434) (xy 458.655898 -285.422083)
			(xy 458.697569 -285.455314) (xy 458.733821 -285.494385) (xy 458.763845 -285.538422) (xy 458.786971 -285.586443)
			(xy 458.802681 -285.637373) (xy 458.810624 -285.690077) (xy 458.811122 -285.716726) (xy 458.810624 -285.743375)
			(xy 458.802681 -285.796079) (xy 458.786971 -285.847009) (xy 458.763845 -285.89503) (xy 458.733821 -285.939067)
			(xy 458.697569 -285.978138) (xy 458.655898 -286.011369) (xy 458.60974 -286.038018) (xy 458.560126 -286.05749)
			(xy 458.508164 -286.06935) (xy 458.455014 -286.073334) (xy 458.401864 -286.06935) (xy 458.349902 -286.05749)
			(xy 458.300288 -286.038018) (xy 458.25413 -286.011369) (xy 458.212459 -285.978138) (xy 458.176207 -285.939067)
			(xy 458.146183 -285.89503) (xy 458.123057 -285.847009) (xy 458.107347 -285.796079) (xy 458.099404 -285.743375)
			(xy 455.366892 -285.743375) (xy 455.358949 -285.796079) (xy 455.343239 -285.847009) (xy 455.320113 -285.89503)
			(xy 455.290089 -285.939067) (xy 455.253837 -285.978138) (xy 455.212166 -286.011369) (xy 455.166008 -286.038018)
			(xy 455.116394 -286.05749) (xy 455.064432 -286.06935) (xy 455.011282 -286.073334) (xy 454.958132 -286.06935)
			(xy 454.90617 -286.05749) (xy 454.856556 -286.038018) (xy 454.810398 -286.011369) (xy 454.768727 -285.978138)
			(xy 454.732475 -285.939067) (xy 454.702451 -285.89503) (xy 454.679325 -285.847009) (xy 454.663615 -285.796079)
			(xy 454.655672 -285.743375) (xy 453.476624 -285.743375) (xy 453.468681 -285.796079) (xy 453.452971 -285.847009)
			(xy 453.429845 -285.89503) (xy 453.399821 -285.939067) (xy 453.363569 -285.978138) (xy 453.321898 -286.011369)
			(xy 453.27574 -286.038018) (xy 453.226126 -286.05749) (xy 453.174164 -286.06935) (xy 453.121014 -286.073334)
			(xy 453.067864 -286.06935) (xy 453.015902 -286.05749) (xy 452.966288 -286.038018) (xy 452.92013 -286.011369)
			(xy 452.878459 -285.978138) (xy 452.842207 -285.939067) (xy 452.812183 -285.89503) (xy 452.789057 -285.847009)
			(xy 452.773347 -285.796079) (xy 452.765404 -285.743375) (xy 451.266824 -285.743375) (xy 451.258881 -285.796079)
			(xy 451.243171 -285.847009) (xy 451.220045 -285.89503) (xy 451.190021 -285.939067) (xy 451.153769 -285.978138)
			(xy 451.112098 -286.011369) (xy 451.06594 -286.038018) (xy 451.016326 -286.05749) (xy 450.964364 -286.06935)
			(xy 450.911214 -286.073334) (xy 450.858064 -286.06935) (xy 450.806102 -286.05749) (xy 450.756488 -286.038018)
			(xy 450.71033 -286.011369) (xy 450.668659 -285.978138) (xy 450.632407 -285.939067) (xy 450.602383 -285.89503)
			(xy 450.579257 -285.847009) (xy 450.563547 -285.796079) (xy 450.555604 -285.743375) (xy 449.793868 -285.743375)
			(xy 449.793868 -286.228536) (xy 449.82384 -286.241998) (xy 449.848455 -286.253679) (xy 449.894118 -286.283397)
			(xy 449.934722 -286.319724) (xy 449.969319 -286.36181) (xy 449.997103 -286.408676) (xy 450.017425 -286.459226)
			(xy 450.02981 -286.512281) (xy 450.033971 -286.566604) (xy 450.031929 -286.593259) (xy 450.555604 -286.593259)
			(xy 450.555604 -286.539961) (xy 450.563547 -286.487257) (xy 450.579257 -286.436327) (xy 450.602383 -286.388306)
			(xy 450.632407 -286.344269) (xy 450.668659 -286.305198) (xy 450.71033 -286.271967) (xy 450.756488 -286.245318)
			(xy 450.806102 -286.225846) (xy 450.858064 -286.213986) (xy 450.911214 -286.210003) (xy 450.964364 -286.213986)
			(xy 451.016326 -286.225846) (xy 451.06594 -286.245318) (xy 451.112098 -286.271967) (xy 451.153769 -286.305198)
			(xy 451.190021 -286.344269) (xy 451.220045 -286.388306) (xy 451.243171 -286.436327) (xy 451.258881 -286.487257)
			(xy 451.266824 -286.539961) (xy 451.267322 -286.56661) (xy 451.266824 -286.593259) (xy 454.655672 -286.593259)
			(xy 454.655672 -286.539961) (xy 454.663615 -286.487257) (xy 454.679325 -286.436327) (xy 454.702451 -286.388306)
			(xy 454.732475 -286.344269) (xy 454.768727 -286.305198) (xy 454.810398 -286.271967) (xy 454.856556 -286.245318)
			(xy 454.90617 -286.225846) (xy 454.958132 -286.213986) (xy 455.011282 -286.210003) (xy 455.064432 -286.213986)
			(xy 455.116394 -286.225846) (xy 455.166008 -286.245318) (xy 455.212166 -286.271967) (xy 455.253837 -286.305198)
			(xy 455.290089 -286.344269) (xy 455.320113 -286.388306) (xy 455.343239 -286.436327) (xy 455.358949 -286.487257)
			(xy 455.366892 -286.539961) (xy 455.36739 -286.56661) (xy 455.366892 -286.593259) (xy 456.865472 -286.593259)
			(xy 456.865472 -286.539961) (xy 456.873415 -286.487257) (xy 456.889125 -286.436327) (xy 456.912251 -286.388306)
			(xy 456.942275 -286.344269) (xy 456.978527 -286.305198) (xy 457.020198 -286.271967) (xy 457.066356 -286.245318)
			(xy 457.11597 -286.225846) (xy 457.167932 -286.213986) (xy 457.221082 -286.210003) (xy 457.274232 -286.213986)
			(xy 457.326194 -286.225846) (xy 457.375808 -286.245318) (xy 457.421966 -286.271967) (xy 457.463637 -286.305198)
			(xy 457.499889 -286.344269) (xy 457.529913 -286.388306) (xy 457.553039 -286.436327) (xy 457.568749 -286.487257)
			(xy 457.576692 -286.539961) (xy 457.57719 -286.56661) (xy 457.576692 -286.593259) (xy 457.568749 -286.645963)
			(xy 457.553039 -286.696893) (xy 457.529913 -286.744914) (xy 457.499889 -286.788951) (xy 457.463637 -286.828022)
			(xy 457.421966 -286.861253) (xy 457.375808 -286.887902) (xy 457.326194 -286.907374) (xy 457.274232 -286.919234)
			(xy 457.221082 -286.923218) (xy 457.167932 -286.919234) (xy 457.11597 -286.907374) (xy 457.066356 -286.887902)
			(xy 457.020198 -286.861253) (xy 456.978527 -286.828022) (xy 456.942275 -286.788951) (xy 456.912251 -286.744914)
			(xy 456.889125 -286.696893) (xy 456.873415 -286.645963) (xy 456.865472 -286.593259) (xy 455.366892 -286.593259)
			(xy 455.358949 -286.645963) (xy 455.343239 -286.696893) (xy 455.320113 -286.744914) (xy 455.290089 -286.788951)
			(xy 455.253837 -286.828022) (xy 455.212166 -286.861253) (xy 455.166008 -286.887902) (xy 455.116394 -286.907374)
			(xy 455.064432 -286.919234) (xy 455.011282 -286.923218) (xy 454.958132 -286.919234) (xy 454.90617 -286.907374)
			(xy 454.856556 -286.887902) (xy 454.810398 -286.861253) (xy 454.768727 -286.828022) (xy 454.732475 -286.788951)
			(xy 454.702451 -286.744914) (xy 454.679325 -286.696893) (xy 454.663615 -286.645963) (xy 454.655672 -286.593259)
			(xy 451.266824 -286.593259) (xy 451.258881 -286.645963) (xy 451.243171 -286.696893) (xy 451.220045 -286.744914)
			(xy 451.190021 -286.788951) (xy 451.153769 -286.828022) (xy 451.112098 -286.861253) (xy 451.06594 -286.887902)
			(xy 451.016326 -286.907374) (xy 450.964364 -286.919234) (xy 450.911214 -286.923218) (xy 450.858064 -286.919234)
			(xy 450.806102 -286.907374) (xy 450.756488 -286.887902) (xy 450.71033 -286.861253) (xy 450.668659 -286.828022)
			(xy 450.632407 -286.788951) (xy 450.602383 -286.744914) (xy 450.579257 -286.696893) (xy 450.563547 -286.645963)
			(xy 450.555604 -286.593259) (xy 450.031929 -286.593259) (xy 450.029809 -286.620927) (xy 450.017422 -286.673982)
			(xy 449.997099 -286.724532) (xy 449.969314 -286.771396) (xy 449.934716 -286.813482) (xy 449.894111 -286.849808)
			(xy 449.848448 -286.879525) (xy 449.82384 -286.891222) (xy 449.793868 -286.904684) (xy 449.793868 -287.443397)
			(xy 450.555604 -287.443397) (xy 450.555604 -287.390099) (xy 450.563547 -287.337395) (xy 450.579257 -287.286465)
			(xy 450.602383 -287.238444) (xy 450.632407 -287.194407) (xy 450.668659 -287.155336) (xy 450.71033 -287.122105)
			(xy 450.756488 -287.095456) (xy 450.806102 -287.075984) (xy 450.858064 -287.064124) (xy 450.911214 -287.060141)
			(xy 450.964364 -287.064124) (xy 451.016326 -287.075984) (xy 451.06594 -287.095456) (xy 451.112098 -287.122105)
			(xy 451.153769 -287.155336) (xy 451.190021 -287.194407) (xy 451.220045 -287.238444) (xy 451.243171 -287.286465)
			(xy 451.258881 -287.337395) (xy 451.266824 -287.390099) (xy 451.267322 -287.416748) (xy 451.266824 -287.443397)
			(xy 452.765404 -287.443397) (xy 452.765404 -287.390099) (xy 452.773347 -287.337395) (xy 452.789057 -287.286465)
			(xy 452.812183 -287.238444) (xy 452.842207 -287.194407) (xy 452.878459 -287.155336) (xy 452.92013 -287.122105)
			(xy 452.966288 -287.095456) (xy 453.015902 -287.075984) (xy 453.067864 -287.064124) (xy 453.121014 -287.060141)
			(xy 453.174164 -287.064124) (xy 453.226126 -287.075984) (xy 453.27574 -287.095456) (xy 453.321898 -287.122105)
			(xy 453.363569 -287.155336) (xy 453.399821 -287.194407) (xy 453.429845 -287.238444) (xy 453.452971 -287.286465)
			(xy 453.468681 -287.337395) (xy 453.476624 -287.390099) (xy 453.477122 -287.416748) (xy 453.476624 -287.443397)
			(xy 454.655672 -287.443397) (xy 454.655672 -287.390099) (xy 454.663615 -287.337395) (xy 454.679325 -287.286465)
			(xy 454.702451 -287.238444) (xy 454.732475 -287.194407) (xy 454.768727 -287.155336) (xy 454.810398 -287.122105)
			(xy 454.856556 -287.095456) (xy 454.90617 -287.075984) (xy 454.958132 -287.064124) (xy 455.011282 -287.060141)
			(xy 455.064432 -287.064124) (xy 455.116394 -287.075984) (xy 455.166008 -287.095456) (xy 455.212166 -287.122105)
			(xy 455.253837 -287.155336) (xy 455.290089 -287.194407) (xy 455.320113 -287.238444) (xy 455.343239 -287.286465)
			(xy 455.358949 -287.337395) (xy 455.366892 -287.390099) (xy 455.36739 -287.416748) (xy 455.366892 -287.443397)
			(xy 458.099404 -287.443397) (xy 458.099404 -287.390099) (xy 458.107347 -287.337395) (xy 458.123057 -287.286465)
			(xy 458.146183 -287.238444) (xy 458.176207 -287.194407) (xy 458.212459 -287.155336) (xy 458.25413 -287.122105)
			(xy 458.300288 -287.095456) (xy 458.349902 -287.075984) (xy 458.401864 -287.064124) (xy 458.455014 -287.060141)
			(xy 458.508164 -287.064124) (xy 458.560126 -287.075984) (xy 458.60974 -287.095456) (xy 458.655898 -287.122105)
			(xy 458.697569 -287.155336) (xy 458.733821 -287.194407) (xy 458.763845 -287.238444) (xy 458.786971 -287.286465)
			(xy 458.802681 -287.337395) (xy 458.810624 -287.390099) (xy 458.811122 -287.416748) (xy 458.810624 -287.443397)
			(xy 458.802681 -287.496101) (xy 458.786971 -287.547031) (xy 458.763845 -287.595052) (xy 458.733821 -287.639089)
			(xy 458.697569 -287.67816) (xy 458.655898 -287.711391) (xy 458.60974 -287.73804) (xy 458.560126 -287.757512)
			(xy 458.508164 -287.769372) (xy 458.455014 -287.773356) (xy 458.401864 -287.769372) (xy 458.349902 -287.757512)
			(xy 458.300288 -287.73804) (xy 458.25413 -287.711391) (xy 458.212459 -287.67816) (xy 458.176207 -287.639089)
			(xy 458.146183 -287.595052) (xy 458.123057 -287.547031) (xy 458.107347 -287.496101) (xy 458.099404 -287.443397)
			(xy 455.366892 -287.443397) (xy 455.358949 -287.496101) (xy 455.343239 -287.547031) (xy 455.320113 -287.595052)
			(xy 455.290089 -287.639089) (xy 455.253837 -287.67816) (xy 455.212166 -287.711391) (xy 455.166008 -287.73804)
			(xy 455.116394 -287.757512) (xy 455.064432 -287.769372) (xy 455.011282 -287.773356) (xy 454.958132 -287.769372)
			(xy 454.90617 -287.757512) (xy 454.856556 -287.73804) (xy 454.810398 -287.711391) (xy 454.768727 -287.67816)
			(xy 454.732475 -287.639089) (xy 454.702451 -287.595052) (xy 454.679325 -287.547031) (xy 454.663615 -287.496101)
			(xy 454.655672 -287.443397) (xy 453.476624 -287.443397) (xy 453.468681 -287.496101) (xy 453.452971 -287.547031)
			(xy 453.429845 -287.595052) (xy 453.399821 -287.639089) (xy 453.363569 -287.67816) (xy 453.321898 -287.711391)
			(xy 453.27574 -287.73804) (xy 453.226126 -287.757512) (xy 453.174164 -287.769372) (xy 453.121014 -287.773356)
			(xy 453.067864 -287.769372) (xy 453.015902 -287.757512) (xy 452.966288 -287.73804) (xy 452.92013 -287.711391)
			(xy 452.878459 -287.67816) (xy 452.842207 -287.639089) (xy 452.812183 -287.595052) (xy 452.789057 -287.547031)
			(xy 452.773347 -287.496101) (xy 452.765404 -287.443397) (xy 451.266824 -287.443397) (xy 451.258881 -287.496101)
			(xy 451.243171 -287.547031) (xy 451.220045 -287.595052) (xy 451.190021 -287.639089) (xy 451.153769 -287.67816)
			(xy 451.112098 -287.711391) (xy 451.06594 -287.73804) (xy 451.016326 -287.757512) (xy 450.964364 -287.769372)
			(xy 450.911214 -287.773356) (xy 450.858064 -287.769372) (xy 450.806102 -287.757512) (xy 450.756488 -287.73804)
			(xy 450.71033 -287.711391) (xy 450.668659 -287.67816) (xy 450.632407 -287.639089) (xy 450.602383 -287.595052)
			(xy 450.579257 -287.547031) (xy 450.563547 -287.496101) (xy 450.555604 -287.443397) (xy 449.793868 -287.443397)
			(xy 449.793868 -287.928558) (xy 449.82384 -287.94202) (xy 449.848453 -287.9537) (xy 449.894113 -287.983418)
			(xy 449.934714 -288.019744) (xy 449.969308 -288.061829) (xy 449.997089 -288.108693) (xy 450.017408 -288.15924)
			(xy 450.029792 -288.212293) (xy 450.033951 -288.266613) (xy 450.031907 -288.293281) (xy 450.555604 -288.293281)
			(xy 450.555604 -288.239983) (xy 450.563547 -288.187279) (xy 450.579257 -288.136349) (xy 450.602383 -288.088328)
			(xy 450.632407 -288.044291) (xy 450.668659 -288.00522) (xy 450.71033 -287.971989) (xy 450.756488 -287.94534)
			(xy 450.806102 -287.925868) (xy 450.858064 -287.914008) (xy 450.911214 -287.910025) (xy 450.964364 -287.914008)
			(xy 451.016326 -287.925868) (xy 451.06594 -287.94534) (xy 451.112098 -287.971989) (xy 451.153769 -288.00522)
			(xy 451.190021 -288.044291) (xy 451.220045 -288.088328) (xy 451.243171 -288.136349) (xy 451.258881 -288.187279)
			(xy 451.266824 -288.239983) (xy 451.267322 -288.266632) (xy 451.266824 -288.293281) (xy 454.655672 -288.293281)
			(xy 454.655672 -288.239983) (xy 454.663615 -288.187279) (xy 454.679325 -288.136349) (xy 454.702451 -288.088328)
			(xy 454.732475 -288.044291) (xy 454.768727 -288.00522) (xy 454.810398 -287.971989) (xy 454.856556 -287.94534)
			(xy 454.90617 -287.925868) (xy 454.958132 -287.914008) (xy 455.011282 -287.910025) (xy 455.064432 -287.914008)
			(xy 455.116394 -287.925868) (xy 455.166008 -287.94534) (xy 455.212166 -287.971989) (xy 455.253837 -288.00522)
			(xy 455.290089 -288.044291) (xy 455.320113 -288.088328) (xy 455.343239 -288.136349) (xy 455.358949 -288.187279)
			(xy 455.366892 -288.239983) (xy 455.36739 -288.266632) (xy 455.366892 -288.293281) (xy 456.865472 -288.293281)
			(xy 456.865472 -288.239983) (xy 456.873415 -288.187279) (xy 456.889125 -288.136349) (xy 456.912251 -288.088328)
			(xy 456.942275 -288.044291) (xy 456.978527 -288.00522) (xy 457.020198 -287.971989) (xy 457.066356 -287.94534)
			(xy 457.11597 -287.925868) (xy 457.167932 -287.914008) (xy 457.221082 -287.910025) (xy 457.274232 -287.914008)
			(xy 457.326194 -287.925868) (xy 457.375808 -287.94534) (xy 457.421966 -287.971989) (xy 457.463637 -288.00522)
			(xy 457.499889 -288.044291) (xy 457.529913 -288.088328) (xy 457.553039 -288.136349) (xy 457.568749 -288.187279)
			(xy 457.576692 -288.239983) (xy 457.57719 -288.266632) (xy 457.576692 -288.293281) (xy 457.568749 -288.345985)
			(xy 457.553039 -288.396915) (xy 457.529913 -288.444936) (xy 457.499889 -288.488973) (xy 457.463637 -288.528044)
			(xy 457.421966 -288.561275) (xy 457.375808 -288.587924) (xy 457.326194 -288.607396) (xy 457.274232 -288.619256)
			(xy 457.221082 -288.62324) (xy 457.167932 -288.619256) (xy 457.11597 -288.607396) (xy 457.066356 -288.587924)
			(xy 457.020198 -288.561275) (xy 456.978527 -288.528044) (xy 456.942275 -288.488973) (xy 456.912251 -288.444936)
			(xy 456.889125 -288.396915) (xy 456.873415 -288.345985) (xy 456.865472 -288.293281) (xy 455.366892 -288.293281)
			(xy 455.358949 -288.345985) (xy 455.343239 -288.396915) (xy 455.320113 -288.444936) (xy 455.290089 -288.488973)
			(xy 455.253837 -288.528044) (xy 455.212166 -288.561275) (xy 455.166008 -288.587924) (xy 455.116394 -288.607396)
			(xy 455.064432 -288.619256) (xy 455.011282 -288.62324) (xy 454.958132 -288.619256) (xy 454.90617 -288.607396)
			(xy 454.856556 -288.587924) (xy 454.810398 -288.561275) (xy 454.768727 -288.528044) (xy 454.732475 -288.488973)
			(xy 454.702451 -288.444936) (xy 454.679325 -288.396915) (xy 454.663615 -288.345985) (xy 454.655672 -288.293281)
			(xy 451.266824 -288.293281) (xy 451.258881 -288.345985) (xy 451.243171 -288.396915) (xy 451.220045 -288.444936)
			(xy 451.190021 -288.488973) (xy 451.153769 -288.528044) (xy 451.112098 -288.561275) (xy 451.06594 -288.587924)
			(xy 451.016326 -288.607396) (xy 450.964364 -288.619256) (xy 450.911214 -288.62324) (xy 450.858064 -288.619256)
			(xy 450.806102 -288.607396) (xy 450.756488 -288.587924) (xy 450.71033 -288.561275) (xy 450.668659 -288.528044)
			(xy 450.632407 -288.488973) (xy 450.602383 -288.444936) (xy 450.579257 -288.396915) (xy 450.563547 -288.345985)
			(xy 450.555604 -288.293281) (xy 450.031907 -288.293281) (xy 450.029788 -288.320933) (xy 450.0174 -288.373985)
			(xy 449.997077 -288.424531) (xy 449.969293 -288.471392) (xy 449.934695 -288.513475) (xy 449.894092 -288.549798)
			(xy 449.84843 -288.579512) (xy 449.82384 -288.591244) (xy 449.793868 -288.604706) (xy 449.793868 -289.143419)
			(xy 450.555604 -289.143419) (xy 450.555604 -289.090121) (xy 450.563547 -289.037417) (xy 450.579257 -288.986487)
			(xy 450.602383 -288.938466) (xy 450.632407 -288.894429) (xy 450.668659 -288.855358) (xy 450.71033 -288.822127)
			(xy 450.756488 -288.795478) (xy 450.806102 -288.776006) (xy 450.858064 -288.764146) (xy 450.911214 -288.760163)
			(xy 450.964364 -288.764146) (xy 451.016326 -288.776006) (xy 451.06594 -288.795478) (xy 451.112098 -288.822127)
			(xy 451.153769 -288.855358) (xy 451.190021 -288.894429) (xy 451.220045 -288.938466) (xy 451.243171 -288.986487)
			(xy 451.258881 -289.037417) (xy 451.266824 -289.090121) (xy 451.267322 -289.11677) (xy 451.266824 -289.143419)
			(xy 452.765404 -289.143419) (xy 452.765404 -289.090121) (xy 452.773347 -289.037417) (xy 452.789057 -288.986487)
			(xy 452.812183 -288.938466) (xy 452.842207 -288.894429) (xy 452.878459 -288.855358) (xy 452.92013 -288.822127)
			(xy 452.966288 -288.795478) (xy 453.015902 -288.776006) (xy 453.067864 -288.764146) (xy 453.121014 -288.760163)
			(xy 453.174164 -288.764146) (xy 453.226126 -288.776006) (xy 453.27574 -288.795478) (xy 453.321898 -288.822127)
			(xy 453.363569 -288.855358) (xy 453.399821 -288.894429) (xy 453.429845 -288.938466) (xy 453.452971 -288.986487)
			(xy 453.468681 -289.037417) (xy 453.476624 -289.090121) (xy 453.477122 -289.11677) (xy 453.476624 -289.143419)
			(xy 454.655672 -289.143419) (xy 454.655672 -289.090121) (xy 454.663615 -289.037417) (xy 454.679325 -288.986487)
			(xy 454.702451 -288.938466) (xy 454.732475 -288.894429) (xy 454.768727 -288.855358) (xy 454.810398 -288.822127)
			(xy 454.856556 -288.795478) (xy 454.90617 -288.776006) (xy 454.958132 -288.764146) (xy 455.011282 -288.760163)
			(xy 455.064432 -288.764146) (xy 455.116394 -288.776006) (xy 455.166008 -288.795478) (xy 455.212166 -288.822127)
			(xy 455.253837 -288.855358) (xy 455.290089 -288.894429) (xy 455.320113 -288.938466) (xy 455.343239 -288.986487)
			(xy 455.358949 -289.037417) (xy 455.366892 -289.090121) (xy 455.36739 -289.11677) (xy 455.366892 -289.143419)
			(xy 458.099404 -289.143419) (xy 458.099404 -289.090121) (xy 458.107347 -289.037417) (xy 458.123057 -288.986487)
			(xy 458.146183 -288.938466) (xy 458.176207 -288.894429) (xy 458.212459 -288.855358) (xy 458.25413 -288.822127)
			(xy 458.300288 -288.795478) (xy 458.349902 -288.776006) (xy 458.401864 -288.764146) (xy 458.455014 -288.760163)
			(xy 458.508164 -288.764146) (xy 458.560126 -288.776006) (xy 458.60974 -288.795478) (xy 458.655898 -288.822127)
			(xy 458.697569 -288.855358) (xy 458.733821 -288.894429) (xy 458.763845 -288.938466) (xy 458.786971 -288.986487)
			(xy 458.802681 -289.037417) (xy 458.810624 -289.090121) (xy 458.811122 -289.11677) (xy 458.810624 -289.143419)
			(xy 458.802681 -289.196123) (xy 458.786971 -289.247053) (xy 458.763845 -289.295074) (xy 458.733821 -289.339111)
			(xy 458.697569 -289.378182) (xy 458.655898 -289.411413) (xy 458.60974 -289.438062) (xy 458.560126 -289.457534)
			(xy 458.508164 -289.469394) (xy 458.455014 -289.473378) (xy 458.401864 -289.469394) (xy 458.349902 -289.457534)
			(xy 458.300288 -289.438062) (xy 458.25413 -289.411413) (xy 458.212459 -289.378182) (xy 458.176207 -289.339111)
			(xy 458.146183 -289.295074) (xy 458.123057 -289.247053) (xy 458.107347 -289.196123) (xy 458.099404 -289.143419)
			(xy 455.366892 -289.143419) (xy 455.358949 -289.196123) (xy 455.343239 -289.247053) (xy 455.320113 -289.295074)
			(xy 455.290089 -289.339111) (xy 455.253837 -289.378182) (xy 455.212166 -289.411413) (xy 455.166008 -289.438062)
			(xy 455.116394 -289.457534) (xy 455.064432 -289.469394) (xy 455.011282 -289.473378) (xy 454.958132 -289.469394)
			(xy 454.90617 -289.457534) (xy 454.856556 -289.438062) (xy 454.810398 -289.411413) (xy 454.768727 -289.378182)
			(xy 454.732475 -289.339111) (xy 454.702451 -289.295074) (xy 454.679325 -289.247053) (xy 454.663615 -289.196123)
			(xy 454.655672 -289.143419) (xy 453.476624 -289.143419) (xy 453.468681 -289.196123) (xy 453.452971 -289.247053)
			(xy 453.429845 -289.295074) (xy 453.399821 -289.339111) (xy 453.363569 -289.378182) (xy 453.321898 -289.411413)
			(xy 453.27574 -289.438062) (xy 453.226126 -289.457534) (xy 453.174164 -289.469394) (xy 453.121014 -289.473378)
			(xy 453.067864 -289.469394) (xy 453.015902 -289.457534) (xy 452.966288 -289.438062) (xy 452.92013 -289.411413)
			(xy 452.878459 -289.378182) (xy 452.842207 -289.339111) (xy 452.812183 -289.295074) (xy 452.789057 -289.247053)
			(xy 452.773347 -289.196123) (xy 452.765404 -289.143419) (xy 451.266824 -289.143419) (xy 451.258881 -289.196123)
			(xy 451.243171 -289.247053) (xy 451.220045 -289.295074) (xy 451.190021 -289.339111) (xy 451.153769 -289.378182)
			(xy 451.112098 -289.411413) (xy 451.06594 -289.438062) (xy 451.016326 -289.457534) (xy 450.964364 -289.469394)
			(xy 450.911214 -289.473378) (xy 450.858064 -289.469394) (xy 450.806102 -289.457534) (xy 450.756488 -289.438062)
			(xy 450.71033 -289.411413) (xy 450.668659 -289.378182) (xy 450.632407 -289.339111) (xy 450.602383 -289.295074)
			(xy 450.579257 -289.247053) (xy 450.563547 -289.196123) (xy 450.555604 -289.143419) (xy 449.793868 -289.143419)
			(xy 449.793868 -289.62858) (xy 449.82384 -289.642042) (xy 449.848459 -289.653723) (xy 449.894131 -289.683442)
			(xy 449.934743 -289.719772) (xy 449.969348 -289.761862) (xy 449.997138 -289.808732) (xy 450.017466 -289.859288)
			(xy 450.029857 -289.912351) (xy 450.034022 -289.966681) (xy 450.031984 -289.993303) (xy 450.555604 -289.993303)
			(xy 450.555604 -289.940005) (xy 450.563547 -289.887301) (xy 450.579257 -289.836371) (xy 450.602383 -289.78835)
			(xy 450.632407 -289.744313) (xy 450.668659 -289.705242) (xy 450.71033 -289.672011) (xy 450.756488 -289.645362)
			(xy 450.806102 -289.62589) (xy 450.858064 -289.61403) (xy 450.911214 -289.610047) (xy 450.964364 -289.61403)
			(xy 451.016326 -289.62589) (xy 451.06594 -289.645362) (xy 451.112098 -289.672011) (xy 451.153769 -289.705242)
			(xy 451.190021 -289.744313) (xy 451.220045 -289.78835) (xy 451.243171 -289.836371) (xy 451.258881 -289.887301)
			(xy 451.266824 -289.940005) (xy 451.267322 -289.966654) (xy 451.266824 -289.993303) (xy 454.655672 -289.993303)
			(xy 454.655672 -289.940005) (xy 454.663615 -289.887301) (xy 454.679325 -289.836371) (xy 454.702451 -289.78835)
			(xy 454.732475 -289.744313) (xy 454.768727 -289.705242) (xy 454.810398 -289.672011) (xy 454.856556 -289.645362)
			(xy 454.90617 -289.62589) (xy 454.958132 -289.61403) (xy 455.011282 -289.610047) (xy 455.064432 -289.61403)
			(xy 455.116394 -289.62589) (xy 455.166008 -289.645362) (xy 455.212166 -289.672011) (xy 455.253837 -289.705242)
			(xy 455.290089 -289.744313) (xy 455.320113 -289.78835) (xy 455.343239 -289.836371) (xy 455.358949 -289.887301)
			(xy 455.366892 -289.940005) (xy 455.36739 -289.966654) (xy 455.366892 -289.993303) (xy 456.865472 -289.993303)
			(xy 456.865472 -289.940005) (xy 456.873415 -289.887301) (xy 456.889125 -289.836371) (xy 456.912251 -289.78835)
			(xy 456.942275 -289.744313) (xy 456.978527 -289.705242) (xy 457.020198 -289.672011) (xy 457.066356 -289.645362)
			(xy 457.11597 -289.62589) (xy 457.167932 -289.61403) (xy 457.221082 -289.610047) (xy 457.274232 -289.61403)
			(xy 457.326194 -289.62589) (xy 457.375808 -289.645362) (xy 457.421966 -289.672011) (xy 457.463637 -289.705242)
			(xy 457.499889 -289.744313) (xy 457.529913 -289.78835) (xy 457.553039 -289.836371) (xy 457.568749 -289.887301)
			(xy 457.576692 -289.940005) (xy 457.57719 -289.966654) (xy 457.576692 -289.993303) (xy 457.568749 -290.046007)
			(xy 457.553039 -290.096937) (xy 457.529913 -290.144958) (xy 457.499889 -290.188995) (xy 457.463637 -290.228066)
			(xy 457.421966 -290.261297) (xy 457.375808 -290.287946) (xy 457.326194 -290.307418) (xy 457.274232 -290.319278)
			(xy 457.221082 -290.323262) (xy 457.167932 -290.319278) (xy 457.11597 -290.307418) (xy 457.066356 -290.287946)
			(xy 457.020198 -290.261297) (xy 456.978527 -290.228066) (xy 456.942275 -290.188995) (xy 456.912251 -290.144958)
			(xy 456.889125 -290.096937) (xy 456.873415 -290.046007) (xy 456.865472 -289.993303) (xy 455.366892 -289.993303)
			(xy 455.358949 -290.046007) (xy 455.343239 -290.096937) (xy 455.320113 -290.144958) (xy 455.290089 -290.188995)
			(xy 455.253837 -290.228066) (xy 455.212166 -290.261297) (xy 455.166008 -290.287946) (xy 455.116394 -290.307418)
			(xy 455.064432 -290.319278) (xy 455.011282 -290.323262) (xy 454.958132 -290.319278) (xy 454.90617 -290.307418)
			(xy 454.856556 -290.287946) (xy 454.810398 -290.261297) (xy 454.768727 -290.228066) (xy 454.732475 -290.188995)
			(xy 454.702451 -290.144958) (xy 454.679325 -290.096937) (xy 454.663615 -290.046007) (xy 454.655672 -289.993303)
			(xy 451.266824 -289.993303) (xy 451.258881 -290.046007) (xy 451.243171 -290.096937) (xy 451.220045 -290.144958)
			(xy 451.190021 -290.188995) (xy 451.153769 -290.228066) (xy 451.112098 -290.261297) (xy 451.06594 -290.287946)
			(xy 451.016326 -290.307418) (xy 450.964364 -290.319278) (xy 450.911214 -290.323262) (xy 450.858064 -290.319278)
			(xy 450.806102 -290.307418) (xy 450.756488 -290.287946) (xy 450.71033 -290.261297) (xy 450.668659 -290.228066)
			(xy 450.632407 -290.188995) (xy 450.602383 -290.144958) (xy 450.579257 -290.096937) (xy 450.563547 -290.046007)
			(xy 450.555604 -289.993303) (xy 450.031984 -289.993303) (xy 450.029863 -290.021012) (xy 450.017478 -290.074075)
			(xy 449.997155 -290.124634) (xy 449.969369 -290.171507) (xy 449.934769 -290.213601) (xy 449.894161 -290.249934)
			(xy 449.848493 -290.279659) (xy 449.82384 -290.291266) (xy 449.793868 -290.304728) (xy 449.793868 -290.843441)
			(xy 450.555604 -290.843441) (xy 450.555604 -290.790143) (xy 450.563547 -290.737439) (xy 450.579257 -290.686509)
			(xy 450.602383 -290.638488) (xy 450.632407 -290.594451) (xy 450.668659 -290.55538) (xy 450.71033 -290.522149)
			(xy 450.756488 -290.4955) (xy 450.806102 -290.476028) (xy 450.858064 -290.464168) (xy 450.911214 -290.460185)
			(xy 450.964364 -290.464168) (xy 451.016326 -290.476028) (xy 451.06594 -290.4955) (xy 451.112098 -290.522149)
			(xy 451.153769 -290.55538) (xy 451.190021 -290.594451) (xy 451.220045 -290.638488) (xy 451.243171 -290.686509)
			(xy 451.258881 -290.737439) (xy 451.266824 -290.790143) (xy 451.267322 -290.816792) (xy 451.266824 -290.843441)
			(xy 452.765404 -290.843441) (xy 452.765404 -290.790143) (xy 452.773347 -290.737439) (xy 452.789057 -290.686509)
			(xy 452.812183 -290.638488) (xy 452.842207 -290.594451) (xy 452.878459 -290.55538) (xy 452.92013 -290.522149)
			(xy 452.966288 -290.4955) (xy 453.015902 -290.476028) (xy 453.067864 -290.464168) (xy 453.121014 -290.460185)
			(xy 453.174164 -290.464168) (xy 453.226126 -290.476028) (xy 453.27574 -290.4955) (xy 453.321898 -290.522149)
			(xy 453.363569 -290.55538) (xy 453.399821 -290.594451) (xy 453.429845 -290.638488) (xy 453.452971 -290.686509)
			(xy 453.468681 -290.737439) (xy 453.476624 -290.790143) (xy 453.477122 -290.816792) (xy 453.476629 -290.843187)
			(xy 454.655672 -290.843187) (xy 454.655672 -290.789889) (xy 454.663615 -290.737185) (xy 454.679325 -290.686255)
			(xy 454.702451 -290.638234) (xy 454.732475 -290.594197) (xy 454.768727 -290.555126) (xy 454.810398 -290.521895)
			(xy 454.856556 -290.495246) (xy 454.90617 -290.475774) (xy 454.958132 -290.463914) (xy 455.011282 -290.459931)
			(xy 455.064432 -290.463914) (xy 455.116394 -290.475774) (xy 455.166008 -290.495246) (xy 455.212166 -290.521895)
			(xy 455.253837 -290.555126) (xy 455.290089 -290.594197) (xy 455.320113 -290.638234) (xy 455.343239 -290.686255)
			(xy 455.358949 -290.737185) (xy 455.366892 -290.789889) (xy 455.36739 -290.816538) (xy 455.366892 -290.843187)
			(xy 455.366854 -290.843441) (xy 458.099404 -290.843441) (xy 458.099404 -290.790143) (xy 458.107347 -290.737439)
			(xy 458.123057 -290.686509) (xy 458.146183 -290.638488) (xy 458.176207 -290.594451) (xy 458.212459 -290.55538)
			(xy 458.25413 -290.522149) (xy 458.300288 -290.4955) (xy 458.349902 -290.476028) (xy 458.401864 -290.464168)
			(xy 458.455014 -290.460185) (xy 458.508164 -290.464168) (xy 458.560126 -290.476028) (xy 458.60974 -290.4955)
			(xy 458.655898 -290.522149) (xy 458.697569 -290.55538) (xy 458.733821 -290.594451) (xy 458.763845 -290.638488)
			(xy 458.786971 -290.686509) (xy 458.802681 -290.737439) (xy 458.810624 -290.790143) (xy 458.811122 -290.816792)
			(xy 458.810624 -290.843441) (xy 458.802681 -290.896145) (xy 458.786971 -290.947075) (xy 458.763845 -290.995096)
			(xy 458.733821 -291.039133) (xy 458.697569 -291.078204) (xy 458.655898 -291.111435) (xy 458.60974 -291.138084)
			(xy 458.560126 -291.157556) (xy 458.508164 -291.169416) (xy 458.455014 -291.1734) (xy 458.401864 -291.169416)
			(xy 458.349902 -291.157556) (xy 458.300288 -291.138084) (xy 458.25413 -291.111435) (xy 458.212459 -291.078204)
			(xy 458.176207 -291.039133) (xy 458.146183 -290.995096) (xy 458.123057 -290.947075) (xy 458.107347 -290.896145)
			(xy 458.099404 -290.843441) (xy 455.366854 -290.843441) (xy 455.358949 -290.895891) (xy 455.343239 -290.946821)
			(xy 455.320113 -290.994842) (xy 455.290089 -291.038879) (xy 455.253837 -291.07795) (xy 455.212166 -291.111181)
			(xy 455.166008 -291.13783) (xy 455.116394 -291.157302) (xy 455.064432 -291.169162) (xy 455.011282 -291.173146)
			(xy 454.958132 -291.169162) (xy 454.90617 -291.157302) (xy 454.856556 -291.13783) (xy 454.810398 -291.111181)
			(xy 454.768727 -291.07795) (xy 454.732475 -291.038879) (xy 454.702451 -290.994842) (xy 454.679325 -290.946821)
			(xy 454.663615 -290.895891) (xy 454.655672 -290.843187) (xy 453.476629 -290.843187) (xy 453.476624 -290.843441)
			(xy 453.468681 -290.896145) (xy 453.452971 -290.947075) (xy 453.429845 -290.995096) (xy 453.399821 -291.039133)
			(xy 453.363569 -291.078204) (xy 453.321898 -291.111435) (xy 453.27574 -291.138084) (xy 453.226126 -291.157556)
			(xy 453.174164 -291.169416) (xy 453.121014 -291.1734) (xy 453.067864 -291.169416) (xy 453.015902 -291.157556)
			(xy 452.966288 -291.138084) (xy 452.92013 -291.111435) (xy 452.878459 -291.078204) (xy 452.842207 -291.039133)
			(xy 452.812183 -290.995096) (xy 452.789057 -290.947075) (xy 452.773347 -290.896145) (xy 452.765404 -290.843441)
			(xy 451.266824 -290.843441) (xy 451.258881 -290.896145) (xy 451.243171 -290.947075) (xy 451.220045 -290.995096)
			(xy 451.190021 -291.039133) (xy 451.153769 -291.078204) (xy 451.112098 -291.111435) (xy 451.06594 -291.138084)
			(xy 451.016326 -291.157556) (xy 450.964364 -291.169416) (xy 450.911214 -291.1734) (xy 450.858064 -291.169416)
			(xy 450.806102 -291.157556) (xy 450.756488 -291.138084) (xy 450.71033 -291.111435) (xy 450.668659 -291.078204)
			(xy 450.632407 -291.039133) (xy 450.602383 -290.995096) (xy 450.579257 -290.947075) (xy 450.563547 -290.896145)
			(xy 450.555604 -290.843441) (xy 449.793868 -290.843441) (xy 449.793868 -291.328602) (xy 449.82384 -291.342064)
			(xy 449.848458 -291.353745) (xy 449.894126 -291.383464) (xy 449.934734 -291.419792) (xy 449.969336 -291.461881)
			(xy 449.997124 -291.508749) (xy 450.01745 -291.559303) (xy 450.029839 -291.612363) (xy 450.034002 -291.66669)
			(xy 450.031963 -291.693325) (xy 450.555604 -291.693325) (xy 450.555604 -291.640027) (xy 450.563547 -291.587323)
			(xy 450.579257 -291.536393) (xy 450.602383 -291.488372) (xy 450.632407 -291.444335) (xy 450.668659 -291.405264)
			(xy 450.71033 -291.372033) (xy 450.756488 -291.345384) (xy 450.806102 -291.325912) (xy 450.858064 -291.314052)
			(xy 450.911214 -291.310069) (xy 450.964364 -291.314052) (xy 451.016326 -291.325912) (xy 451.06594 -291.345384)
			(xy 451.112098 -291.372033) (xy 451.153769 -291.405264) (xy 451.190021 -291.444335) (xy 451.220045 -291.488372)
			(xy 451.243171 -291.536393) (xy 451.258881 -291.587323) (xy 451.266824 -291.640027) (xy 451.267322 -291.666676)
			(xy 451.266824 -291.693325) (xy 454.655672 -291.693325) (xy 454.655672 -291.640027) (xy 454.663615 -291.587323)
			(xy 454.679325 -291.536393) (xy 454.702451 -291.488372) (xy 454.732475 -291.444335) (xy 454.768727 -291.405264)
			(xy 454.810398 -291.372033) (xy 454.856556 -291.345384) (xy 454.90617 -291.325912) (xy 454.958132 -291.314052)
			(xy 455.011282 -291.310069) (xy 455.064432 -291.314052) (xy 455.116394 -291.325912) (xy 455.166008 -291.345384)
			(xy 455.212166 -291.372033) (xy 455.253837 -291.405264) (xy 455.290089 -291.444335) (xy 455.320113 -291.488372)
			(xy 455.343239 -291.536393) (xy 455.358949 -291.587323) (xy 455.366892 -291.640027) (xy 455.36739 -291.666676)
			(xy 455.366892 -291.693325) (xy 456.865472 -291.693325) (xy 456.865472 -291.640027) (xy 456.873415 -291.587323)
			(xy 456.889125 -291.536393) (xy 456.912251 -291.488372) (xy 456.942275 -291.444335) (xy 456.978527 -291.405264)
			(xy 457.020198 -291.372033) (xy 457.066356 -291.345384) (xy 457.11597 -291.325912) (xy 457.167932 -291.314052)
			(xy 457.221082 -291.310069) (xy 457.274232 -291.314052) (xy 457.326194 -291.325912) (xy 457.375808 -291.345384)
			(xy 457.421966 -291.372033) (xy 457.463637 -291.405264) (xy 457.499889 -291.444335) (xy 457.529913 -291.488372)
			(xy 457.553039 -291.536393) (xy 457.568749 -291.587323) (xy 457.576692 -291.640027) (xy 457.57719 -291.666676)
			(xy 457.576692 -291.693325) (xy 457.568749 -291.746029) (xy 457.553039 -291.796959) (xy 457.529913 -291.84498)
			(xy 457.499889 -291.889017) (xy 457.463637 -291.928088) (xy 457.421966 -291.961319) (xy 457.375808 -291.987968)
			(xy 457.326194 -292.00744) (xy 457.274232 -292.0193) (xy 457.221082 -292.023284) (xy 457.167932 -292.0193)
			(xy 457.11597 -292.00744) (xy 457.066356 -291.987968) (xy 457.020198 -291.961319) (xy 456.978527 -291.928088)
			(xy 456.942275 -291.889017) (xy 456.912251 -291.84498) (xy 456.889125 -291.796959) (xy 456.873415 -291.746029)
			(xy 456.865472 -291.693325) (xy 455.366892 -291.693325) (xy 455.358949 -291.746029) (xy 455.343239 -291.796959)
			(xy 455.320113 -291.84498) (xy 455.290089 -291.889017) (xy 455.253837 -291.928088) (xy 455.212166 -291.961319)
			(xy 455.166008 -291.987968) (xy 455.116394 -292.00744) (xy 455.064432 -292.0193) (xy 455.011282 -292.023284)
			(xy 454.958132 -292.0193) (xy 454.90617 -292.00744) (xy 454.856556 -291.987968) (xy 454.810398 -291.961319)
			(xy 454.768727 -291.928088) (xy 454.732475 -291.889017) (xy 454.702451 -291.84498) (xy 454.679325 -291.796959)
			(xy 454.663615 -291.746029) (xy 454.655672 -291.693325) (xy 451.266824 -291.693325) (xy 451.258881 -291.746029)
			(xy 451.243171 -291.796959) (xy 451.220045 -291.84498) (xy 451.190021 -291.889017) (xy 451.153769 -291.928088)
			(xy 451.112098 -291.961319) (xy 451.06594 -291.987968) (xy 451.016326 -292.00744) (xy 450.964364 -292.0193)
			(xy 450.911214 -292.023284) (xy 450.858064 -292.0193) (xy 450.806102 -292.00744) (xy 450.756488 -291.987968)
			(xy 450.71033 -291.961319) (xy 450.668659 -291.928088) (xy 450.632407 -291.889017) (xy 450.602383 -291.84498)
			(xy 450.579257 -291.796959) (xy 450.563547 -291.746029) (xy 450.555604 -291.693325) (xy 450.031963 -291.693325)
			(xy 450.029842 -291.721018) (xy 450.017456 -291.774078) (xy 449.997133 -291.824633) (xy 449.969348 -291.871503)
			(xy 449.934748 -291.913594) (xy 449.894141 -291.949924) (xy 449.848475 -291.979646) (xy 449.82384 -291.991288)
			(xy 449.793868 -292.00475) (xy 449.793868 -292.543463) (xy 450.555604 -292.543463) (xy 450.555604 -292.490165)
			(xy 450.563547 -292.437461) (xy 450.579257 -292.386531) (xy 450.602383 -292.33851) (xy 450.632407 -292.294473)
			(xy 450.668659 -292.255402) (xy 450.71033 -292.222171) (xy 450.756488 -292.195522) (xy 450.806102 -292.17605)
			(xy 450.858064 -292.16419) (xy 450.911214 -292.160207) (xy 450.964364 -292.16419) (xy 451.016326 -292.17605)
			(xy 451.06594 -292.195522) (xy 451.112098 -292.222171) (xy 451.153769 -292.255402) (xy 451.190021 -292.294473)
			(xy 451.220045 -292.33851) (xy 451.243171 -292.386531) (xy 451.258881 -292.437461) (xy 451.266824 -292.490165)
			(xy 451.267322 -292.516814) (xy 451.266824 -292.543463) (xy 452.765404 -292.543463) (xy 452.765404 -292.490165)
			(xy 452.773347 -292.437461) (xy 452.789057 -292.386531) (xy 452.812183 -292.33851) (xy 452.842207 -292.294473)
			(xy 452.878459 -292.255402) (xy 452.92013 -292.222171) (xy 452.966288 -292.195522) (xy 453.015902 -292.17605)
			(xy 453.067864 -292.16419) (xy 453.121014 -292.160207) (xy 453.174164 -292.16419) (xy 453.226126 -292.17605)
			(xy 453.27574 -292.195522) (xy 453.321898 -292.222171) (xy 453.363569 -292.255402) (xy 453.399821 -292.294473)
			(xy 453.429845 -292.33851) (xy 453.452971 -292.386531) (xy 453.468681 -292.437461) (xy 453.476624 -292.490165)
			(xy 453.477122 -292.516814) (xy 453.476629 -292.543209) (xy 454.655672 -292.543209) (xy 454.655672 -292.489911)
			(xy 454.663615 -292.437207) (xy 454.679325 -292.386277) (xy 454.702451 -292.338256) (xy 454.732475 -292.294219)
			(xy 454.768727 -292.255148) (xy 454.810398 -292.221917) (xy 454.856556 -292.195268) (xy 454.90617 -292.175796)
			(xy 454.958132 -292.163936) (xy 455.011282 -292.159953) (xy 455.064432 -292.163936) (xy 455.116394 -292.175796)
			(xy 455.166008 -292.195268) (xy 455.212166 -292.221917) (xy 455.253837 -292.255148) (xy 455.290089 -292.294219)
			(xy 455.320113 -292.338256) (xy 455.343239 -292.386277) (xy 455.358949 -292.437207) (xy 455.366892 -292.489911)
			(xy 455.36739 -292.51656) (xy 455.366892 -292.543209) (xy 455.366854 -292.543463) (xy 458.099404 -292.543463)
			(xy 458.099404 -292.490165) (xy 458.107347 -292.437461) (xy 458.123057 -292.386531) (xy 458.146183 -292.33851)
			(xy 458.176207 -292.294473) (xy 458.212459 -292.255402) (xy 458.25413 -292.222171) (xy 458.300288 -292.195522)
			(xy 458.349902 -292.17605) (xy 458.401864 -292.16419) (xy 458.455014 -292.160207) (xy 458.508164 -292.16419)
			(xy 458.560126 -292.17605) (xy 458.60974 -292.195522) (xy 458.655898 -292.222171) (xy 458.697569 -292.255402)
			(xy 458.733821 -292.294473) (xy 458.763845 -292.33851) (xy 458.786971 -292.386531) (xy 458.802681 -292.437461)
			(xy 458.810624 -292.490165) (xy 458.811122 -292.516814) (xy 458.810624 -292.543463) (xy 458.802681 -292.596167)
			(xy 458.786971 -292.647097) (xy 458.763845 -292.695118) (xy 458.733821 -292.739155) (xy 458.697569 -292.778226)
			(xy 458.655898 -292.811457) (xy 458.60974 -292.838106) (xy 458.560126 -292.857578) (xy 458.508164 -292.869438)
			(xy 458.455014 -292.873422) (xy 458.401864 -292.869438) (xy 458.349902 -292.857578) (xy 458.300288 -292.838106)
			(xy 458.25413 -292.811457) (xy 458.212459 -292.778226) (xy 458.176207 -292.739155) (xy 458.146183 -292.695118)
			(xy 458.123057 -292.647097) (xy 458.107347 -292.596167) (xy 458.099404 -292.543463) (xy 455.366854 -292.543463)
			(xy 455.358949 -292.595913) (xy 455.343239 -292.646843) (xy 455.320113 -292.694864) (xy 455.290089 -292.738901)
			(xy 455.253837 -292.777972) (xy 455.212166 -292.811203) (xy 455.166008 -292.837852) (xy 455.116394 -292.857324)
			(xy 455.064432 -292.869184) (xy 455.011282 -292.873168) (xy 454.958132 -292.869184) (xy 454.90617 -292.857324)
			(xy 454.856556 -292.837852) (xy 454.810398 -292.811203) (xy 454.768727 -292.777972) (xy 454.732475 -292.738901)
			(xy 454.702451 -292.694864) (xy 454.679325 -292.646843) (xy 454.663615 -292.595913) (xy 454.655672 -292.543209)
			(xy 453.476629 -292.543209) (xy 453.476624 -292.543463) (xy 453.468681 -292.596167) (xy 453.452971 -292.647097)
			(xy 453.429845 -292.695118) (xy 453.399821 -292.739155) (xy 453.363569 -292.778226) (xy 453.321898 -292.811457)
			(xy 453.27574 -292.838106) (xy 453.226126 -292.857578) (xy 453.174164 -292.869438) (xy 453.121014 -292.873422)
			(xy 453.067864 -292.869438) (xy 453.015902 -292.857578) (xy 452.966288 -292.838106) (xy 452.92013 -292.811457)
			(xy 452.878459 -292.778226) (xy 452.842207 -292.739155) (xy 452.812183 -292.695118) (xy 452.789057 -292.647097)
			(xy 452.773347 -292.596167) (xy 452.765404 -292.543463) (xy 451.266824 -292.543463) (xy 451.258881 -292.596167)
			(xy 451.243171 -292.647097) (xy 451.220045 -292.695118) (xy 451.190021 -292.739155) (xy 451.153769 -292.778226)
			(xy 451.112098 -292.811457) (xy 451.06594 -292.838106) (xy 451.016326 -292.857578) (xy 450.964364 -292.869438)
			(xy 450.911214 -292.873422) (xy 450.858064 -292.869438) (xy 450.806102 -292.857578) (xy 450.756488 -292.838106)
			(xy 450.71033 -292.811457) (xy 450.668659 -292.778226) (xy 450.632407 -292.739155) (xy 450.602383 -292.695118)
			(xy 450.579257 -292.647097) (xy 450.563547 -292.596167) (xy 450.555604 -292.543463) (xy 449.793868 -292.543463)
			(xy 449.793868 -293.393347) (xy 450.555604 -293.393347) (xy 450.555604 -293.340049) (xy 450.563547 -293.287345)
			(xy 450.579257 -293.236415) (xy 450.602383 -293.188394) (xy 450.632407 -293.144357) (xy 450.668659 -293.105286)
			(xy 450.71033 -293.072055) (xy 450.756488 -293.045406) (xy 450.806102 -293.025934) (xy 450.858064 -293.014074)
			(xy 450.911214 -293.010091) (xy 450.964364 -293.014074) (xy 451.016326 -293.025934) (xy 451.06594 -293.045406)
			(xy 451.112098 -293.072055) (xy 451.153769 -293.105286) (xy 451.190021 -293.144357) (xy 451.220045 -293.188394)
			(xy 451.243171 -293.236415) (xy 451.258881 -293.287345) (xy 451.266824 -293.340049) (xy 451.267322 -293.366698)
			(xy 451.266824 -293.393347) (xy 454.655672 -293.393347) (xy 454.655672 -293.340049) (xy 454.663615 -293.287345)
			(xy 454.679325 -293.236415) (xy 454.702451 -293.188394) (xy 454.732475 -293.144357) (xy 454.768727 -293.105286)
			(xy 454.810398 -293.072055) (xy 454.856556 -293.045406) (xy 454.90617 -293.025934) (xy 454.958132 -293.014074)
			(xy 455.011282 -293.010091) (xy 455.064432 -293.014074) (xy 455.116394 -293.025934) (xy 455.166008 -293.045406)
			(xy 455.212166 -293.072055) (xy 455.253837 -293.105286) (xy 455.290089 -293.144357) (xy 455.320113 -293.188394)
			(xy 455.343239 -293.236415) (xy 455.358949 -293.287345) (xy 455.366892 -293.340049) (xy 455.36739 -293.366698)
			(xy 455.366892 -293.393347) (xy 455.358949 -293.446051) (xy 455.343239 -293.496981) (xy 455.320113 -293.545002)
			(xy 455.290089 -293.589039) (xy 455.253837 -293.62811) (xy 455.212166 -293.661341) (xy 455.166008 -293.68799)
			(xy 455.116394 -293.707462) (xy 455.064432 -293.719322) (xy 455.011282 -293.723306) (xy 454.958132 -293.719322)
			(xy 454.90617 -293.707462) (xy 454.856556 -293.68799) (xy 454.810398 -293.661341) (xy 454.768727 -293.62811)
			(xy 454.732475 -293.589039) (xy 454.702451 -293.545002) (xy 454.679325 -293.496981) (xy 454.663615 -293.446051)
			(xy 454.655672 -293.393347) (xy 451.266824 -293.393347) (xy 451.258881 -293.446051) (xy 451.243171 -293.496981)
			(xy 451.220045 -293.545002) (xy 451.190021 -293.589039) (xy 451.153769 -293.62811) (xy 451.112098 -293.661341)
			(xy 451.06594 -293.68799) (xy 451.016326 -293.707462) (xy 450.964364 -293.719322) (xy 450.911214 -293.723306)
			(xy 450.858064 -293.719322) (xy 450.806102 -293.707462) (xy 450.756488 -293.68799) (xy 450.71033 -293.661341)
			(xy 450.668659 -293.62811) (xy 450.632407 -293.589039) (xy 450.602383 -293.545002) (xy 450.579257 -293.496981)
			(xy 450.563547 -293.446051) (xy 450.555604 -293.393347) (xy 449.793868 -293.393347) (xy 449.793868 -293.878508)
			(xy 449.82384 -293.89197) (xy 449.848457 -293.903651) (xy 449.894124 -293.93337) (xy 449.934732 -293.969698)
			(xy 449.969333 -294.011786) (xy 449.997121 -294.058654) (xy 450.017445 -294.109207) (xy 450.029834 -294.162266)
			(xy 450.033996 -294.216593) (xy 450.031956 -294.243231) (xy 450.555604 -294.243231) (xy 450.555604 -294.189933)
			(xy 450.563547 -294.137229) (xy 450.579257 -294.086299) (xy 450.602383 -294.038278) (xy 450.632407 -293.994241)
			(xy 450.668659 -293.95517) (xy 450.71033 -293.921939) (xy 450.756488 -293.89529) (xy 450.806102 -293.875818)
			(xy 450.858064 -293.863958) (xy 450.911214 -293.859975) (xy 450.964364 -293.863958) (xy 451.016326 -293.875818)
			(xy 451.06594 -293.89529) (xy 451.112098 -293.921939) (xy 451.153769 -293.95517) (xy 451.190021 -293.994241)
			(xy 451.220045 -294.038278) (xy 451.243171 -294.086299) (xy 451.258881 -294.137229) (xy 451.266824 -294.189933)
			(xy 451.267322 -294.216582) (xy 451.266824 -294.243231) (xy 454.655672 -294.243231) (xy 454.655672 -294.189933)
			(xy 454.663615 -294.137229) (xy 454.679325 -294.086299) (xy 454.702451 -294.038278) (xy 454.732475 -293.994241)
			(xy 454.768727 -293.95517) (xy 454.810398 -293.921939) (xy 454.856556 -293.89529) (xy 454.90617 -293.875818)
			(xy 454.958132 -293.863958) (xy 455.011282 -293.859975) (xy 455.064432 -293.863958) (xy 455.116394 -293.875818)
			(xy 455.166008 -293.89529) (xy 455.212166 -293.921939) (xy 455.253837 -293.95517) (xy 455.290089 -293.994241)
			(xy 455.320113 -294.038278) (xy 455.343239 -294.086299) (xy 455.358949 -294.137229) (xy 455.366892 -294.189933)
			(xy 455.36739 -294.216582) (xy 455.366892 -294.243231) (xy 456.865472 -294.243231) (xy 456.865472 -294.189933)
			(xy 456.873415 -294.137229) (xy 456.889125 -294.086299) (xy 456.912251 -294.038278) (xy 456.942275 -293.994241)
			(xy 456.978527 -293.95517) (xy 457.020198 -293.921939) (xy 457.066356 -293.89529) (xy 457.11597 -293.875818)
			(xy 457.167932 -293.863958) (xy 457.221082 -293.859975) (xy 457.274232 -293.863958) (xy 457.326194 -293.875818)
			(xy 457.375808 -293.89529) (xy 457.421966 -293.921939) (xy 457.463637 -293.95517) (xy 457.499889 -293.994241)
			(xy 457.529913 -294.038278) (xy 457.553039 -294.086299) (xy 457.568749 -294.137229) (xy 457.576692 -294.189933)
			(xy 457.57719 -294.216582) (xy 457.576692 -294.243231) (xy 457.568749 -294.295935) (xy 457.553039 -294.346865)
			(xy 457.529913 -294.394886) (xy 457.499889 -294.438923) (xy 457.463637 -294.477994) (xy 457.421966 -294.511225)
			(xy 457.375808 -294.537874) (xy 457.326194 -294.557346) (xy 457.274232 -294.569206) (xy 457.221082 -294.57319)
			(xy 457.167932 -294.569206) (xy 457.11597 -294.557346) (xy 457.066356 -294.537874) (xy 457.020198 -294.511225)
			(xy 456.978527 -294.477994) (xy 456.942275 -294.438923) (xy 456.912251 -294.394886) (xy 456.889125 -294.346865)
			(xy 456.873415 -294.295935) (xy 456.865472 -294.243231) (xy 455.366892 -294.243231) (xy 455.358949 -294.295935)
			(xy 455.343239 -294.346865) (xy 455.320113 -294.394886) (xy 455.290089 -294.438923) (xy 455.253837 -294.477994)
			(xy 455.212166 -294.511225) (xy 455.166008 -294.537874) (xy 455.116394 -294.557346) (xy 455.064432 -294.569206)
			(xy 455.011282 -294.57319) (xy 454.958132 -294.569206) (xy 454.90617 -294.557346) (xy 454.856556 -294.537874)
			(xy 454.810398 -294.511225) (xy 454.768727 -294.477994) (xy 454.732475 -294.438923) (xy 454.702451 -294.394886)
			(xy 454.679325 -294.346865) (xy 454.663615 -294.295935) (xy 454.655672 -294.243231) (xy 451.266824 -294.243231)
			(xy 451.258881 -294.295935) (xy 451.243171 -294.346865) (xy 451.220045 -294.394886) (xy 451.190021 -294.438923)
			(xy 451.153769 -294.477994) (xy 451.112098 -294.511225) (xy 451.06594 -294.537874) (xy 451.016326 -294.557346)
			(xy 450.964364 -294.569206) (xy 450.911214 -294.57319) (xy 450.858064 -294.569206) (xy 450.806102 -294.557346)
			(xy 450.756488 -294.537874) (xy 450.71033 -294.511225) (xy 450.668659 -294.477994) (xy 450.632407 -294.438923)
			(xy 450.602383 -294.394886) (xy 450.579257 -294.346865) (xy 450.563547 -294.295935) (xy 450.555604 -294.243231)
			(xy 450.031956 -294.243231) (xy 450.029836 -294.270919) (xy 450.01745 -294.323979) (xy 449.997127 -294.374533)
			(xy 449.969342 -294.421402) (xy 449.934742 -294.463492) (xy 449.894136 -294.499821) (xy 449.84847 -294.529542)
			(xy 449.82384 -294.541194) (xy 449.793868 -294.554656) (xy 449.793868 -295.093369) (xy 450.555604 -295.093369)
			(xy 450.555604 -295.040071) (xy 450.563547 -294.987367) (xy 450.579257 -294.936437) (xy 450.602383 -294.888416)
			(xy 450.632407 -294.844379) (xy 450.668659 -294.805308) (xy 450.71033 -294.772077) (xy 450.756488 -294.745428)
			(xy 450.806102 -294.725956) (xy 450.858064 -294.714096) (xy 450.911214 -294.710113) (xy 450.964364 -294.714096)
			(xy 451.016326 -294.725956) (xy 451.06594 -294.745428) (xy 451.112098 -294.772077) (xy 451.153769 -294.805308)
			(xy 451.190021 -294.844379) (xy 451.220045 -294.888416) (xy 451.243171 -294.936437) (xy 451.258881 -294.987367)
			(xy 451.266824 -295.040071) (xy 451.267322 -295.06672) (xy 451.266824 -295.093369) (xy 452.765404 -295.093369)
			(xy 452.765404 -295.040071) (xy 452.773347 -294.987367) (xy 452.789057 -294.936437) (xy 452.812183 -294.888416)
			(xy 452.842207 -294.844379) (xy 452.878459 -294.805308) (xy 452.92013 -294.772077) (xy 452.966288 -294.745428)
			(xy 453.015902 -294.725956) (xy 453.067864 -294.714096) (xy 453.121014 -294.710113) (xy 453.174164 -294.714096)
			(xy 453.226126 -294.725956) (xy 453.27574 -294.745428) (xy 453.321898 -294.772077) (xy 453.363569 -294.805308)
			(xy 453.399821 -294.844379) (xy 453.429845 -294.888416) (xy 453.452971 -294.936437) (xy 453.468681 -294.987367)
			(xy 453.476624 -295.040071) (xy 453.477122 -295.06672) (xy 453.476624 -295.093369) (xy 454.655672 -295.093369)
			(xy 454.655672 -295.040071) (xy 454.663615 -294.987367) (xy 454.679325 -294.936437) (xy 454.702451 -294.888416)
			(xy 454.732475 -294.844379) (xy 454.768727 -294.805308) (xy 454.810398 -294.772077) (xy 454.856556 -294.745428)
			(xy 454.90617 -294.725956) (xy 454.958132 -294.714096) (xy 455.011282 -294.710113) (xy 455.064432 -294.714096)
			(xy 455.116394 -294.725956) (xy 455.166008 -294.745428) (xy 455.212166 -294.772077) (xy 455.253837 -294.805308)
			(xy 455.290089 -294.844379) (xy 455.320113 -294.888416) (xy 455.343239 -294.936437) (xy 455.358949 -294.987367)
			(xy 455.366892 -295.040071) (xy 455.36739 -295.06672) (xy 455.366892 -295.093369) (xy 458.099404 -295.093369)
			(xy 458.099404 -295.040071) (xy 458.107347 -294.987367) (xy 458.123057 -294.936437) (xy 458.146183 -294.888416)
			(xy 458.176207 -294.844379) (xy 458.212459 -294.805308) (xy 458.25413 -294.772077) (xy 458.300288 -294.745428)
			(xy 458.349902 -294.725956) (xy 458.401864 -294.714096) (xy 458.455014 -294.710113) (xy 458.508164 -294.714096)
			(xy 458.560126 -294.725956) (xy 458.60974 -294.745428) (xy 458.655898 -294.772077) (xy 458.697569 -294.805308)
			(xy 458.733821 -294.844379) (xy 458.763845 -294.888416) (xy 458.786971 -294.936437) (xy 458.802681 -294.987367)
			(xy 458.810624 -295.040071) (xy 458.811122 -295.06672) (xy 458.810624 -295.093369) (xy 458.802681 -295.146073)
			(xy 458.786971 -295.197003) (xy 458.763845 -295.245024) (xy 458.733821 -295.289061) (xy 458.697569 -295.328132)
			(xy 458.655898 -295.361363) (xy 458.60974 -295.388012) (xy 458.560126 -295.407484) (xy 458.508164 -295.419344)
			(xy 458.455014 -295.423328) (xy 458.401864 -295.419344) (xy 458.349902 -295.407484) (xy 458.300288 -295.388012)
			(xy 458.25413 -295.361363) (xy 458.212459 -295.328132) (xy 458.176207 -295.289061) (xy 458.146183 -295.245024)
			(xy 458.123057 -295.197003) (xy 458.107347 -295.146073) (xy 458.099404 -295.093369) (xy 455.366892 -295.093369)
			(xy 455.358949 -295.146073) (xy 455.343239 -295.197003) (xy 455.320113 -295.245024) (xy 455.290089 -295.289061)
			(xy 455.253837 -295.328132) (xy 455.212166 -295.361363) (xy 455.166008 -295.388012) (xy 455.116394 -295.407484)
			(xy 455.064432 -295.419344) (xy 455.011282 -295.423328) (xy 454.958132 -295.419344) (xy 454.90617 -295.407484)
			(xy 454.856556 -295.388012) (xy 454.810398 -295.361363) (xy 454.768727 -295.328132) (xy 454.732475 -295.289061)
			(xy 454.702451 -295.245024) (xy 454.679325 -295.197003) (xy 454.663615 -295.146073) (xy 454.655672 -295.093369)
			(xy 453.476624 -295.093369) (xy 453.468681 -295.146073) (xy 453.452971 -295.197003) (xy 453.429845 -295.245024)
			(xy 453.399821 -295.289061) (xy 453.363569 -295.328132) (xy 453.321898 -295.361363) (xy 453.27574 -295.388012)
			(xy 453.226126 -295.407484) (xy 453.174164 -295.419344) (xy 453.121014 -295.423328) (xy 453.067864 -295.419344)
			(xy 453.015902 -295.407484) (xy 452.966288 -295.388012) (xy 452.92013 -295.361363) (xy 452.878459 -295.328132)
			(xy 452.842207 -295.289061) (xy 452.812183 -295.245024) (xy 452.789057 -295.197003) (xy 452.773347 -295.146073)
			(xy 452.765404 -295.093369) (xy 451.266824 -295.093369) (xy 451.258881 -295.146073) (xy 451.243171 -295.197003)
			(xy 451.220045 -295.245024) (xy 451.190021 -295.289061) (xy 451.153769 -295.328132) (xy 451.112098 -295.361363)
			(xy 451.06594 -295.388012) (xy 451.016326 -295.407484) (xy 450.964364 -295.419344) (xy 450.911214 -295.423328)
			(xy 450.858064 -295.419344) (xy 450.806102 -295.407484) (xy 450.756488 -295.388012) (xy 450.71033 -295.361363)
			(xy 450.668659 -295.328132) (xy 450.632407 -295.289061) (xy 450.602383 -295.245024) (xy 450.579257 -295.197003)
			(xy 450.563547 -295.146073) (xy 450.555604 -295.093369) (xy 449.793868 -295.093369) (xy 449.793868 -295.57853)
			(xy 449.82384 -295.591992) (xy 449.848456 -295.603673) (xy 449.894119 -295.633391) (xy 449.934724 -295.669718)
			(xy 449.969322 -295.711805) (xy 449.997107 -295.758671) (xy 450.017429 -295.809222) (xy 450.029815 -295.862278)
			(xy 450.033976 -295.916602) (xy 450.031935 -295.943253) (xy 450.555604 -295.943253) (xy 450.555604 -295.889955)
			(xy 450.563547 -295.837251) (xy 450.579257 -295.786321) (xy 450.602383 -295.7383) (xy 450.632407 -295.694263)
			(xy 450.668659 -295.655192) (xy 450.71033 -295.621961) (xy 450.756488 -295.595312) (xy 450.806102 -295.57584)
			(xy 450.858064 -295.56398) (xy 450.911214 -295.559997) (xy 450.964364 -295.56398) (xy 451.016326 -295.57584)
			(xy 451.06594 -295.595312) (xy 451.112098 -295.621961) (xy 451.153769 -295.655192) (xy 451.190021 -295.694263)
			(xy 451.220045 -295.7383) (xy 451.243171 -295.786321) (xy 451.258881 -295.837251) (xy 451.266824 -295.889955)
			(xy 451.267322 -295.916604) (xy 451.266824 -295.943253) (xy 454.655672 -295.943253) (xy 454.655672 -295.889955)
			(xy 454.663615 -295.837251) (xy 454.679325 -295.786321) (xy 454.702451 -295.7383) (xy 454.732475 -295.694263)
			(xy 454.768727 -295.655192) (xy 454.810398 -295.621961) (xy 454.856556 -295.595312) (xy 454.90617 -295.57584)
			(xy 454.958132 -295.56398) (xy 455.011282 -295.559997) (xy 455.064432 -295.56398) (xy 455.116394 -295.57584)
			(xy 455.166008 -295.595312) (xy 455.212166 -295.621961) (xy 455.253837 -295.655192) (xy 455.290089 -295.694263)
			(xy 455.320113 -295.7383) (xy 455.343239 -295.786321) (xy 455.358949 -295.837251) (xy 455.366892 -295.889955)
			(xy 455.36739 -295.916604) (xy 455.366892 -295.943253) (xy 456.865472 -295.943253) (xy 456.865472 -295.889955)
			(xy 456.873415 -295.837251) (xy 456.889125 -295.786321) (xy 456.912251 -295.7383) (xy 456.942275 -295.694263)
			(xy 456.978527 -295.655192) (xy 457.020198 -295.621961) (xy 457.066356 -295.595312) (xy 457.11597 -295.57584)
			(xy 457.167932 -295.56398) (xy 457.221082 -295.559997) (xy 457.274232 -295.56398) (xy 457.326194 -295.57584)
			(xy 457.375808 -295.595312) (xy 457.421966 -295.621961) (xy 457.463637 -295.655192) (xy 457.499889 -295.694263)
			(xy 457.529913 -295.7383) (xy 457.553039 -295.786321) (xy 457.568749 -295.837251) (xy 457.576692 -295.889955)
			(xy 457.57719 -295.916604) (xy 457.576692 -295.943253) (xy 457.568749 -295.995957) (xy 457.553039 -296.046887)
			(xy 457.529913 -296.094908) (xy 457.499889 -296.138945) (xy 457.463637 -296.178016) (xy 457.421966 -296.211247)
			(xy 457.375808 -296.237896) (xy 457.326194 -296.257368) (xy 457.274232 -296.269228) (xy 457.221082 -296.273212)
			(xy 457.167932 -296.269228) (xy 457.11597 -296.257368) (xy 457.066356 -296.237896) (xy 457.020198 -296.211247)
			(xy 456.978527 -296.178016) (xy 456.942275 -296.138945) (xy 456.912251 -296.094908) (xy 456.889125 -296.046887)
			(xy 456.873415 -295.995957) (xy 456.865472 -295.943253) (xy 455.366892 -295.943253) (xy 455.358949 -295.995957)
			(xy 455.343239 -296.046887) (xy 455.320113 -296.094908) (xy 455.290089 -296.138945) (xy 455.253837 -296.178016)
			(xy 455.212166 -296.211247) (xy 455.166008 -296.237896) (xy 455.116394 -296.257368) (xy 455.064432 -296.269228)
			(xy 455.011282 -296.273212) (xy 454.958132 -296.269228) (xy 454.90617 -296.257368) (xy 454.856556 -296.237896)
			(xy 454.810398 -296.211247) (xy 454.768727 -296.178016) (xy 454.732475 -296.138945) (xy 454.702451 -296.094908)
			(xy 454.679325 -296.046887) (xy 454.663615 -295.995957) (xy 454.655672 -295.943253) (xy 451.266824 -295.943253)
			(xy 451.258881 -295.995957) (xy 451.243171 -296.046887) (xy 451.220045 -296.094908) (xy 451.190021 -296.138945)
			(xy 451.153769 -296.178016) (xy 451.112098 -296.211247) (xy 451.06594 -296.237896) (xy 451.016326 -296.257368)
			(xy 450.964364 -296.269228) (xy 450.911214 -296.273212) (xy 450.858064 -296.269228) (xy 450.806102 -296.257368)
			(xy 450.756488 -296.237896) (xy 450.71033 -296.211247) (xy 450.668659 -296.178016) (xy 450.632407 -296.138945)
			(xy 450.602383 -296.094908) (xy 450.579257 -296.046887) (xy 450.563547 -295.995957) (xy 450.555604 -295.943253)
			(xy 450.031935 -295.943253) (xy 450.029815 -295.970925) (xy 450.017428 -296.023981) (xy 449.997105 -296.074532)
			(xy 449.96932 -296.121397) (xy 449.934722 -296.163484) (xy 449.894117 -296.199811) (xy 449.848453 -296.229529)
			(xy 449.82384 -296.241216) (xy 449.793868 -296.254678) (xy 449.793868 -296.793391) (xy 450.555604 -296.793391)
			(xy 450.555604 -296.740093) (xy 450.563547 -296.687389) (xy 450.579257 -296.636459) (xy 450.602383 -296.588438)
			(xy 450.632407 -296.544401) (xy 450.668659 -296.50533) (xy 450.71033 -296.472099) (xy 450.756488 -296.44545)
			(xy 450.806102 -296.425978) (xy 450.858064 -296.414118) (xy 450.911214 -296.410135) (xy 450.964364 -296.414118)
			(xy 451.016326 -296.425978) (xy 451.06594 -296.44545) (xy 451.112098 -296.472099) (xy 451.153769 -296.50533)
			(xy 451.190021 -296.544401) (xy 451.220045 -296.588438) (xy 451.243171 -296.636459) (xy 451.258881 -296.687389)
			(xy 451.266824 -296.740093) (xy 451.267322 -296.766742) (xy 451.266824 -296.793391) (xy 452.765404 -296.793391)
			(xy 452.765404 -296.740093) (xy 452.773347 -296.687389) (xy 452.789057 -296.636459) (xy 452.812183 -296.588438)
			(xy 452.842207 -296.544401) (xy 452.878459 -296.50533) (xy 452.92013 -296.472099) (xy 452.966288 -296.44545)
			(xy 453.015902 -296.425978) (xy 453.067864 -296.414118) (xy 453.121014 -296.410135) (xy 453.174164 -296.414118)
			(xy 453.226126 -296.425978) (xy 453.27574 -296.44545) (xy 453.321898 -296.472099) (xy 453.363569 -296.50533)
			(xy 453.399821 -296.544401) (xy 453.429845 -296.588438) (xy 453.452971 -296.636459) (xy 453.468681 -296.687389)
			(xy 453.476624 -296.740093) (xy 453.477122 -296.766742) (xy 453.476624 -296.793391) (xy 454.655672 -296.793391)
			(xy 454.655672 -296.740093) (xy 454.663615 -296.687389) (xy 454.679325 -296.636459) (xy 454.702451 -296.588438)
			(xy 454.732475 -296.544401) (xy 454.768727 -296.50533) (xy 454.810398 -296.472099) (xy 454.856556 -296.44545)
			(xy 454.90617 -296.425978) (xy 454.958132 -296.414118) (xy 455.011282 -296.410135) (xy 455.064432 -296.414118)
			(xy 455.116394 -296.425978) (xy 455.166008 -296.44545) (xy 455.212166 -296.472099) (xy 455.253837 -296.50533)
			(xy 455.290089 -296.544401) (xy 455.320113 -296.588438) (xy 455.343239 -296.636459) (xy 455.358949 -296.687389)
			(xy 455.366892 -296.740093) (xy 455.36739 -296.766742) (xy 455.366892 -296.793391) (xy 458.099404 -296.793391)
			(xy 458.099404 -296.740093) (xy 458.107347 -296.687389) (xy 458.123057 -296.636459) (xy 458.146183 -296.588438)
			(xy 458.176207 -296.544401) (xy 458.212459 -296.50533) (xy 458.25413 -296.472099) (xy 458.300288 -296.44545)
			(xy 458.349902 -296.425978) (xy 458.401864 -296.414118) (xy 458.455014 -296.410135) (xy 458.508164 -296.414118)
			(xy 458.560126 -296.425978) (xy 458.60974 -296.44545) (xy 458.655898 -296.472099) (xy 458.697569 -296.50533)
			(xy 458.733821 -296.544401) (xy 458.763845 -296.588438) (xy 458.786971 -296.636459) (xy 458.802681 -296.687389)
			(xy 458.810624 -296.740093) (xy 458.811122 -296.766742) (xy 458.810624 -296.793391) (xy 458.802681 -296.846095)
			(xy 458.786971 -296.897025) (xy 458.763845 -296.945046) (xy 458.733821 -296.989083) (xy 458.697569 -297.028154)
			(xy 458.655898 -297.061385) (xy 458.60974 -297.088034) (xy 458.560126 -297.107506) (xy 458.508164 -297.119366)
			(xy 458.455014 -297.12335) (xy 458.401864 -297.119366) (xy 458.349902 -297.107506) (xy 458.300288 -297.088034)
			(xy 458.25413 -297.061385) (xy 458.212459 -297.028154) (xy 458.176207 -296.989083) (xy 458.146183 -296.945046)
			(xy 458.123057 -296.897025) (xy 458.107347 -296.846095) (xy 458.099404 -296.793391) (xy 455.366892 -296.793391)
			(xy 455.358949 -296.846095) (xy 455.343239 -296.897025) (xy 455.320113 -296.945046) (xy 455.290089 -296.989083)
			(xy 455.253837 -297.028154) (xy 455.212166 -297.061385) (xy 455.166008 -297.088034) (xy 455.116394 -297.107506)
			(xy 455.064432 -297.119366) (xy 455.011282 -297.12335) (xy 454.958132 -297.119366) (xy 454.90617 -297.107506)
			(xy 454.856556 -297.088034) (xy 454.810398 -297.061385) (xy 454.768727 -297.028154) (xy 454.732475 -296.989083)
			(xy 454.702451 -296.945046) (xy 454.679325 -296.897025) (xy 454.663615 -296.846095) (xy 454.655672 -296.793391)
			(xy 453.476624 -296.793391) (xy 453.468681 -296.846095) (xy 453.452971 -296.897025) (xy 453.429845 -296.945046)
			(xy 453.399821 -296.989083) (xy 453.363569 -297.028154) (xy 453.321898 -297.061385) (xy 453.27574 -297.088034)
			(xy 453.226126 -297.107506) (xy 453.174164 -297.119366) (xy 453.121014 -297.12335) (xy 453.067864 -297.119366)
			(xy 453.015902 -297.107506) (xy 452.966288 -297.088034) (xy 452.92013 -297.061385) (xy 452.878459 -297.028154)
			(xy 452.842207 -296.989083) (xy 452.812183 -296.945046) (xy 452.789057 -296.897025) (xy 452.773347 -296.846095)
			(xy 452.765404 -296.793391) (xy 451.266824 -296.793391) (xy 451.258881 -296.846095) (xy 451.243171 -296.897025)
			(xy 451.220045 -296.945046) (xy 451.190021 -296.989083) (xy 451.153769 -297.028154) (xy 451.112098 -297.061385)
			(xy 451.06594 -297.088034) (xy 451.016326 -297.107506) (xy 450.964364 -297.119366) (xy 450.911214 -297.12335)
			(xy 450.858064 -297.119366) (xy 450.806102 -297.107506) (xy 450.756488 -297.088034) (xy 450.71033 -297.061385)
			(xy 450.668659 -297.028154) (xy 450.632407 -296.989083) (xy 450.602383 -296.945046) (xy 450.579257 -296.897025)
			(xy 450.563547 -296.846095) (xy 450.555604 -296.793391) (xy 449.793868 -296.793391) (xy 449.793868 -297.278552)
			(xy 449.82384 -297.292014) (xy 449.848454 -297.303694) (xy 449.894114 -297.333413) (xy 449.934716 -297.369738)
			(xy 449.969311 -297.411824) (xy 449.997093 -297.458688) (xy 450.017413 -297.509236) (xy 450.029797 -297.56229)
			(xy 450.033956 -297.616611) (xy 450.031913 -297.643275) (xy 450.555604 -297.643275) (xy 450.555604 -297.589977)
			(xy 450.563547 -297.537273) (xy 450.579257 -297.486343) (xy 450.602383 -297.438322) (xy 450.632407 -297.394285)
			(xy 450.668659 -297.355214) (xy 450.71033 -297.321983) (xy 450.756488 -297.295334) (xy 450.806102 -297.275862)
			(xy 450.858064 -297.264002) (xy 450.911214 -297.260019) (xy 450.964364 -297.264002) (xy 451.016326 -297.275862)
			(xy 451.06594 -297.295334) (xy 451.112098 -297.321983) (xy 451.153769 -297.355214) (xy 451.190021 -297.394285)
			(xy 451.220045 -297.438322) (xy 451.243171 -297.486343) (xy 451.258881 -297.537273) (xy 451.266824 -297.589977)
			(xy 451.267322 -297.616626) (xy 451.266824 -297.643275) (xy 454.655672 -297.643275) (xy 454.655672 -297.589977)
			(xy 454.663615 -297.537273) (xy 454.679325 -297.486343) (xy 454.702451 -297.438322) (xy 454.732475 -297.394285)
			(xy 454.768727 -297.355214) (xy 454.810398 -297.321983) (xy 454.856556 -297.295334) (xy 454.90617 -297.275862)
			(xy 454.958132 -297.264002) (xy 455.011282 -297.260019) (xy 455.064432 -297.264002) (xy 455.116394 -297.275862)
			(xy 455.166008 -297.295334) (xy 455.212166 -297.321983) (xy 455.253837 -297.355214) (xy 455.290089 -297.394285)
			(xy 455.320113 -297.438322) (xy 455.343239 -297.486343) (xy 455.358949 -297.537273) (xy 455.366892 -297.589977)
			(xy 455.36739 -297.616626) (xy 455.366892 -297.643275) (xy 456.865472 -297.643275) (xy 456.865472 -297.589977)
			(xy 456.873415 -297.537273) (xy 456.889125 -297.486343) (xy 456.912251 -297.438322) (xy 456.942275 -297.394285)
			(xy 456.978527 -297.355214) (xy 457.020198 -297.321983) (xy 457.066356 -297.295334) (xy 457.11597 -297.275862)
			(xy 457.167932 -297.264002) (xy 457.221082 -297.260019) (xy 457.274232 -297.264002) (xy 457.326194 -297.275862)
			(xy 457.375808 -297.295334) (xy 457.421966 -297.321983) (xy 457.463637 -297.355214) (xy 457.499889 -297.394285)
			(xy 457.529913 -297.438322) (xy 457.553039 -297.486343) (xy 457.568749 -297.537273) (xy 457.576692 -297.589977)
			(xy 457.57719 -297.616626) (xy 457.576692 -297.643275) (xy 457.568749 -297.695979) (xy 457.553039 -297.746909)
			(xy 457.529913 -297.79493) (xy 457.499889 -297.838967) (xy 457.463637 -297.878038) (xy 457.421966 -297.911269)
			(xy 457.375808 -297.937918) (xy 457.326194 -297.95739) (xy 457.274232 -297.96925) (xy 457.221082 -297.973234)
			(xy 457.167932 -297.96925) (xy 457.11597 -297.95739) (xy 457.066356 -297.937918) (xy 457.020198 -297.911269)
			(xy 456.978527 -297.878038) (xy 456.942275 -297.838967) (xy 456.912251 -297.79493) (xy 456.889125 -297.746909)
			(xy 456.873415 -297.695979) (xy 456.865472 -297.643275) (xy 455.366892 -297.643275) (xy 455.358949 -297.695979)
			(xy 455.343239 -297.746909) (xy 455.320113 -297.79493) (xy 455.290089 -297.838967) (xy 455.253837 -297.878038)
			(xy 455.212166 -297.911269) (xy 455.166008 -297.937918) (xy 455.116394 -297.95739) (xy 455.064432 -297.96925)
			(xy 455.011282 -297.973234) (xy 454.958132 -297.96925) (xy 454.90617 -297.95739) (xy 454.856556 -297.937918)
			(xy 454.810398 -297.911269) (xy 454.768727 -297.878038) (xy 454.732475 -297.838967) (xy 454.702451 -297.79493)
			(xy 454.679325 -297.746909) (xy 454.663615 -297.695979) (xy 454.655672 -297.643275) (xy 451.266824 -297.643275)
			(xy 451.258881 -297.695979) (xy 451.243171 -297.746909) (xy 451.220045 -297.79493) (xy 451.190021 -297.838967)
			(xy 451.153769 -297.878038) (xy 451.112098 -297.911269) (xy 451.06594 -297.937918) (xy 451.016326 -297.95739)
			(xy 450.964364 -297.96925) (xy 450.911214 -297.973234) (xy 450.858064 -297.96925) (xy 450.806102 -297.95739)
			(xy 450.756488 -297.937918) (xy 450.71033 -297.911269) (xy 450.668659 -297.878038) (xy 450.632407 -297.838967)
			(xy 450.602383 -297.79493) (xy 450.579257 -297.746909) (xy 450.563547 -297.695979) (xy 450.555604 -297.643275)
			(xy 450.031913 -297.643275) (xy 450.029793 -297.670931) (xy 450.017406 -297.723984) (xy 449.997083 -297.774531)
			(xy 449.969299 -297.821393) (xy 449.934701 -297.863477) (xy 449.894097 -297.8998) (xy 449.848435 -297.929516)
			(xy 449.82384 -297.941238) (xy 449.793868 -297.9547) (xy 449.793868 -298.493413) (xy 450.555604 -298.493413)
			(xy 450.555604 -298.440115) (xy 450.563547 -298.387411) (xy 450.579257 -298.336481) (xy 450.602383 -298.28846)
			(xy 450.632407 -298.244423) (xy 450.668659 -298.205352) (xy 450.71033 -298.172121) (xy 450.756488 -298.145472)
			(xy 450.806102 -298.126) (xy 450.858064 -298.11414) (xy 450.911214 -298.110157) (xy 450.964364 -298.11414)
			(xy 451.016326 -298.126) (xy 451.06594 -298.145472) (xy 451.112098 -298.172121) (xy 451.153769 -298.205352)
			(xy 451.190021 -298.244423) (xy 451.220045 -298.28846) (xy 451.243171 -298.336481) (xy 451.258881 -298.387411)
			(xy 451.266824 -298.440115) (xy 451.267322 -298.466764) (xy 451.266824 -298.493413) (xy 452.765404 -298.493413)
			(xy 452.765404 -298.440115) (xy 452.773347 -298.387411) (xy 452.789057 -298.336481) (xy 452.812183 -298.28846)
			(xy 452.842207 -298.244423) (xy 452.878459 -298.205352) (xy 452.92013 -298.172121) (xy 452.966288 -298.145472)
			(xy 453.015902 -298.126) (xy 453.067864 -298.11414) (xy 453.121014 -298.110157) (xy 453.174164 -298.11414)
			(xy 453.226126 -298.126) (xy 453.27574 -298.145472) (xy 453.321898 -298.172121) (xy 453.363569 -298.205352)
			(xy 453.399821 -298.244423) (xy 453.429845 -298.28846) (xy 453.452971 -298.336481) (xy 453.468681 -298.387411)
			(xy 453.476624 -298.440115) (xy 453.477122 -298.466764) (xy 453.476624 -298.493413) (xy 454.655672 -298.493413)
			(xy 454.655672 -298.440115) (xy 454.663615 -298.387411) (xy 454.679325 -298.336481) (xy 454.702451 -298.28846)
			(xy 454.732475 -298.244423) (xy 454.768727 -298.205352) (xy 454.810398 -298.172121) (xy 454.856556 -298.145472)
			(xy 454.90617 -298.126) (xy 454.958132 -298.11414) (xy 455.011282 -298.110157) (xy 455.064432 -298.11414)
			(xy 455.116394 -298.126) (xy 455.166008 -298.145472) (xy 455.212166 -298.172121) (xy 455.253837 -298.205352)
			(xy 455.290089 -298.244423) (xy 455.320113 -298.28846) (xy 455.343239 -298.336481) (xy 455.358949 -298.387411)
			(xy 455.366892 -298.440115) (xy 455.36739 -298.466764) (xy 455.366892 -298.493413) (xy 458.099404 -298.493413)
			(xy 458.099404 -298.440115) (xy 458.107347 -298.387411) (xy 458.123057 -298.336481) (xy 458.146183 -298.28846)
			(xy 458.176207 -298.244423) (xy 458.212459 -298.205352) (xy 458.25413 -298.172121) (xy 458.300288 -298.145472)
			(xy 458.349902 -298.126) (xy 458.401864 -298.11414) (xy 458.455014 -298.110157) (xy 458.508164 -298.11414)
			(xy 458.560126 -298.126) (xy 458.60974 -298.145472) (xy 458.655898 -298.172121) (xy 458.697569 -298.205352)
			(xy 458.733821 -298.244423) (xy 458.763845 -298.28846) (xy 458.786971 -298.336481) (xy 458.802681 -298.387411)
			(xy 458.810624 -298.440115) (xy 458.811122 -298.466764) (xy 458.810624 -298.493413) (xy 458.802681 -298.546117)
			(xy 458.786971 -298.597047) (xy 458.763845 -298.645068) (xy 458.733821 -298.689105) (xy 458.697569 -298.728176)
			(xy 458.655898 -298.761407) (xy 458.60974 -298.788056) (xy 458.560126 -298.807528) (xy 458.508164 -298.819388)
			(xy 458.455014 -298.823372) (xy 458.401864 -298.819388) (xy 458.349902 -298.807528) (xy 458.300288 -298.788056)
			(xy 458.25413 -298.761407) (xy 458.212459 -298.728176) (xy 458.176207 -298.689105) (xy 458.146183 -298.645068)
			(xy 458.123057 -298.597047) (xy 458.107347 -298.546117) (xy 458.099404 -298.493413) (xy 455.366892 -298.493413)
			(xy 455.358949 -298.546117) (xy 455.343239 -298.597047) (xy 455.320113 -298.645068) (xy 455.290089 -298.689105)
			(xy 455.253837 -298.728176) (xy 455.212166 -298.761407) (xy 455.166008 -298.788056) (xy 455.116394 -298.807528)
			(xy 455.064432 -298.819388) (xy 455.011282 -298.823372) (xy 454.958132 -298.819388) (xy 454.90617 -298.807528)
			(xy 454.856556 -298.788056) (xy 454.810398 -298.761407) (xy 454.768727 -298.728176) (xy 454.732475 -298.689105)
			(xy 454.702451 -298.645068) (xy 454.679325 -298.597047) (xy 454.663615 -298.546117) (xy 454.655672 -298.493413)
			(xy 453.476624 -298.493413) (xy 453.468681 -298.546117) (xy 453.452971 -298.597047) (xy 453.429845 -298.645068)
			(xy 453.399821 -298.689105) (xy 453.363569 -298.728176) (xy 453.321898 -298.761407) (xy 453.27574 -298.788056)
			(xy 453.226126 -298.807528) (xy 453.174164 -298.819388) (xy 453.121014 -298.823372) (xy 453.067864 -298.819388)
			(xy 453.015902 -298.807528) (xy 452.966288 -298.788056) (xy 452.92013 -298.761407) (xy 452.878459 -298.728176)
			(xy 452.842207 -298.689105) (xy 452.812183 -298.645068) (xy 452.789057 -298.597047) (xy 452.773347 -298.546117)
			(xy 452.765404 -298.493413) (xy 451.266824 -298.493413) (xy 451.258881 -298.546117) (xy 451.243171 -298.597047)
			(xy 451.220045 -298.645068) (xy 451.190021 -298.689105) (xy 451.153769 -298.728176) (xy 451.112098 -298.761407)
			(xy 451.06594 -298.788056) (xy 451.016326 -298.807528) (xy 450.964364 -298.819388) (xy 450.911214 -298.823372)
			(xy 450.858064 -298.819388) (xy 450.806102 -298.807528) (xy 450.756488 -298.788056) (xy 450.71033 -298.761407)
			(xy 450.668659 -298.728176) (xy 450.632407 -298.689105) (xy 450.602383 -298.645068) (xy 450.579257 -298.597047)
			(xy 450.563547 -298.546117) (xy 450.555604 -298.493413) (xy 449.793868 -298.493413) (xy 449.793868 -298.978574)
			(xy 449.82384 -298.992036) (xy 449.848452 -299.003716) (xy 449.894109 -299.033434) (xy 449.934708 -299.069759)
			(xy 449.9693 -299.111843) (xy 449.997079 -299.158705) (xy 450.017396 -299.209251) (xy 450.029778 -299.262302)
			(xy 450.033936 -299.31662) (xy 450.031891 -299.343297) (xy 450.555604 -299.343297) (xy 450.555604 -299.289999)
			(xy 450.563547 -299.237295) (xy 450.579257 -299.186365) (xy 450.602383 -299.138344) (xy 450.632407 -299.094307)
			(xy 450.668659 -299.055236) (xy 450.71033 -299.022005) (xy 450.756488 -298.995356) (xy 450.806102 -298.975884)
			(xy 450.858064 -298.964024) (xy 450.911214 -298.960041) (xy 450.964364 -298.964024) (xy 451.016326 -298.975884)
			(xy 451.06594 -298.995356) (xy 451.112098 -299.022005) (xy 451.153769 -299.055236) (xy 451.190021 -299.094307)
			(xy 451.220045 -299.138344) (xy 451.243171 -299.186365) (xy 451.258881 -299.237295) (xy 451.266824 -299.289999)
			(xy 451.267322 -299.316648) (xy 451.266824 -299.343297) (xy 454.655672 -299.343297) (xy 454.655672 -299.289999)
			(xy 454.663615 -299.237295) (xy 454.679325 -299.186365) (xy 454.702451 -299.138344) (xy 454.732475 -299.094307)
			(xy 454.768727 -299.055236) (xy 454.810398 -299.022005) (xy 454.856556 -298.995356) (xy 454.90617 -298.975884)
			(xy 454.958132 -298.964024) (xy 455.011282 -298.960041) (xy 455.064432 -298.964024) (xy 455.116394 -298.975884)
			(xy 455.166008 -298.995356) (xy 455.212166 -299.022005) (xy 455.253837 -299.055236) (xy 455.290089 -299.094307)
			(xy 455.320113 -299.138344) (xy 455.343239 -299.186365) (xy 455.358949 -299.237295) (xy 455.366892 -299.289999)
			(xy 455.36739 -299.316648) (xy 455.366892 -299.343297) (xy 456.865472 -299.343297) (xy 456.865472 -299.289999)
			(xy 456.873415 -299.237295) (xy 456.889125 -299.186365) (xy 456.912251 -299.138344) (xy 456.942275 -299.094307)
			(xy 456.978527 -299.055236) (xy 457.020198 -299.022005) (xy 457.066356 -298.995356) (xy 457.11597 -298.975884)
			(xy 457.167932 -298.964024) (xy 457.221082 -298.960041) (xy 457.274232 -298.964024) (xy 457.326194 -298.975884)
			(xy 457.375808 -298.995356) (xy 457.421966 -299.022005) (xy 457.463637 -299.055236) (xy 457.499889 -299.094307)
			(xy 457.529913 -299.138344) (xy 457.553039 -299.186365) (xy 457.568749 -299.237295) (xy 457.576692 -299.289999)
			(xy 457.57719 -299.316648) (xy 457.576692 -299.343297) (xy 457.568749 -299.396001) (xy 457.553039 -299.446931)
			(xy 457.529913 -299.494952) (xy 457.499889 -299.538989) (xy 457.463637 -299.57806) (xy 457.421966 -299.611291)
			(xy 457.375808 -299.63794) (xy 457.326194 -299.657412) (xy 457.274232 -299.669272) (xy 457.221082 -299.673256)
			(xy 457.167932 -299.669272) (xy 457.11597 -299.657412) (xy 457.066356 -299.63794) (xy 457.020198 -299.611291)
			(xy 456.978527 -299.57806) (xy 456.942275 -299.538989) (xy 456.912251 -299.494952) (xy 456.889125 -299.446931)
			(xy 456.873415 -299.396001) (xy 456.865472 -299.343297) (xy 455.366892 -299.343297) (xy 455.358949 -299.396001)
			(xy 455.343239 -299.446931) (xy 455.320113 -299.494952) (xy 455.290089 -299.538989) (xy 455.253837 -299.57806)
			(xy 455.212166 -299.611291) (xy 455.166008 -299.63794) (xy 455.116394 -299.657412) (xy 455.064432 -299.669272)
			(xy 455.011282 -299.673256) (xy 454.958132 -299.669272) (xy 454.90617 -299.657412) (xy 454.856556 -299.63794)
			(xy 454.810398 -299.611291) (xy 454.768727 -299.57806) (xy 454.732475 -299.538989) (xy 454.702451 -299.494952)
			(xy 454.679325 -299.446931) (xy 454.663615 -299.396001) (xy 454.655672 -299.343297) (xy 451.266824 -299.343297)
			(xy 451.258881 -299.396001) (xy 451.243171 -299.446931) (xy 451.220045 -299.494952) (xy 451.190021 -299.538989)
			(xy 451.153769 -299.57806) (xy 451.112098 -299.611291) (xy 451.06594 -299.63794) (xy 451.016326 -299.657412)
			(xy 450.964364 -299.669272) (xy 450.911214 -299.673256) (xy 450.858064 -299.669272) (xy 450.806102 -299.657412)
			(xy 450.756488 -299.63794) (xy 450.71033 -299.611291) (xy 450.668659 -299.57806) (xy 450.632407 -299.538989)
			(xy 450.602383 -299.494952) (xy 450.579257 -299.446931) (xy 450.563547 -299.396001) (xy 450.555604 -299.343297)
			(xy 450.031891 -299.343297) (xy 450.029772 -299.370937) (xy 450.017384 -299.423987) (xy 449.997061 -299.47453)
			(xy 449.969277 -299.521389) (xy 449.93468 -299.56347) (xy 449.894078 -299.59979) (xy 449.848418 -299.629503)
			(xy 449.82384 -299.64126) (xy 449.793868 -299.654722) (xy 449.793868 -300.193435) (xy 450.555604 -300.193435)
			(xy 450.555604 -300.140137) (xy 450.563547 -300.087433) (xy 450.579257 -300.036503) (xy 450.602383 -299.988482)
			(xy 450.632407 -299.944445) (xy 450.668659 -299.905374) (xy 450.71033 -299.872143) (xy 450.756488 -299.845494)
			(xy 450.806102 -299.826022) (xy 450.858064 -299.814162) (xy 450.911214 -299.810179) (xy 450.964364 -299.814162)
			(xy 451.016326 -299.826022) (xy 451.06594 -299.845494) (xy 451.112098 -299.872143) (xy 451.153769 -299.905374)
			(xy 451.190021 -299.944445) (xy 451.220045 -299.988482) (xy 451.243171 -300.036503) (xy 451.258881 -300.087433)
			(xy 451.266824 -300.140137) (xy 451.267322 -300.166786) (xy 451.266824 -300.193435) (xy 452.765404 -300.193435)
			(xy 452.765404 -300.140137) (xy 452.773347 -300.087433) (xy 452.789057 -300.036503) (xy 452.812183 -299.988482)
			(xy 452.842207 -299.944445) (xy 452.878459 -299.905374) (xy 452.92013 -299.872143) (xy 452.966288 -299.845494)
			(xy 453.015902 -299.826022) (xy 453.067864 -299.814162) (xy 453.121014 -299.810179) (xy 453.174164 -299.814162)
			(xy 453.226126 -299.826022) (xy 453.27574 -299.845494) (xy 453.321898 -299.872143) (xy 453.363569 -299.905374)
			(xy 453.399821 -299.944445) (xy 453.429845 -299.988482) (xy 453.452971 -300.036503) (xy 453.468681 -300.087433)
			(xy 453.476624 -300.140137) (xy 453.477122 -300.166786) (xy 453.476629 -300.193181) (xy 454.655672 -300.193181)
			(xy 454.655672 -300.139883) (xy 454.663615 -300.087179) (xy 454.679325 -300.036249) (xy 454.702451 -299.988228)
			(xy 454.732475 -299.944191) (xy 454.768727 -299.90512) (xy 454.810398 -299.871889) (xy 454.856556 -299.84524)
			(xy 454.90617 -299.825768) (xy 454.958132 -299.813908) (xy 455.011282 -299.809925) (xy 455.064432 -299.813908)
			(xy 455.116394 -299.825768) (xy 455.166008 -299.84524) (xy 455.212166 -299.871889) (xy 455.253837 -299.90512)
			(xy 455.290089 -299.944191) (xy 455.320113 -299.988228) (xy 455.343239 -300.036249) (xy 455.358949 -300.087179)
			(xy 455.366892 -300.139883) (xy 455.36739 -300.166532) (xy 455.366892 -300.193181) (xy 455.366854 -300.193435)
			(xy 458.099404 -300.193435) (xy 458.099404 -300.140137) (xy 458.107347 -300.087433) (xy 458.123057 -300.036503)
			(xy 458.146183 -299.988482) (xy 458.176207 -299.944445) (xy 458.212459 -299.905374) (xy 458.25413 -299.872143)
			(xy 458.300288 -299.845494) (xy 458.349902 -299.826022) (xy 458.401864 -299.814162) (xy 458.455014 -299.810179)
			(xy 458.508164 -299.814162) (xy 458.560126 -299.826022) (xy 458.60974 -299.845494) (xy 458.655898 -299.872143)
			(xy 458.697569 -299.905374) (xy 458.733821 -299.944445) (xy 458.763845 -299.988482) (xy 458.786971 -300.036503)
			(xy 458.802681 -300.087433) (xy 458.810624 -300.140137) (xy 458.811122 -300.166786) (xy 458.810624 -300.193435)
			(xy 458.802681 -300.246139) (xy 458.786971 -300.297069) (xy 458.763845 -300.34509) (xy 458.733821 -300.389127)
			(xy 458.697569 -300.428198) (xy 458.655898 -300.461429) (xy 458.60974 -300.488078) (xy 458.560126 -300.50755)
			(xy 458.508164 -300.51941) (xy 458.455014 -300.523394) (xy 458.401864 -300.51941) (xy 458.349902 -300.50755)
			(xy 458.300288 -300.488078) (xy 458.25413 -300.461429) (xy 458.212459 -300.428198) (xy 458.176207 -300.389127)
			(xy 458.146183 -300.34509) (xy 458.123057 -300.297069) (xy 458.107347 -300.246139) (xy 458.099404 -300.193435)
			(xy 455.366854 -300.193435) (xy 455.358949 -300.245885) (xy 455.343239 -300.296815) (xy 455.320113 -300.344836)
			(xy 455.290089 -300.388873) (xy 455.253837 -300.427944) (xy 455.212166 -300.461175) (xy 455.166008 -300.487824)
			(xy 455.116394 -300.507296) (xy 455.064432 -300.519156) (xy 455.011282 -300.52314) (xy 454.958132 -300.519156)
			(xy 454.90617 -300.507296) (xy 454.856556 -300.487824) (xy 454.810398 -300.461175) (xy 454.768727 -300.427944)
			(xy 454.732475 -300.388873) (xy 454.702451 -300.344836) (xy 454.679325 -300.296815) (xy 454.663615 -300.245885)
			(xy 454.655672 -300.193181) (xy 453.476629 -300.193181) (xy 453.476624 -300.193435) (xy 453.468681 -300.246139)
			(xy 453.452971 -300.297069) (xy 453.429845 -300.34509) (xy 453.399821 -300.389127) (xy 453.363569 -300.428198)
			(xy 453.321898 -300.461429) (xy 453.27574 -300.488078) (xy 453.226126 -300.50755) (xy 453.174164 -300.51941)
			(xy 453.121014 -300.523394) (xy 453.067864 -300.51941) (xy 453.015902 -300.50755) (xy 452.966288 -300.488078)
			(xy 452.92013 -300.461429) (xy 452.878459 -300.428198) (xy 452.842207 -300.389127) (xy 452.812183 -300.34509)
			(xy 452.789057 -300.297069) (xy 452.773347 -300.246139) (xy 452.765404 -300.193435) (xy 451.266824 -300.193435)
			(xy 451.258881 -300.246139) (xy 451.243171 -300.297069) (xy 451.220045 -300.34509) (xy 451.190021 -300.389127)
			(xy 451.153769 -300.428198) (xy 451.112098 -300.461429) (xy 451.06594 -300.488078) (xy 451.016326 -300.50755)
			(xy 450.964364 -300.51941) (xy 450.911214 -300.523394) (xy 450.858064 -300.51941) (xy 450.806102 -300.50755)
			(xy 450.756488 -300.488078) (xy 450.71033 -300.461429) (xy 450.668659 -300.428198) (xy 450.632407 -300.389127)
			(xy 450.602383 -300.34509) (xy 450.579257 -300.297069) (xy 450.563547 -300.246139) (xy 450.555604 -300.193435)
			(xy 449.793868 -300.193435) (xy 449.793868 -300.678596) (xy 449.82384 -300.692058) (xy 449.848458 -300.703739)
			(xy 449.894127 -300.733458) (xy 449.934737 -300.769786) (xy 449.96934 -300.811876) (xy 449.997128 -300.858745)
			(xy 450.017454 -300.909299) (xy 450.029844 -300.962359) (xy 450.034007 -301.016688) (xy 450.031968 -301.043319)
			(xy 450.555604 -301.043319) (xy 450.555604 -300.990021) (xy 450.563547 -300.937317) (xy 450.579257 -300.886387)
			(xy 450.602383 -300.838366) (xy 450.632407 -300.794329) (xy 450.668659 -300.755258) (xy 450.71033 -300.722027)
			(xy 450.756488 -300.695378) (xy 450.806102 -300.675906) (xy 450.858064 -300.664046) (xy 450.911214 -300.660063)
			(xy 450.964364 -300.664046) (xy 451.016326 -300.675906) (xy 451.06594 -300.695378) (xy 451.112098 -300.722027)
			(xy 451.153769 -300.755258) (xy 451.190021 -300.794329) (xy 451.220045 -300.838366) (xy 451.243171 -300.886387)
			(xy 451.258881 -300.937317) (xy 451.266824 -300.990021) (xy 451.267322 -301.01667) (xy 451.266824 -301.043319)
			(xy 454.655672 -301.043319) (xy 454.655672 -300.990021) (xy 454.663615 -300.937317) (xy 454.679325 -300.886387)
			(xy 454.702451 -300.838366) (xy 454.732475 -300.794329) (xy 454.768727 -300.755258) (xy 454.810398 -300.722027)
			(xy 454.856556 -300.695378) (xy 454.90617 -300.675906) (xy 454.958132 -300.664046) (xy 455.011282 -300.660063)
			(xy 455.064432 -300.664046) (xy 455.116394 -300.675906) (xy 455.166008 -300.695378) (xy 455.212166 -300.722027)
			(xy 455.253837 -300.755258) (xy 455.290089 -300.794329) (xy 455.320113 -300.838366) (xy 455.343239 -300.886387)
			(xy 455.358949 -300.937317) (xy 455.366892 -300.990021) (xy 455.36739 -301.01667) (xy 455.366892 -301.043319)
			(xy 456.865472 -301.043319) (xy 456.865472 -300.990021) (xy 456.873415 -300.937317) (xy 456.889125 -300.886387)
			(xy 456.912251 -300.838366) (xy 456.942275 -300.794329) (xy 456.978527 -300.755258) (xy 457.020198 -300.722027)
			(xy 457.066356 -300.695378) (xy 457.11597 -300.675906) (xy 457.167932 -300.664046) (xy 457.221082 -300.660063)
			(xy 457.274232 -300.664046) (xy 457.326194 -300.675906) (xy 457.375808 -300.695378) (xy 457.421966 -300.722027)
			(xy 457.463637 -300.755258) (xy 457.499889 -300.794329) (xy 457.529913 -300.838366) (xy 457.553039 -300.886387)
			(xy 457.568749 -300.937317) (xy 457.576692 -300.990021) (xy 457.57719 -301.01667) (xy 457.576692 -301.043319)
			(xy 457.568749 -301.096023) (xy 457.553039 -301.146953) (xy 457.529913 -301.194974) (xy 457.499889 -301.239011)
			(xy 457.463637 -301.278082) (xy 457.421966 -301.311313) (xy 457.375808 -301.337962) (xy 457.326194 -301.357434)
			(xy 457.274232 -301.369294) (xy 457.221082 -301.373278) (xy 457.167932 -301.369294) (xy 457.11597 -301.357434)
			(xy 457.066356 -301.337962) (xy 457.020198 -301.311313) (xy 456.978527 -301.278082) (xy 456.942275 -301.239011)
			(xy 456.912251 -301.194974) (xy 456.889125 -301.146953) (xy 456.873415 -301.096023) (xy 456.865472 -301.043319)
			(xy 455.366892 -301.043319) (xy 455.358949 -301.096023) (xy 455.343239 -301.146953) (xy 455.320113 -301.194974)
			(xy 455.290089 -301.239011) (xy 455.253837 -301.278082) (xy 455.212166 -301.311313) (xy 455.166008 -301.337962)
			(xy 455.116394 -301.357434) (xy 455.064432 -301.369294) (xy 455.011282 -301.373278) (xy 454.958132 -301.369294)
			(xy 454.90617 -301.357434) (xy 454.856556 -301.337962) (xy 454.810398 -301.311313) (xy 454.768727 -301.278082)
			(xy 454.732475 -301.239011) (xy 454.702451 -301.194974) (xy 454.679325 -301.146953) (xy 454.663615 -301.096023)
			(xy 454.655672 -301.043319) (xy 451.266824 -301.043319) (xy 451.258881 -301.096023) (xy 451.243171 -301.146953)
			(xy 451.220045 -301.194974) (xy 451.190021 -301.239011) (xy 451.153769 -301.278082) (xy 451.112098 -301.311313)
			(xy 451.06594 -301.337962) (xy 451.016326 -301.357434) (xy 450.964364 -301.369294) (xy 450.911214 -301.373278)
			(xy 450.858064 -301.369294) (xy 450.806102 -301.357434) (xy 450.756488 -301.337962) (xy 450.71033 -301.311313)
			(xy 450.668659 -301.278082) (xy 450.632407 -301.239011) (xy 450.602383 -301.194974) (xy 450.579257 -301.146953)
			(xy 450.563547 -301.096023) (xy 450.555604 -301.043319) (xy 450.031968 -301.043319) (xy 450.029847 -301.071016)
			(xy 450.017462 -301.124077) (xy 449.997139 -301.174633) (xy 449.969354 -301.221504) (xy 449.934754 -301.263596)
			(xy 449.894147 -301.299927) (xy 449.84848 -301.32965) (xy 449.82384 -301.341282) (xy 449.793868 -301.354744)
			(xy 449.793868 -301.893457) (xy 450.555604 -301.893457) (xy 450.555604 -301.840159) (xy 450.563547 -301.787455)
			(xy 450.579257 -301.736525) (xy 450.602383 -301.688504) (xy 450.632407 -301.644467) (xy 450.668659 -301.605396)
			(xy 450.71033 -301.572165) (xy 450.756488 -301.545516) (xy 450.806102 -301.526044) (xy 450.858064 -301.514184)
			(xy 450.911214 -301.510201) (xy 450.964364 -301.514184) (xy 451.016326 -301.526044) (xy 451.06594 -301.545516)
			(xy 451.112098 -301.572165) (xy 451.153769 -301.605396) (xy 451.190021 -301.644467) (xy 451.220045 -301.688504)
			(xy 451.243171 -301.736525) (xy 451.258881 -301.787455) (xy 451.266824 -301.840159) (xy 451.267322 -301.866808)
			(xy 451.266824 -301.893457) (xy 452.765404 -301.893457) (xy 452.765404 -301.840159) (xy 452.773347 -301.787455)
			(xy 452.789057 -301.736525) (xy 452.812183 -301.688504) (xy 452.842207 -301.644467) (xy 452.878459 -301.605396)
			(xy 452.92013 -301.572165) (xy 452.966288 -301.545516) (xy 453.015902 -301.526044) (xy 453.067864 -301.514184)
			(xy 453.121014 -301.510201) (xy 453.174164 -301.514184) (xy 453.226126 -301.526044) (xy 453.27574 -301.545516)
			(xy 453.321898 -301.572165) (xy 453.363569 -301.605396) (xy 453.399821 -301.644467) (xy 453.429845 -301.688504)
			(xy 453.452971 -301.736525) (xy 453.468681 -301.787455) (xy 453.476624 -301.840159) (xy 453.477122 -301.866808)
			(xy 453.476629 -301.893203) (xy 454.655672 -301.893203) (xy 454.655672 -301.839905) (xy 454.663615 -301.787201)
			(xy 454.679325 -301.736271) (xy 454.702451 -301.68825) (xy 454.732475 -301.644213) (xy 454.768727 -301.605142)
			(xy 454.810398 -301.571911) (xy 454.856556 -301.545262) (xy 454.90617 -301.52579) (xy 454.958132 -301.51393)
			(xy 455.011282 -301.509947) (xy 455.064432 -301.51393) (xy 455.116394 -301.52579) (xy 455.166008 -301.545262)
			(xy 455.212166 -301.571911) (xy 455.253837 -301.605142) (xy 455.290089 -301.644213) (xy 455.320113 -301.68825)
			(xy 455.343239 -301.736271) (xy 455.358949 -301.787201) (xy 455.366892 -301.839905) (xy 455.36739 -301.866554)
			(xy 455.366892 -301.893203) (xy 455.366854 -301.893457) (xy 458.099404 -301.893457) (xy 458.099404 -301.840159)
			(xy 458.107347 -301.787455) (xy 458.123057 -301.736525) (xy 458.146183 -301.688504) (xy 458.176207 -301.644467)
			(xy 458.212459 -301.605396) (xy 458.25413 -301.572165) (xy 458.300288 -301.545516) (xy 458.349902 -301.526044)
			(xy 458.401864 -301.514184) (xy 458.455014 -301.510201) (xy 458.508164 -301.514184) (xy 458.560126 -301.526044)
			(xy 458.60974 -301.545516) (xy 458.655898 -301.572165) (xy 458.697569 -301.605396) (xy 458.733821 -301.644467)
			(xy 458.763845 -301.688504) (xy 458.786971 -301.736525) (xy 458.802681 -301.787455) (xy 458.810624 -301.840159)
			(xy 458.811122 -301.866808) (xy 458.810624 -301.893457) (xy 458.802681 -301.946161) (xy 458.786971 -301.997091)
			(xy 458.763845 -302.045112) (xy 458.733821 -302.089149) (xy 458.697569 -302.12822) (xy 458.655898 -302.161451)
			(xy 458.60974 -302.1881) (xy 458.560126 -302.207572) (xy 458.508164 -302.219432) (xy 458.455014 -302.223416)
			(xy 458.401864 -302.219432) (xy 458.349902 -302.207572) (xy 458.300288 -302.1881) (xy 458.25413 -302.161451)
			(xy 458.212459 -302.12822) (xy 458.176207 -302.089149) (xy 458.146183 -302.045112) (xy 458.123057 -301.997091)
			(xy 458.107347 -301.946161) (xy 458.099404 -301.893457) (xy 455.366854 -301.893457) (xy 455.358949 -301.945907)
			(xy 455.343239 -301.996837) (xy 455.320113 -302.044858) (xy 455.290089 -302.088895) (xy 455.253837 -302.127966)
			(xy 455.212166 -302.161197) (xy 455.166008 -302.187846) (xy 455.116394 -302.207318) (xy 455.064432 -302.219178)
			(xy 455.011282 -302.223162) (xy 454.958132 -302.219178) (xy 454.90617 -302.207318) (xy 454.856556 -302.187846)
			(xy 454.810398 -302.161197) (xy 454.768727 -302.127966) (xy 454.732475 -302.088895) (xy 454.702451 -302.044858)
			(xy 454.679325 -301.996837) (xy 454.663615 -301.945907) (xy 454.655672 -301.893203) (xy 453.476629 -301.893203)
			(xy 453.476624 -301.893457) (xy 453.468681 -301.946161) (xy 453.452971 -301.997091) (xy 453.429845 -302.045112)
			(xy 453.399821 -302.089149) (xy 453.363569 -302.12822) (xy 453.321898 -302.161451) (xy 453.27574 -302.1881)
			(xy 453.226126 -302.207572) (xy 453.174164 -302.219432) (xy 453.121014 -302.223416) (xy 453.067864 -302.219432)
			(xy 453.015902 -302.207572) (xy 452.966288 -302.1881) (xy 452.92013 -302.161451) (xy 452.878459 -302.12822)
			(xy 452.842207 -302.089149) (xy 452.812183 -302.045112) (xy 452.789057 -301.997091) (xy 452.773347 -301.946161)
			(xy 452.765404 -301.893457) (xy 451.266824 -301.893457) (xy 451.258881 -301.946161) (xy 451.243171 -301.997091)
			(xy 451.220045 -302.045112) (xy 451.190021 -302.089149) (xy 451.153769 -302.12822) (xy 451.112098 -302.161451)
			(xy 451.06594 -302.1881) (xy 451.016326 -302.207572) (xy 450.964364 -302.219432) (xy 450.911214 -302.223416)
			(xy 450.858064 -302.219432) (xy 450.806102 -302.207572) (xy 450.756488 -302.1881) (xy 450.71033 -302.161451)
			(xy 450.668659 -302.12822) (xy 450.632407 -302.089149) (xy 450.602383 -302.045112) (xy 450.579257 -301.997091)
			(xy 450.563547 -301.946161) (xy 450.555604 -301.893457) (xy 449.793868 -301.893457) (xy 449.793868 -302.743341)
			(xy 450.555604 -302.743341) (xy 450.555604 -302.690043) (xy 450.563547 -302.637339) (xy 450.579257 -302.586409)
			(xy 450.602383 -302.538388) (xy 450.632407 -302.494351) (xy 450.668659 -302.45528) (xy 450.71033 -302.422049)
			(xy 450.756488 -302.3954) (xy 450.806102 -302.375928) (xy 450.858064 -302.364068) (xy 450.911214 -302.360085)
			(xy 450.964364 -302.364068) (xy 451.016326 -302.375928) (xy 451.06594 -302.3954) (xy 451.112098 -302.422049)
			(xy 451.153769 -302.45528) (xy 451.190021 -302.494351) (xy 451.220045 -302.538388) (xy 451.243171 -302.586409)
			(xy 451.258881 -302.637339) (xy 451.266824 -302.690043) (xy 451.267322 -302.716692) (xy 451.266824 -302.743341)
			(xy 454.655672 -302.743341) (xy 454.655672 -302.690043) (xy 454.663615 -302.637339) (xy 454.679325 -302.586409)
			(xy 454.702451 -302.538388) (xy 454.732475 -302.494351) (xy 454.768727 -302.45528) (xy 454.810398 -302.422049)
			(xy 454.856556 -302.3954) (xy 454.90617 -302.375928) (xy 454.958132 -302.364068) (xy 455.011282 -302.360085)
			(xy 455.064432 -302.364068) (xy 455.116394 -302.375928) (xy 455.166008 -302.3954) (xy 455.212166 -302.422049)
			(xy 455.253837 -302.45528) (xy 455.290089 -302.494351) (xy 455.320113 -302.538388) (xy 455.343239 -302.586409)
			(xy 455.358949 -302.637339) (xy 455.366892 -302.690043) (xy 455.36739 -302.716692) (xy 455.366892 -302.743341)
			(xy 455.358949 -302.796045) (xy 455.343239 -302.846975) (xy 455.320113 -302.894996) (xy 455.290089 -302.939033)
			(xy 455.253837 -302.978104) (xy 455.212166 -303.011335) (xy 455.166008 -303.037984) (xy 455.116394 -303.057456)
			(xy 455.064432 -303.069316) (xy 455.011282 -303.0733) (xy 454.958132 -303.069316) (xy 454.90617 -303.057456)
			(xy 454.856556 -303.037984) (xy 454.810398 -303.011335) (xy 454.768727 -302.978104) (xy 454.732475 -302.939033)
			(xy 454.702451 -302.894996) (xy 454.679325 -302.846975) (xy 454.663615 -302.796045) (xy 454.655672 -302.743341)
			(xy 451.266824 -302.743341) (xy 451.258881 -302.796045) (xy 451.243171 -302.846975) (xy 451.220045 -302.894996)
			(xy 451.190021 -302.939033) (xy 451.153769 -302.978104) (xy 451.112098 -303.011335) (xy 451.06594 -303.037984)
			(xy 451.016326 -303.057456) (xy 450.964364 -303.069316) (xy 450.911214 -303.0733) (xy 450.858064 -303.069316)
			(xy 450.806102 -303.057456) (xy 450.756488 -303.037984) (xy 450.71033 -303.011335) (xy 450.668659 -302.978104)
			(xy 450.632407 -302.939033) (xy 450.602383 -302.894996) (xy 450.579257 -302.846975) (xy 450.563547 -302.796045)
			(xy 450.555604 -302.743341) (xy 449.793868 -302.743341) (xy 449.793868 -303.228502) (xy 449.82384 -303.241964)
			(xy 449.848458 -303.253645) (xy 449.894126 -303.283364) (xy 449.934734 -303.319692) (xy 449.969336 -303.361781)
			(xy 449.997124 -303.408649) (xy 450.01745 -303.459203) (xy 450.029839 -303.512263) (xy 450.034002 -303.56659)
			(xy 450.031963 -303.593225) (xy 450.555604 -303.593225) (xy 450.555604 -303.539927) (xy 450.563547 -303.487223)
			(xy 450.579257 -303.436293) (xy 450.602383 -303.388272) (xy 450.632407 -303.344235) (xy 450.668659 -303.305164)
			(xy 450.71033 -303.271933) (xy 450.756488 -303.245284) (xy 450.806102 -303.225812) (xy 450.858064 -303.213952)
			(xy 450.911214 -303.209969) (xy 450.964364 -303.213952) (xy 451.016326 -303.225812) (xy 451.06594 -303.245284)
			(xy 451.112098 -303.271933) (xy 451.153769 -303.305164) (xy 451.190021 -303.344235) (xy 451.220045 -303.388272)
			(xy 451.243171 -303.436293) (xy 451.258881 -303.487223) (xy 451.266824 -303.539927) (xy 451.267322 -303.566576)
			(xy 451.266824 -303.593225) (xy 454.655672 -303.593225) (xy 454.655672 -303.539927) (xy 454.663615 -303.487223)
			(xy 454.679325 -303.436293) (xy 454.702451 -303.388272) (xy 454.732475 -303.344235) (xy 454.768727 -303.305164)
			(xy 454.810398 -303.271933) (xy 454.856556 -303.245284) (xy 454.90617 -303.225812) (xy 454.958132 -303.213952)
			(xy 455.011282 -303.209969) (xy 455.064432 -303.213952) (xy 455.116394 -303.225812) (xy 455.166008 -303.245284)
			(xy 455.212166 -303.271933) (xy 455.253837 -303.305164) (xy 455.290089 -303.344235) (xy 455.320113 -303.388272)
			(xy 455.343239 -303.436293) (xy 455.358949 -303.487223) (xy 455.366892 -303.539927) (xy 455.36739 -303.566576)
			(xy 455.366892 -303.593225) (xy 456.865472 -303.593225) (xy 456.865472 -303.539927) (xy 456.873415 -303.487223)
			(xy 456.889125 -303.436293) (xy 456.912251 -303.388272) (xy 456.942275 -303.344235) (xy 456.978527 -303.305164)
			(xy 457.020198 -303.271933) (xy 457.066356 -303.245284) (xy 457.11597 -303.225812) (xy 457.167932 -303.213952)
			(xy 457.221082 -303.209969) (xy 457.274232 -303.213952) (xy 457.326194 -303.225812) (xy 457.375808 -303.245284)
			(xy 457.421966 -303.271933) (xy 457.463637 -303.305164) (xy 457.499889 -303.344235) (xy 457.529913 -303.388272)
			(xy 457.553039 -303.436293) (xy 457.568749 -303.487223) (xy 457.576692 -303.539927) (xy 457.57719 -303.566576)
			(xy 457.576692 -303.593225) (xy 457.568749 -303.645929) (xy 457.553039 -303.696859) (xy 457.529913 -303.74488)
			(xy 457.499889 -303.788917) (xy 457.463637 -303.827988) (xy 457.421966 -303.861219) (xy 457.375808 -303.887868)
			(xy 457.326194 -303.90734) (xy 457.274232 -303.9192) (xy 457.221082 -303.923184) (xy 457.167932 -303.9192)
			(xy 457.11597 -303.90734) (xy 457.066356 -303.887868) (xy 457.020198 -303.861219) (xy 456.978527 -303.827988)
			(xy 456.942275 -303.788917) (xy 456.912251 -303.74488) (xy 456.889125 -303.696859) (xy 456.873415 -303.645929)
			(xy 456.865472 -303.593225) (xy 455.366892 -303.593225) (xy 455.358949 -303.645929) (xy 455.343239 -303.696859)
			(xy 455.320113 -303.74488) (xy 455.290089 -303.788917) (xy 455.253837 -303.827988) (xy 455.212166 -303.861219)
			(xy 455.166008 -303.887868) (xy 455.116394 -303.90734) (xy 455.064432 -303.9192) (xy 455.011282 -303.923184)
			(xy 454.958132 -303.9192) (xy 454.90617 -303.90734) (xy 454.856556 -303.887868) (xy 454.810398 -303.861219)
			(xy 454.768727 -303.827988) (xy 454.732475 -303.788917) (xy 454.702451 -303.74488) (xy 454.679325 -303.696859)
			(xy 454.663615 -303.645929) (xy 454.655672 -303.593225) (xy 451.266824 -303.593225) (xy 451.258881 -303.645929)
			(xy 451.243171 -303.696859) (xy 451.220045 -303.74488) (xy 451.190021 -303.788917) (xy 451.153769 -303.827988)
			(xy 451.112098 -303.861219) (xy 451.06594 -303.887868) (xy 451.016326 -303.90734) (xy 450.964364 -303.9192)
			(xy 450.911214 -303.923184) (xy 450.858064 -303.9192) (xy 450.806102 -303.90734) (xy 450.756488 -303.887868)
			(xy 450.71033 -303.861219) (xy 450.668659 -303.827988) (xy 450.632407 -303.788917) (xy 450.602383 -303.74488)
			(xy 450.579257 -303.696859) (xy 450.563547 -303.645929) (xy 450.555604 -303.593225) (xy 450.031963 -303.593225)
			(xy 450.029842 -303.620918) (xy 450.017456 -303.673978) (xy 449.997133 -303.724533) (xy 449.969348 -303.771403)
			(xy 449.934748 -303.813494) (xy 449.894141 -303.849824) (xy 449.848475 -303.879546) (xy 449.82384 -303.891188)
			(xy 449.793868 -303.90465) (xy 449.793868 -304.443363) (xy 450.555604 -304.443363) (xy 450.555604 -304.390065)
			(xy 450.563547 -304.337361) (xy 450.579257 -304.286431) (xy 450.602383 -304.23841) (xy 450.632407 -304.194373)
			(xy 450.668659 -304.155302) (xy 450.71033 -304.122071) (xy 450.756488 -304.095422) (xy 450.806102 -304.07595)
			(xy 450.858064 -304.06409) (xy 450.911214 -304.060107) (xy 450.964364 -304.06409) (xy 451.016326 -304.07595)
			(xy 451.06594 -304.095422) (xy 451.112098 -304.122071) (xy 451.153769 -304.155302) (xy 451.190021 -304.194373)
			(xy 451.220045 -304.23841) (xy 451.243171 -304.286431) (xy 451.258881 -304.337361) (xy 451.266824 -304.390065)
			(xy 451.267322 -304.416714) (xy 451.266824 -304.443363) (xy 452.765404 -304.443363) (xy 452.765404 -304.390065)
			(xy 452.773347 -304.337361) (xy 452.789057 -304.286431) (xy 452.812183 -304.23841) (xy 452.842207 -304.194373)
			(xy 452.878459 -304.155302) (xy 452.92013 -304.122071) (xy 452.966288 -304.095422) (xy 453.015902 -304.07595)
			(xy 453.067864 -304.06409) (xy 453.121014 -304.060107) (xy 453.174164 -304.06409) (xy 453.226126 -304.07595)
			(xy 453.27574 -304.095422) (xy 453.321898 -304.122071) (xy 453.363569 -304.155302) (xy 453.399821 -304.194373)
			(xy 453.429845 -304.23841) (xy 453.452971 -304.286431) (xy 453.468681 -304.337361) (xy 453.476624 -304.390065)
			(xy 453.477122 -304.416714) (xy 453.476624 -304.443363) (xy 454.655672 -304.443363) (xy 454.655672 -304.390065)
			(xy 454.663615 -304.337361) (xy 454.679325 -304.286431) (xy 454.702451 -304.23841) (xy 454.732475 -304.194373)
			(xy 454.768727 -304.155302) (xy 454.810398 -304.122071) (xy 454.856556 -304.095422) (xy 454.90617 -304.07595)
			(xy 454.958132 -304.06409) (xy 455.011282 -304.060107) (xy 455.064432 -304.06409) (xy 455.116394 -304.07595)
			(xy 455.166008 -304.095422) (xy 455.212166 -304.122071) (xy 455.253837 -304.155302) (xy 455.290089 -304.194373)
			(xy 455.320113 -304.23841) (xy 455.343239 -304.286431) (xy 455.358949 -304.337361) (xy 455.366892 -304.390065)
			(xy 455.36739 -304.416714) (xy 455.366892 -304.443363) (xy 458.099404 -304.443363) (xy 458.099404 -304.390065)
			(xy 458.107347 -304.337361) (xy 458.123057 -304.286431) (xy 458.146183 -304.23841) (xy 458.176207 -304.194373)
			(xy 458.212459 -304.155302) (xy 458.25413 -304.122071) (xy 458.300288 -304.095422) (xy 458.349902 -304.07595)
			(xy 458.401864 -304.06409) (xy 458.455014 -304.060107) (xy 458.508164 -304.06409) (xy 458.560126 -304.07595)
			(xy 458.60974 -304.095422) (xy 458.655898 -304.122071) (xy 458.697569 -304.155302) (xy 458.733821 -304.194373)
			(xy 458.763845 -304.23841) (xy 458.786971 -304.286431) (xy 458.802681 -304.337361) (xy 458.810624 -304.390065)
			(xy 458.811122 -304.416714) (xy 458.810624 -304.443363) (xy 458.802681 -304.496067) (xy 458.786971 -304.546997)
			(xy 458.763845 -304.595018) (xy 458.733821 -304.639055) (xy 458.697569 -304.678126) (xy 458.655898 -304.711357)
			(xy 458.60974 -304.738006) (xy 458.560126 -304.757478) (xy 458.508164 -304.769338) (xy 458.455014 -304.773322)
			(xy 458.401864 -304.769338) (xy 458.349902 -304.757478) (xy 458.300288 -304.738006) (xy 458.25413 -304.711357)
			(xy 458.212459 -304.678126) (xy 458.176207 -304.639055) (xy 458.146183 -304.595018) (xy 458.123057 -304.546997)
			(xy 458.107347 -304.496067) (xy 458.099404 -304.443363) (xy 455.366892 -304.443363) (xy 455.358949 -304.496067)
			(xy 455.343239 -304.546997) (xy 455.320113 -304.595018) (xy 455.290089 -304.639055) (xy 455.253837 -304.678126)
			(xy 455.212166 -304.711357) (xy 455.166008 -304.738006) (xy 455.116394 -304.757478) (xy 455.064432 -304.769338)
			(xy 455.011282 -304.773322) (xy 454.958132 -304.769338) (xy 454.90617 -304.757478) (xy 454.856556 -304.738006)
			(xy 454.810398 -304.711357) (xy 454.768727 -304.678126) (xy 454.732475 -304.639055) (xy 454.702451 -304.595018)
			(xy 454.679325 -304.546997) (xy 454.663615 -304.496067) (xy 454.655672 -304.443363) (xy 453.476624 -304.443363)
			(xy 453.468681 -304.496067) (xy 453.452971 -304.546997) (xy 453.429845 -304.595018) (xy 453.399821 -304.639055)
			(xy 453.363569 -304.678126) (xy 453.321898 -304.711357) (xy 453.27574 -304.738006) (xy 453.226126 -304.757478)
			(xy 453.174164 -304.769338) (xy 453.121014 -304.773322) (xy 453.067864 -304.769338) (xy 453.015902 -304.757478)
			(xy 452.966288 -304.738006) (xy 452.92013 -304.711357) (xy 452.878459 -304.678126) (xy 452.842207 -304.639055)
			(xy 452.812183 -304.595018) (xy 452.789057 -304.546997) (xy 452.773347 -304.496067) (xy 452.765404 -304.443363)
			(xy 451.266824 -304.443363) (xy 451.258881 -304.496067) (xy 451.243171 -304.546997) (xy 451.220045 -304.595018)
			(xy 451.190021 -304.639055) (xy 451.153769 -304.678126) (xy 451.112098 -304.711357) (xy 451.06594 -304.738006)
			(xy 451.016326 -304.757478) (xy 450.964364 -304.769338) (xy 450.911214 -304.773322) (xy 450.858064 -304.769338)
			(xy 450.806102 -304.757478) (xy 450.756488 -304.738006) (xy 450.71033 -304.711357) (xy 450.668659 -304.678126)
			(xy 450.632407 -304.639055) (xy 450.602383 -304.595018) (xy 450.579257 -304.546997) (xy 450.563547 -304.496067)
			(xy 450.555604 -304.443363) (xy 449.793868 -304.443363) (xy 449.793868 -304.928524) (xy 449.82384 -304.941986)
			(xy 449.848456 -304.953667) (xy 449.894121 -304.983385) (xy 449.934726 -305.019712) (xy 449.969325 -305.0618)
			(xy 449.99711 -305.108666) (xy 450.017434 -305.159218) (xy 450.02982 -305.212275) (xy 450.033982 -305.266599)
			(xy 450.03194 -305.293247) (xy 450.555604 -305.293247) (xy 450.555604 -305.239949) (xy 450.563547 -305.187245)
			(xy 450.579257 -305.136315) (xy 450.602383 -305.088294) (xy 450.632407 -305.044257) (xy 450.668659 -305.005186)
			(xy 450.71033 -304.971955) (xy 450.756488 -304.945306) (xy 450.806102 -304.925834) (xy 450.858064 -304.913974)
			(xy 450.911214 -304.909991) (xy 450.964364 -304.913974) (xy 451.016326 -304.925834) (xy 451.06594 -304.945306)
			(xy 451.112098 -304.971955) (xy 451.153769 -305.005186) (xy 451.190021 -305.044257) (xy 451.220045 -305.088294)
			(xy 451.243171 -305.136315) (xy 451.258881 -305.187245) (xy 451.266824 -305.239949) (xy 451.267322 -305.266598)
			(xy 451.266824 -305.293247) (xy 454.655672 -305.293247) (xy 454.655672 -305.239949) (xy 454.663615 -305.187245)
			(xy 454.679325 -305.136315) (xy 454.702451 -305.088294) (xy 454.732475 -305.044257) (xy 454.768727 -305.005186)
			(xy 454.810398 -304.971955) (xy 454.856556 -304.945306) (xy 454.90617 -304.925834) (xy 454.958132 -304.913974)
			(xy 455.011282 -304.909991) (xy 455.064432 -304.913974) (xy 455.116394 -304.925834) (xy 455.166008 -304.945306)
			(xy 455.212166 -304.971955) (xy 455.253837 -305.005186) (xy 455.290089 -305.044257) (xy 455.320113 -305.088294)
			(xy 455.343239 -305.136315) (xy 455.358949 -305.187245) (xy 455.366892 -305.239949) (xy 455.36739 -305.266598)
			(xy 455.366892 -305.293247) (xy 456.865472 -305.293247) (xy 456.865472 -305.239949) (xy 456.873415 -305.187245)
			(xy 456.889125 -305.136315) (xy 456.912251 -305.088294) (xy 456.942275 -305.044257) (xy 456.978527 -305.005186)
			(xy 457.020198 -304.971955) (xy 457.066356 -304.945306) (xy 457.11597 -304.925834) (xy 457.167932 -304.913974)
			(xy 457.221082 -304.909991) (xy 457.274232 -304.913974) (xy 457.326194 -304.925834) (xy 457.375808 -304.945306)
			(xy 457.421966 -304.971955) (xy 457.463637 -305.005186) (xy 457.499889 -305.044257) (xy 457.529913 -305.088294)
			(xy 457.553039 -305.136315) (xy 457.568749 -305.187245) (xy 457.576692 -305.239949) (xy 457.57719 -305.266598)
			(xy 457.576692 -305.293247) (xy 457.568749 -305.345951) (xy 457.553039 -305.396881) (xy 457.529913 -305.444902)
			(xy 457.499889 -305.488939) (xy 457.463637 -305.52801) (xy 457.421966 -305.561241) (xy 457.375808 -305.58789)
			(xy 457.326194 -305.607362) (xy 457.274232 -305.619222) (xy 457.221082 -305.623206) (xy 457.167932 -305.619222)
			(xy 457.11597 -305.607362) (xy 457.066356 -305.58789) (xy 457.020198 -305.561241) (xy 456.978527 -305.52801)
			(xy 456.942275 -305.488939) (xy 456.912251 -305.444902) (xy 456.889125 -305.396881) (xy 456.873415 -305.345951)
			(xy 456.865472 -305.293247) (xy 455.366892 -305.293247) (xy 455.358949 -305.345951) (xy 455.343239 -305.396881)
			(xy 455.320113 -305.444902) (xy 455.290089 -305.488939) (xy 455.253837 -305.52801) (xy 455.212166 -305.561241)
			(xy 455.166008 -305.58789) (xy 455.116394 -305.607362) (xy 455.064432 -305.619222) (xy 455.011282 -305.623206)
			(xy 454.958132 -305.619222) (xy 454.90617 -305.607362) (xy 454.856556 -305.58789) (xy 454.810398 -305.561241)
			(xy 454.768727 -305.52801) (xy 454.732475 -305.488939) (xy 454.702451 -305.444902) (xy 454.679325 -305.396881)
			(xy 454.663615 -305.345951) (xy 454.655672 -305.293247) (xy 451.266824 -305.293247) (xy 451.258881 -305.345951)
			(xy 451.243171 -305.396881) (xy 451.220045 -305.444902) (xy 451.190021 -305.488939) (xy 451.153769 -305.52801)
			(xy 451.112098 -305.561241) (xy 451.06594 -305.58789) (xy 451.016326 -305.607362) (xy 450.964364 -305.619222)
			(xy 450.911214 -305.623206) (xy 450.858064 -305.619222) (xy 450.806102 -305.607362) (xy 450.756488 -305.58789)
			(xy 450.71033 -305.561241) (xy 450.668659 -305.52801) (xy 450.632407 -305.488939) (xy 450.602383 -305.444902)
			(xy 450.579257 -305.396881) (xy 450.563547 -305.345951) (xy 450.555604 -305.293247) (xy 450.03194 -305.293247)
			(xy 450.02982 -305.320924) (xy 450.017434 -305.373981) (xy 449.997111 -305.424532) (xy 449.969326 -305.471399)
			(xy 449.934727 -305.513486) (xy 449.894122 -305.549814) (xy 449.848457 -305.579533) (xy 449.82384 -305.59121)
			(xy 449.793868 -305.604672) (xy 449.793868 -306.143385) (xy 450.555604 -306.143385) (xy 450.555604 -306.090087)
			(xy 450.563547 -306.037383) (xy 450.579257 -305.986453) (xy 450.602383 -305.938432) (xy 450.632407 -305.894395)
			(xy 450.668659 -305.855324) (xy 450.71033 -305.822093) (xy 450.756488 -305.795444) (xy 450.806102 -305.775972)
			(xy 450.858064 -305.764112) (xy 450.911214 -305.760129) (xy 450.964364 -305.764112) (xy 451.016326 -305.775972)
			(xy 451.06594 -305.795444) (xy 451.112098 -305.822093) (xy 451.153769 -305.855324) (xy 451.190021 -305.894395)
			(xy 451.220045 -305.938432) (xy 451.243171 -305.986453) (xy 451.258881 -306.037383) (xy 451.266824 -306.090087)
			(xy 451.267322 -306.116736) (xy 451.266824 -306.143385) (xy 452.765404 -306.143385) (xy 452.765404 -306.090087)
			(xy 452.773347 -306.037383) (xy 452.789057 -305.986453) (xy 452.812183 -305.938432) (xy 452.842207 -305.894395)
			(xy 452.878459 -305.855324) (xy 452.92013 -305.822093) (xy 452.966288 -305.795444) (xy 453.015902 -305.775972)
			(xy 453.067864 -305.764112) (xy 453.121014 -305.760129) (xy 453.174164 -305.764112) (xy 453.226126 -305.775972)
			(xy 453.27574 -305.795444) (xy 453.321898 -305.822093) (xy 453.363569 -305.855324) (xy 453.399821 -305.894395)
			(xy 453.429845 -305.938432) (xy 453.452971 -305.986453) (xy 453.468681 -306.037383) (xy 453.476624 -306.090087)
			(xy 453.477122 -306.116736) (xy 453.476624 -306.143385) (xy 454.655672 -306.143385) (xy 454.655672 -306.090087)
			(xy 454.663615 -306.037383) (xy 454.679325 -305.986453) (xy 454.702451 -305.938432) (xy 454.732475 -305.894395)
			(xy 454.768727 -305.855324) (xy 454.810398 -305.822093) (xy 454.856556 -305.795444) (xy 454.90617 -305.775972)
			(xy 454.958132 -305.764112) (xy 455.011282 -305.760129) (xy 455.064432 -305.764112) (xy 455.116394 -305.775972)
			(xy 455.166008 -305.795444) (xy 455.212166 -305.822093) (xy 455.253837 -305.855324) (xy 455.290089 -305.894395)
			(xy 455.320113 -305.938432) (xy 455.343239 -305.986453) (xy 455.358949 -306.037383) (xy 455.366892 -306.090087)
			(xy 455.36739 -306.116736) (xy 455.366892 -306.143385) (xy 458.099404 -306.143385) (xy 458.099404 -306.090087)
			(xy 458.107347 -306.037383) (xy 458.123057 -305.986453) (xy 458.146183 -305.938432) (xy 458.176207 -305.894395)
			(xy 458.212459 -305.855324) (xy 458.25413 -305.822093) (xy 458.300288 -305.795444) (xy 458.349902 -305.775972)
			(xy 458.401864 -305.764112) (xy 458.455014 -305.760129) (xy 458.508164 -305.764112) (xy 458.560126 -305.775972)
			(xy 458.60974 -305.795444) (xy 458.655898 -305.822093) (xy 458.697569 -305.855324) (xy 458.733821 -305.894395)
			(xy 458.763845 -305.938432) (xy 458.786971 -305.986453) (xy 458.802681 -306.037383) (xy 458.810624 -306.090087)
			(xy 458.811122 -306.116736) (xy 458.810624 -306.143385) (xy 458.802681 -306.196089) (xy 458.786971 -306.247019)
			(xy 458.763845 -306.29504) (xy 458.733821 -306.339077) (xy 458.697569 -306.378148) (xy 458.655898 -306.411379)
			(xy 458.60974 -306.438028) (xy 458.560126 -306.4575) (xy 458.508164 -306.46936) (xy 458.455014 -306.473344)
			(xy 458.401864 -306.46936) (xy 458.349902 -306.4575) (xy 458.300288 -306.438028) (xy 458.25413 -306.411379)
			(xy 458.212459 -306.378148) (xy 458.176207 -306.339077) (xy 458.146183 -306.29504) (xy 458.123057 -306.247019)
			(xy 458.107347 -306.196089) (xy 458.099404 -306.143385) (xy 455.366892 -306.143385) (xy 455.358949 -306.196089)
			(xy 455.343239 -306.247019) (xy 455.320113 -306.29504) (xy 455.290089 -306.339077) (xy 455.253837 -306.378148)
			(xy 455.212166 -306.411379) (xy 455.166008 -306.438028) (xy 455.116394 -306.4575) (xy 455.064432 -306.46936)
			(xy 455.011282 -306.473344) (xy 454.958132 -306.46936) (xy 454.90617 -306.4575) (xy 454.856556 -306.438028)
			(xy 454.810398 -306.411379) (xy 454.768727 -306.378148) (xy 454.732475 -306.339077) (xy 454.702451 -306.29504)
			(xy 454.679325 -306.247019) (xy 454.663615 -306.196089) (xy 454.655672 -306.143385) (xy 453.476624 -306.143385)
			(xy 453.468681 -306.196089) (xy 453.452971 -306.247019) (xy 453.429845 -306.29504) (xy 453.399821 -306.339077)
			(xy 453.363569 -306.378148) (xy 453.321898 -306.411379) (xy 453.27574 -306.438028) (xy 453.226126 -306.4575)
			(xy 453.174164 -306.46936) (xy 453.121014 -306.473344) (xy 453.067864 -306.46936) (xy 453.015902 -306.4575)
			(xy 452.966288 -306.438028) (xy 452.92013 -306.411379) (xy 452.878459 -306.378148) (xy 452.842207 -306.339077)
			(xy 452.812183 -306.29504) (xy 452.789057 -306.247019) (xy 452.773347 -306.196089) (xy 452.765404 -306.143385)
			(xy 451.266824 -306.143385) (xy 451.258881 -306.196089) (xy 451.243171 -306.247019) (xy 451.220045 -306.29504)
			(xy 451.190021 -306.339077) (xy 451.153769 -306.378148) (xy 451.112098 -306.411379) (xy 451.06594 -306.438028)
			(xy 451.016326 -306.4575) (xy 450.964364 -306.46936) (xy 450.911214 -306.473344) (xy 450.858064 -306.46936)
			(xy 450.806102 -306.4575) (xy 450.756488 -306.438028) (xy 450.71033 -306.411379) (xy 450.668659 -306.378148)
			(xy 450.632407 -306.339077) (xy 450.602383 -306.29504) (xy 450.579257 -306.247019) (xy 450.563547 -306.196089)
			(xy 450.555604 -306.143385) (xy 449.793868 -306.143385) (xy 449.793868 -306.628546) (xy 449.82384 -306.642008)
			(xy 449.848454 -306.653688) (xy 449.894116 -306.683407) (xy 449.934718 -306.719733) (xy 449.969314 -306.761819)
			(xy 449.997096 -306.808683) (xy 450.017417 -306.859232) (xy 450.029802 -306.912287) (xy 450.033962 -306.966608)
			(xy 450.031919 -306.993269) (xy 450.555604 -306.993269) (xy 450.555604 -306.939971) (xy 450.563547 -306.887267)
			(xy 450.579257 -306.836337) (xy 450.602383 -306.788316) (xy 450.632407 -306.744279) (xy 450.668659 -306.705208)
			(xy 450.71033 -306.671977) (xy 450.756488 -306.645328) (xy 450.806102 -306.625856) (xy 450.858064 -306.613996)
			(xy 450.911214 -306.610013) (xy 450.964364 -306.613996) (xy 451.016326 -306.625856) (xy 451.06594 -306.645328)
			(xy 451.112098 -306.671977) (xy 451.153769 -306.705208) (xy 451.190021 -306.744279) (xy 451.220045 -306.788316)
			(xy 451.243171 -306.836337) (xy 451.258881 -306.887267) (xy 451.266824 -306.939971) (xy 451.267322 -306.96662)
			(xy 451.266824 -306.993269) (xy 454.655672 -306.993269) (xy 454.655672 -306.939971) (xy 454.663615 -306.887267)
			(xy 454.679325 -306.836337) (xy 454.702451 -306.788316) (xy 454.732475 -306.744279) (xy 454.768727 -306.705208)
			(xy 454.810398 -306.671977) (xy 454.856556 -306.645328) (xy 454.90617 -306.625856) (xy 454.958132 -306.613996)
			(xy 455.011282 -306.610013) (xy 455.064432 -306.613996) (xy 455.116394 -306.625856) (xy 455.166008 -306.645328)
			(xy 455.212166 -306.671977) (xy 455.253837 -306.705208) (xy 455.290089 -306.744279) (xy 455.320113 -306.788316)
			(xy 455.343239 -306.836337) (xy 455.358949 -306.887267) (xy 455.366892 -306.939971) (xy 455.36739 -306.96662)
			(xy 455.366892 -306.993269) (xy 456.865472 -306.993269) (xy 456.865472 -306.939971) (xy 456.873415 -306.887267)
			(xy 456.889125 -306.836337) (xy 456.912251 -306.788316) (xy 456.942275 -306.744279) (xy 456.978527 -306.705208)
			(xy 457.020198 -306.671977) (xy 457.066356 -306.645328) (xy 457.11597 -306.625856) (xy 457.167932 -306.613996)
			(xy 457.221082 -306.610013) (xy 457.274232 -306.613996) (xy 457.326194 -306.625856) (xy 457.375808 -306.645328)
			(xy 457.421966 -306.671977) (xy 457.463637 -306.705208) (xy 457.499889 -306.744279) (xy 457.529913 -306.788316)
			(xy 457.553039 -306.836337) (xy 457.568749 -306.887267) (xy 457.576692 -306.939971) (xy 457.57719 -306.96662)
			(xy 457.576692 -306.993269) (xy 457.568749 -307.045973) (xy 457.553039 -307.096903) (xy 457.529913 -307.144924)
			(xy 457.499889 -307.188961) (xy 457.463637 -307.228032) (xy 457.421966 -307.261263) (xy 457.375808 -307.287912)
			(xy 457.326194 -307.307384) (xy 457.274232 -307.319244) (xy 457.221082 -307.323228) (xy 457.167932 -307.319244)
			(xy 457.11597 -307.307384) (xy 457.066356 -307.287912) (xy 457.020198 -307.261263) (xy 456.978527 -307.228032)
			(xy 456.942275 -307.188961) (xy 456.912251 -307.144924) (xy 456.889125 -307.096903) (xy 456.873415 -307.045973)
			(xy 456.865472 -306.993269) (xy 455.366892 -306.993269) (xy 455.358949 -307.045973) (xy 455.343239 -307.096903)
			(xy 455.320113 -307.144924) (xy 455.290089 -307.188961) (xy 455.253837 -307.228032) (xy 455.212166 -307.261263)
			(xy 455.166008 -307.287912) (xy 455.116394 -307.307384) (xy 455.064432 -307.319244) (xy 455.011282 -307.323228)
			(xy 454.958132 -307.319244) (xy 454.90617 -307.307384) (xy 454.856556 -307.287912) (xy 454.810398 -307.261263)
			(xy 454.768727 -307.228032) (xy 454.732475 -307.188961) (xy 454.702451 -307.144924) (xy 454.679325 -307.096903)
			(xy 454.663615 -307.045973) (xy 454.655672 -306.993269) (xy 451.266824 -306.993269) (xy 451.258881 -307.045973)
			(xy 451.243171 -307.096903) (xy 451.220045 -307.144924) (xy 451.190021 -307.188961) (xy 451.153769 -307.228032)
			(xy 451.112098 -307.261263) (xy 451.06594 -307.287912) (xy 451.016326 -307.307384) (xy 450.964364 -307.319244)
			(xy 450.911214 -307.323228) (xy 450.858064 -307.319244) (xy 450.806102 -307.307384) (xy 450.756488 -307.287912)
			(xy 450.71033 -307.261263) (xy 450.668659 -307.228032) (xy 450.632407 -307.188961) (xy 450.602383 -307.144924)
			(xy 450.579257 -307.096903) (xy 450.563547 -307.045973) (xy 450.555604 -306.993269) (xy 450.031919 -306.993269)
			(xy 450.029799 -307.02093) (xy 450.017412 -307.073983) (xy 449.997089 -307.124531) (xy 449.969305 -307.171394)
			(xy 449.934707 -307.213479) (xy 449.894103 -307.249803) (xy 449.84844 -307.279519) (xy 449.82384 -307.291232)
			(xy 449.793868 -307.304694) (xy 449.793868 -307.843407) (xy 450.555604 -307.843407) (xy 450.555604 -307.790109)
			(xy 450.563547 -307.737405) (xy 450.579257 -307.686475) (xy 450.602383 -307.638454) (xy 450.632407 -307.594417)
			(xy 450.668659 -307.555346) (xy 450.71033 -307.522115) (xy 450.756488 -307.495466) (xy 450.806102 -307.475994)
			(xy 450.858064 -307.464134) (xy 450.911214 -307.460151) (xy 450.964364 -307.464134) (xy 451.016326 -307.475994)
			(xy 451.06594 -307.495466) (xy 451.112098 -307.522115) (xy 451.153769 -307.555346) (xy 451.190021 -307.594417)
			(xy 451.220045 -307.638454) (xy 451.243171 -307.686475) (xy 451.258881 -307.737405) (xy 451.266824 -307.790109)
			(xy 451.267322 -307.816758) (xy 451.266824 -307.843407) (xy 452.765404 -307.843407) (xy 452.765404 -307.790109)
			(xy 452.773347 -307.737405) (xy 452.789057 -307.686475) (xy 452.812183 -307.638454) (xy 452.842207 -307.594417)
			(xy 452.878459 -307.555346) (xy 452.92013 -307.522115) (xy 452.966288 -307.495466) (xy 453.015902 -307.475994)
			(xy 453.067864 -307.464134) (xy 453.121014 -307.460151) (xy 453.174164 -307.464134) (xy 453.226126 -307.475994)
			(xy 453.27574 -307.495466) (xy 453.321898 -307.522115) (xy 453.363569 -307.555346) (xy 453.399821 -307.594417)
			(xy 453.429845 -307.638454) (xy 453.452971 -307.686475) (xy 453.468681 -307.737405) (xy 453.476624 -307.790109)
			(xy 453.477122 -307.816758) (xy 453.476624 -307.843407) (xy 454.655672 -307.843407) (xy 454.655672 -307.790109)
			(xy 454.663615 -307.737405) (xy 454.679325 -307.686475) (xy 454.702451 -307.638454) (xy 454.732475 -307.594417)
			(xy 454.768727 -307.555346) (xy 454.810398 -307.522115) (xy 454.856556 -307.495466) (xy 454.90617 -307.475994)
			(xy 454.958132 -307.464134) (xy 455.011282 -307.460151) (xy 455.064432 -307.464134) (xy 455.116394 -307.475994)
			(xy 455.166008 -307.495466) (xy 455.212166 -307.522115) (xy 455.253837 -307.555346) (xy 455.290089 -307.594417)
			(xy 455.320113 -307.638454) (xy 455.343239 -307.686475) (xy 455.358949 -307.737405) (xy 455.366892 -307.790109)
			(xy 455.36739 -307.816758) (xy 455.366892 -307.843407) (xy 458.099404 -307.843407) (xy 458.099404 -307.790109)
			(xy 458.107347 -307.737405) (xy 458.123057 -307.686475) (xy 458.146183 -307.638454) (xy 458.176207 -307.594417)
			(xy 458.212459 -307.555346) (xy 458.25413 -307.522115) (xy 458.300288 -307.495466) (xy 458.349902 -307.475994)
			(xy 458.401864 -307.464134) (xy 458.455014 -307.460151) (xy 458.508164 -307.464134) (xy 458.560126 -307.475994)
			(xy 458.60974 -307.495466) (xy 458.655898 -307.522115) (xy 458.697569 -307.555346) (xy 458.733821 -307.594417)
			(xy 458.763845 -307.638454) (xy 458.786971 -307.686475) (xy 458.802681 -307.737405) (xy 458.810624 -307.790109)
			(xy 458.811122 -307.816758) (xy 458.810624 -307.843407) (xy 458.802681 -307.896111) (xy 458.786971 -307.947041)
			(xy 458.763845 -307.995062) (xy 458.733821 -308.039099) (xy 458.697569 -308.07817) (xy 458.655898 -308.111401)
			(xy 458.60974 -308.13805) (xy 458.560126 -308.157522) (xy 458.508164 -308.169382) (xy 458.455014 -308.173366)
			(xy 458.401864 -308.169382) (xy 458.349902 -308.157522) (xy 458.300288 -308.13805) (xy 458.25413 -308.111401)
			(xy 458.212459 -308.07817) (xy 458.176207 -308.039099) (xy 458.146183 -307.995062) (xy 458.123057 -307.947041)
			(xy 458.107347 -307.896111) (xy 458.099404 -307.843407) (xy 455.366892 -307.843407) (xy 455.358949 -307.896111)
			(xy 455.343239 -307.947041) (xy 455.320113 -307.995062) (xy 455.290089 -308.039099) (xy 455.253837 -308.07817)
			(xy 455.212166 -308.111401) (xy 455.166008 -308.13805) (xy 455.116394 -308.157522) (xy 455.064432 -308.169382)
			(xy 455.011282 -308.173366) (xy 454.958132 -308.169382) (xy 454.90617 -308.157522) (xy 454.856556 -308.13805)
			(xy 454.810398 -308.111401) (xy 454.768727 -308.07817) (xy 454.732475 -308.039099) (xy 454.702451 -307.995062)
			(xy 454.679325 -307.947041) (xy 454.663615 -307.896111) (xy 454.655672 -307.843407) (xy 453.476624 -307.843407)
			(xy 453.468681 -307.896111) (xy 453.452971 -307.947041) (xy 453.429845 -307.995062) (xy 453.399821 -308.039099)
			(xy 453.363569 -308.07817) (xy 453.321898 -308.111401) (xy 453.27574 -308.13805) (xy 453.226126 -308.157522)
			(xy 453.174164 -308.169382) (xy 453.121014 -308.173366) (xy 453.067864 -308.169382) (xy 453.015902 -308.157522)
			(xy 452.966288 -308.13805) (xy 452.92013 -308.111401) (xy 452.878459 -308.07817) (xy 452.842207 -308.039099)
			(xy 452.812183 -307.995062) (xy 452.789057 -307.947041) (xy 452.773347 -307.896111) (xy 452.765404 -307.843407)
			(xy 451.266824 -307.843407) (xy 451.258881 -307.896111) (xy 451.243171 -307.947041) (xy 451.220045 -307.995062)
			(xy 451.190021 -308.039099) (xy 451.153769 -308.07817) (xy 451.112098 -308.111401) (xy 451.06594 -308.13805)
			(xy 451.016326 -308.157522) (xy 450.964364 -308.169382) (xy 450.911214 -308.173366) (xy 450.858064 -308.169382)
			(xy 450.806102 -308.157522) (xy 450.756488 -308.13805) (xy 450.71033 -308.111401) (xy 450.668659 -308.07817)
			(xy 450.632407 -308.039099) (xy 450.602383 -307.995062) (xy 450.579257 -307.947041) (xy 450.563547 -307.896111)
			(xy 450.555604 -307.843407) (xy 449.793868 -307.843407) (xy 449.793868 -308.328568) (xy 449.82384 -308.34203)
			(xy 449.848453 -308.35371) (xy 449.894111 -308.383428) (xy 449.93471 -308.419753) (xy 449.969303 -308.461838)
			(xy 449.997083 -308.5087) (xy 450.017401 -308.559247) (xy 450.029783 -308.612299) (xy 450.033941 -308.666617)
			(xy 450.031897 -308.693291) (xy 450.555604 -308.693291) (xy 450.555604 -308.639993) (xy 450.563547 -308.587289)
			(xy 450.579257 -308.536359) (xy 450.602383 -308.488338) (xy 450.632407 -308.444301) (xy 450.668659 -308.40523)
			(xy 450.71033 -308.371999) (xy 450.756488 -308.34535) (xy 450.806102 -308.325878) (xy 450.858064 -308.314018)
			(xy 450.911214 -308.310035) (xy 450.964364 -308.314018) (xy 451.016326 -308.325878) (xy 451.06594 -308.34535)
			(xy 451.112098 -308.371999) (xy 451.153769 -308.40523) (xy 451.190021 -308.444301) (xy 451.220045 -308.488338)
			(xy 451.243171 -308.536359) (xy 451.258881 -308.587289) (xy 451.266824 -308.639993) (xy 451.267322 -308.666642)
			(xy 451.266824 -308.693291) (xy 454.655672 -308.693291) (xy 454.655672 -308.639993) (xy 454.663615 -308.587289)
			(xy 454.679325 -308.536359) (xy 454.702451 -308.488338) (xy 454.732475 -308.444301) (xy 454.768727 -308.40523)
			(xy 454.810398 -308.371999) (xy 454.856556 -308.34535) (xy 454.90617 -308.325878) (xy 454.958132 -308.314018)
			(xy 455.011282 -308.310035) (xy 455.064432 -308.314018) (xy 455.116394 -308.325878) (xy 455.166008 -308.34535)
			(xy 455.212166 -308.371999) (xy 455.253837 -308.40523) (xy 455.290089 -308.444301) (xy 455.320113 -308.488338)
			(xy 455.343239 -308.536359) (xy 455.358949 -308.587289) (xy 455.366892 -308.639993) (xy 455.36739 -308.666642)
			(xy 455.366892 -308.693291) (xy 456.865472 -308.693291) (xy 456.865472 -308.639993) (xy 456.873415 -308.587289)
			(xy 456.889125 -308.536359) (xy 456.912251 -308.488338) (xy 456.942275 -308.444301) (xy 456.978527 -308.40523)
			(xy 457.020198 -308.371999) (xy 457.066356 -308.34535) (xy 457.11597 -308.325878) (xy 457.167932 -308.314018)
			(xy 457.221082 -308.310035) (xy 457.274232 -308.314018) (xy 457.326194 -308.325878) (xy 457.375808 -308.34535)
			(xy 457.421966 -308.371999) (xy 457.463637 -308.40523) (xy 457.499889 -308.444301) (xy 457.529913 -308.488338)
			(xy 457.553039 -308.536359) (xy 457.568749 -308.587289) (xy 457.576692 -308.639993) (xy 457.57719 -308.666642)
			(xy 457.576692 -308.693291) (xy 457.568749 -308.745995) (xy 457.553039 -308.796925) (xy 457.529913 -308.844946)
			(xy 457.499889 -308.888983) (xy 457.463637 -308.928054) (xy 457.421966 -308.961285) (xy 457.375808 -308.987934)
			(xy 457.326194 -309.007406) (xy 457.274232 -309.019266) (xy 457.221082 -309.02325) (xy 457.167932 -309.019266)
			(xy 457.11597 -309.007406) (xy 457.066356 -308.987934) (xy 457.020198 -308.961285) (xy 456.978527 -308.928054)
			(xy 456.942275 -308.888983) (xy 456.912251 -308.844946) (xy 456.889125 -308.796925) (xy 456.873415 -308.745995)
			(xy 456.865472 -308.693291) (xy 455.366892 -308.693291) (xy 455.358949 -308.745995) (xy 455.343239 -308.796925)
			(xy 455.320113 -308.844946) (xy 455.290089 -308.888983) (xy 455.253837 -308.928054) (xy 455.212166 -308.961285)
			(xy 455.166008 -308.987934) (xy 455.116394 -309.007406) (xy 455.064432 -309.019266) (xy 455.011282 -309.02325)
			(xy 454.958132 -309.019266) (xy 454.90617 -309.007406) (xy 454.856556 -308.987934) (xy 454.810398 -308.961285)
			(xy 454.768727 -308.928054) (xy 454.732475 -308.888983) (xy 454.702451 -308.844946) (xy 454.679325 -308.796925)
			(xy 454.663615 -308.745995) (xy 454.655672 -308.693291) (xy 451.266824 -308.693291) (xy 451.258881 -308.745995)
			(xy 451.243171 -308.796925) (xy 451.220045 -308.844946) (xy 451.190021 -308.888983) (xy 451.153769 -308.928054)
			(xy 451.112098 -308.961285) (xy 451.06594 -308.987934) (xy 451.016326 -309.007406) (xy 450.964364 -309.019266)
			(xy 450.911214 -309.02325) (xy 450.858064 -309.019266) (xy 450.806102 -309.007406) (xy 450.756488 -308.987934)
			(xy 450.71033 -308.961285) (xy 450.668659 -308.928054) (xy 450.632407 -308.888983) (xy 450.602383 -308.844946)
			(xy 450.579257 -308.796925) (xy 450.563547 -308.745995) (xy 450.555604 -308.693291) (xy 450.031897 -308.693291)
			(xy 450.029778 -308.720935) (xy 450.01739 -308.773986) (xy 449.997067 -308.824531) (xy 449.969283 -308.87139)
			(xy 449.934686 -308.913472) (xy 449.894083 -308.949793) (xy 449.848422 -308.979506) (xy 449.82384 -308.991254)
			(xy 449.793868 -309.004716) (xy 449.793868 -309.543429) (xy 450.555604 -309.543429) (xy 450.555604 -309.490131)
			(xy 450.563547 -309.437427) (xy 450.579257 -309.386497) (xy 450.602383 -309.338476) (xy 450.632407 -309.294439)
			(xy 450.668659 -309.255368) (xy 450.71033 -309.222137) (xy 450.756488 -309.195488) (xy 450.806102 -309.176016)
			(xy 450.858064 -309.164156) (xy 450.911214 -309.160173) (xy 450.964364 -309.164156) (xy 451.016326 -309.176016)
			(xy 451.06594 -309.195488) (xy 451.112098 -309.222137) (xy 451.153769 -309.255368) (xy 451.190021 -309.294439)
			(xy 451.220045 -309.338476) (xy 451.243171 -309.386497) (xy 451.258881 -309.437427) (xy 451.266824 -309.490131)
			(xy 451.267322 -309.51678) (xy 451.266824 -309.543429) (xy 452.765404 -309.543429) (xy 452.765404 -309.490131)
			(xy 452.773347 -309.437427) (xy 452.789057 -309.386497) (xy 452.812183 -309.338476) (xy 452.842207 -309.294439)
			(xy 452.878459 -309.255368) (xy 452.92013 -309.222137) (xy 452.966288 -309.195488) (xy 453.015902 -309.176016)
			(xy 453.067864 -309.164156) (xy 453.121014 -309.160173) (xy 453.174164 -309.164156) (xy 453.226126 -309.176016)
			(xy 453.27574 -309.195488) (xy 453.321898 -309.222137) (xy 453.363569 -309.255368) (xy 453.399821 -309.294439)
			(xy 453.429845 -309.338476) (xy 453.452971 -309.386497) (xy 453.468681 -309.437427) (xy 453.476624 -309.490131)
			(xy 453.477122 -309.51678) (xy 453.476624 -309.543429) (xy 454.655672 -309.543429) (xy 454.655672 -309.490131)
			(xy 454.663615 -309.437427) (xy 454.679325 -309.386497) (xy 454.702451 -309.338476) (xy 454.732475 -309.294439)
			(xy 454.768727 -309.255368) (xy 454.810398 -309.222137) (xy 454.856556 -309.195488) (xy 454.90617 -309.176016)
			(xy 454.958132 -309.164156) (xy 455.011282 -309.160173) (xy 455.064432 -309.164156) (xy 455.116394 -309.176016)
			(xy 455.166008 -309.195488) (xy 455.212166 -309.222137) (xy 455.253837 -309.255368) (xy 455.290089 -309.294439)
			(xy 455.320113 -309.338476) (xy 455.343239 -309.386497) (xy 455.358949 -309.437427) (xy 455.366892 -309.490131)
			(xy 455.36739 -309.51678) (xy 455.366892 -309.543429) (xy 458.099404 -309.543429) (xy 458.099404 -309.490131)
			(xy 458.107347 -309.437427) (xy 458.123057 -309.386497) (xy 458.146183 -309.338476) (xy 458.176207 -309.294439)
			(xy 458.212459 -309.255368) (xy 458.25413 -309.222137) (xy 458.300288 -309.195488) (xy 458.349902 -309.176016)
			(xy 458.401864 -309.164156) (xy 458.455014 -309.160173) (xy 458.508164 -309.164156) (xy 458.560126 -309.176016)
			(xy 458.60974 -309.195488) (xy 458.655898 -309.222137) (xy 458.697569 -309.255368) (xy 458.733821 -309.294439)
			(xy 458.763845 -309.338476) (xy 458.786971 -309.386497) (xy 458.802681 -309.437427) (xy 458.810624 -309.490131)
			(xy 458.811122 -309.51678) (xy 458.810624 -309.543429) (xy 458.802681 -309.596133) (xy 458.786971 -309.647063)
			(xy 458.763845 -309.695084) (xy 458.733821 -309.739121) (xy 458.697569 -309.778192) (xy 458.655898 -309.811423)
			(xy 458.60974 -309.838072) (xy 458.560126 -309.857544) (xy 458.508164 -309.869404) (xy 458.455014 -309.873388)
			(xy 458.401864 -309.869404) (xy 458.349902 -309.857544) (xy 458.300288 -309.838072) (xy 458.25413 -309.811423)
			(xy 458.212459 -309.778192) (xy 458.176207 -309.739121) (xy 458.146183 -309.695084) (xy 458.123057 -309.647063)
			(xy 458.107347 -309.596133) (xy 458.099404 -309.543429) (xy 455.366892 -309.543429) (xy 455.358949 -309.596133)
			(xy 455.343239 -309.647063) (xy 455.320113 -309.695084) (xy 455.290089 -309.739121) (xy 455.253837 -309.778192)
			(xy 455.212166 -309.811423) (xy 455.166008 -309.838072) (xy 455.116394 -309.857544) (xy 455.064432 -309.869404)
			(xy 455.011282 -309.873388) (xy 454.958132 -309.869404) (xy 454.90617 -309.857544) (xy 454.856556 -309.838072)
			(xy 454.810398 -309.811423) (xy 454.768727 -309.778192) (xy 454.732475 -309.739121) (xy 454.702451 -309.695084)
			(xy 454.679325 -309.647063) (xy 454.663615 -309.596133) (xy 454.655672 -309.543429) (xy 453.476624 -309.543429)
			(xy 453.468681 -309.596133) (xy 453.452971 -309.647063) (xy 453.429845 -309.695084) (xy 453.399821 -309.739121)
			(xy 453.363569 -309.778192) (xy 453.321898 -309.811423) (xy 453.27574 -309.838072) (xy 453.226126 -309.857544)
			(xy 453.174164 -309.869404) (xy 453.121014 -309.873388) (xy 453.067864 -309.869404) (xy 453.015902 -309.857544)
			(xy 452.966288 -309.838072) (xy 452.92013 -309.811423) (xy 452.878459 -309.778192) (xy 452.842207 -309.739121)
			(xy 452.812183 -309.695084) (xy 452.789057 -309.647063) (xy 452.773347 -309.596133) (xy 452.765404 -309.543429)
			(xy 451.266824 -309.543429) (xy 451.258881 -309.596133) (xy 451.243171 -309.647063) (xy 451.220045 -309.695084)
			(xy 451.190021 -309.739121) (xy 451.153769 -309.778192) (xy 451.112098 -309.811423) (xy 451.06594 -309.838072)
			(xy 451.016326 -309.857544) (xy 450.964364 -309.869404) (xy 450.911214 -309.873388) (xy 450.858064 -309.869404)
			(xy 450.806102 -309.857544) (xy 450.756488 -309.838072) (xy 450.71033 -309.811423) (xy 450.668659 -309.778192)
			(xy 450.632407 -309.739121) (xy 450.602383 -309.695084) (xy 450.579257 -309.647063) (xy 450.563547 -309.596133)
			(xy 450.555604 -309.543429) (xy 449.793868 -309.543429) (xy 449.793868 -310.02859) (xy 449.82384 -310.042052)
			(xy 449.848459 -310.053733) (xy 449.894128 -310.083452) (xy 449.934739 -310.119781) (xy 449.969343 -310.161871)
			(xy 449.997132 -310.20874) (xy 450.017459 -310.259295) (xy 450.029849 -310.312356) (xy 450.034013 -310.366685)
			(xy 450.031974 -310.393313) (xy 450.555604 -310.393313) (xy 450.555604 -310.340015) (xy 450.563547 -310.287311)
			(xy 450.579257 -310.236381) (xy 450.602383 -310.18836) (xy 450.632407 -310.144323) (xy 450.668659 -310.105252)
			(xy 450.71033 -310.072021) (xy 450.756488 -310.045372) (xy 450.806102 -310.0259) (xy 450.858064 -310.01404)
			(xy 450.911214 -310.010057) (xy 450.964364 -310.01404) (xy 451.016326 -310.0259) (xy 451.06594 -310.045372)
			(xy 451.112098 -310.072021) (xy 451.153769 -310.105252) (xy 451.190021 -310.144323) (xy 451.220045 -310.18836)
			(xy 451.243171 -310.236381) (xy 451.258881 -310.287311) (xy 451.266824 -310.340015) (xy 451.267322 -310.366664)
			(xy 451.266824 -310.393313) (xy 454.655672 -310.393313) (xy 454.655672 -310.340015) (xy 454.663615 -310.287311)
			(xy 454.679325 -310.236381) (xy 454.702451 -310.18836) (xy 454.732475 -310.144323) (xy 454.768727 -310.105252)
			(xy 454.810398 -310.072021) (xy 454.856556 -310.045372) (xy 454.90617 -310.0259) (xy 454.958132 -310.01404)
			(xy 455.011282 -310.010057) (xy 455.064432 -310.01404) (xy 455.116394 -310.0259) (xy 455.166008 -310.045372)
			(xy 455.212166 -310.072021) (xy 455.253837 -310.105252) (xy 455.290089 -310.144323) (xy 455.320113 -310.18836)
			(xy 455.343239 -310.236381) (xy 455.358949 -310.287311) (xy 455.366892 -310.340015) (xy 455.36739 -310.366664)
			(xy 455.366892 -310.393313) (xy 456.865472 -310.393313) (xy 456.865472 -310.340015) (xy 456.873415 -310.287311)
			(xy 456.889125 -310.236381) (xy 456.912251 -310.18836) (xy 456.942275 -310.144323) (xy 456.978527 -310.105252)
			(xy 457.020198 -310.072021) (xy 457.066356 -310.045372) (xy 457.11597 -310.0259) (xy 457.167932 -310.01404)
			(xy 457.221082 -310.010057) (xy 457.274232 -310.01404) (xy 457.326194 -310.0259) (xy 457.375808 -310.045372)
			(xy 457.421966 -310.072021) (xy 457.463637 -310.105252) (xy 457.499889 -310.144323) (xy 457.529913 -310.18836)
			(xy 457.553039 -310.236381) (xy 457.568749 -310.287311) (xy 457.576692 -310.340015) (xy 457.57719 -310.366664)
			(xy 457.576692 -310.393313) (xy 457.568749 -310.446017) (xy 457.553039 -310.496947) (xy 457.529913 -310.544968)
			(xy 457.499889 -310.589005) (xy 457.463637 -310.628076) (xy 457.421966 -310.661307) (xy 457.375808 -310.687956)
			(xy 457.326194 -310.707428) (xy 457.274232 -310.719288) (xy 457.221082 -310.723272) (xy 457.167932 -310.719288)
			(xy 457.11597 -310.707428) (xy 457.066356 -310.687956) (xy 457.020198 -310.661307) (xy 456.978527 -310.628076)
			(xy 456.942275 -310.589005) (xy 456.912251 -310.544968) (xy 456.889125 -310.496947) (xy 456.873415 -310.446017)
			(xy 456.865472 -310.393313) (xy 455.366892 -310.393313) (xy 455.358949 -310.446017) (xy 455.343239 -310.496947)
			(xy 455.320113 -310.544968) (xy 455.290089 -310.589005) (xy 455.253837 -310.628076) (xy 455.212166 -310.661307)
			(xy 455.166008 -310.687956) (xy 455.116394 -310.707428) (xy 455.064432 -310.719288) (xy 455.011282 -310.723272)
			(xy 454.958132 -310.719288) (xy 454.90617 -310.707428) (xy 454.856556 -310.687956) (xy 454.810398 -310.661307)
			(xy 454.768727 -310.628076) (xy 454.732475 -310.589005) (xy 454.702451 -310.544968) (xy 454.679325 -310.496947)
			(xy 454.663615 -310.446017) (xy 454.655672 -310.393313) (xy 451.266824 -310.393313) (xy 451.258881 -310.446017)
			(xy 451.243171 -310.496947) (xy 451.220045 -310.544968) (xy 451.190021 -310.589005) (xy 451.153769 -310.628076)
			(xy 451.112098 -310.661307) (xy 451.06594 -310.687956) (xy 451.016326 -310.707428) (xy 450.964364 -310.719288)
			(xy 450.911214 -310.723272) (xy 450.858064 -310.719288) (xy 450.806102 -310.707428) (xy 450.756488 -310.687956)
			(xy 450.71033 -310.661307) (xy 450.668659 -310.628076) (xy 450.632407 -310.589005) (xy 450.602383 -310.544968)
			(xy 450.579257 -310.496947) (xy 450.563547 -310.446017) (xy 450.555604 -310.393313) (xy 450.031974 -310.393313)
			(xy 450.029853 -310.421015) (xy 450.017468 -310.474077) (xy 449.997145 -310.524633) (xy 449.96936 -310.571505)
			(xy 449.934759 -310.613598) (xy 449.894152 -310.64993) (xy 449.848485 -310.679653) (xy 449.82384 -310.691276)
			(xy 449.793868 -310.704738) (xy 449.793868 -311.243451) (xy 450.555604 -311.243451) (xy 450.555604 -311.190153)
			(xy 450.563547 -311.137449) (xy 450.579257 -311.086519) (xy 450.602383 -311.038498) (xy 450.632407 -310.994461)
			(xy 450.668659 -310.95539) (xy 450.71033 -310.922159) (xy 450.756488 -310.89551) (xy 450.806102 -310.876038)
			(xy 450.858064 -310.864178) (xy 450.911214 -310.860195) (xy 450.964364 -310.864178) (xy 451.016326 -310.876038)
			(xy 451.06594 -310.89551) (xy 451.112098 -310.922159) (xy 451.153769 -310.95539) (xy 451.190021 -310.994461)
			(xy 451.220045 -311.038498) (xy 451.243171 -311.086519) (xy 451.258881 -311.137449) (xy 451.266824 -311.190153)
			(xy 451.267322 -311.216802) (xy 451.266824 -311.243451) (xy 452.765404 -311.243451) (xy 452.765404 -311.190153)
			(xy 452.773347 -311.137449) (xy 452.789057 -311.086519) (xy 452.812183 -311.038498) (xy 452.842207 -310.994461)
			(xy 452.878459 -310.95539) (xy 452.92013 -310.922159) (xy 452.966288 -310.89551) (xy 453.015902 -310.876038)
			(xy 453.067864 -310.864178) (xy 453.121014 -310.860195) (xy 453.174164 -310.864178) (xy 453.226126 -310.876038)
			(xy 453.27574 -310.89551) (xy 453.321898 -310.922159) (xy 453.363569 -310.95539) (xy 453.399821 -310.994461)
			(xy 453.429845 -311.038498) (xy 453.452971 -311.086519) (xy 453.468681 -311.137449) (xy 453.476624 -311.190153)
			(xy 453.477122 -311.216802) (xy 453.476624 -311.243451) (xy 454.655672 -311.243451) (xy 454.655672 -311.190153)
			(xy 454.663615 -311.137449) (xy 454.679325 -311.086519) (xy 454.702451 -311.038498) (xy 454.732475 -310.994461)
			(xy 454.768727 -310.95539) (xy 454.810398 -310.922159) (xy 454.856556 -310.89551) (xy 454.90617 -310.876038)
			(xy 454.958132 -310.864178) (xy 455.011282 -310.860195) (xy 455.064432 -310.864178) (xy 455.116394 -310.876038)
			(xy 455.166008 -310.89551) (xy 455.212166 -310.922159) (xy 455.253837 -310.95539) (xy 455.290089 -310.994461)
			(xy 455.320113 -311.038498) (xy 455.343239 -311.086519) (xy 455.358949 -311.137449) (xy 455.366892 -311.190153)
			(xy 455.36739 -311.216802) (xy 455.366892 -311.243451) (xy 458.099404 -311.243451) (xy 458.099404 -311.190153)
			(xy 458.107347 -311.137449) (xy 458.123057 -311.086519) (xy 458.146183 -311.038498) (xy 458.176207 -310.994461)
			(xy 458.212459 -310.95539) (xy 458.25413 -310.922159) (xy 458.300288 -310.89551) (xy 458.349902 -310.876038)
			(xy 458.401864 -310.864178) (xy 458.455014 -310.860195) (xy 458.508164 -310.864178) (xy 458.560126 -310.876038)
			(xy 458.60974 -310.89551) (xy 458.655898 -310.922159) (xy 458.697569 -310.95539) (xy 458.733821 -310.994461)
			(xy 458.763845 -311.038498) (xy 458.786971 -311.086519) (xy 458.802681 -311.137449) (xy 458.810624 -311.190153)
			(xy 458.811122 -311.216802) (xy 458.810624 -311.243451) (xy 458.802681 -311.296155) (xy 458.786971 -311.347085)
			(xy 458.763845 -311.395106) (xy 458.733821 -311.439143) (xy 458.697569 -311.478214) (xy 458.655898 -311.511445)
			(xy 458.60974 -311.538094) (xy 458.560126 -311.557566) (xy 458.508164 -311.569426) (xy 458.455014 -311.57341)
			(xy 458.401864 -311.569426) (xy 458.349902 -311.557566) (xy 458.300288 -311.538094) (xy 458.25413 -311.511445)
			(xy 458.212459 -311.478214) (xy 458.176207 -311.439143) (xy 458.146183 -311.395106) (xy 458.123057 -311.347085)
			(xy 458.107347 -311.296155) (xy 458.099404 -311.243451) (xy 455.366892 -311.243451) (xy 455.358949 -311.296155)
			(xy 455.343239 -311.347085) (xy 455.320113 -311.395106) (xy 455.290089 -311.439143) (xy 455.253837 -311.478214)
			(xy 455.212166 -311.511445) (xy 455.166008 -311.538094) (xy 455.116394 -311.557566) (xy 455.064432 -311.569426)
			(xy 455.011282 -311.57341) (xy 454.958132 -311.569426) (xy 454.90617 -311.557566) (xy 454.856556 -311.538094)
			(xy 454.810398 -311.511445) (xy 454.768727 -311.478214) (xy 454.732475 -311.439143) (xy 454.702451 -311.395106)
			(xy 454.679325 -311.347085) (xy 454.663615 -311.296155) (xy 454.655672 -311.243451) (xy 453.476624 -311.243451)
			(xy 453.468681 -311.296155) (xy 453.452971 -311.347085) (xy 453.429845 -311.395106) (xy 453.399821 -311.439143)
			(xy 453.363569 -311.478214) (xy 453.321898 -311.511445) (xy 453.27574 -311.538094) (xy 453.226126 -311.557566)
			(xy 453.174164 -311.569426) (xy 453.121014 -311.57341) (xy 453.067864 -311.569426) (xy 453.015902 -311.557566)
			(xy 452.966288 -311.538094) (xy 452.92013 -311.511445) (xy 452.878459 -311.478214) (xy 452.842207 -311.439143)
			(xy 452.812183 -311.395106) (xy 452.789057 -311.347085) (xy 452.773347 -311.296155) (xy 452.765404 -311.243451)
			(xy 451.266824 -311.243451) (xy 451.258881 -311.296155) (xy 451.243171 -311.347085) (xy 451.220045 -311.395106)
			(xy 451.190021 -311.439143) (xy 451.153769 -311.478214) (xy 451.112098 -311.511445) (xy 451.06594 -311.538094)
			(xy 451.016326 -311.557566) (xy 450.964364 -311.569426) (xy 450.911214 -311.57341) (xy 450.858064 -311.569426)
			(xy 450.806102 -311.557566) (xy 450.756488 -311.538094) (xy 450.71033 -311.511445) (xy 450.668659 -311.478214)
			(xy 450.632407 -311.439143) (xy 450.602383 -311.395106) (xy 450.579257 -311.347085) (xy 450.563547 -311.296155)
			(xy 450.555604 -311.243451) (xy 449.793868 -311.243451) (xy 449.793868 -312.093335) (xy 450.555604 -312.093335)
			(xy 450.555604 -312.040037) (xy 450.563547 -311.987333) (xy 450.579257 -311.936403) (xy 450.602383 -311.888382)
			(xy 450.632407 -311.844345) (xy 450.668659 -311.805274) (xy 450.71033 -311.772043) (xy 450.756488 -311.745394)
			(xy 450.806102 -311.725922) (xy 450.858064 -311.714062) (xy 450.911214 -311.710079) (xy 450.964364 -311.714062)
			(xy 451.016326 -311.725922) (xy 451.06594 -311.745394) (xy 451.112098 -311.772043) (xy 451.153769 -311.805274)
			(xy 451.190021 -311.844345) (xy 451.220045 -311.888382) (xy 451.243171 -311.936403) (xy 451.258881 -311.987333)
			(xy 451.266824 -312.040037) (xy 451.267322 -312.066686) (xy 451.266824 -312.093335) (xy 454.655672 -312.093335)
			(xy 454.655672 -312.040037) (xy 454.663615 -311.987333) (xy 454.679325 -311.936403) (xy 454.702451 -311.888382)
			(xy 454.732475 -311.844345) (xy 454.768727 -311.805274) (xy 454.810398 -311.772043) (xy 454.856556 -311.745394)
			(xy 454.90617 -311.725922) (xy 454.958132 -311.714062) (xy 455.011282 -311.710079) (xy 455.064432 -311.714062)
			(xy 455.116394 -311.725922) (xy 455.166008 -311.745394) (xy 455.212166 -311.772043) (xy 455.253837 -311.805274)
			(xy 455.290089 -311.844345) (xy 455.320113 -311.888382) (xy 455.343239 -311.936403) (xy 455.358949 -311.987333)
			(xy 455.366892 -312.040037) (xy 455.36739 -312.066686) (xy 455.366892 -312.093335) (xy 455.358949 -312.146039)
			(xy 455.343239 -312.196969) (xy 455.320113 -312.24499) (xy 455.290089 -312.289027) (xy 455.253837 -312.328098)
			(xy 455.212166 -312.361329) (xy 455.166008 -312.387978) (xy 455.116394 -312.40745) (xy 455.064432 -312.41931)
			(xy 455.011282 -312.423294) (xy 454.958132 -312.41931) (xy 454.90617 -312.40745) (xy 454.856556 -312.387978)
			(xy 454.810398 -312.361329) (xy 454.768727 -312.328098) (xy 454.732475 -312.289027) (xy 454.702451 -312.24499)
			(xy 454.679325 -312.196969) (xy 454.663615 -312.146039) (xy 454.655672 -312.093335) (xy 451.266824 -312.093335)
			(xy 451.258881 -312.146039) (xy 451.243171 -312.196969) (xy 451.220045 -312.24499) (xy 451.190021 -312.289027)
			(xy 451.153769 -312.328098) (xy 451.112098 -312.361329) (xy 451.06594 -312.387978) (xy 451.016326 -312.40745)
			(xy 450.964364 -312.41931) (xy 450.911214 -312.423294) (xy 450.858064 -312.41931) (xy 450.806102 -312.40745)
			(xy 450.756488 -312.387978) (xy 450.71033 -312.361329) (xy 450.668659 -312.328098) (xy 450.632407 -312.289027)
			(xy 450.602383 -312.24499) (xy 450.579257 -312.196969) (xy 450.563547 -312.146039) (xy 450.555604 -312.093335)
			(xy 449.793868 -312.093335) (xy 449.793868 -312.578496) (xy 449.82384 -312.591958) (xy 449.846934 -312.602865)
			(xy 449.890005 -312.630313) (xy 449.92871 -312.663636) (xy 449.962255 -312.702148) (xy 449.989952 -312.745059)
			(xy 450.011231 -312.791487) (xy 450.025657 -312.840481) (xy 450.032932 -312.891033) (xy 450.03339 -312.91657)
			(xy 450.032897 -312.943219) (xy 450.555604 -312.943219) (xy 450.555604 -312.889921) (xy 450.563547 -312.837217)
			(xy 450.579257 -312.786287) (xy 450.602383 -312.738266) (xy 450.632407 -312.694229) (xy 450.668659 -312.655158)
			(xy 450.71033 -312.621927) (xy 450.756488 -312.595278) (xy 450.806102 -312.575806) (xy 450.858064 -312.563946)
			(xy 450.911214 -312.559963) (xy 450.964364 -312.563946) (xy 451.016326 -312.575806) (xy 451.06594 -312.595278)
			(xy 451.112098 -312.621927) (xy 451.153769 -312.655158) (xy 451.190021 -312.694229) (xy 451.220045 -312.738266)
			(xy 451.243171 -312.786287) (xy 451.258881 -312.837217) (xy 451.266824 -312.889921) (xy 451.267322 -312.91657)
			(xy 451.266824 -312.943219) (xy 454.655672 -312.943219) (xy 454.655672 -312.889921) (xy 454.663615 -312.837217)
			(xy 454.679325 -312.786287) (xy 454.702451 -312.738266) (xy 454.732475 -312.694229) (xy 454.768727 -312.655158)
			(xy 454.810398 -312.621927) (xy 454.856556 -312.595278) (xy 454.90617 -312.575806) (xy 454.958132 -312.563946)
			(xy 455.011282 -312.559963) (xy 455.064432 -312.563946) (xy 455.116394 -312.575806) (xy 455.166008 -312.595278)
			(xy 455.212166 -312.621927) (xy 455.253837 -312.655158) (xy 455.290089 -312.694229) (xy 455.320113 -312.738266)
			(xy 455.343239 -312.786287) (xy 455.358949 -312.837217) (xy 455.366892 -312.889921) (xy 455.36739 -312.91657)
			(xy 455.366892 -312.943219) (xy 456.865472 -312.943219) (xy 456.865472 -312.889921) (xy 456.873415 -312.837217)
			(xy 456.889125 -312.786287) (xy 456.912251 -312.738266) (xy 456.942275 -312.694229) (xy 456.978527 -312.655158)
			(xy 457.020198 -312.621927) (xy 457.066356 -312.595278) (xy 457.11597 -312.575806) (xy 457.167932 -312.563946)
			(xy 457.221082 -312.559963) (xy 457.274232 -312.563946) (xy 457.326194 -312.575806) (xy 457.375808 -312.595278)
			(xy 457.421966 -312.621927) (xy 457.463637 -312.655158) (xy 457.499889 -312.694229) (xy 457.529913 -312.738266)
			(xy 457.553039 -312.786287) (xy 457.568749 -312.837217) (xy 457.576692 -312.889921) (xy 457.57719 -312.91657)
			(xy 457.576692 -312.943219) (xy 457.568749 -312.995923) (xy 457.553039 -313.046853) (xy 457.529913 -313.094874)
			(xy 457.499889 -313.138911) (xy 457.463637 -313.177982) (xy 457.421966 -313.211213) (xy 457.375808 -313.237862)
			(xy 457.326194 -313.257334) (xy 457.274232 -313.269194) (xy 457.221082 -313.273178) (xy 457.167932 -313.269194)
			(xy 457.11597 -313.257334) (xy 457.066356 -313.237862) (xy 457.020198 -313.211213) (xy 456.978527 -313.177982)
			(xy 456.942275 -313.138911) (xy 456.912251 -313.094874) (xy 456.889125 -313.046853) (xy 456.873415 -312.995923)
			(xy 456.865472 -312.943219) (xy 455.366892 -312.943219) (xy 455.358949 -312.995923) (xy 455.343239 -313.046853)
			(xy 455.320113 -313.094874) (xy 455.290089 -313.138911) (xy 455.253837 -313.177982) (xy 455.212166 -313.211213)
			(xy 455.166008 -313.237862) (xy 455.116394 -313.257334) (xy 455.064432 -313.269194) (xy 455.011282 -313.273178)
			(xy 454.958132 -313.269194) (xy 454.90617 -313.257334) (xy 454.856556 -313.237862) (xy 454.810398 -313.211213)
			(xy 454.768727 -313.177982) (xy 454.732475 -313.138911) (xy 454.702451 -313.094874) (xy 454.679325 -313.046853)
			(xy 454.663615 -312.995923) (xy 454.655672 -312.943219) (xy 451.266824 -312.943219) (xy 451.258881 -312.995923)
			(xy 451.243171 -313.046853) (xy 451.220045 -313.094874) (xy 451.190021 -313.138911) (xy 451.153769 -313.177982)
			(xy 451.112098 -313.211213) (xy 451.06594 -313.237862) (xy 451.016326 -313.257334) (xy 450.964364 -313.269194)
			(xy 450.911214 -313.273178) (xy 450.858064 -313.269194) (xy 450.806102 -313.257334) (xy 450.756488 -313.237862)
			(xy 450.71033 -313.211213) (xy 450.668659 -313.177982) (xy 450.632407 -313.138911) (xy 450.602383 -313.094874)
			(xy 450.579257 -313.046853) (xy 450.563547 -312.995923) (xy 450.555604 -312.943219) (xy 450.032897 -312.943219)
			(xy 450.032872 -312.944556) (xy 450.02412 -312.999841) (xy 450.006826 -313.053075) (xy 449.981417 -313.102948)
			(xy 449.948519 -313.148232) (xy 449.908941 -313.187811) (xy 449.863658 -313.220711) (xy 449.813786 -313.246121)
			(xy 449.760552 -313.263417) (xy 449.705268 -313.272171) (xy 449.677282 -313.272678) (xy 449.661384 -313.272531)
			(xy 449.629713 -313.269731) (xy 449.614036 -313.26709) (xy 449.587874 -313.262264) (xy 449.056781 -313.793357)
			(xy 450.555604 -313.793357) (xy 450.555604 -313.740059) (xy 450.563547 -313.687355) (xy 450.579257 -313.636425)
			(xy 450.602383 -313.588404) (xy 450.632407 -313.544367) (xy 450.668659 -313.505296) (xy 450.71033 -313.472065)
			(xy 450.756488 -313.445416) (xy 450.806102 -313.425944) (xy 450.858064 -313.414084) (xy 450.911214 -313.410101)
			(xy 450.964364 -313.414084) (xy 451.016326 -313.425944) (xy 451.06594 -313.445416) (xy 451.112098 -313.472065)
			(xy 451.153769 -313.505296) (xy 451.190021 -313.544367) (xy 451.220045 -313.588404) (xy 451.243171 -313.636425)
			(xy 451.258881 -313.687355) (xy 451.266824 -313.740059) (xy 451.267322 -313.766708) (xy 451.266824 -313.793357)
			(xy 452.765404 -313.793357) (xy 452.765404 -313.740059) (xy 452.773347 -313.687355) (xy 452.789057 -313.636425)
			(xy 452.812183 -313.588404) (xy 452.842207 -313.544367) (xy 452.878459 -313.505296) (xy 452.92013 -313.472065)
			(xy 452.966288 -313.445416) (xy 453.015902 -313.425944) (xy 453.067864 -313.414084) (xy 453.121014 -313.410101)
			(xy 453.174164 -313.414084) (xy 453.226126 -313.425944) (xy 453.27574 -313.445416) (xy 453.321898 -313.472065)
			(xy 453.363569 -313.505296) (xy 453.399821 -313.544367) (xy 453.429845 -313.588404) (xy 453.452971 -313.636425)
			(xy 453.468681 -313.687355) (xy 453.476624 -313.740059) (xy 453.477122 -313.766708) (xy 453.476624 -313.793357)
			(xy 454.655672 -313.793357) (xy 454.655672 -313.740059) (xy 454.663615 -313.687355) (xy 454.679325 -313.636425)
			(xy 454.702451 -313.588404) (xy 454.732475 -313.544367) (xy 454.768727 -313.505296) (xy 454.810398 -313.472065)
			(xy 454.856556 -313.445416) (xy 454.90617 -313.425944) (xy 454.958132 -313.414084) (xy 455.011282 -313.410101)
			(xy 455.064432 -313.414084) (xy 455.116394 -313.425944) (xy 455.166008 -313.445416) (xy 455.212166 -313.472065)
			(xy 455.253837 -313.505296) (xy 455.290089 -313.544367) (xy 455.320113 -313.588404) (xy 455.343239 -313.636425)
			(xy 455.358949 -313.687355) (xy 455.366892 -313.740059) (xy 455.36739 -313.766708) (xy 455.366892 -313.793357)
			(xy 458.099404 -313.793357) (xy 458.099404 -313.740059) (xy 458.107347 -313.687355) (xy 458.123057 -313.636425)
			(xy 458.146183 -313.588404) (xy 458.176207 -313.544367) (xy 458.212459 -313.505296) (xy 458.25413 -313.472065)
			(xy 458.300288 -313.445416) (xy 458.349902 -313.425944) (xy 458.401864 -313.414084) (xy 458.455014 -313.410101)
			(xy 458.508164 -313.414084) (xy 458.560126 -313.425944) (xy 458.60974 -313.445416) (xy 458.655898 -313.472065)
			(xy 458.697569 -313.505296) (xy 458.733821 -313.544367) (xy 458.763845 -313.588404) (xy 458.786971 -313.636425)
			(xy 458.802681 -313.687355) (xy 458.810624 -313.740059) (xy 458.811122 -313.766708) (xy 458.810624 -313.793357)
			(xy 458.802681 -313.846061) (xy 458.786971 -313.896991) (xy 458.763845 -313.945012) (xy 458.733821 -313.989049)
			(xy 458.697569 -314.02812) (xy 458.655898 -314.061351) (xy 458.60974 -314.088) (xy 458.560126 -314.107472)
			(xy 458.508164 -314.119332) (xy 458.455014 -314.123316) (xy 458.401864 -314.119332) (xy 458.349902 -314.107472)
			(xy 458.300288 -314.088) (xy 458.25413 -314.061351) (xy 458.212459 -314.02812) (xy 458.176207 -313.989049)
			(xy 458.146183 -313.945012) (xy 458.123057 -313.896991) (xy 458.107347 -313.846061) (xy 458.099404 -313.793357)
			(xy 455.366892 -313.793357) (xy 455.358949 -313.846061) (xy 455.343239 -313.896991) (xy 455.320113 -313.945012)
			(xy 455.290089 -313.989049) (xy 455.253837 -314.02812) (xy 455.212166 -314.061351) (xy 455.166008 -314.088)
			(xy 455.116394 -314.107472) (xy 455.064432 -314.119332) (xy 455.011282 -314.123316) (xy 454.958132 -314.119332)
			(xy 454.90617 -314.107472) (xy 454.856556 -314.088) (xy 454.810398 -314.061351) (xy 454.768727 -314.02812)
			(xy 454.732475 -313.989049) (xy 454.702451 -313.945012) (xy 454.679325 -313.896991) (xy 454.663615 -313.846061)
			(xy 454.655672 -313.793357) (xy 453.476624 -313.793357) (xy 453.468681 -313.846061) (xy 453.452971 -313.896991)
			(xy 453.429845 -313.945012) (xy 453.399821 -313.989049) (xy 453.363569 -314.02812) (xy 453.321898 -314.061351)
			(xy 453.27574 -314.088) (xy 453.226126 -314.107472) (xy 453.174164 -314.119332) (xy 453.121014 -314.123316)
			(xy 453.067864 -314.119332) (xy 453.015902 -314.107472) (xy 452.966288 -314.088) (xy 452.92013 -314.061351)
			(xy 452.878459 -314.02812) (xy 452.842207 -313.989049) (xy 452.812183 -313.945012) (xy 452.789057 -313.896991)
			(xy 452.773347 -313.846061) (xy 452.765404 -313.793357) (xy 451.266824 -313.793357) (xy 451.258881 -313.846061)
			(xy 451.243171 -313.896991) (xy 451.220045 -313.945012) (xy 451.190021 -313.989049) (xy 451.153769 -314.02812)
			(xy 451.112098 -314.061351) (xy 451.06594 -314.088) (xy 451.016326 -314.107472) (xy 450.964364 -314.119332)
			(xy 450.911214 -314.123316) (xy 450.858064 -314.119332) (xy 450.806102 -314.107472) (xy 450.756488 -314.088)
			(xy 450.71033 -314.061351) (xy 450.668659 -314.02812) (xy 450.632407 -313.989049) (xy 450.602383 -313.945012)
			(xy 450.579257 -313.896991) (xy 450.563547 -313.846061) (xy 450.555604 -313.793357) (xy 449.056781 -313.793357)
			(xy 448.206897 -314.643241) (xy 449.321672 -314.643241) (xy 449.321672 -314.589943) (xy 449.329615 -314.537239)
			(xy 449.345325 -314.486309) (xy 449.368451 -314.438288) (xy 449.398475 -314.394251) (xy 449.434727 -314.35518)
			(xy 449.476398 -314.321949) (xy 449.522556 -314.2953) (xy 449.57217 -314.275828) (xy 449.624132 -314.263968)
			(xy 449.677282 -314.259985) (xy 449.730432 -314.263968) (xy 449.782394 -314.275828) (xy 449.832008 -314.2953)
			(xy 449.878166 -314.321949) (xy 449.919837 -314.35518) (xy 449.956089 -314.394251) (xy 449.986113 -314.438288)
			(xy 450.009239 -314.486309) (xy 450.024949 -314.537239) (xy 450.032892 -314.589943) (xy 450.03339 -314.616592)
			(xy 450.032892 -314.643241) (xy 450.555604 -314.643241) (xy 450.555604 -314.589943) (xy 450.563547 -314.537239)
			(xy 450.579257 -314.486309) (xy 450.602383 -314.438288) (xy 450.632407 -314.394251) (xy 450.668659 -314.35518)
			(xy 450.71033 -314.321949) (xy 450.756488 -314.2953) (xy 450.806102 -314.275828) (xy 450.858064 -314.263968)
			(xy 450.911214 -314.259985) (xy 450.964364 -314.263968) (xy 451.016326 -314.275828) (xy 451.06594 -314.2953)
			(xy 451.112098 -314.321949) (xy 451.153769 -314.35518) (xy 451.190021 -314.394251) (xy 451.220045 -314.438288)
			(xy 451.243171 -314.486309) (xy 451.258881 -314.537239) (xy 451.266824 -314.589943) (xy 451.267322 -314.616592)
			(xy 451.266824 -314.643241) (xy 454.655672 -314.643241) (xy 454.655672 -314.589943) (xy 454.663615 -314.537239)
			(xy 454.679325 -314.486309) (xy 454.702451 -314.438288) (xy 454.732475 -314.394251) (xy 454.768727 -314.35518)
			(xy 454.810398 -314.321949) (xy 454.856556 -314.2953) (xy 454.90617 -314.275828) (xy 454.958132 -314.263968)
			(xy 455.011282 -314.259985) (xy 455.064432 -314.263968) (xy 455.116394 -314.275828) (xy 455.166008 -314.2953)
			(xy 455.212166 -314.321949) (xy 455.253837 -314.35518) (xy 455.290089 -314.394251) (xy 455.320113 -314.438288)
			(xy 455.343239 -314.486309) (xy 455.358949 -314.537239) (xy 455.366892 -314.589943) (xy 455.36739 -314.616592)
			(xy 455.366892 -314.643241) (xy 456.865472 -314.643241) (xy 456.865472 -314.589943) (xy 456.873415 -314.537239)
			(xy 456.889125 -314.486309) (xy 456.912251 -314.438288) (xy 456.942275 -314.394251) (xy 456.978527 -314.35518)
			(xy 457.020198 -314.321949) (xy 457.066356 -314.2953) (xy 457.11597 -314.275828) (xy 457.167932 -314.263968)
			(xy 457.221082 -314.259985) (xy 457.274232 -314.263968) (xy 457.326194 -314.275828) (xy 457.375808 -314.2953)
			(xy 457.421966 -314.321949) (xy 457.463637 -314.35518) (xy 457.499889 -314.394251) (xy 457.529913 -314.438288)
			(xy 457.553039 -314.486309) (xy 457.568749 -314.537239) (xy 457.576692 -314.589943) (xy 457.57719 -314.616592)
			(xy 457.576692 -314.643241) (xy 457.568749 -314.695945) (xy 457.553039 -314.746875) (xy 457.529913 -314.794896)
			(xy 457.499889 -314.838933) (xy 457.463637 -314.878004) (xy 457.421966 -314.911235) (xy 457.375808 -314.937884)
			(xy 457.326194 -314.957356) (xy 457.274232 -314.969216) (xy 457.221082 -314.9732) (xy 457.167932 -314.969216)
			(xy 457.11597 -314.957356) (xy 457.066356 -314.937884) (xy 457.020198 -314.911235) (xy 456.978527 -314.878004)
			(xy 456.942275 -314.838933) (xy 456.912251 -314.794896) (xy 456.889125 -314.746875) (xy 456.873415 -314.695945)
			(xy 456.865472 -314.643241) (xy 455.366892 -314.643241) (xy 455.358949 -314.695945) (xy 455.343239 -314.746875)
			(xy 455.320113 -314.794896) (xy 455.290089 -314.838933) (xy 455.253837 -314.878004) (xy 455.212166 -314.911235)
			(xy 455.166008 -314.937884) (xy 455.116394 -314.957356) (xy 455.064432 -314.969216) (xy 455.011282 -314.9732)
			(xy 454.958132 -314.969216) (xy 454.90617 -314.957356) (xy 454.856556 -314.937884) (xy 454.810398 -314.911235)
			(xy 454.768727 -314.878004) (xy 454.732475 -314.838933) (xy 454.702451 -314.794896) (xy 454.679325 -314.746875)
			(xy 454.663615 -314.695945) (xy 454.655672 -314.643241) (xy 451.266824 -314.643241) (xy 451.258881 -314.695945)
			(xy 451.243171 -314.746875) (xy 451.220045 -314.794896) (xy 451.190021 -314.838933) (xy 451.153769 -314.878004)
			(xy 451.112098 -314.911235) (xy 451.06594 -314.937884) (xy 451.016326 -314.957356) (xy 450.964364 -314.969216)
			(xy 450.911214 -314.9732) (xy 450.858064 -314.969216) (xy 450.806102 -314.957356) (xy 450.756488 -314.937884)
			(xy 450.71033 -314.911235) (xy 450.668659 -314.878004) (xy 450.632407 -314.838933) (xy 450.602383 -314.794896)
			(xy 450.579257 -314.746875) (xy 450.563547 -314.695945) (xy 450.555604 -314.643241) (xy 450.032892 -314.643241)
			(xy 450.024949 -314.695945) (xy 450.009239 -314.746875) (xy 449.986113 -314.794896) (xy 449.956089 -314.838933)
			(xy 449.919837 -314.878004) (xy 449.878166 -314.911235) (xy 449.832008 -314.937884) (xy 449.782394 -314.957356)
			(xy 449.730432 -314.969216) (xy 449.677282 -314.9732) (xy 449.624132 -314.969216) (xy 449.57217 -314.957356)
			(xy 449.522556 -314.937884) (xy 449.476398 -314.911235) (xy 449.434727 -314.878004) (xy 449.398475 -314.838933)
			(xy 449.368451 -314.794896) (xy 449.345325 -314.746875) (xy 449.329615 -314.695945) (xy 449.321672 -314.643241)
			(xy 448.206897 -314.643241) (xy 447.936366 -314.913772) (xy 447.66357 -314.913772) (xy 447.64163 -314.927675)
			(xy 447.594579 -314.949672) (xy 447.544836 -314.964615) (xy 447.493451 -314.972187) (xy 447.467482 -314.9727)
			(xy 447.441508 -314.972255) (xy 447.390111 -314.964702) (xy 447.340362 -314.949745) (xy 447.293321 -314.927704)
			(xy 447.271394 -314.913772) (xy 442.32957 -314.913772) (xy 442.30763 -314.927675) (xy 442.260579 -314.949672)
			(xy 442.210836 -314.964615) (xy 442.159451 -314.972187) (xy 442.133482 -314.9727) (xy 442.107508 -314.972255)
			(xy 442.056111 -314.964702) (xy 442.006362 -314.949745) (xy 441.959321 -314.927704) (xy 441.937394 -314.913772)
			(xy 440.11977 -314.913772) (xy 440.09783 -314.927675) (xy 440.050779 -314.949672) (xy 440.001036 -314.964615)
			(xy 439.949651 -314.972187) (xy 439.923682 -314.9727) (xy 439.897708 -314.972255) (xy 439.846311 -314.964702)
			(xy 439.796562 -314.949745) (xy 439.749521 -314.927704) (xy 439.727594 -314.913772) (xy 436.019702 -314.913772)
			(xy 435.997763 -314.927677) (xy 435.950712 -314.949679) (xy 435.900969 -314.964626) (xy 435.849584 -314.972202)
			(xy 435.823614 -314.9727) (xy 435.797639 -314.972257) (xy 435.74624 -314.964708) (xy 435.696489 -314.949756)
			(xy 435.649445 -314.927718) (xy 435.627526 -314.913772) (xy 434.78577 -314.913772) (xy 434.76383 -314.927675)
			(xy 434.716779 -314.949672) (xy 434.667036 -314.964615) (xy 434.615651 -314.972187) (xy 434.589682 -314.9727)
			(xy 434.563708 -314.972255) (xy 434.512311 -314.964702) (xy 434.462562 -314.949745) (xy 434.415521 -314.927704)
			(xy 434.393594 -314.913772) (xy 432.57597 -314.913772) (xy 432.55403 -314.927675) (xy 432.506979 -314.949672)
			(xy 432.457236 -314.964615) (xy 432.405851 -314.972187) (xy 432.379882 -314.9727) (xy 432.353908 -314.972255)
			(xy 432.302511 -314.964702) (xy 432.252762 -314.949745) (xy 432.205721 -314.927704) (xy 432.183794 -314.913772)
			(xy 427.24197 -314.913772) (xy 427.22003 -314.927675) (xy 427.172979 -314.949672) (xy 427.123236 -314.964615)
			(xy 427.071851 -314.972187) (xy 427.045882 -314.9727) (xy 427.019908 -314.972255) (xy 426.968511 -314.964702)
			(xy 426.918762 -314.949745) (xy 426.871721 -314.927704) (xy 426.849794 -314.913772) (xy 425.03217 -314.913772)
			(xy 425.01023 -314.927675) (xy 424.963179 -314.949672) (xy 424.913436 -314.964615) (xy 424.862051 -314.972187)
			(xy 424.836082 -314.9727) (xy 424.810108 -314.972255) (xy 424.758711 -314.964702) (xy 424.708962 -314.949745)
			(xy 424.661921 -314.927704) (xy 424.639994 -314.913772) (xy 420.932102 -314.913772) (xy 420.910163 -314.927677)
			(xy 420.863112 -314.949679) (xy 420.813369 -314.964626) (xy 420.761984 -314.972202) (xy 420.736014 -314.9727)
			(xy 420.710039 -314.972257) (xy 420.65864 -314.964708) (xy 420.608889 -314.949756) (xy 420.561845 -314.927718)
			(xy 420.539926 -314.913772) (xy 419.69817 -314.913772) (xy 419.67623 -314.927675) (xy 419.629179 -314.949672)
			(xy 419.579436 -314.964615) (xy 419.528051 -314.972187) (xy 419.502082 -314.9727) (xy 419.476108 -314.972255)
			(xy 419.424711 -314.964702) (xy 419.374962 -314.949745) (xy 419.327921 -314.927704) (xy 419.305994 -314.913772)
			(xy 417.48837 -314.913772) (xy 417.46643 -314.927675) (xy 417.419379 -314.949672) (xy 417.369636 -314.964615)
			(xy 417.318251 -314.972187) (xy 417.292282 -314.9727) (xy 417.266308 -314.972255) (xy 417.214911 -314.964702)
			(xy 417.165162 -314.949745) (xy 417.118121 -314.927704) (xy 417.096194 -314.913772) (xy 412.15437 -314.913772)
			(xy 412.13243 -314.927675) (xy 412.085379 -314.949672) (xy 412.035636 -314.964615) (xy 411.984251 -314.972187)
			(xy 411.958282 -314.9727) (xy 411.932308 -314.972255) (xy 411.880911 -314.964702) (xy 411.831162 -314.949745)
			(xy 411.784121 -314.927704) (xy 411.762194 -314.913772) (xy 409.94457 -314.913772) (xy 409.92263 -314.927675)
			(xy 409.875579 -314.949672) (xy 409.825836 -314.964615) (xy 409.774451 -314.972187) (xy 409.748482 -314.9727)
			(xy 409.722508 -314.972255) (xy 409.671111 -314.964702) (xy 409.621362 -314.949745) (xy 409.574321 -314.927704)
			(xy 409.552394 -314.913772) (xy 406.895808 -314.913772) (xy 406.316201 -315.493379) (xy 407.502604 -315.493379)
			(xy 407.502604 -315.440081) (xy 407.510547 -315.387377) (xy 407.526257 -315.336447) (xy 407.549383 -315.288426)
			(xy 407.579407 -315.244389) (xy 407.615659 -315.205318) (xy 407.65733 -315.172087) (xy 407.703488 -315.145438)
			(xy 407.753102 -315.125966) (xy 407.805064 -315.114106) (xy 407.858214 -315.110123) (xy 407.911364 -315.114106)
			(xy 407.963326 -315.125966) (xy 408.01294 -315.145438) (xy 408.059098 -315.172087) (xy 408.100769 -315.205318)
			(xy 408.137021 -315.244389) (xy 408.167045 -315.288426) (xy 408.190171 -315.336447) (xy 408.205881 -315.387377)
			(xy 408.213824 -315.440081) (xy 408.214322 -315.46673) (xy 408.213824 -315.493379) (xy 412.836604 -315.493379)
			(xy 412.836604 -315.440081) (xy 412.844547 -315.387377) (xy 412.860257 -315.336447) (xy 412.883383 -315.288426)
			(xy 412.913407 -315.244389) (xy 412.949659 -315.205318) (xy 412.99133 -315.172087) (xy 413.037488 -315.145438)
			(xy 413.087102 -315.125966) (xy 413.139064 -315.114106) (xy 413.192214 -315.110123) (xy 413.245364 -315.114106)
			(xy 413.297326 -315.125966) (xy 413.34694 -315.145438) (xy 413.393098 -315.172087) (xy 413.434769 -315.205318)
			(xy 413.471021 -315.244389) (xy 413.501045 -315.288426) (xy 413.524171 -315.336447) (xy 413.539881 -315.387377)
			(xy 413.547824 -315.440081) (xy 413.548322 -315.46673) (xy 413.547824 -315.493379) (xy 415.046404 -315.493379)
			(xy 415.046404 -315.440081) (xy 415.054347 -315.387377) (xy 415.070057 -315.336447) (xy 415.093183 -315.288426)
			(xy 415.123207 -315.244389) (xy 415.159459 -315.205318) (xy 415.20113 -315.172087) (xy 415.247288 -315.145438)
			(xy 415.296902 -315.125966) (xy 415.348864 -315.114106) (xy 415.402014 -315.110123) (xy 415.455164 -315.114106)
			(xy 415.507126 -315.125966) (xy 415.55674 -315.145438) (xy 415.602898 -315.172087) (xy 415.644569 -315.205318)
			(xy 415.680821 -315.244389) (xy 415.710845 -315.288426) (xy 415.733971 -315.336447) (xy 415.749681 -315.387377)
			(xy 415.757624 -315.440081) (xy 415.758122 -315.46673) (xy 415.757624 -315.493379) (xy 420.380404 -315.493379)
			(xy 420.380404 -315.440081) (xy 420.388347 -315.387377) (xy 420.404057 -315.336447) (xy 420.427183 -315.288426)
			(xy 420.457207 -315.244389) (xy 420.493459 -315.205318) (xy 420.53513 -315.172087) (xy 420.581288 -315.145438)
			(xy 420.630902 -315.125966) (xy 420.682864 -315.114106) (xy 420.736014 -315.110123) (xy 420.789164 -315.114106)
			(xy 420.841126 -315.125966) (xy 420.89074 -315.145438) (xy 420.936898 -315.172087) (xy 420.978569 -315.205318)
			(xy 421.014821 -315.244389) (xy 421.044845 -315.288426) (xy 421.067971 -315.336447) (xy 421.083681 -315.387377)
			(xy 421.091624 -315.440081) (xy 421.092122 -315.46673) (xy 421.091624 -315.493379) (xy 422.590204 -315.493379)
			(xy 422.590204 -315.440081) (xy 422.598147 -315.387377) (xy 422.613857 -315.336447) (xy 422.636983 -315.288426)
			(xy 422.667007 -315.244389) (xy 422.703259 -315.205318) (xy 422.74493 -315.172087) (xy 422.791088 -315.145438)
			(xy 422.840702 -315.125966) (xy 422.892664 -315.114106) (xy 422.945814 -315.110123) (xy 422.998964 -315.114106)
			(xy 423.050926 -315.125966) (xy 423.10054 -315.145438) (xy 423.146698 -315.172087) (xy 423.188369 -315.205318)
			(xy 423.224621 -315.244389) (xy 423.254645 -315.288426) (xy 423.277771 -315.336447) (xy 423.293481 -315.387377)
			(xy 423.301424 -315.440081) (xy 423.301922 -315.46673) (xy 423.301424 -315.493379) (xy 424.480472 -315.493379)
			(xy 424.480472 -315.440081) (xy 424.488415 -315.387377) (xy 424.504125 -315.336447) (xy 424.527251 -315.288426)
			(xy 424.557275 -315.244389) (xy 424.593527 -315.205318) (xy 424.635198 -315.172087) (xy 424.681356 -315.145438)
			(xy 424.73097 -315.125966) (xy 424.782932 -315.114106) (xy 424.836082 -315.110123) (xy 424.889232 -315.114106)
			(xy 424.941194 -315.125966) (xy 424.990808 -315.145438) (xy 425.036966 -315.172087) (xy 425.078637 -315.205318)
			(xy 425.114889 -315.244389) (xy 425.144913 -315.288426) (xy 425.168039 -315.336447) (xy 425.183749 -315.387377)
			(xy 425.191692 -315.440081) (xy 425.19219 -315.46673) (xy 425.191692 -315.493379) (xy 427.924204 -315.493379)
			(xy 427.924204 -315.440081) (xy 427.932147 -315.387377) (xy 427.947857 -315.336447) (xy 427.970983 -315.288426)
			(xy 428.001007 -315.244389) (xy 428.037259 -315.205318) (xy 428.07893 -315.172087) (xy 428.125088 -315.145438)
			(xy 428.174702 -315.125966) (xy 428.226664 -315.114106) (xy 428.279814 -315.110123) (xy 428.332964 -315.114106)
			(xy 428.384926 -315.125966) (xy 428.43454 -315.145438) (xy 428.480698 -315.172087) (xy 428.522369 -315.205318)
			(xy 428.558621 -315.244389) (xy 428.588645 -315.288426) (xy 428.611771 -315.336447) (xy 428.627481 -315.387377)
			(xy 428.635424 -315.440081) (xy 428.635922 -315.46673) (xy 428.635424 -315.493379) (xy 430.134004 -315.493379)
			(xy 430.134004 -315.440081) (xy 430.141947 -315.387377) (xy 430.157657 -315.336447) (xy 430.180783 -315.288426)
			(xy 430.210807 -315.244389) (xy 430.247059 -315.205318) (xy 430.28873 -315.172087) (xy 430.334888 -315.145438)
			(xy 430.384502 -315.125966) (xy 430.436464 -315.114106) (xy 430.489614 -315.110123) (xy 430.542764 -315.114106)
			(xy 430.594726 -315.125966) (xy 430.64434 -315.145438) (xy 430.690498 -315.172087) (xy 430.732169 -315.205318)
			(xy 430.768421 -315.244389) (xy 430.798445 -315.288426) (xy 430.821571 -315.336447) (xy 430.837281 -315.387377)
			(xy 430.845224 -315.440081) (xy 430.845722 -315.46673) (xy 430.845224 -315.493379) (xy 435.468004 -315.493379)
			(xy 435.468004 -315.440081) (xy 435.475947 -315.387377) (xy 435.491657 -315.336447) (xy 435.514783 -315.288426)
			(xy 435.544807 -315.244389) (xy 435.581059 -315.205318) (xy 435.62273 -315.172087) (xy 435.668888 -315.145438)
			(xy 435.718502 -315.125966) (xy 435.770464 -315.114106) (xy 435.823614 -315.110123) (xy 435.876764 -315.114106)
			(xy 435.928726 -315.125966) (xy 435.97834 -315.145438) (xy 436.024498 -315.172087) (xy 436.066169 -315.205318)
			(xy 436.102421 -315.244389) (xy 436.132445 -315.288426) (xy 436.155571 -315.336447) (xy 436.171281 -315.387377)
			(xy 436.179224 -315.440081) (xy 436.179722 -315.46673) (xy 436.179224 -315.493379) (xy 437.677804 -315.493379)
			(xy 437.677804 -315.440081) (xy 437.685747 -315.387377) (xy 437.701457 -315.336447) (xy 437.724583 -315.288426)
			(xy 437.754607 -315.244389) (xy 437.790859 -315.205318) (xy 437.83253 -315.172087) (xy 437.878688 -315.145438)
			(xy 437.928302 -315.125966) (xy 437.980264 -315.114106) (xy 438.033414 -315.110123) (xy 438.086564 -315.114106)
			(xy 438.138526 -315.125966) (xy 438.18814 -315.145438) (xy 438.234298 -315.172087) (xy 438.275969 -315.205318)
			(xy 438.312221 -315.244389) (xy 438.342245 -315.288426) (xy 438.365371 -315.336447) (xy 438.381081 -315.387377)
			(xy 438.389024 -315.440081) (xy 438.389522 -315.46673) (xy 438.389024 -315.493379) (xy 439.568072 -315.493379)
			(xy 439.568072 -315.440081) (xy 439.576015 -315.387377) (xy 439.591725 -315.336447) (xy 439.614851 -315.288426)
			(xy 439.644875 -315.244389) (xy 439.681127 -315.205318) (xy 439.722798 -315.172087) (xy 439.768956 -315.145438)
			(xy 439.81857 -315.125966) (xy 439.870532 -315.114106) (xy 439.923682 -315.110123) (xy 439.976832 -315.114106)
			(xy 440.028794 -315.125966) (xy 440.078408 -315.145438) (xy 440.124566 -315.172087) (xy 440.166237 -315.205318)
			(xy 440.202489 -315.244389) (xy 440.232513 -315.288426) (xy 440.255639 -315.336447) (xy 440.271349 -315.387377)
			(xy 440.279292 -315.440081) (xy 440.27979 -315.46673) (xy 440.279292 -315.493379) (xy 443.011804 -315.493379)
			(xy 443.011804 -315.440081) (xy 443.019747 -315.387377) (xy 443.035457 -315.336447) (xy 443.058583 -315.288426)
			(xy 443.088607 -315.244389) (xy 443.124859 -315.205318) (xy 443.16653 -315.172087) (xy 443.212688 -315.145438)
			(xy 443.262302 -315.125966) (xy 443.314264 -315.114106) (xy 443.367414 -315.110123) (xy 443.420564 -315.114106)
			(xy 443.472526 -315.125966) (xy 443.52214 -315.145438) (xy 443.568298 -315.172087) (xy 443.609969 -315.205318)
			(xy 443.646221 -315.244389) (xy 443.676245 -315.288426) (xy 443.699371 -315.336447) (xy 443.715081 -315.387377)
			(xy 443.723024 -315.440081) (xy 443.723522 -315.46673) (xy 443.723024 -315.493379) (xy 445.221604 -315.493379)
			(xy 445.221604 -315.440081) (xy 445.229547 -315.387377) (xy 445.245257 -315.336447) (xy 445.268383 -315.288426)
			(xy 445.298407 -315.244389) (xy 445.334659 -315.205318) (xy 445.37633 -315.172087) (xy 445.422488 -315.145438)
			(xy 445.472102 -315.125966) (xy 445.524064 -315.114106) (xy 445.577214 -315.110123) (xy 445.630364 -315.114106)
			(xy 445.682326 -315.125966) (xy 445.73194 -315.145438) (xy 445.778098 -315.172087) (xy 445.819769 -315.205318)
			(xy 445.856021 -315.244389) (xy 445.886045 -315.288426) (xy 445.909171 -315.336447) (xy 445.924881 -315.387377)
			(xy 445.932824 -315.440081) (xy 445.933322 -315.46673) (xy 445.932824 -315.493379) (xy 450.555604 -315.493379)
			(xy 450.555604 -315.440081) (xy 450.563547 -315.387377) (xy 450.579257 -315.336447) (xy 450.602383 -315.288426)
			(xy 450.632407 -315.244389) (xy 450.668659 -315.205318) (xy 450.71033 -315.172087) (xy 450.756488 -315.145438)
			(xy 450.806102 -315.125966) (xy 450.858064 -315.114106) (xy 450.911214 -315.110123) (xy 450.964364 -315.114106)
			(xy 451.016326 -315.125966) (xy 451.06594 -315.145438) (xy 451.112098 -315.172087) (xy 451.153769 -315.205318)
			(xy 451.190021 -315.244389) (xy 451.220045 -315.288426) (xy 451.243171 -315.336447) (xy 451.258881 -315.387377)
			(xy 451.266824 -315.440081) (xy 451.267322 -315.46673) (xy 451.266824 -315.493379) (xy 452.765404 -315.493379)
			(xy 452.765404 -315.440081) (xy 452.773347 -315.387377) (xy 452.789057 -315.336447) (xy 452.812183 -315.288426)
			(xy 452.842207 -315.244389) (xy 452.878459 -315.205318) (xy 452.92013 -315.172087) (xy 452.966288 -315.145438)
			(xy 453.015902 -315.125966) (xy 453.067864 -315.114106) (xy 453.121014 -315.110123) (xy 453.174164 -315.114106)
			(xy 453.226126 -315.125966) (xy 453.27574 -315.145438) (xy 453.321898 -315.172087) (xy 453.363569 -315.205318)
			(xy 453.399821 -315.244389) (xy 453.429845 -315.288426) (xy 453.452971 -315.336447) (xy 453.468681 -315.387377)
			(xy 453.471985 -315.4093) (xy 453.890094 -315.4093) (xy 453.894078 -315.356147) (xy 453.905939 -315.304181)
			(xy 453.925414 -315.254564) (xy 453.952067 -315.208403) (xy 453.985303 -315.166732) (xy 454.024379 -315.130479)
			(xy 454.068421 -315.100456) (xy 454.116447 -315.077333) (xy 454.167383 -315.061627) (xy 454.220091 -315.053688)
			(xy 454.246742 -315.053218) (xy 454.273906 -315.053764) (xy 454.327601 -315.062035) (xy 454.379418 -315.078361)
			(xy 454.428155 -315.102366) (xy 454.472683 -315.133493) (xy 454.511968 -315.171019) (xy 454.5451 -315.214075)
			(xy 454.558654 -315.237622) (xy 454.566017 -315.250054) (xy 454.586453 -315.270463) (xy 454.611789 -315.284327)
			(xy 454.639996 -315.290535) (xy 454.668812 -315.288589) (xy 454.695928 -315.278646) (xy 454.719171 -315.261501)
			(xy 454.728326 -315.250322) (xy 454.745301 -315.228992) (xy 454.784653 -315.191271) (xy 454.829289 -315.15998)
			(xy 454.878168 -315.13585) (xy 454.930151 -315.119443) (xy 454.984026 -315.111141) (xy 455.011282 -315.110622)
			(xy 455.037936 -315.111034) (xy 455.09065 -315.118977) (xy 455.14159 -315.134688) (xy 455.189621 -315.157816)
			(xy 455.233667 -315.187844) (xy 455.272746 -315.224102) (xy 455.305984 -315.265779) (xy 455.332639 -315.311946)
			(xy 455.352115 -315.361569) (xy 455.363978 -315.413541) (xy 455.367962 -315.4667) (xy 455.365963 -315.493379)
			(xy 458.099404 -315.493379) (xy 458.099404 -315.440081) (xy 458.107347 -315.387377) (xy 458.123057 -315.336447)
			(xy 458.146183 -315.288426) (xy 458.176207 -315.244389) (xy 458.212459 -315.205318) (xy 458.25413 -315.172087)
			(xy 458.300288 -315.145438) (xy 458.349902 -315.125966) (xy 458.401864 -315.114106) (xy 458.455014 -315.110123)
			(xy 458.508164 -315.114106) (xy 458.560126 -315.125966) (xy 458.60974 -315.145438) (xy 458.655898 -315.172087)
			(xy 458.697569 -315.205318) (xy 458.733821 -315.244389) (xy 458.763845 -315.288426) (xy 458.786971 -315.336447)
			(xy 458.802681 -315.387377) (xy 458.810624 -315.440081) (xy 458.811122 -315.46673) (xy 458.810624 -315.493379)
			(xy 458.802681 -315.546083) (xy 458.786971 -315.597013) (xy 458.763845 -315.645034) (xy 458.733821 -315.689071)
			(xy 458.697569 -315.728142) (xy 458.655898 -315.761373) (xy 458.60974 -315.788022) (xy 458.560126 -315.807494)
			(xy 458.508164 -315.819354) (xy 458.455014 -315.823338) (xy 458.401864 -315.819354) (xy 458.349902 -315.807494)
			(xy 458.300288 -315.788022) (xy 458.25413 -315.761373) (xy 458.212459 -315.728142) (xy 458.176207 -315.689071)
			(xy 458.146183 -315.645034) (xy 458.123057 -315.597013) (xy 458.107347 -315.546083) (xy 458.099404 -315.493379)
			(xy 455.365963 -315.493379) (xy 455.363978 -315.519859) (xy 455.352115 -315.571831) (xy 455.332639 -315.621454)
			(xy 455.305984 -315.667621) (xy 455.272746 -315.709298) (xy 455.233667 -315.745556) (xy 455.189621 -315.775584)
			(xy 455.14159 -315.798712) (xy 455.09065 -315.814423) (xy 455.037936 -315.822366) (xy 455.011282 -315.822838)
			(xy 454.984118 -315.822295) (xy 454.930421 -315.814027) (xy 454.878603 -315.797702) (xy 454.829865 -315.773696)
			(xy 454.785337 -315.742569) (xy 454.746052 -315.705041) (xy 454.712922 -315.661982) (xy 454.69937 -315.638434)
			(xy 454.691976 -315.626024) (xy 454.671543 -315.605624) (xy 454.646214 -315.591766) (xy 454.618016 -315.585558)
			(xy 454.589208 -315.587499) (xy 454.562098 -315.597432) (xy 454.538855 -315.614562) (xy 454.529698 -315.625734)
			(xy 454.512698 -315.647043) (xy 454.473353 -315.684768) (xy 454.428722 -315.716062) (xy 454.379848 -315.740196)
			(xy 454.327868 -315.756608) (xy 454.273996 -315.764913) (xy 454.246742 -315.765434) (xy 454.220091 -315.764912)
			(xy 454.167383 -315.756973) (xy 454.116447 -315.741267) (xy 454.068421 -315.718144) (xy 454.024379 -315.688121)
			(xy 453.985303 -315.651868) (xy 453.952067 -315.610197) (xy 453.925414 -315.564036) (xy 453.905939 -315.514419)
			(xy 453.894078 -315.462453) (xy 453.890094 -315.4093) (xy 453.471985 -315.4093) (xy 453.476624 -315.440081)
			(xy 453.477122 -315.46673) (xy 453.476624 -315.493379) (xy 453.468681 -315.546083) (xy 453.452971 -315.597013)
			(xy 453.429845 -315.645034) (xy 453.399821 -315.689071) (xy 453.363569 -315.728142) (xy 453.321898 -315.761373)
			(xy 453.27574 -315.788022) (xy 453.226126 -315.807494) (xy 453.174164 -315.819354) (xy 453.121014 -315.823338)
			(xy 453.067864 -315.819354) (xy 453.015902 -315.807494) (xy 452.966288 -315.788022) (xy 452.92013 -315.761373)
			(xy 452.878459 -315.728142) (xy 452.842207 -315.689071) (xy 452.812183 -315.645034) (xy 452.789057 -315.597013)
			(xy 452.773347 -315.546083) (xy 452.765404 -315.493379) (xy 451.266824 -315.493379) (xy 451.258881 -315.546083)
			(xy 451.243171 -315.597013) (xy 451.220045 -315.645034) (xy 451.190021 -315.689071) (xy 451.153769 -315.728142)
			(xy 451.112098 -315.761373) (xy 451.06594 -315.788022) (xy 451.016326 -315.807494) (xy 450.964364 -315.819354)
			(xy 450.911214 -315.823338) (xy 450.858064 -315.819354) (xy 450.806102 -315.807494) (xy 450.756488 -315.788022)
			(xy 450.71033 -315.761373) (xy 450.668659 -315.728142) (xy 450.632407 -315.689071) (xy 450.602383 -315.645034)
			(xy 450.579257 -315.597013) (xy 450.563547 -315.546083) (xy 450.555604 -315.493379) (xy 445.932824 -315.493379)
			(xy 445.924881 -315.546083) (xy 445.909171 -315.597013) (xy 445.886045 -315.645034) (xy 445.856021 -315.689071)
			(xy 445.819769 -315.728142) (xy 445.778098 -315.761373) (xy 445.73194 -315.788022) (xy 445.682326 -315.807494)
			(xy 445.630364 -315.819354) (xy 445.577214 -315.823338) (xy 445.524064 -315.819354) (xy 445.472102 -315.807494)
			(xy 445.422488 -315.788022) (xy 445.37633 -315.761373) (xy 445.334659 -315.728142) (xy 445.298407 -315.689071)
			(xy 445.268383 -315.645034) (xy 445.245257 -315.597013) (xy 445.229547 -315.546083) (xy 445.221604 -315.493379)
			(xy 443.723024 -315.493379) (xy 443.715081 -315.546083) (xy 443.699371 -315.597013) (xy 443.676245 -315.645034)
			(xy 443.646221 -315.689071) (xy 443.609969 -315.728142) (xy 443.568298 -315.761373) (xy 443.52214 -315.788022)
			(xy 443.472526 -315.807494) (xy 443.420564 -315.819354) (xy 443.367414 -315.823338) (xy 443.314264 -315.819354)
			(xy 443.262302 -315.807494) (xy 443.212688 -315.788022) (xy 443.16653 -315.761373) (xy 443.124859 -315.728142)
			(xy 443.088607 -315.689071) (xy 443.058583 -315.645034) (xy 443.035457 -315.597013) (xy 443.019747 -315.546083)
			(xy 443.011804 -315.493379) (xy 440.279292 -315.493379) (xy 440.271349 -315.546083) (xy 440.255639 -315.597013)
			(xy 440.232513 -315.645034) (xy 440.202489 -315.689071) (xy 440.166237 -315.728142) (xy 440.124566 -315.761373)
			(xy 440.078408 -315.788022) (xy 440.028794 -315.807494) (xy 439.976832 -315.819354) (xy 439.923682 -315.823338)
			(xy 439.870532 -315.819354) (xy 439.81857 -315.807494) (xy 439.768956 -315.788022) (xy 439.722798 -315.761373)
			(xy 439.681127 -315.728142) (xy 439.644875 -315.689071) (xy 439.614851 -315.645034) (xy 439.591725 -315.597013)
			(xy 439.576015 -315.546083) (xy 439.568072 -315.493379) (xy 438.389024 -315.493379) (xy 438.381081 -315.546083)
			(xy 438.365371 -315.597013) (xy 438.342245 -315.645034) (xy 438.312221 -315.689071) (xy 438.275969 -315.728142)
			(xy 438.234298 -315.761373) (xy 438.18814 -315.788022) (xy 438.138526 -315.807494) (xy 438.086564 -315.819354)
			(xy 438.033414 -315.823338) (xy 437.980264 -315.819354) (xy 437.928302 -315.807494) (xy 437.878688 -315.788022)
			(xy 437.83253 -315.761373) (xy 437.790859 -315.728142) (xy 437.754607 -315.689071) (xy 437.724583 -315.645034)
			(xy 437.701457 -315.597013) (xy 437.685747 -315.546083) (xy 437.677804 -315.493379) (xy 436.179224 -315.493379)
			(xy 436.171281 -315.546083) (xy 436.155571 -315.597013) (xy 436.132445 -315.645034) (xy 436.102421 -315.689071)
			(xy 436.066169 -315.728142) (xy 436.024498 -315.761373) (xy 435.97834 -315.788022) (xy 435.928726 -315.807494)
			(xy 435.876764 -315.819354) (xy 435.823614 -315.823338) (xy 435.770464 -315.819354) (xy 435.718502 -315.807494)
			(xy 435.668888 -315.788022) (xy 435.62273 -315.761373) (xy 435.581059 -315.728142) (xy 435.544807 -315.689071)
			(xy 435.514783 -315.645034) (xy 435.491657 -315.597013) (xy 435.475947 -315.546083) (xy 435.468004 -315.493379)
			(xy 430.845224 -315.493379) (xy 430.837281 -315.546083) (xy 430.821571 -315.597013) (xy 430.798445 -315.645034)
			(xy 430.768421 -315.689071) (xy 430.732169 -315.728142) (xy 430.690498 -315.761373) (xy 430.64434 -315.788022)
			(xy 430.594726 -315.807494) (xy 430.542764 -315.819354) (xy 430.489614 -315.823338) (xy 430.436464 -315.819354)
			(xy 430.384502 -315.807494) (xy 430.334888 -315.788022) (xy 430.28873 -315.761373) (xy 430.247059 -315.728142)
			(xy 430.210807 -315.689071) (xy 430.180783 -315.645034) (xy 430.157657 -315.597013) (xy 430.141947 -315.546083)
			(xy 430.134004 -315.493379) (xy 428.635424 -315.493379) (xy 428.627481 -315.546083) (xy 428.611771 -315.597013)
			(xy 428.588645 -315.645034) (xy 428.558621 -315.689071) (xy 428.522369 -315.728142) (xy 428.480698 -315.761373)
			(xy 428.43454 -315.788022) (xy 428.384926 -315.807494) (xy 428.332964 -315.819354) (xy 428.279814 -315.823338)
			(xy 428.226664 -315.819354) (xy 428.174702 -315.807494) (xy 428.125088 -315.788022) (xy 428.07893 -315.761373)
			(xy 428.037259 -315.728142) (xy 428.001007 -315.689071) (xy 427.970983 -315.645034) (xy 427.947857 -315.597013)
			(xy 427.932147 -315.546083) (xy 427.924204 -315.493379) (xy 425.191692 -315.493379) (xy 425.183749 -315.546083)
			(xy 425.168039 -315.597013) (xy 425.144913 -315.645034) (xy 425.114889 -315.689071) (xy 425.078637 -315.728142)
			(xy 425.036966 -315.761373) (xy 424.990808 -315.788022) (xy 424.941194 -315.807494) (xy 424.889232 -315.819354)
			(xy 424.836082 -315.823338) (xy 424.782932 -315.819354) (xy 424.73097 -315.807494) (xy 424.681356 -315.788022)
			(xy 424.635198 -315.761373) (xy 424.593527 -315.728142) (xy 424.557275 -315.689071) (xy 424.527251 -315.645034)
			(xy 424.504125 -315.597013) (xy 424.488415 -315.546083) (xy 424.480472 -315.493379) (xy 423.301424 -315.493379)
			(xy 423.293481 -315.546083) (xy 423.277771 -315.597013) (xy 423.254645 -315.645034) (xy 423.224621 -315.689071)
			(xy 423.188369 -315.728142) (xy 423.146698 -315.761373) (xy 423.10054 -315.788022) (xy 423.050926 -315.807494)
			(xy 422.998964 -315.819354) (xy 422.945814 -315.823338) (xy 422.892664 -315.819354) (xy 422.840702 -315.807494)
			(xy 422.791088 -315.788022) (xy 422.74493 -315.761373) (xy 422.703259 -315.728142) (xy 422.667007 -315.689071)
			(xy 422.636983 -315.645034) (xy 422.613857 -315.597013) (xy 422.598147 -315.546083) (xy 422.590204 -315.493379)
			(xy 421.091624 -315.493379) (xy 421.083681 -315.546083) (xy 421.067971 -315.597013) (xy 421.044845 -315.645034)
			(xy 421.014821 -315.689071) (xy 420.978569 -315.728142) (xy 420.936898 -315.761373) (xy 420.89074 -315.788022)
			(xy 420.841126 -315.807494) (xy 420.789164 -315.819354) (xy 420.736014 -315.823338) (xy 420.682864 -315.819354)
			(xy 420.630902 -315.807494) (xy 420.581288 -315.788022) (xy 420.53513 -315.761373) (xy 420.493459 -315.728142)
			(xy 420.457207 -315.689071) (xy 420.427183 -315.645034) (xy 420.404057 -315.597013) (xy 420.388347 -315.546083)
			(xy 420.380404 -315.493379) (xy 415.757624 -315.493379) (xy 415.749681 -315.546083) (xy 415.733971 -315.597013)
			(xy 415.710845 -315.645034) (xy 415.680821 -315.689071) (xy 415.644569 -315.728142) (xy 415.602898 -315.761373)
			(xy 415.55674 -315.788022) (xy 415.507126 -315.807494) (xy 415.455164 -315.819354) (xy 415.402014 -315.823338)
			(xy 415.348864 -315.819354) (xy 415.296902 -315.807494) (xy 415.247288 -315.788022) (xy 415.20113 -315.761373)
			(xy 415.159459 -315.728142) (xy 415.123207 -315.689071) (xy 415.093183 -315.645034) (xy 415.070057 -315.597013)
			(xy 415.054347 -315.546083) (xy 415.046404 -315.493379) (xy 413.547824 -315.493379) (xy 413.539881 -315.546083)
			(xy 413.524171 -315.597013) (xy 413.501045 -315.645034) (xy 413.471021 -315.689071) (xy 413.434769 -315.728142)
			(xy 413.393098 -315.761373) (xy 413.34694 -315.788022) (xy 413.297326 -315.807494) (xy 413.245364 -315.819354)
			(xy 413.192214 -315.823338) (xy 413.139064 -315.819354) (xy 413.087102 -315.807494) (xy 413.037488 -315.788022)
			(xy 412.99133 -315.761373) (xy 412.949659 -315.728142) (xy 412.913407 -315.689071) (xy 412.883383 -315.645034)
			(xy 412.860257 -315.597013) (xy 412.844547 -315.546083) (xy 412.836604 -315.493379) (xy 408.213824 -315.493379)
			(xy 408.205881 -315.546083) (xy 408.190171 -315.597013) (xy 408.167045 -315.645034) (xy 408.137021 -315.689071)
			(xy 408.100769 -315.728142) (xy 408.059098 -315.761373) (xy 408.01294 -315.788022) (xy 407.963326 -315.807494)
			(xy 407.911364 -315.819354) (xy 407.858214 -315.823338) (xy 407.805064 -315.819354) (xy 407.753102 -315.807494)
			(xy 407.703488 -315.788022) (xy 407.65733 -315.761373) (xy 407.615659 -315.728142) (xy 407.579407 -315.689071)
			(xy 407.549383 -315.645034) (xy 407.526257 -315.597013) (xy 407.510547 -315.546083) (xy 407.502604 -315.493379)
			(xy 406.316201 -315.493379) (xy 406.226772 -315.582808) (xy 406.226772 -316.343263) (xy 409.392872 -316.343263)
			(xy 409.392872 -316.289965) (xy 409.400815 -316.237261) (xy 409.416525 -316.186331) (xy 409.439651 -316.13831)
			(xy 409.469675 -316.094273) (xy 409.505927 -316.055202) (xy 409.547598 -316.021971) (xy 409.593756 -315.995322)
			(xy 409.64337 -315.97585) (xy 409.695332 -315.96399) (xy 409.748482 -315.960007) (xy 409.801632 -315.96399)
			(xy 409.853594 -315.97585) (xy 409.903208 -315.995322) (xy 409.949366 -316.021971) (xy 409.991037 -316.055202)
			(xy 410.027289 -316.094273) (xy 410.057313 -316.13831) (xy 410.080439 -316.186331) (xy 410.096149 -316.237261)
			(xy 410.104092 -316.289965) (xy 410.10459 -316.316614) (xy 410.104092 -316.343263) (xy 411.602672 -316.343263)
			(xy 411.602672 -316.289965) (xy 411.610615 -316.237261) (xy 411.626325 -316.186331) (xy 411.649451 -316.13831)
			(xy 411.679475 -316.094273) (xy 411.715727 -316.055202) (xy 411.757398 -316.021971) (xy 411.803556 -315.995322)
			(xy 411.85317 -315.97585) (xy 411.905132 -315.96399) (xy 411.958282 -315.960007) (xy 412.011432 -315.96399)
			(xy 412.063394 -315.97585) (xy 412.113008 -315.995322) (xy 412.159166 -316.021971) (xy 412.200837 -316.055202)
			(xy 412.237089 -316.094273) (xy 412.267113 -316.13831) (xy 412.290239 -316.186331) (xy 412.305949 -316.237261)
			(xy 412.313892 -316.289965) (xy 412.31439 -316.316614) (xy 412.313892 -316.343263) (xy 416.936672 -316.343263)
			(xy 416.936672 -316.289965) (xy 416.944615 -316.237261) (xy 416.960325 -316.186331) (xy 416.983451 -316.13831)
			(xy 417.013475 -316.094273) (xy 417.049727 -316.055202) (xy 417.091398 -316.021971) (xy 417.137556 -315.995322)
			(xy 417.18717 -315.97585) (xy 417.239132 -315.96399) (xy 417.292282 -315.960007) (xy 417.345432 -315.96399)
			(xy 417.397394 -315.97585) (xy 417.447008 -315.995322) (xy 417.493166 -316.021971) (xy 417.534837 -316.055202)
			(xy 417.571089 -316.094273) (xy 417.601113 -316.13831) (xy 417.624239 -316.186331) (xy 417.639949 -316.237261)
			(xy 417.647892 -316.289965) (xy 417.64839 -316.316614) (xy 417.647892 -316.343263) (xy 419.146472 -316.343263)
			(xy 419.146472 -316.289965) (xy 419.154415 -316.237261) (xy 419.170125 -316.186331) (xy 419.193251 -316.13831)
			(xy 419.223275 -316.094273) (xy 419.259527 -316.055202) (xy 419.301198 -316.021971) (xy 419.347356 -315.995322)
			(xy 419.39697 -315.97585) (xy 419.448932 -315.96399) (xy 419.502082 -315.960007) (xy 419.555232 -315.96399)
			(xy 419.607194 -315.97585) (xy 419.656808 -315.995322) (xy 419.702966 -316.021971) (xy 419.744637 -316.055202)
			(xy 419.780889 -316.094273) (xy 419.810913 -316.13831) (xy 419.834039 -316.186331) (xy 419.849749 -316.237261)
			(xy 419.857692 -316.289965) (xy 419.85819 -316.316614) (xy 419.857692 -316.343263) (xy 420.380404 -316.343263)
			(xy 420.380404 -316.289965) (xy 420.388347 -316.237261) (xy 420.404057 -316.186331) (xy 420.427183 -316.13831)
			(xy 420.457207 -316.094273) (xy 420.493459 -316.055202) (xy 420.53513 -316.021971) (xy 420.581288 -315.995322)
			(xy 420.630902 -315.97585) (xy 420.682864 -315.96399) (xy 420.736014 -315.960007) (xy 420.789164 -315.96399)
			(xy 420.841126 -315.97585) (xy 420.89074 -315.995322) (xy 420.936898 -316.021971) (xy 420.978569 -316.055202)
			(xy 421.014821 -316.094273) (xy 421.044845 -316.13831) (xy 421.067971 -316.186331) (xy 421.083681 -316.237261)
			(xy 421.091624 -316.289965) (xy 421.092122 -316.316614) (xy 421.091624 -316.343263) (xy 424.480472 -316.343263)
			(xy 424.480472 -316.289965) (xy 424.488415 -316.237261) (xy 424.504125 -316.186331) (xy 424.527251 -316.13831)
			(xy 424.557275 -316.094273) (xy 424.593527 -316.055202) (xy 424.635198 -316.021971) (xy 424.681356 -315.995322)
			(xy 424.73097 -315.97585) (xy 424.782932 -315.96399) (xy 424.836082 -315.960007) (xy 424.889232 -315.96399)
			(xy 424.941194 -315.97585) (xy 424.990808 -315.995322) (xy 425.036966 -316.021971) (xy 425.078637 -316.055202)
			(xy 425.114889 -316.094273) (xy 425.144913 -316.13831) (xy 425.168039 -316.186331) (xy 425.183749 -316.237261)
			(xy 425.191692 -316.289965) (xy 425.19219 -316.316614) (xy 425.191692 -316.343263) (xy 426.690272 -316.343263)
			(xy 426.690272 -316.289965) (xy 426.698215 -316.237261) (xy 426.713925 -316.186331) (xy 426.737051 -316.13831)
			(xy 426.767075 -316.094273) (xy 426.803327 -316.055202) (xy 426.844998 -316.021971) (xy 426.891156 -315.995322)
			(xy 426.94077 -315.97585) (xy 426.992732 -315.96399) (xy 427.045882 -315.960007) (xy 427.099032 -315.96399)
			(xy 427.150994 -315.97585) (xy 427.200608 -315.995322) (xy 427.246766 -316.021971) (xy 427.288437 -316.055202)
			(xy 427.324689 -316.094273) (xy 427.354713 -316.13831) (xy 427.377839 -316.186331) (xy 427.393549 -316.237261)
			(xy 427.401492 -316.289965) (xy 427.40199 -316.316614) (xy 427.401624 -316.3362) (xy 431.40574 -316.3362)
			(xy 431.409724 -316.283042) (xy 431.421586 -316.231071) (xy 431.441061 -316.181449) (xy 431.467715 -316.135284)
			(xy 431.500952 -316.093607) (xy 431.54003 -316.057349) (xy 431.584075 -316.027321) (xy 431.632103 -316.004192)
			(xy 431.683042 -315.988481) (xy 431.735754 -315.980537) (xy 431.762408 -315.980064) (xy 431.787674 -315.980478)
			(xy 431.8377 -315.987624) (xy 431.886212 -316.00177) (xy 431.932237 -316.022634) (xy 431.97485 -316.049795)
			(xy 431.99431 -316.065916) (xy 432.006095 -316.075365) (xy 432.033751 -316.08748) (xy 432.06374 -316.09099)
			(xy 432.093446 -316.085588) (xy 432.120279 -316.071745) (xy 432.13147 -316.061598) (xy 432.151499 -316.042725)
			(xy 432.196343 -316.010826) (xy 432.245564 -315.986214) (xy 432.297989 -315.969477) (xy 432.352366 -315.961014)
			(xy 432.379882 -315.960506) (xy 432.406535 -315.96095) (xy 432.459246 -315.968892) (xy 432.510185 -315.984603)
			(xy 432.558213 -316.007729) (xy 432.602257 -316.037757) (xy 432.641334 -316.074013) (xy 432.674571 -316.115688)
			(xy 432.701225 -316.161852) (xy 432.7207 -316.211473) (xy 432.732562 -316.263443) (xy 432.736546 -316.3166)
			(xy 432.734548 -316.343263) (xy 434.234072 -316.343263) (xy 434.234072 -316.289965) (xy 434.242015 -316.237261)
			(xy 434.257725 -316.186331) (xy 434.280851 -316.13831) (xy 434.310875 -316.094273) (xy 434.347127 -316.055202)
			(xy 434.388798 -316.021971) (xy 434.434956 -315.995322) (xy 434.48457 -315.97585) (xy 434.536532 -315.96399)
			(xy 434.589682 -315.960007) (xy 434.642832 -315.96399) (xy 434.694794 -315.97585) (xy 434.744408 -315.995322)
			(xy 434.790566 -316.021971) (xy 434.832237 -316.055202) (xy 434.868489 -316.094273) (xy 434.898513 -316.13831)
			(xy 434.921639 -316.186331) (xy 434.937349 -316.237261) (xy 434.945292 -316.289965) (xy 434.94579 -316.316614)
			(xy 434.945292 -316.343263) (xy 435.468004 -316.343263) (xy 435.468004 -316.289965) (xy 435.475947 -316.237261)
			(xy 435.491657 -316.186331) (xy 435.514783 -316.13831) (xy 435.544807 -316.094273) (xy 435.581059 -316.055202)
			(xy 435.62273 -316.021971) (xy 435.668888 -315.995322) (xy 435.718502 -315.97585) (xy 435.770464 -315.96399)
			(xy 435.823614 -315.960007) (xy 435.876764 -315.96399) (xy 435.928726 -315.97585) (xy 435.97834 -315.995322)
			(xy 436.024498 -316.021971) (xy 436.066169 -316.055202) (xy 436.102421 -316.094273) (xy 436.132445 -316.13831)
			(xy 436.155571 -316.186331) (xy 436.171281 -316.237261) (xy 436.179224 -316.289965) (xy 436.179722 -316.316614)
			(xy 436.179224 -316.343263) (xy 439.568072 -316.343263) (xy 439.568072 -316.289965) (xy 439.576015 -316.237261)
			(xy 439.591725 -316.186331) (xy 439.614851 -316.13831) (xy 439.644875 -316.094273) (xy 439.681127 -316.055202)
			(xy 439.722798 -316.021971) (xy 439.768956 -315.995322) (xy 439.81857 -315.97585) (xy 439.870532 -315.96399)
			(xy 439.923682 -315.960007) (xy 439.976832 -315.96399) (xy 440.028794 -315.97585) (xy 440.078408 -315.995322)
			(xy 440.124566 -316.021971) (xy 440.166237 -316.055202) (xy 440.202489 -316.094273) (xy 440.232513 -316.13831)
			(xy 440.255639 -316.186331) (xy 440.271349 -316.237261) (xy 440.279292 -316.289965) (xy 440.27979 -316.316614)
			(xy 440.279292 -316.343263) (xy 441.777872 -316.343263) (xy 441.777872 -316.289965) (xy 441.785815 -316.237261)
			(xy 441.801525 -316.186331) (xy 441.824651 -316.13831) (xy 441.854675 -316.094273) (xy 441.890927 -316.055202)
			(xy 441.932598 -316.021971) (xy 441.978756 -315.995322) (xy 442.02837 -315.97585) (xy 442.080332 -315.96399)
			(xy 442.133482 -315.960007) (xy 442.186632 -315.96399) (xy 442.238594 -315.97585) (xy 442.288208 -315.995322)
			(xy 442.334366 -316.021971) (xy 442.376037 -316.055202) (xy 442.412289 -316.094273) (xy 442.442313 -316.13831)
			(xy 442.465439 -316.186331) (xy 442.481149 -316.237261) (xy 442.489092 -316.289965) (xy 442.48959 -316.316614)
			(xy 442.489092 -316.343263) (xy 447.111872 -316.343263) (xy 447.111872 -316.289965) (xy 447.119815 -316.237261)
			(xy 447.135525 -316.186331) (xy 447.158651 -316.13831) (xy 447.188675 -316.094273) (xy 447.224927 -316.055202)
			(xy 447.266598 -316.021971) (xy 447.312756 -315.995322) (xy 447.36237 -315.97585) (xy 447.414332 -315.96399)
			(xy 447.467482 -315.960007) (xy 447.520632 -315.96399) (xy 447.572594 -315.97585) (xy 447.622208 -315.995322)
			(xy 447.668366 -316.021971) (xy 447.710037 -316.055202) (xy 447.746289 -316.094273) (xy 447.776313 -316.13831)
			(xy 447.799439 -316.186331) (xy 447.815149 -316.237261) (xy 447.823092 -316.289965) (xy 447.82359 -316.316614)
			(xy 447.823092 -316.343263) (xy 449.321672 -316.343263) (xy 449.321672 -316.289965) (xy 449.329615 -316.237261)
			(xy 449.345325 -316.186331) (xy 449.368451 -316.13831) (xy 449.398475 -316.094273) (xy 449.434727 -316.055202)
			(xy 449.476398 -316.021971) (xy 449.522556 -315.995322) (xy 449.57217 -315.97585) (xy 449.624132 -315.96399)
			(xy 449.677282 -315.960007) (xy 449.730432 -315.96399) (xy 449.782394 -315.97585) (xy 449.832008 -315.995322)
			(xy 449.878166 -316.021971) (xy 449.919837 -316.055202) (xy 449.956089 -316.094273) (xy 449.986113 -316.13831)
			(xy 450.009239 -316.186331) (xy 450.024949 -316.237261) (xy 450.032892 -316.289965) (xy 450.03339 -316.316614)
			(xy 450.032892 -316.343263) (xy 450.555604 -316.343263) (xy 450.555604 -316.289965) (xy 450.563547 -316.237261)
			(xy 450.579257 -316.186331) (xy 450.602383 -316.13831) (xy 450.632407 -316.094273) (xy 450.668659 -316.055202)
			(xy 450.71033 -316.021971) (xy 450.756488 -315.995322) (xy 450.806102 -315.97585) (xy 450.858064 -315.96399)
			(xy 450.911214 -315.960007) (xy 450.964364 -315.96399) (xy 451.016326 -315.97585) (xy 451.06594 -315.995322)
			(xy 451.112098 -316.021971) (xy 451.153769 -316.055202) (xy 451.190021 -316.094273) (xy 451.220045 -316.13831)
			(xy 451.243171 -316.186331) (xy 451.258881 -316.237261) (xy 451.266824 -316.289965) (xy 451.267322 -316.316614)
			(xy 451.266824 -316.343263) (xy 454.655672 -316.343263) (xy 454.655672 -316.289965) (xy 454.663615 -316.237261)
			(xy 454.679325 -316.186331) (xy 454.702451 -316.13831) (xy 454.732475 -316.094273) (xy 454.768727 -316.055202)
			(xy 454.810398 -316.021971) (xy 454.856556 -315.995322) (xy 454.90617 -315.97585) (xy 454.958132 -315.96399)
			(xy 455.011282 -315.960007) (xy 455.064432 -315.96399) (xy 455.116394 -315.97585) (xy 455.166008 -315.995322)
			(xy 455.212166 -316.021971) (xy 455.253837 -316.055202) (xy 455.290089 -316.094273) (xy 455.320113 -316.13831)
			(xy 455.343239 -316.186331) (xy 455.358949 -316.237261) (xy 455.366892 -316.289965) (xy 455.36739 -316.316614)
			(xy 455.366892 -316.343263) (xy 456.865472 -316.343263) (xy 456.865472 -316.289965) (xy 456.873415 -316.237261)
			(xy 456.889125 -316.186331) (xy 456.912251 -316.13831) (xy 456.942275 -316.094273) (xy 456.978527 -316.055202)
			(xy 457.020198 -316.021971) (xy 457.066356 -315.995322) (xy 457.11597 -315.97585) (xy 457.167932 -315.96399)
			(xy 457.221082 -315.960007) (xy 457.274232 -315.96399) (xy 457.326194 -315.97585) (xy 457.375808 -315.995322)
			(xy 457.421966 -316.021971) (xy 457.463637 -316.055202) (xy 457.499889 -316.094273) (xy 457.529913 -316.13831)
			(xy 457.553039 -316.186331) (xy 457.568749 -316.237261) (xy 457.576692 -316.289965) (xy 457.57719 -316.316614)
			(xy 457.576692 -316.343263) (xy 457.568749 -316.395967) (xy 457.553039 -316.446897) (xy 457.529913 -316.494918)
			(xy 457.499889 -316.538955) (xy 457.463637 -316.578026) (xy 457.421966 -316.611257) (xy 457.375808 -316.637906)
			(xy 457.326194 -316.657378) (xy 457.274232 -316.669238) (xy 457.221082 -316.673222) (xy 457.167932 -316.669238)
			(xy 457.11597 -316.657378) (xy 457.066356 -316.637906) (xy 457.020198 -316.611257) (xy 456.978527 -316.578026)
			(xy 456.942275 -316.538955) (xy 456.912251 -316.494918) (xy 456.889125 -316.446897) (xy 456.873415 -316.395967)
			(xy 456.865472 -316.343263) (xy 455.366892 -316.343263) (xy 455.358949 -316.395967) (xy 455.343239 -316.446897)
			(xy 455.320113 -316.494918) (xy 455.290089 -316.538955) (xy 455.253837 -316.578026) (xy 455.212166 -316.611257)
			(xy 455.166008 -316.637906) (xy 455.116394 -316.657378) (xy 455.064432 -316.669238) (xy 455.011282 -316.673222)
			(xy 454.958132 -316.669238) (xy 454.90617 -316.657378) (xy 454.856556 -316.637906) (xy 454.810398 -316.611257)
			(xy 454.768727 -316.578026) (xy 454.732475 -316.538955) (xy 454.702451 -316.494918) (xy 454.679325 -316.446897)
			(xy 454.663615 -316.395967) (xy 454.655672 -316.343263) (xy 451.266824 -316.343263) (xy 451.258881 -316.395967)
			(xy 451.243171 -316.446897) (xy 451.220045 -316.494918) (xy 451.190021 -316.538955) (xy 451.153769 -316.578026)
			(xy 451.112098 -316.611257) (xy 451.06594 -316.637906) (xy 451.016326 -316.657378) (xy 450.964364 -316.669238)
			(xy 450.911214 -316.673222) (xy 450.858064 -316.669238) (xy 450.806102 -316.657378) (xy 450.756488 -316.637906)
			(xy 450.71033 -316.611257) (xy 450.668659 -316.578026) (xy 450.632407 -316.538955) (xy 450.602383 -316.494918)
			(xy 450.579257 -316.446897) (xy 450.563547 -316.395967) (xy 450.555604 -316.343263) (xy 450.032892 -316.343263)
			(xy 450.024949 -316.395967) (xy 450.009239 -316.446897) (xy 449.986113 -316.494918) (xy 449.956089 -316.538955)
			(xy 449.919837 -316.578026) (xy 449.878166 -316.611257) (xy 449.832008 -316.637906) (xy 449.782394 -316.657378)
			(xy 449.730432 -316.669238) (xy 449.677282 -316.673222) (xy 449.624132 -316.669238) (xy 449.57217 -316.657378)
			(xy 449.522556 -316.637906) (xy 449.476398 -316.611257) (xy 449.434727 -316.578026) (xy 449.398475 -316.538955)
			(xy 449.368451 -316.494918) (xy 449.345325 -316.446897) (xy 449.329615 -316.395967) (xy 449.321672 -316.343263)
			(xy 447.823092 -316.343263) (xy 447.815149 -316.395967) (xy 447.799439 -316.446897) (xy 447.776313 -316.494918)
			(xy 447.746289 -316.538955) (xy 447.710037 -316.578026) (xy 447.668366 -316.611257) (xy 447.622208 -316.637906)
			(xy 447.572594 -316.657378) (xy 447.520632 -316.669238) (xy 447.467482 -316.673222) (xy 447.414332 -316.669238)
			(xy 447.36237 -316.657378) (xy 447.312756 -316.637906) (xy 447.266598 -316.611257) (xy 447.224927 -316.578026)
			(xy 447.188675 -316.538955) (xy 447.158651 -316.494918) (xy 447.135525 -316.446897) (xy 447.119815 -316.395967)
			(xy 447.111872 -316.343263) (xy 442.489092 -316.343263) (xy 442.481149 -316.395967) (xy 442.465439 -316.446897)
			(xy 442.442313 -316.494918) (xy 442.412289 -316.538955) (xy 442.376037 -316.578026) (xy 442.334366 -316.611257)
			(xy 442.288208 -316.637906) (xy 442.238594 -316.657378) (xy 442.186632 -316.669238) (xy 442.133482 -316.673222)
			(xy 442.080332 -316.669238) (xy 442.02837 -316.657378) (xy 441.978756 -316.637906) (xy 441.932598 -316.611257)
			(xy 441.890927 -316.578026) (xy 441.854675 -316.538955) (xy 441.824651 -316.494918) (xy 441.801525 -316.446897)
			(xy 441.785815 -316.395967) (xy 441.777872 -316.343263) (xy 440.279292 -316.343263) (xy 440.271349 -316.395967)
			(xy 440.255639 -316.446897) (xy 440.232513 -316.494918) (xy 440.202489 -316.538955) (xy 440.166237 -316.578026)
			(xy 440.124566 -316.611257) (xy 440.078408 -316.637906) (xy 440.028794 -316.657378) (xy 439.976832 -316.669238)
			(xy 439.923682 -316.673222) (xy 439.870532 -316.669238) (xy 439.81857 -316.657378) (xy 439.768956 -316.637906)
			(xy 439.722798 -316.611257) (xy 439.681127 -316.578026) (xy 439.644875 -316.538955) (xy 439.614851 -316.494918)
			(xy 439.591725 -316.446897) (xy 439.576015 -316.395967) (xy 439.568072 -316.343263) (xy 436.179224 -316.343263)
			(xy 436.171281 -316.395967) (xy 436.155571 -316.446897) (xy 436.132445 -316.494918) (xy 436.102421 -316.538955)
			(xy 436.066169 -316.578026) (xy 436.024498 -316.611257) (xy 435.97834 -316.637906) (xy 435.928726 -316.657378)
			(xy 435.876764 -316.669238) (xy 435.823614 -316.673222) (xy 435.770464 -316.669238) (xy 435.718502 -316.657378)
			(xy 435.668888 -316.637906) (xy 435.62273 -316.611257) (xy 435.581059 -316.578026) (xy 435.544807 -316.538955)
			(xy 435.514783 -316.494918) (xy 435.491657 -316.446897) (xy 435.475947 -316.395967) (xy 435.468004 -316.343263)
			(xy 434.945292 -316.343263) (xy 434.937349 -316.395967) (xy 434.921639 -316.446897) (xy 434.898513 -316.494918)
			(xy 434.868489 -316.538955) (xy 434.832237 -316.578026) (xy 434.790566 -316.611257) (xy 434.744408 -316.637906)
			(xy 434.694794 -316.657378) (xy 434.642832 -316.669238) (xy 434.589682 -316.673222) (xy 434.536532 -316.669238)
			(xy 434.48457 -316.657378) (xy 434.434956 -316.637906) (xy 434.388798 -316.611257) (xy 434.347127 -316.578026)
			(xy 434.310875 -316.538955) (xy 434.280851 -316.494918) (xy 434.257725 -316.446897) (xy 434.242015 -316.395967)
			(xy 434.234072 -316.343263) (xy 432.734548 -316.343263) (xy 432.732562 -316.369757) (xy 432.7207 -316.421727)
			(xy 432.701225 -316.471348) (xy 432.674571 -316.517512) (xy 432.641334 -316.559187) (xy 432.602257 -316.595443)
			(xy 432.558213 -316.625471) (xy 432.510185 -316.648597) (xy 432.459246 -316.664308) (xy 432.406535 -316.67225)
			(xy 432.379882 -316.672722) (xy 432.354615 -316.672317) (xy 432.304589 -316.66517) (xy 432.256077 -316.651021)
			(xy 432.210052 -316.630156) (xy 432.167439 -316.602993) (xy 432.14798 -316.58687) (xy 432.136202 -316.577413)
			(xy 432.108543 -316.5653) (xy 432.078553 -316.561793) (xy 432.048846 -316.567196) (xy 432.022012 -316.58104)
			(xy 432.01082 -316.591188) (xy 431.99075 -316.610015) (xy 431.945918 -316.641921) (xy 431.896707 -316.666542)
			(xy 431.844291 -316.68329) (xy 431.789921 -316.691765) (xy 431.762408 -316.69228) (xy 431.735754 -316.691863)
			(xy 431.683042 -316.683919) (xy 431.632103 -316.668208) (xy 431.584075 -316.645079) (xy 431.54003 -316.615051)
			(xy 431.500952 -316.578793) (xy 431.467715 -316.537116) (xy 431.441061 -316.490951) (xy 431.421586 -316.441329)
			(xy 431.409724 -316.389358) (xy 431.40574 -316.3362) (xy 427.401624 -316.3362) (xy 427.401492 -316.343263)
			(xy 427.393549 -316.395967) (xy 427.377839 -316.446897) (xy 427.354713 -316.494918) (xy 427.324689 -316.538955)
			(xy 427.288437 -316.578026) (xy 427.246766 -316.611257) (xy 427.200608 -316.637906) (xy 427.150994 -316.657378)
			(xy 427.099032 -316.669238) (xy 427.045882 -316.673222) (xy 426.992732 -316.669238) (xy 426.94077 -316.657378)
			(xy 426.891156 -316.637906) (xy 426.844998 -316.611257) (xy 426.803327 -316.578026) (xy 426.767075 -316.538955)
			(xy 426.737051 -316.494918) (xy 426.713925 -316.446897) (xy 426.698215 -316.395967) (xy 426.690272 -316.343263)
			(xy 425.191692 -316.343263) (xy 425.183749 -316.395967) (xy 425.168039 -316.446897) (xy 425.144913 -316.494918)
			(xy 425.114889 -316.538955) (xy 425.078637 -316.578026) (xy 425.036966 -316.611257) (xy 424.990808 -316.637906)
			(xy 424.941194 -316.657378) (xy 424.889232 -316.669238) (xy 424.836082 -316.673222) (xy 424.782932 -316.669238)
			(xy 424.73097 -316.657378) (xy 424.681356 -316.637906) (xy 424.635198 -316.611257) (xy 424.593527 -316.578026)
			(xy 424.557275 -316.538955) (xy 424.527251 -316.494918) (xy 424.504125 -316.446897) (xy 424.488415 -316.395967)
			(xy 424.480472 -316.343263) (xy 421.091624 -316.343263) (xy 421.083681 -316.395967) (xy 421.067971 -316.446897)
			(xy 421.044845 -316.494918) (xy 421.014821 -316.538955) (xy 420.978569 -316.578026) (xy 420.936898 -316.611257)
			(xy 420.89074 -316.637906) (xy 420.841126 -316.657378) (xy 420.789164 -316.669238) (xy 420.736014 -316.673222)
			(xy 420.682864 -316.669238) (xy 420.630902 -316.657378) (xy 420.581288 -316.637906) (xy 420.53513 -316.611257)
			(xy 420.493459 -316.578026) (xy 420.457207 -316.538955) (xy 420.427183 -316.494918) (xy 420.404057 -316.446897)
			(xy 420.388347 -316.395967) (xy 420.380404 -316.343263) (xy 419.857692 -316.343263) (xy 419.849749 -316.395967)
			(xy 419.834039 -316.446897) (xy 419.810913 -316.494918) (xy 419.780889 -316.538955) (xy 419.744637 -316.578026)
			(xy 419.702966 -316.611257) (xy 419.656808 -316.637906) (xy 419.607194 -316.657378) (xy 419.555232 -316.669238)
			(xy 419.502082 -316.673222) (xy 419.448932 -316.669238) (xy 419.39697 -316.657378) (xy 419.347356 -316.637906)
			(xy 419.301198 -316.611257) (xy 419.259527 -316.578026) (xy 419.223275 -316.538955) (xy 419.193251 -316.494918)
			(xy 419.170125 -316.446897) (xy 419.154415 -316.395967) (xy 419.146472 -316.343263) (xy 417.647892 -316.343263)
			(xy 417.639949 -316.395967) (xy 417.624239 -316.446897) (xy 417.601113 -316.494918) (xy 417.571089 -316.538955)
			(xy 417.534837 -316.578026) (xy 417.493166 -316.611257) (xy 417.447008 -316.637906) (xy 417.397394 -316.657378)
			(xy 417.345432 -316.669238) (xy 417.292282 -316.673222) (xy 417.239132 -316.669238) (xy 417.18717 -316.657378)
			(xy 417.137556 -316.637906) (xy 417.091398 -316.611257) (xy 417.049727 -316.578026) (xy 417.013475 -316.538955)
			(xy 416.983451 -316.494918) (xy 416.960325 -316.446897) (xy 416.944615 -316.395967) (xy 416.936672 -316.343263)
			(xy 412.313892 -316.343263) (xy 412.305949 -316.395967) (xy 412.290239 -316.446897) (xy 412.267113 -316.494918)
			(xy 412.237089 -316.538955) (xy 412.200837 -316.578026) (xy 412.159166 -316.611257) (xy 412.113008 -316.637906)
			(xy 412.063394 -316.657378) (xy 412.011432 -316.669238) (xy 411.958282 -316.673222) (xy 411.905132 -316.669238)
			(xy 411.85317 -316.657378) (xy 411.803556 -316.637906) (xy 411.757398 -316.611257) (xy 411.715727 -316.578026)
			(xy 411.679475 -316.538955) (xy 411.649451 -316.494918) (xy 411.626325 -316.446897) (xy 411.610615 -316.395967)
			(xy 411.602672 -316.343263) (xy 410.104092 -316.343263) (xy 410.096149 -316.395967) (xy 410.080439 -316.446897)
			(xy 410.057313 -316.494918) (xy 410.027289 -316.538955) (xy 409.991037 -316.578026) (xy 409.949366 -316.611257)
			(xy 409.903208 -316.637906) (xy 409.853594 -316.657378) (xy 409.801632 -316.669238) (xy 409.748482 -316.673222)
			(xy 409.695332 -316.669238) (xy 409.64337 -316.657378) (xy 409.593756 -316.637906) (xy 409.547598 -316.611257)
			(xy 409.505927 -316.578026) (xy 409.469675 -316.538955) (xy 409.439651 -316.494918) (xy 409.416525 -316.446897)
			(xy 409.400815 -316.395967) (xy 409.392872 -316.343263) (xy 406.226772 -316.343263) (xy 406.226772 -317.193401)
			(xy 407.502604 -317.193401) (xy 407.502604 -317.140103) (xy 407.510547 -317.087399) (xy 407.526257 -317.036469)
			(xy 407.549383 -316.988448) (xy 407.579407 -316.944411) (xy 407.615659 -316.90534) (xy 407.65733 -316.872109)
			(xy 407.703488 -316.84546) (xy 407.753102 -316.825988) (xy 407.805064 -316.814128) (xy 407.858214 -316.810145)
			(xy 407.911364 -316.814128) (xy 407.963326 -316.825988) (xy 408.01294 -316.84546) (xy 408.059098 -316.872109)
			(xy 408.100769 -316.90534) (xy 408.137021 -316.944411) (xy 408.167045 -316.988448) (xy 408.190171 -317.036469)
			(xy 408.205881 -317.087399) (xy 408.213824 -317.140103) (xy 408.214322 -317.166752) (xy 408.213824 -317.193401)
			(xy 408.209345 -317.223119) (xy 409.353248 -317.223119) (xy 409.353248 -317.169821) (xy 409.361191 -317.117117)
			(xy 409.376901 -317.066187) (xy 409.400027 -317.018166) (xy 409.430051 -316.974129) (xy 409.466303 -316.935058)
			(xy 409.507974 -316.901827) (xy 409.554132 -316.875178) (xy 409.603746 -316.855706) (xy 409.655708 -316.843846)
			(xy 409.708858 -316.839863) (xy 409.762008 -316.843846) (xy 409.81397 -316.855706) (xy 409.863584 -316.875178)
			(xy 409.909742 -316.901827) (xy 409.951413 -316.935058) (xy 409.987665 -316.974129) (xy 410.017689 -317.018166)
			(xy 410.040815 -317.066187) (xy 410.056525 -317.117117) (xy 410.064468 -317.169821) (xy 410.064909 -317.193401)
			(xy 412.836604 -317.193401) (xy 412.836604 -317.140103) (xy 412.844547 -317.087399) (xy 412.860257 -317.036469)
			(xy 412.883383 -316.988448) (xy 412.913407 -316.944411) (xy 412.949659 -316.90534) (xy 412.99133 -316.872109)
			(xy 413.037488 -316.84546) (xy 413.087102 -316.825988) (xy 413.139064 -316.814128) (xy 413.192214 -316.810145)
			(xy 413.245364 -316.814128) (xy 413.297326 -316.825988) (xy 413.34694 -316.84546) (xy 413.393098 -316.872109)
			(xy 413.434769 -316.90534) (xy 413.471021 -316.944411) (xy 413.501045 -316.988448) (xy 413.524171 -317.036469)
			(xy 413.539881 -317.087399) (xy 413.547824 -317.140103) (xy 413.548322 -317.166752) (xy 413.547824 -317.193401)
			(xy 415.046404 -317.193401) (xy 415.046404 -317.140103) (xy 415.054347 -317.087399) (xy 415.070057 -317.036469)
			(xy 415.093183 -316.988448) (xy 415.123207 -316.944411) (xy 415.159459 -316.90534) (xy 415.20113 -316.872109)
			(xy 415.247288 -316.84546) (xy 415.296902 -316.825988) (xy 415.348864 -316.814128) (xy 415.402014 -316.810145)
			(xy 415.455164 -316.814128) (xy 415.507126 -316.825988) (xy 415.55674 -316.84546) (xy 415.602898 -316.872109)
			(xy 415.644569 -316.90534) (xy 415.680821 -316.944411) (xy 415.710845 -316.988448) (xy 415.733971 -317.036469)
			(xy 415.749681 -317.087399) (xy 415.757624 -317.140103) (xy 415.758122 -317.166752) (xy 415.757624 -317.193401)
			(xy 415.750083 -317.243439) (xy 419.170856 -317.243439) (xy 419.170856 -317.190141) (xy 419.178799 -317.137437)
			(xy 419.194509 -317.086507) (xy 419.217635 -317.038486) (xy 419.247659 -316.994449) (xy 419.283911 -316.955378)
			(xy 419.325582 -316.922147) (xy 419.37174 -316.895498) (xy 419.421354 -316.876026) (xy 419.473316 -316.864166)
			(xy 419.526466 -316.860183) (xy 419.579616 -316.864166) (xy 419.631578 -316.876026) (xy 419.681192 -316.895498)
			(xy 419.72735 -316.922147) (xy 419.769021 -316.955378) (xy 419.805273 -316.994449) (xy 419.835297 -317.038486)
			(xy 419.858423 -317.086507) (xy 419.874133 -317.137437) (xy 419.882076 -317.190141) (xy 419.882137 -317.193401)
			(xy 420.380404 -317.193401) (xy 420.380404 -317.140103) (xy 420.388347 -317.087399) (xy 420.404057 -317.036469)
			(xy 420.427183 -316.988448) (xy 420.457207 -316.944411) (xy 420.493459 -316.90534) (xy 420.53513 -316.872109)
			(xy 420.581288 -316.84546) (xy 420.630902 -316.825988) (xy 420.682864 -316.814128) (xy 420.736014 -316.810145)
			(xy 420.789164 -316.814128) (xy 420.841126 -316.825988) (xy 420.89074 -316.84546) (xy 420.936898 -316.872109)
			(xy 420.978569 -316.90534) (xy 421.014821 -316.944411) (xy 421.044845 -316.988448) (xy 421.067971 -317.036469)
			(xy 421.083681 -317.087399) (xy 421.091624 -317.140103) (xy 421.092122 -317.166752) (xy 421.091624 -317.193401)
			(xy 422.590204 -317.193401) (xy 422.590204 -317.140103) (xy 422.598147 -317.087399) (xy 422.613857 -317.036469)
			(xy 422.636983 -316.988448) (xy 422.667007 -316.944411) (xy 422.703259 -316.90534) (xy 422.74493 -316.872109)
			(xy 422.791088 -316.84546) (xy 422.840702 -316.825988) (xy 422.892664 -316.814128) (xy 422.945814 -316.810145)
			(xy 422.998964 -316.814128) (xy 423.050926 -316.825988) (xy 423.10054 -316.84546) (xy 423.146698 -316.872109)
			(xy 423.188369 -316.90534) (xy 423.224621 -316.944411) (xy 423.254645 -316.988448) (xy 423.277771 -317.036469)
			(xy 423.293481 -317.087399) (xy 423.301424 -317.140103) (xy 423.301922 -317.166752) (xy 423.301424 -317.193401)
			(xy 424.480472 -317.193401) (xy 424.480472 -317.140103) (xy 424.488415 -317.087399) (xy 424.504125 -317.036469)
			(xy 424.527251 -316.988448) (xy 424.557275 -316.944411) (xy 424.593527 -316.90534) (xy 424.635198 -316.872109)
			(xy 424.681356 -316.84546) (xy 424.73097 -316.825988) (xy 424.782932 -316.814128) (xy 424.836082 -316.810145)
			(xy 424.889232 -316.814128) (xy 424.941194 -316.825988) (xy 424.990808 -316.84546) (xy 425.036966 -316.872109)
			(xy 425.078637 -316.90534) (xy 425.114889 -316.944411) (xy 425.144913 -316.988448) (xy 425.168039 -317.036469)
			(xy 425.183749 -317.087399) (xy 425.191692 -317.140103) (xy 425.19219 -317.166752) (xy 425.191692 -317.193401)
			(xy 427.924204 -317.193401) (xy 427.924204 -317.140103) (xy 427.932147 -317.087399) (xy 427.947857 -317.036469)
			(xy 427.970983 -316.988448) (xy 428.001007 -316.944411) (xy 428.037259 -316.90534) (xy 428.07893 -316.872109)
			(xy 428.125088 -316.84546) (xy 428.174702 -316.825988) (xy 428.226664 -316.814128) (xy 428.279814 -316.810145)
			(xy 428.332964 -316.814128) (xy 428.384926 -316.825988) (xy 428.43454 -316.84546) (xy 428.480698 -316.872109)
			(xy 428.522369 -316.90534) (xy 428.558621 -316.944411) (xy 428.588645 -316.988448) (xy 428.611771 -317.036469)
			(xy 428.627481 -317.087399) (xy 428.635424 -317.140103) (xy 428.635922 -317.166752) (xy 428.635424 -317.193401)
			(xy 430.134004 -317.193401) (xy 430.134004 -317.140103) (xy 430.141947 -317.087399) (xy 430.157657 -317.036469)
			(xy 430.180783 -316.988448) (xy 430.210807 -316.944411) (xy 430.247059 -316.90534) (xy 430.28873 -316.872109)
			(xy 430.334888 -316.84546) (xy 430.384502 -316.825988) (xy 430.436464 -316.814128) (xy 430.489614 -316.810145)
			(xy 430.542764 -316.814128) (xy 430.594726 -316.825988) (xy 430.64434 -316.84546) (xy 430.690498 -316.872109)
			(xy 430.732169 -316.90534) (xy 430.768421 -316.944411) (xy 430.798445 -316.988448) (xy 430.821571 -317.036469)
			(xy 430.837281 -317.087399) (xy 430.845224 -317.140103) (xy 430.845722 -317.166752) (xy 430.845224 -317.193401)
			(xy 432.024272 -317.193401) (xy 432.024272 -317.140103) (xy 432.032215 -317.087399) (xy 432.047925 -317.036469)
			(xy 432.071051 -316.988448) (xy 432.101075 -316.944411) (xy 432.137327 -316.90534) (xy 432.178998 -316.872109)
			(xy 432.225156 -316.84546) (xy 432.27477 -316.825988) (xy 432.326732 -316.814128) (xy 432.379882 -316.810145)
			(xy 432.433032 -316.814128) (xy 432.484994 -316.825988) (xy 432.534608 -316.84546) (xy 432.580766 -316.872109)
			(xy 432.622437 -316.90534) (xy 432.658689 -316.944411) (xy 432.688713 -316.988448) (xy 432.711839 -317.036469)
			(xy 432.727549 -317.087399) (xy 432.735492 -317.140103) (xy 432.73599 -317.166752) (xy 432.735492 -317.193401)
			(xy 435.468004 -317.193401) (xy 435.468004 -317.140103) (xy 435.475947 -317.087399) (xy 435.491657 -317.036469)
			(xy 435.514783 -316.988448) (xy 435.544807 -316.944411) (xy 435.581059 -316.90534) (xy 435.62273 -316.872109)
			(xy 435.668888 -316.84546) (xy 435.718502 -316.825988) (xy 435.770464 -316.814128) (xy 435.823614 -316.810145)
			(xy 435.876764 -316.814128) (xy 435.928726 -316.825988) (xy 435.97834 -316.84546) (xy 436.024498 -316.872109)
			(xy 436.066169 -316.90534) (xy 436.102421 -316.944411) (xy 436.132445 -316.988448) (xy 436.155571 -317.036469)
			(xy 436.171281 -317.087399) (xy 436.179224 -317.140103) (xy 436.179722 -317.166752) (xy 436.179721 -317.1668)
			(xy 437.67672 -317.1668) (xy 437.680704 -317.113638) (xy 437.692567 -317.061664) (xy 437.712044 -317.012039)
			(xy 437.7387 -316.965871) (xy 437.77194 -316.924191) (xy 437.81102 -316.887931) (xy 437.855068 -316.857901)
			(xy 437.9031 -316.834772) (xy 437.954043 -316.81906) (xy 438.006759 -316.811116) (xy 438.033414 -316.810644)
			(xy 438.060736 -316.811144) (xy 438.114739 -316.819486) (xy 438.166836 -316.835971) (xy 438.215807 -316.860213)
			(xy 438.260505 -316.891646) (xy 438.280556 -316.910212) (xy 438.292178 -316.920609) (xy 438.320112 -316.934433)
			(xy 438.350914 -316.939189) (xy 438.381716 -316.934433) (xy 438.40965 -316.920609) (xy 438.421272 -316.910212)
			(xy 438.441306 -316.891623) (xy 438.485993 -316.860163) (xy 438.534967 -316.835909) (xy 438.587074 -316.819432)
			(xy 438.641088 -316.811119) (xy 438.668414 -316.810644) (xy 438.695059 -316.811239) (xy 438.747754 -316.819183)
			(xy 438.798676 -316.834892) (xy 438.846688 -316.858016) (xy 438.890717 -316.888036) (xy 438.929781 -316.924283)
			(xy 438.963006 -316.965948) (xy 438.98965 -317.012098) (xy 439.009119 -317.061705) (xy 439.020977 -317.113659)
			(xy 439.024959 -317.1668) (xy 439.022966 -317.193401) (xy 439.568072 -317.193401) (xy 439.568072 -317.140103)
			(xy 439.576015 -317.087399) (xy 439.591725 -317.036469) (xy 439.614851 -316.988448) (xy 439.644875 -316.944411)
			(xy 439.681127 -316.90534) (xy 439.722798 -316.872109) (xy 439.768956 -316.84546) (xy 439.81857 -316.825988)
			(xy 439.870532 -316.814128) (xy 439.923682 -316.810145) (xy 439.976832 -316.814128) (xy 440.028794 -316.825988)
			(xy 440.078408 -316.84546) (xy 440.124566 -316.872109) (xy 440.166237 -316.90534) (xy 440.202489 -316.944411)
			(xy 440.232513 -316.988448) (xy 440.255639 -317.036469) (xy 440.271349 -317.087399) (xy 440.279292 -317.140103)
			(xy 440.27979 -317.166752) (xy 440.279292 -317.193401) (xy 443.011804 -317.193401) (xy 443.011804 -317.140103)
			(xy 443.019747 -317.087399) (xy 443.035457 -317.036469) (xy 443.058583 -316.988448) (xy 443.088607 -316.944411)
			(xy 443.124859 -316.90534) (xy 443.16653 -316.872109) (xy 443.212688 -316.84546) (xy 443.262302 -316.825988)
			(xy 443.314264 -316.814128) (xy 443.367414 -316.810145) (xy 443.420564 -316.814128) (xy 443.472526 -316.825988)
			(xy 443.52214 -316.84546) (xy 443.568298 -316.872109) (xy 443.609969 -316.90534) (xy 443.646221 -316.944411)
			(xy 443.676245 -316.988448) (xy 443.699371 -317.036469) (xy 443.715081 -317.087399) (xy 443.723024 -317.140103)
			(xy 443.723522 -317.166752) (xy 443.723521 -317.1668) (xy 445.22052 -317.1668) (xy 445.224504 -317.113638)
			(xy 445.236367 -317.061664) (xy 445.255844 -317.012039) (xy 445.2825 -316.965871) (xy 445.31574 -316.924191)
			(xy 445.35482 -316.887931) (xy 445.398868 -316.857901) (xy 445.4469 -316.834772) (xy 445.497843 -316.81906)
			(xy 445.550559 -316.811116) (xy 445.577214 -316.810644) (xy 445.601756 -316.811076) (xy 445.650372 -316.817838)
			(xy 445.697597 -316.831217) (xy 445.742535 -316.850961) (xy 445.76365 -316.863476) (xy 445.775345 -316.870183)
			(xy 445.801203 -316.877781) (xy 445.828149 -316.878347) (xy 445.854303 -316.871841) (xy 445.877843 -316.858717)
			(xy 445.897128 -316.839889) (xy 445.910813 -316.816671) (xy 445.91478 -316.803786) (xy 445.922071 -316.779067)
			(xy 445.942805 -316.731887) (xy 445.970123 -316.688188) (xy 446.003453 -316.648882) (xy 446.042101 -316.61479)
			(xy 446.085258 -316.586623) (xy 446.132023 -316.564971) (xy 446.181421 -316.550284) (xy 446.23242 -316.542869)
			(xy 446.258188 -316.54242) (xy 446.284842 -316.542836) (xy 446.337554 -316.55078) (xy 446.388494 -316.566491)
			(xy 446.436523 -316.589619) (xy 446.480569 -316.619648) (xy 446.519646 -316.655905) (xy 446.552884 -316.697582)
			(xy 446.579538 -316.743748) (xy 446.599014 -316.79337) (xy 446.610876 -316.845341) (xy 446.61486 -316.8985)
			(xy 446.610876 -316.951659) (xy 446.599014 -317.00363) (xy 446.579538 -317.053252) (xy 446.552884 -317.099418)
			(xy 446.519646 -317.141095) (xy 446.480569 -317.177352) (xy 446.457029 -317.193401) (xy 447.111872 -317.193401)
			(xy 447.111872 -317.140103) (xy 447.119815 -317.087399) (xy 447.135525 -317.036469) (xy 447.158651 -316.988448)
			(xy 447.188675 -316.944411) (xy 447.224927 -316.90534) (xy 447.266598 -316.872109) (xy 447.312756 -316.84546)
			(xy 447.36237 -316.825988) (xy 447.414332 -316.814128) (xy 447.467482 -316.810145) (xy 447.520632 -316.814128)
			(xy 447.572594 -316.825988) (xy 447.622208 -316.84546) (xy 447.668366 -316.872109) (xy 447.710037 -316.90534)
			(xy 447.746289 -316.944411) (xy 447.776313 -316.988448) (xy 447.799439 -317.036469) (xy 447.815149 -317.087399)
			(xy 447.823092 -317.140103) (xy 447.82359 -317.166752) (xy 447.823092 -317.193401) (xy 450.555604 -317.193401)
			(xy 450.555604 -317.140103) (xy 450.563547 -317.087399) (xy 450.579257 -317.036469) (xy 450.602383 -316.988448)
			(xy 450.632407 -316.944411) (xy 450.668659 -316.90534) (xy 450.71033 -316.872109) (xy 450.756488 -316.84546)
			(xy 450.806102 -316.825988) (xy 450.858064 -316.814128) (xy 450.911214 -316.810145) (xy 450.964364 -316.814128)
			(xy 451.016326 -316.825988) (xy 451.06594 -316.84546) (xy 451.112098 -316.872109) (xy 451.153769 -316.90534)
			(xy 451.190021 -316.944411) (xy 451.220045 -316.988448) (xy 451.243171 -317.036469) (xy 451.258881 -317.087399)
			(xy 451.266824 -317.140103) (xy 451.267322 -317.166752) (xy 451.266824 -317.193401) (xy 452.765404 -317.193401)
			(xy 452.765404 -317.140103) (xy 452.773347 -317.087399) (xy 452.789057 -317.036469) (xy 452.812183 -316.988448)
			(xy 452.842207 -316.944411) (xy 452.878459 -316.90534) (xy 452.92013 -316.872109) (xy 452.966288 -316.84546)
			(xy 453.015902 -316.825988) (xy 453.067864 -316.814128) (xy 453.121014 -316.810145) (xy 453.174164 -316.814128)
			(xy 453.226126 -316.825988) (xy 453.27574 -316.84546) (xy 453.321898 -316.872109) (xy 453.363569 -316.90534)
			(xy 453.399821 -316.944411) (xy 453.429845 -316.988448) (xy 453.452971 -317.036469) (xy 453.468681 -317.087399)
			(xy 453.476624 -317.140103) (xy 453.477122 -317.166752) (xy 453.476624 -317.193401) (xy 454.655672 -317.193401)
			(xy 454.655672 -317.140103) (xy 454.663615 -317.087399) (xy 454.679325 -317.036469) (xy 454.702451 -316.988448)
			(xy 454.732475 -316.944411) (xy 454.768727 -316.90534) (xy 454.810398 -316.872109) (xy 454.856556 -316.84546)
			(xy 454.90617 -316.825988) (xy 454.958132 -316.814128) (xy 455.011282 -316.810145) (xy 455.064432 -316.814128)
			(xy 455.116394 -316.825988) (xy 455.166008 -316.84546) (xy 455.212166 -316.872109) (xy 455.253837 -316.90534)
			(xy 455.290089 -316.944411) (xy 455.320113 -316.988448) (xy 455.343239 -317.036469) (xy 455.358949 -317.087399)
			(xy 455.366892 -317.140103) (xy 455.36739 -317.166752) (xy 455.366892 -317.193401) (xy 458.099404 -317.193401)
			(xy 458.099404 -317.140103) (xy 458.107347 -317.087399) (xy 458.123057 -317.036469) (xy 458.146183 -316.988448)
			(xy 458.176207 -316.944411) (xy 458.212459 -316.90534) (xy 458.25413 -316.872109) (xy 458.300288 -316.84546)
			(xy 458.349902 -316.825988) (xy 458.401864 -316.814128) (xy 458.455014 -316.810145) (xy 458.508164 -316.814128)
			(xy 458.560126 -316.825988) (xy 458.60974 -316.84546) (xy 458.655898 -316.872109) (xy 458.697569 -316.90534)
			(xy 458.733821 -316.944411) (xy 458.763845 -316.988448) (xy 458.786971 -317.036469) (xy 458.802681 -317.087399)
			(xy 458.810624 -317.140103) (xy 458.811122 -317.166752) (xy 458.810624 -317.193401) (xy 458.802681 -317.246105)
			(xy 458.786971 -317.297035) (xy 458.763845 -317.345056) (xy 458.733821 -317.389093) (xy 458.697569 -317.428164)
			(xy 458.655898 -317.461395) (xy 458.60974 -317.488044) (xy 458.560126 -317.507516) (xy 458.508164 -317.519376)
			(xy 458.455014 -317.52336) (xy 458.401864 -317.519376) (xy 458.349902 -317.507516) (xy 458.300288 -317.488044)
			(xy 458.25413 -317.461395) (xy 458.212459 -317.428164) (xy 458.176207 -317.389093) (xy 458.146183 -317.345056)
			(xy 458.123057 -317.297035) (xy 458.107347 -317.246105) (xy 458.099404 -317.193401) (xy 455.366892 -317.193401)
			(xy 455.358949 -317.246105) (xy 455.343239 -317.297035) (xy 455.320113 -317.345056) (xy 455.290089 -317.389093)
			(xy 455.253837 -317.428164) (xy 455.212166 -317.461395) (xy 455.166008 -317.488044) (xy 455.116394 -317.507516)
			(xy 455.064432 -317.519376) (xy 455.011282 -317.52336) (xy 454.958132 -317.519376) (xy 454.90617 -317.507516)
			(xy 454.856556 -317.488044) (xy 454.810398 -317.461395) (xy 454.768727 -317.428164) (xy 454.732475 -317.389093)
			(xy 454.702451 -317.345056) (xy 454.679325 -317.297035) (xy 454.663615 -317.246105) (xy 454.655672 -317.193401)
			(xy 453.476624 -317.193401) (xy 453.468681 -317.246105) (xy 453.452971 -317.297035) (xy 453.429845 -317.345056)
			(xy 453.399821 -317.389093) (xy 453.363569 -317.428164) (xy 453.321898 -317.461395) (xy 453.27574 -317.488044)
			(xy 453.226126 -317.507516) (xy 453.174164 -317.519376) (xy 453.121014 -317.52336) (xy 453.067864 -317.519376)
			(xy 453.015902 -317.507516) (xy 452.966288 -317.488044) (xy 452.92013 -317.461395) (xy 452.878459 -317.428164)
			(xy 452.842207 -317.389093) (xy 452.812183 -317.345056) (xy 452.789057 -317.297035) (xy 452.773347 -317.246105)
			(xy 452.765404 -317.193401) (xy 451.266824 -317.193401) (xy 451.258881 -317.246105) (xy 451.243171 -317.297035)
			(xy 451.220045 -317.345056) (xy 451.190021 -317.389093) (xy 451.153769 -317.428164) (xy 451.112098 -317.461395)
			(xy 451.06594 -317.488044) (xy 451.016326 -317.507516) (xy 450.964364 -317.519376) (xy 450.911214 -317.52336)
			(xy 450.858064 -317.519376) (xy 450.806102 -317.507516) (xy 450.756488 -317.488044) (xy 450.71033 -317.461395)
			(xy 450.668659 -317.428164) (xy 450.632407 -317.389093) (xy 450.602383 -317.345056) (xy 450.579257 -317.297035)
			(xy 450.563547 -317.246105) (xy 450.555604 -317.193401) (xy 447.823092 -317.193401) (xy 447.815149 -317.246105)
			(xy 447.799439 -317.297035) (xy 447.776313 -317.345056) (xy 447.746289 -317.389093) (xy 447.710037 -317.428164)
			(xy 447.668366 -317.461395) (xy 447.622208 -317.488044) (xy 447.572594 -317.507516) (xy 447.520632 -317.519376)
			(xy 447.467482 -317.52336) (xy 447.414332 -317.519376) (xy 447.36237 -317.507516) (xy 447.312756 -317.488044)
			(xy 447.266598 -317.461395) (xy 447.224927 -317.428164) (xy 447.188675 -317.389093) (xy 447.158651 -317.345056)
			(xy 447.135525 -317.297035) (xy 447.119815 -317.246105) (xy 447.111872 -317.193401) (xy 446.457029 -317.193401)
			(xy 446.436523 -317.207381) (xy 446.388494 -317.230509) (xy 446.337554 -317.24622) (xy 446.284842 -317.254164)
			(xy 446.258188 -317.254636) (xy 446.233646 -317.254206) (xy 446.18503 -317.247444) (xy 446.137805 -317.234064)
			(xy 446.092867 -317.21432) (xy 446.071752 -317.201804) (xy 446.060078 -317.195053) (xy 446.034211 -317.187445)
			(xy 446.007255 -317.186876) (xy 445.98109 -317.193387) (xy 445.957544 -317.206522) (xy 445.938259 -317.225365)
			(xy 445.924582 -317.248601) (xy 445.920622 -317.261494) (xy 445.913381 -317.286228) (xy 445.892636 -317.333406)
			(xy 445.865309 -317.377103) (xy 445.831971 -317.416407) (xy 445.793318 -317.450496) (xy 445.750156 -317.47866)
			(xy 445.703386 -317.500311) (xy 445.653985 -317.514997) (xy 445.602983 -317.522411) (xy 445.577214 -317.52286)
			(xy 445.550559 -317.522484) (xy 445.497843 -317.51454) (xy 445.4469 -317.498828) (xy 445.398868 -317.475699)
			(xy 445.35482 -317.445669) (xy 445.31574 -317.409409) (xy 445.2825 -317.367729) (xy 445.255844 -317.321561)
			(xy 445.236367 -317.271936) (xy 445.224504 -317.219962) (xy 445.22052 -317.1668) (xy 443.723521 -317.1668)
			(xy 443.723024 -317.193401) (xy 443.715081 -317.246105) (xy 443.699371 -317.297035) (xy 443.676245 -317.345056)
			(xy 443.646221 -317.389093) (xy 443.609969 -317.428164) (xy 443.568298 -317.461395) (xy 443.52214 -317.488044)
			(xy 443.472526 -317.507516) (xy 443.420564 -317.519376) (xy 443.367414 -317.52336) (xy 443.314264 -317.519376)
			(xy 443.262302 -317.507516) (xy 443.212688 -317.488044) (xy 443.16653 -317.461395) (xy 443.124859 -317.428164)
			(xy 443.088607 -317.389093) (xy 443.058583 -317.345056) (xy 443.035457 -317.297035) (xy 443.019747 -317.246105)
			(xy 443.011804 -317.193401) (xy 440.279292 -317.193401) (xy 440.271349 -317.246105) (xy 440.255639 -317.297035)
			(xy 440.232513 -317.345056) (xy 440.202489 -317.389093) (xy 440.166237 -317.428164) (xy 440.124566 -317.461395)
			(xy 440.078408 -317.488044) (xy 440.028794 -317.507516) (xy 439.976832 -317.519376) (xy 439.923682 -317.52336)
			(xy 439.870532 -317.519376) (xy 439.81857 -317.507516) (xy 439.768956 -317.488044) (xy 439.722798 -317.461395)
			(xy 439.681127 -317.428164) (xy 439.644875 -317.389093) (xy 439.614851 -317.345056) (xy 439.591725 -317.297035)
			(xy 439.576015 -317.246105) (xy 439.568072 -317.193401) (xy 439.022966 -317.193401) (xy 439.020977 -317.219941)
			(xy 439.009119 -317.271895) (xy 438.98965 -317.321502) (xy 438.963006 -317.367652) (xy 438.929781 -317.409317)
			(xy 438.890717 -317.445564) (xy 438.846688 -317.475584) (xy 438.798676 -317.498708) (xy 438.747754 -317.514417)
			(xy 438.695059 -317.522361) (xy 438.668414 -317.52286) (xy 438.641093 -317.522341) (xy 438.587091 -317.514004)
			(xy 438.534994 -317.497524) (xy 438.486022 -317.473285) (xy 438.441324 -317.441856) (xy 438.421272 -317.423292)
			(xy 438.40965 -317.412895) (xy 438.381716 -317.399071) (xy 438.350914 -317.394315) (xy 438.320112 -317.399071)
			(xy 438.292178 -317.412895) (xy 438.280556 -317.423292) (xy 438.260553 -317.441916) (xy 438.215857 -317.473371)
			(xy 438.166876 -317.497619) (xy 438.114762 -317.514087) (xy 438.060742 -317.52239) (xy 438.033414 -317.52286)
			(xy 438.006759 -317.522484) (xy 437.954043 -317.51454) (xy 437.9031 -317.498828) (xy 437.855068 -317.475699)
			(xy 437.81102 -317.445669) (xy 437.77194 -317.409409) (xy 437.7387 -317.367729) (xy 437.712044 -317.321561)
			(xy 437.692567 -317.271936) (xy 437.680704 -317.219962) (xy 437.67672 -317.1668) (xy 436.179721 -317.1668)
			(xy 436.179224 -317.193401) (xy 436.171281 -317.246105) (xy 436.155571 -317.297035) (xy 436.132445 -317.345056)
			(xy 436.102421 -317.389093) (xy 436.066169 -317.428164) (xy 436.024498 -317.461395) (xy 435.97834 -317.488044)
			(xy 435.928726 -317.507516) (xy 435.876764 -317.519376) (xy 435.823614 -317.52336) (xy 435.770464 -317.519376)
			(xy 435.718502 -317.507516) (xy 435.668888 -317.488044) (xy 435.62273 -317.461395) (xy 435.581059 -317.428164)
			(xy 435.544807 -317.389093) (xy 435.514783 -317.345056) (xy 435.491657 -317.297035) (xy 435.475947 -317.246105)
			(xy 435.468004 -317.193401) (xy 432.735492 -317.193401) (xy 432.727549 -317.246105) (xy 432.711839 -317.297035)
			(xy 432.688713 -317.345056) (xy 432.658689 -317.389093) (xy 432.622437 -317.428164) (xy 432.580766 -317.461395)
			(xy 432.534608 -317.488044) (xy 432.484994 -317.507516) (xy 432.433032 -317.519376) (xy 432.379882 -317.52336)
			(xy 432.326732 -317.519376) (xy 432.27477 -317.507516) (xy 432.225156 -317.488044) (xy 432.178998 -317.461395)
			(xy 432.137327 -317.428164) (xy 432.101075 -317.389093) (xy 432.071051 -317.345056) (xy 432.047925 -317.297035)
			(xy 432.032215 -317.246105) (xy 432.024272 -317.193401) (xy 430.845224 -317.193401) (xy 430.837281 -317.246105)
			(xy 430.821571 -317.297035) (xy 430.798445 -317.345056) (xy 430.768421 -317.389093) (xy 430.732169 -317.428164)
			(xy 430.690498 -317.461395) (xy 430.64434 -317.488044) (xy 430.594726 -317.507516) (xy 430.542764 -317.519376)
			(xy 430.489614 -317.52336) (xy 430.436464 -317.519376) (xy 430.384502 -317.507516) (xy 430.334888 -317.488044)
			(xy 430.28873 -317.461395) (xy 430.247059 -317.428164) (xy 430.210807 -317.389093) (xy 430.180783 -317.345056)
			(xy 430.157657 -317.297035) (xy 430.141947 -317.246105) (xy 430.134004 -317.193401) (xy 428.635424 -317.193401)
			(xy 428.627481 -317.246105) (xy 428.611771 -317.297035) (xy 428.588645 -317.345056) (xy 428.558621 -317.389093)
			(xy 428.522369 -317.428164) (xy 428.480698 -317.461395) (xy 428.43454 -317.488044) (xy 428.384926 -317.507516)
			(xy 428.332964 -317.519376) (xy 428.279814 -317.52336) (xy 428.226664 -317.519376) (xy 428.174702 -317.507516)
			(xy 428.125088 -317.488044) (xy 428.07893 -317.461395) (xy 428.037259 -317.428164) (xy 428.001007 -317.389093)
			(xy 427.970983 -317.345056) (xy 427.947857 -317.297035) (xy 427.932147 -317.246105) (xy 427.924204 -317.193401)
			(xy 425.191692 -317.193401) (xy 425.183749 -317.246105) (xy 425.168039 -317.297035) (xy 425.144913 -317.345056)
			(xy 425.114889 -317.389093) (xy 425.078637 -317.428164) (xy 425.036966 -317.461395) (xy 424.990808 -317.488044)
			(xy 424.941194 -317.507516) (xy 424.889232 -317.519376) (xy 424.836082 -317.52336) (xy 424.782932 -317.519376)
			(xy 424.73097 -317.507516) (xy 424.681356 -317.488044) (xy 424.635198 -317.461395) (xy 424.593527 -317.428164)
			(xy 424.557275 -317.389093) (xy 424.527251 -317.345056) (xy 424.504125 -317.297035) (xy 424.488415 -317.246105)
			(xy 424.480472 -317.193401) (xy 423.301424 -317.193401) (xy 423.293481 -317.246105) (xy 423.277771 -317.297035)
			(xy 423.254645 -317.345056) (xy 423.224621 -317.389093) (xy 423.188369 -317.428164) (xy 423.146698 -317.461395)
			(xy 423.10054 -317.488044) (xy 423.050926 -317.507516) (xy 422.998964 -317.519376) (xy 422.945814 -317.52336)
			(xy 422.892664 -317.519376) (xy 422.840702 -317.507516) (xy 422.791088 -317.488044) (xy 422.74493 -317.461395)
			(xy 422.703259 -317.428164) (xy 422.667007 -317.389093) (xy 422.636983 -317.345056) (xy 422.613857 -317.297035)
			(xy 422.598147 -317.246105) (xy 422.590204 -317.193401) (xy 421.091624 -317.193401) (xy 421.083681 -317.246105)
			(xy 421.067971 -317.297035) (xy 421.044845 -317.345056) (xy 421.014821 -317.389093) (xy 420.978569 -317.428164)
			(xy 420.936898 -317.461395) (xy 420.89074 -317.488044) (xy 420.841126 -317.507516) (xy 420.789164 -317.519376)
			(xy 420.736014 -317.52336) (xy 420.682864 -317.519376) (xy 420.630902 -317.507516) (xy 420.581288 -317.488044)
			(xy 420.53513 -317.461395) (xy 420.493459 -317.428164) (xy 420.457207 -317.389093) (xy 420.427183 -317.345056)
			(xy 420.404057 -317.297035) (xy 420.388347 -317.246105) (xy 420.380404 -317.193401) (xy 419.882137 -317.193401)
			(xy 419.882574 -317.21679) (xy 419.882076 -317.243439) (xy 419.874133 -317.296143) (xy 419.858423 -317.347073)
			(xy 419.835297 -317.395094) (xy 419.805273 -317.439131) (xy 419.769021 -317.478202) (xy 419.72735 -317.511433)
			(xy 419.681192 -317.538082) (xy 419.631578 -317.557554) (xy 419.579616 -317.569414) (xy 419.526466 -317.573398)
			(xy 419.473316 -317.569414) (xy 419.421354 -317.557554) (xy 419.37174 -317.538082) (xy 419.325582 -317.511433)
			(xy 419.283911 -317.478202) (xy 419.247659 -317.439131) (xy 419.217635 -317.395094) (xy 419.194509 -317.347073)
			(xy 419.178799 -317.296143) (xy 419.170856 -317.243439) (xy 415.750083 -317.243439) (xy 415.749681 -317.246105)
			(xy 415.733971 -317.297035) (xy 415.710845 -317.345056) (xy 415.680821 -317.389093) (xy 415.644569 -317.428164)
			(xy 415.602898 -317.461395) (xy 415.55674 -317.488044) (xy 415.507126 -317.507516) (xy 415.455164 -317.519376)
			(xy 415.402014 -317.52336) (xy 415.348864 -317.519376) (xy 415.296902 -317.507516) (xy 415.247288 -317.488044)
			(xy 415.20113 -317.461395) (xy 415.159459 -317.428164) (xy 415.123207 -317.389093) (xy 415.093183 -317.345056)
			(xy 415.070057 -317.297035) (xy 415.054347 -317.246105) (xy 415.046404 -317.193401) (xy 413.547824 -317.193401)
			(xy 413.539881 -317.246105) (xy 413.524171 -317.297035) (xy 413.501045 -317.345056) (xy 413.471021 -317.389093)
			(xy 413.434769 -317.428164) (xy 413.393098 -317.461395) (xy 413.34694 -317.488044) (xy 413.297326 -317.507516)
			(xy 413.245364 -317.519376) (xy 413.192214 -317.52336) (xy 413.139064 -317.519376) (xy 413.087102 -317.507516)
			(xy 413.037488 -317.488044) (xy 412.99133 -317.461395) (xy 412.949659 -317.428164) (xy 412.913407 -317.389093)
			(xy 412.883383 -317.345056) (xy 412.860257 -317.297035) (xy 412.844547 -317.246105) (xy 412.836604 -317.193401)
			(xy 410.064909 -317.193401) (xy 410.064966 -317.19647) (xy 410.064468 -317.223119) (xy 410.056525 -317.275823)
			(xy 410.040815 -317.326753) (xy 410.017689 -317.374774) (xy 409.987665 -317.418811) (xy 409.951413 -317.457882)
			(xy 409.909742 -317.491113) (xy 409.863584 -317.517762) (xy 409.81397 -317.537234) (xy 409.762008 -317.549094)
			(xy 409.708858 -317.553078) (xy 409.655708 -317.549094) (xy 409.603746 -317.537234) (xy 409.554132 -317.517762)
			(xy 409.507974 -317.491113) (xy 409.466303 -317.457882) (xy 409.430051 -317.418811) (xy 409.400027 -317.374774)
			(xy 409.376901 -317.326753) (xy 409.361191 -317.275823) (xy 409.353248 -317.223119) (xy 408.209345 -317.223119)
			(xy 408.205881 -317.246105) (xy 408.190171 -317.297035) (xy 408.167045 -317.345056) (xy 408.137021 -317.389093)
			(xy 408.100769 -317.428164) (xy 408.059098 -317.461395) (xy 408.01294 -317.488044) (xy 407.963326 -317.507516)
			(xy 407.911364 -317.519376) (xy 407.858214 -317.52336) (xy 407.805064 -317.519376) (xy 407.753102 -317.507516)
			(xy 407.703488 -317.488044) (xy 407.65733 -317.461395) (xy 407.615659 -317.428164) (xy 407.579407 -317.389093)
			(xy 407.549383 -317.345056) (xy 407.526257 -317.297035) (xy 407.510547 -317.246105) (xy 407.502604 -317.193401)
			(xy 406.226772 -317.193401) (xy 406.226772 -317.679557) (xy 408.344614 -317.679557) (xy 408.344614 -317.626259)
			(xy 408.352557 -317.573555) (xy 408.368267 -317.522625) (xy 408.391393 -317.474604) (xy 408.421417 -317.430567)
			(xy 408.457669 -317.391496) (xy 408.49934 -317.358265) (xy 408.545498 -317.331616) (xy 408.595112 -317.312144)
			(xy 408.647074 -317.300284) (xy 408.700224 -317.296301) (xy 408.753374 -317.300284) (xy 408.805336 -317.312144)
			(xy 408.85495 -317.331616) (xy 408.901108 -317.358265) (xy 408.942779 -317.391496) (xy 408.979031 -317.430567)
			(xy 409.009055 -317.474604) (xy 409.032181 -317.522625) (xy 409.047891 -317.573555) (xy 409.055834 -317.626259)
			(xy 409.056332 -317.652908) (xy 409.055834 -317.679557) (xy 409.047891 -317.732261) (xy 409.032181 -317.783191)
			(xy 409.009055 -317.831212) (xy 408.979031 -317.875249) (xy 408.942779 -317.91432) (xy 408.901108 -317.947551)
			(xy 408.85495 -317.9742) (xy 408.805336 -317.993672) (xy 408.753374 -318.005532) (xy 408.700224 -318.009516)
			(xy 408.647074 -318.005532) (xy 408.595112 -317.993672) (xy 408.545498 -317.9742) (xy 408.49934 -317.947551)
			(xy 408.457669 -317.91432) (xy 408.421417 -317.875249) (xy 408.391393 -317.831212) (xy 408.368267 -317.783191)
			(xy 408.352557 -317.732261) (xy 408.344614 -317.679557) (xy 406.226772 -317.679557) (xy 406.226772 -318.043285)
			(xy 409.392872 -318.043285) (xy 409.392872 -317.989987) (xy 409.400815 -317.937283) (xy 409.416525 -317.886353)
			(xy 409.439651 -317.838332) (xy 409.469675 -317.794295) (xy 409.505927 -317.755224) (xy 409.547598 -317.721993)
			(xy 409.593756 -317.695344) (xy 409.64337 -317.675872) (xy 409.695332 -317.664012) (xy 409.748482 -317.660029)
			(xy 409.801632 -317.664012) (xy 409.853594 -317.675872) (xy 409.903208 -317.695344) (xy 409.949366 -317.721993)
			(xy 409.991037 -317.755224) (xy 410.027289 -317.794295) (xy 410.057313 -317.838332) (xy 410.080439 -317.886353)
			(xy 410.096149 -317.937283) (xy 410.104092 -317.989987) (xy 410.10459 -318.016636) (xy 410.104092 -318.043285)
			(xy 410.096149 -318.095989) (xy 410.09611 -318.096117) (xy 412.12261 -318.096117) (xy 412.12261 -318.042819)
			(xy 412.130553 -317.990115) (xy 412.146263 -317.939185) (xy 412.169389 -317.891164) (xy 412.199413 -317.847127)
			(xy 412.235665 -317.808056) (xy 412.277336 -317.774825) (xy 412.323494 -317.748176) (xy 412.373108 -317.728704)
			(xy 412.42507 -317.716844) (xy 412.47822 -317.712861) (xy 412.53137 -317.716844) (xy 412.583332 -317.728704)
			(xy 412.632946 -317.748176) (xy 412.679104 -317.774825) (xy 412.720775 -317.808056) (xy 412.757027 -317.847127)
			(xy 412.787051 -317.891164) (xy 412.810177 -317.939185) (xy 412.825887 -317.990115) (xy 412.83383 -318.042819)
			(xy 412.833839 -318.043285) (xy 416.936672 -318.043285) (xy 416.936672 -317.989987) (xy 416.944615 -317.937283)
			(xy 416.960325 -317.886353) (xy 416.983451 -317.838332) (xy 417.013475 -317.794295) (xy 417.049727 -317.755224)
			(xy 417.091398 -317.721993) (xy 417.137556 -317.695344) (xy 417.18717 -317.675872) (xy 417.239132 -317.664012)
			(xy 417.292282 -317.660029) (xy 417.345432 -317.664012) (xy 417.397394 -317.675872) (xy 417.447008 -317.695344)
			(xy 417.493166 -317.721993) (xy 417.534837 -317.755224) (xy 417.571089 -317.794295) (xy 417.601113 -317.838332)
			(xy 417.624239 -317.886353) (xy 417.639949 -317.937283) (xy 417.647892 -317.989987) (xy 417.64822 -318.007532)
			(xy 426.663017 -318.007532) (xy 426.668501 -317.953655) (xy 426.682081 -317.90123) (xy 426.703442 -317.851465)
			(xy 426.732093 -317.80551) (xy 426.767372 -317.764422) (xy 426.808466 -317.729151) (xy 426.854428 -317.700509)
			(xy 426.904196 -317.679158) (xy 426.956624 -317.665589) (xy 427.010502 -317.660116) (xy 427.064587 -317.662864)
			(xy 427.117633 -317.67377) (xy 427.168415 -317.692584) (xy 427.215763 -317.71887) (xy 427.258584 -317.752023)
			(xy 427.295892 -317.791278) (xy 427.326824 -317.83573) (xy 427.350669 -317.884353) (xy 427.366876 -317.936027)
			(xy 427.375071 -317.989558) (xy 427.375574 -318.016636) (xy 427.375574 -318.02578) (xy 427.375695 -318.039824)
			(xy 427.376589 -318.043285) (xy 434.266076 -318.043285) (xy 434.266076 -317.989987) (xy 434.274019 -317.937283)
			(xy 434.289729 -317.886353) (xy 434.312855 -317.838332) (xy 434.342879 -317.794295) (xy 434.379131 -317.755224)
			(xy 434.420802 -317.721993) (xy 434.46696 -317.695344) (xy 434.516574 -317.675872) (xy 434.568536 -317.664012)
			(xy 434.621686 -317.660029) (xy 434.674836 -317.664012) (xy 434.726798 -317.675872) (xy 434.776412 -317.695344)
			(xy 434.82257 -317.721993) (xy 434.864241 -317.755224) (xy 434.900493 -317.794295) (xy 434.930517 -317.838332)
			(xy 434.953643 -317.886353) (xy 434.969353 -317.937283) (xy 434.977296 -317.989987) (xy 434.977794 -318.016636)
			(xy 434.977296 -318.043285) (xy 439.568072 -318.043285) (xy 439.568072 -317.989987) (xy 439.576015 -317.937283)
			(xy 439.591725 -317.886353) (xy 439.614851 -317.838332) (xy 439.644875 -317.794295) (xy 439.681127 -317.755224)
			(xy 439.722798 -317.721993) (xy 439.768956 -317.695344) (xy 439.81857 -317.675872) (xy 439.870532 -317.664012)
			(xy 439.923682 -317.660029) (xy 439.976832 -317.664012) (xy 440.028794 -317.675872) (xy 440.078408 -317.695344)
			(xy 440.124566 -317.721993) (xy 440.166237 -317.755224) (xy 440.202489 -317.794295) (xy 440.232513 -317.838332)
			(xy 440.255639 -317.886353) (xy 440.271349 -317.937283) (xy 440.279292 -317.989987) (xy 440.27979 -318.016636)
			(xy 440.279292 -318.043285) (xy 440.271349 -318.095989) (xy 440.266765 -318.110849) (xy 442.197988 -318.110849)
			(xy 442.197988 -318.057551) (xy 442.205931 -318.004847) (xy 442.221641 -317.953917) (xy 442.244767 -317.905896)
			(xy 442.274791 -317.861859) (xy 442.311043 -317.822788) (xy 442.352714 -317.789557) (xy 442.398872 -317.762908)
			(xy 442.448486 -317.743436) (xy 442.500448 -317.731576) (xy 442.553598 -317.727593) (xy 442.606748 -317.731576)
			(xy 442.65871 -317.743436) (xy 442.708324 -317.762908) (xy 442.754482 -317.789557) (xy 442.796153 -317.822788)
			(xy 442.832405 -317.861859) (xy 442.862429 -317.905896) (xy 442.885555 -317.953917) (xy 442.901265 -318.004847)
			(xy 442.907058 -318.043285) (xy 449.300336 -318.043285) (xy 449.300336 -317.989987) (xy 449.308279 -317.937283)
			(xy 449.323989 -317.886353) (xy 449.347115 -317.838332) (xy 449.377139 -317.794295) (xy 449.413391 -317.755224)
			(xy 449.455062 -317.721993) (xy 449.50122 -317.695344) (xy 449.550834 -317.675872) (xy 449.602796 -317.664012)
			(xy 449.655946 -317.660029) (xy 449.709096 -317.664012) (xy 449.761058 -317.675872) (xy 449.810672 -317.695344)
			(xy 449.85683 -317.721993) (xy 449.898501 -317.755224) (xy 449.934753 -317.794295) (xy 449.964777 -317.838332)
			(xy 449.987903 -317.886353) (xy 450.003613 -317.937283) (xy 450.011556 -317.989987) (xy 450.012054 -318.016636)
			(xy 450.011556 -318.043285) (xy 456.849216 -318.043285) (xy 456.849216 -317.989987) (xy 456.857159 -317.937283)
			(xy 456.872869 -317.886353) (xy 456.895995 -317.838332) (xy 456.926019 -317.794295) (xy 456.962271 -317.755224)
			(xy 457.003942 -317.721993) (xy 457.0501 -317.695344) (xy 457.099714 -317.675872) (xy 457.151676 -317.664012)
			(xy 457.204826 -317.660029) (xy 457.257976 -317.664012) (xy 457.309938 -317.675872) (xy 457.359552 -317.695344)
			(xy 457.40571 -317.721993) (xy 457.447381 -317.755224) (xy 457.483633 -317.794295) (xy 457.513657 -317.838332)
			(xy 457.536783 -317.886353) (xy 457.552493 -317.937283) (xy 457.560436 -317.989987) (xy 457.560934 -318.016636)
			(xy 457.560436 -318.043285) (xy 457.552493 -318.095989) (xy 457.536783 -318.146919) (xy 457.513657 -318.19494)
			(xy 457.483633 -318.238977) (xy 457.447381 -318.278048) (xy 457.40571 -318.311279) (xy 457.359552 -318.337928)
			(xy 457.309938 -318.3574) (xy 457.257976 -318.36926) (xy 457.204826 -318.373244) (xy 457.151676 -318.36926)
			(xy 457.099714 -318.3574) (xy 457.0501 -318.337928) (xy 457.003942 -318.311279) (xy 456.962271 -318.278048)
			(xy 456.926019 -318.238977) (xy 456.895995 -318.19494) (xy 456.872869 -318.146919) (xy 456.857159 -318.095989)
			(xy 456.849216 -318.043285) (xy 450.011556 -318.043285) (xy 450.003613 -318.095989) (xy 449.987903 -318.146919)
			(xy 449.964777 -318.19494) (xy 449.934753 -318.238977) (xy 449.898501 -318.278048) (xy 449.85683 -318.311279)
			(xy 449.810672 -318.337928) (xy 449.761058 -318.3574) (xy 449.709096 -318.36926) (xy 449.655946 -318.373244)
			(xy 449.602796 -318.36926) (xy 449.550834 -318.3574) (xy 449.50122 -318.337928) (xy 449.455062 -318.311279)
			(xy 449.413391 -318.278048) (xy 449.377139 -318.238977) (xy 449.347115 -318.19494) (xy 449.323989 -318.146919)
			(xy 449.308279 -318.095989) (xy 449.300336 -318.043285) (xy 442.907058 -318.043285) (xy 442.909208 -318.057551)
			(xy 442.909706 -318.0842) (xy 442.909208 -318.110849) (xy 442.901265 -318.163553) (xy 442.885555 -318.214483)
			(xy 442.862429 -318.262504) (xy 442.832405 -318.306541) (xy 442.796153 -318.345612) (xy 442.754482 -318.378843)
			(xy 442.708324 -318.405492) (xy 442.65871 -318.424964) (xy 442.606748 -318.436824) (xy 442.553598 -318.440808)
			(xy 442.500448 -318.436824) (xy 442.448486 -318.424964) (xy 442.398872 -318.405492) (xy 442.352714 -318.378843)
			(xy 442.311043 -318.345612) (xy 442.274791 -318.306541) (xy 442.244767 -318.262504) (xy 442.221641 -318.214483)
			(xy 442.205931 -318.163553) (xy 442.197988 -318.110849) (xy 440.266765 -318.110849) (xy 440.255639 -318.146919)
			(xy 440.232513 -318.19494) (xy 440.202489 -318.238977) (xy 440.166237 -318.278048) (xy 440.124566 -318.311279)
			(xy 440.078408 -318.337928) (xy 440.028794 -318.3574) (xy 439.976832 -318.36926) (xy 439.923682 -318.373244)
			(xy 439.870532 -318.36926) (xy 439.81857 -318.3574) (xy 439.768956 -318.337928) (xy 439.722798 -318.311279)
			(xy 439.681127 -318.278048) (xy 439.644875 -318.238977) (xy 439.614851 -318.19494) (xy 439.591725 -318.146919)
			(xy 439.576015 -318.095989) (xy 439.568072 -318.043285) (xy 434.977296 -318.043285) (xy 434.969353 -318.095989)
			(xy 434.953643 -318.146919) (xy 434.930517 -318.19494) (xy 434.900493 -318.238977) (xy 434.864241 -318.278048)
			(xy 434.82257 -318.311279) (xy 434.776412 -318.337928) (xy 434.726798 -318.3574) (xy 434.674836 -318.36926)
			(xy 434.621686 -318.373244) (xy 434.568536 -318.36926) (xy 434.516574 -318.3574) (xy 434.46696 -318.337928)
			(xy 434.420802 -318.311279) (xy 434.379131 -318.278048) (xy 434.342879 -318.238977) (xy 434.312855 -318.19494)
			(xy 434.289729 -318.146919) (xy 434.274019 -318.095989) (xy 434.266076 -318.043285) (xy 427.376589 -318.043285)
			(xy 427.382718 -318.067007) (xy 427.396873 -318.091253) (xy 427.417093 -318.110731) (xy 427.441851 -318.12397)
			(xy 427.469277 -318.129972) (xy 427.497301 -318.128283) (xy 427.510702 -318.124078) (xy 427.539328 -318.114715)
			(xy 427.5987 -318.104623) (xy 427.628812 -318.104012) (xy 427.655891 -318.10451) (xy 427.709423 -318.112713)
			(xy 427.761097 -318.128927) (xy 427.809719 -318.152779) (xy 427.854169 -318.183719) (xy 427.893421 -318.221032)
			(xy 427.926571 -318.263859) (xy 427.952853 -318.311212) (xy 427.971661 -318.361998) (xy 427.982563 -318.415047)
			(xy 427.985067 -318.464417) (xy 450.10831 -318.464417) (xy 450.10831 -318.411119) (xy 450.116253 -318.358415)
			(xy 450.131963 -318.307485) (xy 450.155089 -318.259464) (xy 450.185113 -318.215427) (xy 450.221365 -318.176356)
			(xy 450.263036 -318.143125) (xy 450.309194 -318.116476) (xy 450.358808 -318.097004) (xy 450.41077 -318.085144)
			(xy 450.46392 -318.081161) (xy 450.51707 -318.085144) (xy 450.569032 -318.097004) (xy 450.618646 -318.116476)
			(xy 450.664804 -318.143125) (xy 450.706475 -318.176356) (xy 450.742727 -318.215427) (xy 450.772751 -318.259464)
			(xy 450.795877 -318.307485) (xy 450.811587 -318.358415) (xy 450.81953 -318.411119) (xy 450.820028 -318.437768)
			(xy 450.81953 -318.464417) (xy 450.811587 -318.517121) (xy 450.795877 -318.568051) (xy 450.772751 -318.616072)
			(xy 450.742727 -318.660109) (xy 450.706475 -318.69918) (xy 450.664804 -318.732411) (xy 450.618646 -318.75906)
			(xy 450.569032 -318.778532) (xy 450.51707 -318.790392) (xy 450.46392 -318.794376) (xy 450.41077 -318.790392)
			(xy 450.358808 -318.778532) (xy 450.309194 -318.75906) (xy 450.263036 -318.732411) (xy 450.221365 -318.69918)
			(xy 450.185113 -318.660109) (xy 450.155089 -318.616072) (xy 450.131963 -318.568051) (xy 450.116253 -318.517121)
			(xy 450.10831 -318.464417) (xy 427.985067 -318.464417) (xy 427.985306 -318.469135) (xy 427.979826 -318.523015)
			(xy 427.966252 -318.575444) (xy 427.944895 -318.625212) (xy 427.916248 -318.671173) (xy 427.880971 -318.712266)
			(xy 427.839879 -318.747543) (xy 427.793919 -318.776191) (xy 427.744151 -318.797549) (xy 427.691723 -318.811125)
			(xy 427.637843 -318.816605) (xy 427.583755 -318.813864) (xy 427.530706 -318.802964) (xy 427.479919 -318.784156)
			(xy 427.432566 -318.757875) (xy 427.389738 -318.724727) (xy 427.352424 -318.685475) (xy 427.321483 -318.641026)
			(xy 427.29763 -318.592404) (xy 427.281415 -318.540731) (xy 427.273211 -318.487199) (xy 427.272704 -318.46012)
			(xy 427.272704 -318.450976) (xy 427.272649 -318.436929) (xy 427.265614 -318.409741) (xy 427.251447 -318.385493)
			(xy 427.231216 -318.366015) (xy 427.206448 -318.352777) (xy 427.179013 -318.346778) (xy 427.15098 -318.348471)
			(xy 427.137576 -318.352678) (xy 427.108951 -318.362045) (xy 427.049578 -318.372135) (xy 427.019466 -318.372744)
			(xy 426.992388 -318.372166) (xy 426.938858 -318.36396) (xy 426.887188 -318.347743) (xy 426.83857 -318.323889)
			(xy 426.794124 -318.292947) (xy 426.754876 -318.255632) (xy 426.721732 -318.212805) (xy 426.695455 -318.165451)
			(xy 426.676651 -318.114665) (xy 426.665755 -318.061618) (xy 426.663017 -318.007532) (xy 417.64822 -318.007532)
			(xy 417.64839 -318.016636) (xy 417.647892 -318.043285) (xy 417.639949 -318.095989) (xy 417.624239 -318.146919)
			(xy 417.601113 -318.19494) (xy 417.571089 -318.238977) (xy 417.534837 -318.278048) (xy 417.493166 -318.311279)
			(xy 417.447008 -318.337928) (xy 417.397394 -318.3574) (xy 417.345432 -318.36926) (xy 417.292282 -318.373244)
			(xy 417.239132 -318.36926) (xy 417.18717 -318.3574) (xy 417.137556 -318.337928) (xy 417.091398 -318.311279)
			(xy 417.049727 -318.278048) (xy 417.013475 -318.238977) (xy 416.983451 -318.19494) (xy 416.960325 -318.146919)
			(xy 416.944615 -318.095989) (xy 416.936672 -318.043285) (xy 412.833839 -318.043285) (xy 412.834328 -318.069468)
			(xy 412.83383 -318.096117) (xy 412.825887 -318.148821) (xy 412.810177 -318.199751) (xy 412.787051 -318.247772)
			(xy 412.757027 -318.291809) (xy 412.720775 -318.33088) (xy 412.679104 -318.364111) (xy 412.632946 -318.39076)
			(xy 412.583332 -318.410232) (xy 412.53137 -318.422092) (xy 412.47822 -318.426076) (xy 412.42507 -318.422092)
			(xy 412.373108 -318.410232) (xy 412.323494 -318.39076) (xy 412.277336 -318.364111) (xy 412.235665 -318.33088)
			(xy 412.199413 -318.291809) (xy 412.169389 -318.247772) (xy 412.146263 -318.199751) (xy 412.130553 -318.148821)
			(xy 412.12261 -318.096117) (xy 410.09611 -318.096117) (xy 410.080439 -318.146919) (xy 410.057313 -318.19494)
			(xy 410.027289 -318.238977) (xy 409.991037 -318.278048) (xy 409.949366 -318.311279) (xy 409.903208 -318.337928)
			(xy 409.853594 -318.3574) (xy 409.801632 -318.36926) (xy 409.748482 -318.373244) (xy 409.695332 -318.36926)
			(xy 409.64337 -318.3574) (xy 409.593756 -318.337928) (xy 409.547598 -318.311279) (xy 409.505927 -318.278048)
			(xy 409.469675 -318.238977) (xy 409.439651 -318.19494) (xy 409.416525 -318.146919) (xy 409.400815 -318.095989)
			(xy 409.392872 -318.043285) (xy 406.226772 -318.043285) (xy 406.226772 -318.893423) (xy 416.936672 -318.893423)
			(xy 416.936672 -318.840125) (xy 416.944615 -318.787421) (xy 416.960325 -318.736491) (xy 416.983451 -318.68847)
			(xy 417.013475 -318.644433) (xy 417.049727 -318.605362) (xy 417.091398 -318.572131) (xy 417.137556 -318.545482)
			(xy 417.18717 -318.52601) (xy 417.239132 -318.51415) (xy 417.292282 -318.510167) (xy 417.345432 -318.51415)
			(xy 417.397394 -318.52601) (xy 417.447008 -318.545482) (xy 417.493166 -318.572131) (xy 417.534837 -318.605362)
			(xy 417.571089 -318.644433) (xy 417.601113 -318.68847) (xy 417.624239 -318.736491) (xy 417.639949 -318.787421)
			(xy 417.647892 -318.840125) (xy 417.64839 -318.866774) (xy 417.647892 -318.893423) (xy 424.480472 -318.893423)
			(xy 424.480472 -318.840125) (xy 424.488415 -318.787421) (xy 424.504125 -318.736491) (xy 424.527251 -318.68847)
			(xy 424.557275 -318.644433) (xy 424.593527 -318.605362) (xy 424.635198 -318.572131) (xy 424.681356 -318.545482)
			(xy 424.73097 -318.52601) (xy 424.782932 -318.51415) (xy 424.836082 -318.510167) (xy 424.889232 -318.51415)
			(xy 424.941194 -318.52601) (xy 424.990808 -318.545482) (xy 425.036966 -318.572131) (xy 425.078637 -318.605362)
			(xy 425.114889 -318.644433) (xy 425.144913 -318.68847) (xy 425.168039 -318.736491) (xy 425.183749 -318.787421)
			(xy 425.191692 -318.840125) (xy 425.19219 -318.866774) (xy 425.191692 -318.893423) (xy 435.11215 -318.893423)
			(xy 435.11215 -318.840125) (xy 435.120093 -318.787421) (xy 435.135803 -318.736491) (xy 435.158929 -318.68847)
			(xy 435.188953 -318.644433) (xy 435.225205 -318.605362) (xy 435.266876 -318.572131) (xy 435.313034 -318.545482)
			(xy 435.362648 -318.52601) (xy 435.41461 -318.51415) (xy 435.46776 -318.510167) (xy 435.52091 -318.51415)
			(xy 435.572872 -318.52601) (xy 435.622486 -318.545482) (xy 435.668644 -318.572131) (xy 435.710315 -318.605362)
			(xy 435.746567 -318.644433) (xy 435.776591 -318.68847) (xy 435.799717 -318.736491) (xy 435.815427 -318.787421)
			(xy 435.82337 -318.840125) (xy 435.823868 -318.866774) (xy 435.82337 -318.893423) (xy 439.568072 -318.893423)
			(xy 439.568072 -318.840125) (xy 439.576015 -318.787421) (xy 439.591725 -318.736491) (xy 439.614851 -318.68847)
			(xy 439.644875 -318.644433) (xy 439.681127 -318.605362) (xy 439.722798 -318.572131) (xy 439.768956 -318.545482)
			(xy 439.81857 -318.52601) (xy 439.870532 -318.51415) (xy 439.923682 -318.510167) (xy 439.976832 -318.51415)
			(xy 440.028794 -318.52601) (xy 440.078408 -318.545482) (xy 440.124566 -318.572131) (xy 440.166237 -318.605362)
			(xy 440.202489 -318.644433) (xy 440.232513 -318.68847) (xy 440.255639 -318.736491) (xy 440.271349 -318.787421)
			(xy 440.279292 -318.840125) (xy 440.27979 -318.866774) (xy 440.279292 -318.893423) (xy 447.111872 -318.893423)
			(xy 447.111872 -318.840125) (xy 447.119815 -318.787421) (xy 447.135525 -318.736491) (xy 447.158651 -318.68847)
			(xy 447.188675 -318.644433) (xy 447.224927 -318.605362) (xy 447.266598 -318.572131) (xy 447.312756 -318.545482)
			(xy 447.36237 -318.52601) (xy 447.414332 -318.51415) (xy 447.467482 -318.510167) (xy 447.520632 -318.51415)
			(xy 447.572594 -318.52601) (xy 447.622208 -318.545482) (xy 447.668366 -318.572131) (xy 447.710037 -318.605362)
			(xy 447.746289 -318.644433) (xy 447.776313 -318.68847) (xy 447.799439 -318.736491) (xy 447.815149 -318.787421)
			(xy 447.823092 -318.840125) (xy 447.82359 -318.866774) (xy 447.823092 -318.893423) (xy 447.815149 -318.946127)
			(xy 447.799439 -318.997057) (xy 447.776313 -319.045078) (xy 447.746289 -319.089115) (xy 447.710037 -319.128186)
			(xy 447.668366 -319.161417) (xy 447.622208 -319.188066) (xy 447.572594 -319.207538) (xy 447.520632 -319.219398)
			(xy 447.467482 -319.223382) (xy 447.414332 -319.219398) (xy 447.36237 -319.207538) (xy 447.312756 -319.188066)
			(xy 447.266598 -319.161417) (xy 447.224927 -319.128186) (xy 447.188675 -319.089115) (xy 447.158651 -319.045078)
			(xy 447.135525 -318.997057) (xy 447.119815 -318.946127) (xy 447.111872 -318.893423) (xy 440.279292 -318.893423)
			(xy 440.271349 -318.946127) (xy 440.255639 -318.997057) (xy 440.232513 -319.045078) (xy 440.202489 -319.089115)
			(xy 440.166237 -319.128186) (xy 440.124566 -319.161417) (xy 440.078408 -319.188066) (xy 440.028794 -319.207538)
			(xy 439.976832 -319.219398) (xy 439.923682 -319.223382) (xy 439.870532 -319.219398) (xy 439.81857 -319.207538)
			(xy 439.768956 -319.188066) (xy 439.722798 -319.161417) (xy 439.681127 -319.128186) (xy 439.644875 -319.089115)
			(xy 439.614851 -319.045078) (xy 439.591725 -318.997057) (xy 439.576015 -318.946127) (xy 439.568072 -318.893423)
			(xy 435.82337 -318.893423) (xy 435.815427 -318.946127) (xy 435.799717 -318.997057) (xy 435.776591 -319.045078)
			(xy 435.746567 -319.089115) (xy 435.710315 -319.128186) (xy 435.668644 -319.161417) (xy 435.622486 -319.188066)
			(xy 435.572872 -319.207538) (xy 435.52091 -319.219398) (xy 435.46776 -319.223382) (xy 435.41461 -319.219398)
			(xy 435.362648 -319.207538) (xy 435.313034 -319.188066) (xy 435.266876 -319.161417) (xy 435.225205 -319.128186)
			(xy 435.188953 -319.089115) (xy 435.158929 -319.045078) (xy 435.135803 -318.997057) (xy 435.120093 -318.946127)
			(xy 435.11215 -318.893423) (xy 425.191692 -318.893423) (xy 425.183749 -318.946127) (xy 425.168039 -318.997057)
			(xy 425.144913 -319.045078) (xy 425.114889 -319.089115) (xy 425.078637 -319.128186) (xy 425.036966 -319.161417)
			(xy 424.990808 -319.188066) (xy 424.941194 -319.207538) (xy 424.889232 -319.219398) (xy 424.836082 -319.223382)
			(xy 424.782932 -319.219398) (xy 424.73097 -319.207538) (xy 424.681356 -319.188066) (xy 424.635198 -319.161417)
			(xy 424.593527 -319.128186) (xy 424.557275 -319.089115) (xy 424.527251 -319.045078) (xy 424.504125 -318.997057)
			(xy 424.488415 -318.946127) (xy 424.480472 -318.893423) (xy 417.647892 -318.893423) (xy 417.639949 -318.946127)
			(xy 417.624239 -318.997057) (xy 417.601113 -319.045078) (xy 417.571089 -319.089115) (xy 417.534837 -319.128186)
			(xy 417.493166 -319.161417) (xy 417.447008 -319.188066) (xy 417.397394 -319.207538) (xy 417.345432 -319.219398)
			(xy 417.292282 -319.223382) (xy 417.239132 -319.219398) (xy 417.18717 -319.207538) (xy 417.137556 -319.188066)
			(xy 417.091398 -319.161417) (xy 417.049727 -319.128186) (xy 417.013475 -319.089115) (xy 416.983451 -319.045078)
			(xy 416.960325 -318.997057) (xy 416.944615 -318.946127) (xy 416.936672 -318.893423) (xy 406.226772 -318.893423)
			(xy 406.226772 -319.321688) (xy 408.621992 -319.321688) (xy 408.62249 -319.295039) (xy 408.630433 -319.242335)
			(xy 408.646143 -319.191405) (xy 408.669269 -319.143384) (xy 408.699293 -319.099347) (xy 408.735545 -319.060276)
			(xy 408.777216 -319.027045) (xy 408.823374 -319.000396) (xy 408.872988 -318.980924) (xy 408.92495 -318.969064)
			(xy 408.9781 -318.965081) (xy 409.03125 -318.969064) (xy 409.083212 -318.980924) (xy 409.132826 -319.000396)
			(xy 409.178984 -319.027045) (xy 409.220655 -319.060276) (xy 409.256907 -319.099347) (xy 409.286931 -319.143384)
			(xy 409.310057 -319.191405) (xy 409.325767 -319.242335) (xy 409.33371 -319.295039) (xy 409.334208 -319.321688)
			(xy 409.334043 -319.337071) (xy 409.33137 -319.367722) (xy 409.328874 -319.382902) (xy 409.32679 -319.397942)
			(xy 409.330602 -319.428052) (xy 409.343085 -319.455717) (xy 409.363139 -319.478497) (xy 409.388998 -319.494386)
			(xy 409.40355 -319.498726) (xy 409.428711 -319.50569) (xy 409.476817 -319.525968) (xy 409.521447 -319.553051)
			(xy 409.561646 -319.586359) (xy 409.596552 -319.625179) (xy 409.625417 -319.668678) (xy 409.647622 -319.715926)
			(xy 409.655878 -319.743307) (xy 411.628072 -319.743307) (xy 411.628072 -319.690009) (xy 411.636015 -319.637305)
			(xy 411.651725 -319.586375) (xy 411.674851 -319.538354) (xy 411.704875 -319.494317) (xy 411.741127 -319.455246)
			(xy 411.782798 -319.422015) (xy 411.828956 -319.395366) (xy 411.87857 -319.375894) (xy 411.930532 -319.364034)
			(xy 411.983682 -319.360051) (xy 412.036832 -319.364034) (xy 412.088794 -319.375894) (xy 412.138408 -319.395366)
			(xy 412.184566 -319.422015) (xy 412.226237 -319.455246) (xy 412.242993 -319.473305) (xy 415.109142 -319.473305)
			(xy 415.109142 -319.420007) (xy 415.117085 -319.367303) (xy 415.132795 -319.316373) (xy 415.155921 -319.268352)
			(xy 415.185945 -319.224315) (xy 415.222197 -319.185244) (xy 415.263868 -319.152013) (xy 415.310026 -319.125364)
			(xy 415.35964 -319.105892) (xy 415.411602 -319.094032) (xy 415.464752 -319.090049) (xy 415.517902 -319.094032)
			(xy 415.569864 -319.105892) (xy 415.619478 -319.125364) (xy 415.665636 -319.152013) (xy 415.707307 -319.185244)
			(xy 415.743559 -319.224315) (xy 415.773583 -319.268352) (xy 415.796709 -319.316373) (xy 415.812419 -319.367303)
			(xy 415.820362 -319.420007) (xy 415.82086 -319.446656) (xy 415.820362 -319.473305) (xy 415.812419 -319.526009)
			(xy 415.796709 -319.576939) (xy 415.773583 -319.62496) (xy 415.743559 -319.668997) (xy 415.707307 -319.708068)
			(xy 415.665636 -319.741299) (xy 415.662158 -319.743307) (xy 416.936672 -319.743307) (xy 416.936672 -319.690009)
			(xy 416.944615 -319.637305) (xy 416.960325 -319.586375) (xy 416.983451 -319.538354) (xy 417.013475 -319.494317)
			(xy 417.049727 -319.455246) (xy 417.091398 -319.422015) (xy 417.137556 -319.395366) (xy 417.18717 -319.375894)
			(xy 417.239132 -319.364034) (xy 417.292282 -319.360051) (xy 417.345432 -319.364034) (xy 417.397394 -319.375894)
			(xy 417.447008 -319.395366) (xy 417.493166 -319.422015) (xy 417.534837 -319.455246) (xy 417.571089 -319.494317)
			(xy 417.591052 -319.523597) (xy 419.54195 -319.523597) (xy 419.54195 -319.470299) (xy 419.549893 -319.417595)
			(xy 419.565603 -319.366665) (xy 419.588729 -319.318644) (xy 419.618753 -319.274607) (xy 419.655005 -319.235536)
			(xy 419.696676 -319.202305) (xy 419.742834 -319.175656) (xy 419.792448 -319.156184) (xy 419.84441 -319.144324)
			(xy 419.89756 -319.140341) (xy 419.95071 -319.144324) (xy 420.002672 -319.156184) (xy 420.052286 -319.175656)
			(xy 420.098444 -319.202305) (xy 420.140115 -319.235536) (xy 420.176367 -319.274607) (xy 420.206391 -319.318644)
			(xy 420.229517 -319.366665) (xy 420.245227 -319.417595) (xy 420.25317 -319.470299) (xy 420.253668 -319.496948)
			(xy 420.25317 -319.523597) (xy 420.249265 -319.549505) (xy 422.729142 -319.549505) (xy 422.729142 -319.496207)
			(xy 422.737085 -319.443503) (xy 422.752795 -319.392573) (xy 422.775921 -319.344552) (xy 422.805945 -319.300515)
			(xy 422.842197 -319.261444) (xy 422.883868 -319.228213) (xy 422.930026 -319.201564) (xy 422.97964 -319.182092)
			(xy 423.031602 -319.170232) (xy 423.084752 -319.166249) (xy 423.137902 -319.170232) (xy 423.189864 -319.182092)
			(xy 423.239478 -319.201564) (xy 423.285636 -319.228213) (xy 423.327307 -319.261444) (xy 423.363559 -319.300515)
			(xy 423.377461 -319.320905) (xy 430.222142 -319.320905) (xy 430.222142 -319.267607) (xy 430.230085 -319.214903)
			(xy 430.245795 -319.163973) (xy 430.268921 -319.115952) (xy 430.298945 -319.071915) (xy 430.335197 -319.032844)
			(xy 430.376868 -318.999613) (xy 430.423026 -318.972964) (xy 430.47264 -318.953492) (xy 430.524602 -318.941632)
			(xy 430.577752 -318.937649) (xy 430.630902 -318.941632) (xy 430.682864 -318.953492) (xy 430.732478 -318.972964)
			(xy 430.778636 -318.999613) (xy 430.820307 -319.032844) (xy 430.856559 -319.071915) (xy 430.886583 -319.115952)
			(xy 430.909709 -319.163973) (xy 430.925419 -319.214903) (xy 430.933362 -319.267607) (xy 430.93386 -319.294256)
			(xy 430.933362 -319.320905) (xy 430.929534 -319.346305) (xy 437.689742 -319.346305) (xy 437.689742 -319.293007)
			(xy 437.697685 -319.240303) (xy 437.713395 -319.189373) (xy 437.736521 -319.141352) (xy 437.766545 -319.097315)
			(xy 437.802797 -319.058244) (xy 437.844468 -319.025013) (xy 437.890626 -318.998364) (xy 437.94024 -318.978892)
			(xy 437.992202 -318.967032) (xy 438.045352 -318.963049) (xy 438.098502 -318.967032) (xy 438.150464 -318.978892)
			(xy 438.200078 -318.998364) (xy 438.246236 -319.025013) (xy 438.287907 -319.058244) (xy 438.324159 -319.097315)
			(xy 438.354183 -319.141352) (xy 438.377309 -319.189373) (xy 438.393019 -319.240303) (xy 438.400962 -319.293007)
			(xy 438.40146 -319.319656) (xy 438.400962 -319.346305) (xy 438.393019 -319.399009) (xy 438.377309 -319.449939)
			(xy 438.354183 -319.49796) (xy 438.324159 -319.541997) (xy 438.287907 -319.581068) (xy 438.246236 -319.614299)
			(xy 438.200078 -319.640948) (xy 438.150464 -319.66042) (xy 438.098502 -319.67228) (xy 438.045352 -319.676264)
			(xy 437.992202 -319.67228) (xy 437.94024 -319.66042) (xy 437.890626 -319.640948) (xy 437.844468 -319.614299)
			(xy 437.802797 -319.581068) (xy 437.766545 -319.541997) (xy 437.736521 -319.49796) (xy 437.713395 -319.449939)
			(xy 437.697685 -319.399009) (xy 437.689742 -319.346305) (xy 430.929534 -319.346305) (xy 430.925419 -319.373609)
			(xy 430.909709 -319.424539) (xy 430.886583 -319.47256) (xy 430.856559 -319.516597) (xy 430.820307 -319.555668)
			(xy 430.778636 -319.588899) (xy 430.732478 -319.615548) (xy 430.682864 -319.63502) (xy 430.630902 -319.64688)
			(xy 430.577752 -319.650864) (xy 430.524602 -319.64688) (xy 430.47264 -319.63502) (xy 430.423026 -319.615548)
			(xy 430.376868 -319.588899) (xy 430.335197 -319.555668) (xy 430.298945 -319.516597) (xy 430.268921 -319.47256)
			(xy 430.245795 -319.424539) (xy 430.230085 -319.373609) (xy 430.222142 -319.320905) (xy 423.377461 -319.320905)
			(xy 423.393583 -319.344552) (xy 423.416709 -319.392573) (xy 423.432419 -319.443503) (xy 423.440362 -319.496207)
			(xy 423.44086 -319.522856) (xy 423.440362 -319.549505) (xy 423.432419 -319.602209) (xy 423.416709 -319.653139)
			(xy 423.393583 -319.70116) (xy 423.364848 -319.743307) (xy 424.480472 -319.743307) (xy 424.480472 -319.690009)
			(xy 424.488415 -319.637305) (xy 424.504125 -319.586375) (xy 424.527251 -319.538354) (xy 424.557275 -319.494317)
			(xy 424.593527 -319.455246) (xy 424.635198 -319.422015) (xy 424.681356 -319.395366) (xy 424.73097 -319.375894)
			(xy 424.782932 -319.364034) (xy 424.836082 -319.360051) (xy 424.889232 -319.364034) (xy 424.941194 -319.375894)
			(xy 424.990808 -319.395366) (xy 425.036966 -319.422015) (xy 425.078637 -319.455246) (xy 425.114889 -319.494317)
			(xy 425.144913 -319.538354) (xy 425.168039 -319.586375) (xy 425.183749 -319.637305) (xy 425.191692 -319.690009)
			(xy 425.19219 -319.716658) (xy 425.191692 -319.743307) (xy 425.18729 -319.772517) (xy 431.212996 -319.772517)
			(xy 431.212996 -319.719219) (xy 431.220939 -319.666515) (xy 431.236649 -319.615585) (xy 431.259775 -319.567564)
			(xy 431.289799 -319.523527) (xy 431.326051 -319.484456) (xy 431.367722 -319.451225) (xy 431.41388 -319.424576)
			(xy 431.463494 -319.405104) (xy 431.515456 -319.393244) (xy 431.568606 -319.389261) (xy 431.621756 -319.393244)
			(xy 431.673718 -319.405104) (xy 431.723332 -319.424576) (xy 431.76949 -319.451225) (xy 431.811161 -319.484456)
			(xy 431.847413 -319.523527) (xy 431.877437 -319.567564) (xy 431.900563 -319.615585) (xy 431.916273 -319.666515)
			(xy 431.924216 -319.719219) (xy 431.924714 -319.745868) (xy 431.924216 -319.772517) (xy 431.916273 -319.825221)
			(xy 431.900563 -319.876151) (xy 431.877437 -319.924172) (xy 431.847413 -319.968209) (xy 431.811161 -320.00728)
			(xy 431.76949 -320.040511) (xy 431.723332 -320.06716) (xy 431.673718 -320.086632) (xy 431.621756 -320.098492)
			(xy 431.568606 -320.102476) (xy 431.515456 -320.098492) (xy 431.463494 -320.086632) (xy 431.41388 -320.06716)
			(xy 431.367722 -320.040511) (xy 431.326051 -320.00728) (xy 431.289799 -319.968209) (xy 431.259775 -319.924172)
			(xy 431.236649 -319.876151) (xy 431.220939 -319.825221) (xy 431.212996 -319.772517) (xy 425.18729 -319.772517)
			(xy 425.183749 -319.796011) (xy 425.168039 -319.846941) (xy 425.144913 -319.894962) (xy 425.114889 -319.938999)
			(xy 425.078637 -319.97807) (xy 425.036966 -320.011301) (xy 424.990808 -320.03795) (xy 424.941194 -320.057422)
			(xy 424.889232 -320.069282) (xy 424.836082 -320.073266) (xy 424.782932 -320.069282) (xy 424.73097 -320.057422)
			(xy 424.681356 -320.03795) (xy 424.635198 -320.011301) (xy 424.593527 -319.97807) (xy 424.557275 -319.938999)
			(xy 424.527251 -319.894962) (xy 424.504125 -319.846941) (xy 424.488415 -319.796011) (xy 424.480472 -319.743307)
			(xy 423.364848 -319.743307) (xy 423.363559 -319.745197) (xy 423.327307 -319.784268) (xy 423.285636 -319.817499)
			(xy 423.239478 -319.844148) (xy 423.189864 -319.86362) (xy 423.137902 -319.87548) (xy 423.084752 -319.879464)
			(xy 423.031602 -319.87548) (xy 422.97964 -319.86362) (xy 422.930026 -319.844148) (xy 422.883868 -319.817499)
			(xy 422.842197 -319.784268) (xy 422.805945 -319.745197) (xy 422.775921 -319.70116) (xy 422.752795 -319.653139)
			(xy 422.737085 -319.602209) (xy 422.729142 -319.549505) (xy 420.249265 -319.549505) (xy 420.245227 -319.576301)
			(xy 420.229517 -319.627231) (xy 420.206391 -319.675252) (xy 420.176367 -319.719289) (xy 420.140115 -319.75836)
			(xy 420.098444 -319.791591) (xy 420.052286 -319.81824) (xy 420.002672 -319.837712) (xy 419.95071 -319.849572)
			(xy 419.89756 -319.853556) (xy 419.84441 -319.849572) (xy 419.792448 -319.837712) (xy 419.742834 -319.81824)
			(xy 419.696676 -319.791591) (xy 419.655005 -319.75836) (xy 419.618753 -319.719289) (xy 419.588729 -319.675252)
			(xy 419.565603 -319.627231) (xy 419.549893 -319.576301) (xy 419.54195 -319.523597) (xy 417.591052 -319.523597)
			(xy 417.601113 -319.538354) (xy 417.624239 -319.586375) (xy 417.639949 -319.637305) (xy 417.647892 -319.690009)
			(xy 417.64839 -319.716658) (xy 417.647892 -319.743307) (xy 417.639949 -319.796011) (xy 417.624239 -319.846941)
			(xy 417.601113 -319.894962) (xy 417.571089 -319.938999) (xy 417.534837 -319.97807) (xy 417.493166 -320.011301)
			(xy 417.447008 -320.03795) (xy 417.397394 -320.057422) (xy 417.345432 -320.069282) (xy 417.292282 -320.073266)
			(xy 417.239132 -320.069282) (xy 417.18717 -320.057422) (xy 417.137556 -320.03795) (xy 417.091398 -320.011301)
			(xy 417.049727 -319.97807) (xy 417.013475 -319.938999) (xy 416.983451 -319.894962) (xy 416.960325 -319.846941)
			(xy 416.944615 -319.796011) (xy 416.936672 -319.743307) (xy 415.662158 -319.743307) (xy 415.619478 -319.767948)
			(xy 415.569864 -319.78742) (xy 415.517902 -319.79928) (xy 415.464752 -319.803264) (xy 415.411602 -319.79928)
			(xy 415.35964 -319.78742) (xy 415.310026 -319.767948) (xy 415.263868 -319.741299) (xy 415.222197 -319.708068)
			(xy 415.185945 -319.668997) (xy 415.155921 -319.62496) (xy 415.132795 -319.576939) (xy 415.117085 -319.526009)
			(xy 415.109142 -319.473305) (xy 412.242993 -319.473305) (xy 412.262489 -319.494317) (xy 412.292513 -319.538354)
			(xy 412.315639 -319.586375) (xy 412.331349 -319.637305) (xy 412.339292 -319.690009) (xy 412.33979 -319.716658)
			(xy 412.339292 -319.743307) (xy 412.331349 -319.796011) (xy 412.315639 -319.846941) (xy 412.292513 -319.894962)
			(xy 412.262489 -319.938999) (xy 412.226237 -319.97807) (xy 412.184566 -320.011301) (xy 412.138408 -320.03795)
			(xy 412.088794 -320.057422) (xy 412.036832 -320.069282) (xy 411.983682 -320.073266) (xy 411.930532 -320.069282)
			(xy 411.87857 -320.057422) (xy 411.828956 -320.03795) (xy 411.782798 -320.011301) (xy 411.741127 -319.97807)
			(xy 411.704875 -319.938999) (xy 411.674851 -319.894962) (xy 411.651725 -319.846941) (xy 411.636015 -319.796011)
			(xy 411.628072 -319.743307) (xy 409.655878 -319.743307) (xy 409.662693 -319.765908) (xy 409.670305 -319.817555)
			(xy 409.670758 -319.843658) (xy 409.670652 -319.854673) (xy 409.669253 -319.87666) (xy 409.667964 -319.8876)
			(xy 409.666737 -319.900775) (xy 409.670334 -319.92698) (xy 409.680538 -319.951383) (xy 409.696666 -319.972349)
			(xy 409.717635 -319.988472) (xy 409.74204 -319.998671) (xy 409.755086 -320.000884) (xy 409.780342 -320.004837)
			(xy 409.829478 -320.018925) (xy 409.876095 -320.039897) (xy 409.919233 -320.067319) (xy 409.958006 -320.100629)
			(xy 409.991617 -320.139141) (xy 410.019375 -320.182064) (xy 410.040709 -320.228516) (xy 410.05518 -320.277541)
			(xy 410.062492 -320.328132) (xy 410.062934 -320.35369) (xy 410.062436 -320.380339) (xy 410.054493 -320.433043)
			(xy 410.038783 -320.483973) (xy 410.015657 -320.531994) (xy 409.985633 -320.576031) (xy 409.969475 -320.593445)
			(xy 412.29279 -320.593445) (xy 412.29279 -320.540147) (xy 412.300733 -320.487443) (xy 412.316443 -320.436513)
			(xy 412.339569 -320.388492) (xy 412.369593 -320.344455) (xy 412.405845 -320.305384) (xy 412.447516 -320.272153)
			(xy 412.493674 -320.245504) (xy 412.543288 -320.226032) (xy 412.59525 -320.214172) (xy 412.6484 -320.210189)
			(xy 412.70155 -320.214172) (xy 412.753512 -320.226032) (xy 412.803126 -320.245504) (xy 412.849284 -320.272153)
			(xy 412.890955 -320.305384) (xy 412.927207 -320.344455) (xy 412.957231 -320.388492) (xy 412.980357 -320.436513)
			(xy 412.996067 -320.487443) (xy 413.00401 -320.540147) (xy 413.004508 -320.566796) (xy 413.00401 -320.593445)
			(xy 412.996067 -320.646149) (xy 412.980357 -320.697079) (xy 412.957231 -320.7451) (xy 412.927207 -320.789137)
			(xy 412.890955 -320.828208) (xy 412.849284 -320.861439) (xy 412.803126 -320.888088) (xy 412.753512 -320.90756)
			(xy 412.70155 -320.91942) (xy 412.6484 -320.923404) (xy 412.59525 -320.91942) (xy 412.543288 -320.90756)
			(xy 412.493674 -320.888088) (xy 412.447516 -320.861439) (xy 412.405845 -320.828208) (xy 412.369593 -320.789137)
			(xy 412.339569 -320.7451) (xy 412.316443 -320.697079) (xy 412.300733 -320.646149) (xy 412.29279 -320.593445)
			(xy 409.969475 -320.593445) (xy 409.949381 -320.615102) (xy 409.90771 -320.648333) (xy 409.861552 -320.674982)
			(xy 409.811938 -320.694454) (xy 409.759976 -320.706314) (xy 409.706826 -320.710298) (xy 409.653676 -320.706314)
			(xy 409.601714 -320.694454) (xy 409.5521 -320.674982) (xy 409.505942 -320.648333) (xy 409.464271 -320.615102)
			(xy 409.428019 -320.576031) (xy 409.397995 -320.531994) (xy 409.374869 -320.483973) (xy 409.359159 -320.433043)
			(xy 409.351216 -320.380339) (xy 409.350718 -320.35369) (xy 409.350828 -320.342675) (xy 409.352224 -320.320688)
			(xy 409.353512 -320.309748) (xy 409.354712 -320.296571) (xy 409.351125 -320.270366) (xy 409.340929 -320.245962)
			(xy 409.324806 -320.224995) (xy 409.303839 -320.208872) (xy 409.279435 -320.198675) (xy 409.26639 -320.196464)
			(xy 409.241122 -320.19258) (xy 409.191982 -320.178485) (xy 409.145362 -320.157507) (xy 409.102222 -320.130078)
			(xy 409.063448 -320.09676) (xy 409.029838 -320.05824) (xy 409.002083 -320.015308) (xy 408.980752 -319.968849)
			(xy 408.966286 -319.919816) (xy 408.95898 -319.869219) (xy 408.958542 -319.843658) (xy 408.958714 -319.828275)
			(xy 408.961382 -319.797624) (xy 408.963876 -319.782444) (xy 408.965877 -319.767396) (xy 408.962079 -319.737299)
			(xy 408.949615 -319.709642) (xy 408.929581 -319.686862) (xy 408.903743 -319.670966) (xy 408.8892 -319.66662)
			(xy 408.864034 -319.659672) (xy 408.815924 -319.639397) (xy 408.77129 -319.612314) (xy 408.731089 -319.579005)
			(xy 408.696182 -319.540183) (xy 408.667317 -319.49668) (xy 408.645114 -319.449429) (xy 408.630048 -319.399443)
			(xy 408.622441 -319.347792) (xy 408.621992 -319.321688) (xy 406.226772 -319.321688) (xy 406.226772 -319.34658)
			(xy 407.921968 -321.041776) (xy 407.932094 -321.051248) (xy 407.956238 -321.064858) (xy 407.983155 -321.071467)
			(xy 408.010856 -321.070588) (xy 408.037299 -321.062286) (xy 408.060532 -321.047173) (xy 408.07884 -321.026365)
			(xy 408.08529 -321.01409) (xy 408.097906 -320.989176) (xy 408.12972 -320.943283) (xy 408.168317 -320.902927)
			(xy 408.190192 -320.885566) (xy 408.201759 -320.876068) (xy 408.219256 -320.851804) (xy 408.228978 -320.823512)
			(xy 408.230092 -320.793618) (xy 408.222503 -320.764682) (xy 408.20686 -320.739182) (xy 408.196034 -320.728848)
			(xy 408.177497 -320.711873) (xy 408.144906 -320.673608) (xy 408.118019 -320.631141) (xy 408.097371 -320.585316)
			(xy 408.083371 -320.537042) (xy 408.076297 -320.487279) (xy 408.075892 -320.462148) (xy 408.07639 -320.435499)
			(xy 408.084333 -320.382795) (xy 408.100043 -320.331865) (xy 408.123169 -320.283844) (xy 408.153193 -320.239807)
			(xy 408.189445 -320.200736) (xy 408.231116 -320.167505) (xy 408.277274 -320.140856) (xy 408.326888 -320.121384)
			(xy 408.37885 -320.109524) (xy 408.432 -320.105541) (xy 408.48515 -320.109524) (xy 408.537112 -320.121384)
			(xy 408.586726 -320.140856) (xy 408.632884 -320.167505) (xy 408.674555 -320.200736) (xy 408.710807 -320.239807)
			(xy 408.740831 -320.283844) (xy 408.763957 -320.331865) (xy 408.779667 -320.382795) (xy 408.78761 -320.435499)
			(xy 408.788108 -320.462148) (xy 408.787614 -320.489481) (xy 408.77927 -320.543507) (xy 408.76277 -320.595623)
			(xy 408.738501 -320.644607) (xy 408.707034 -320.689308) (xy 408.669106 -320.728677) (xy 408.647646 -320.745612)
			(xy 408.636082 -320.755113) (xy 408.618589 -320.779381) (xy 408.608868 -320.807673) (xy 408.60775 -320.837567)
			(xy 408.615331 -320.866506) (xy 408.630963 -320.892013) (xy 408.641804 -320.90233) (xy 408.660336 -320.919307)
			(xy 408.692914 -320.957576) (xy 408.719789 -321.000044) (xy 408.740425 -321.04587) (xy 408.754413 -321.094142)
			(xy 408.761476 -321.143901) (xy 408.761946 -321.16903) (xy 408.76185 -321.173856) (xy 416.912044 -321.173856)
			(xy 416.91256 -321.146593) (xy 416.920871 -321.092705) (xy 416.937308 -321.040717) (xy 416.961486 -320.991845)
			(xy 416.992838 -320.947235) (xy 417.011358 -320.927222) (xy 417.021278 -320.916226) (xy 417.034853 -320.889921)
			(xy 417.040302 -320.860826) (xy 417.037165 -320.831391) (xy 417.025707 -320.804097) (xy 417.016692 -320.792348)
			(xy 417.00152 -320.773188) (xy 416.976037 -320.731486) (xy 416.956494 -320.686691) (xy 416.943257 -320.639646)
			(xy 416.936577 -320.591232) (xy 416.936174 -320.566796) (xy 416.936672 -320.540147) (xy 416.944615 -320.487443)
			(xy 416.960325 -320.436513) (xy 416.983451 -320.388492) (xy 417.013475 -320.344455) (xy 417.049727 -320.305384)
			(xy 417.091398 -320.272153) (xy 417.137556 -320.245504) (xy 417.18717 -320.226032) (xy 417.239132 -320.214172)
			(xy 417.292282 -320.210189) (xy 417.345432 -320.214172) (xy 417.397394 -320.226032) (xy 417.447008 -320.245504)
			(xy 417.493166 -320.272153) (xy 417.534837 -320.305384) (xy 417.571089 -320.344455) (xy 417.601113 -320.388492)
			(xy 417.624239 -320.436513) (xy 417.639949 -320.487443) (xy 417.647892 -320.540147) (xy 417.64839 -320.566796)
			(xy 417.647897 -320.594059) (xy 417.639579 -320.647948) (xy 417.623136 -320.699937) (xy 417.605059 -320.736468)
			(xy 419.912292 -320.736468) (xy 419.91279 -320.709819) (xy 419.920733 -320.657115) (xy 419.936443 -320.606185)
			(xy 419.959569 -320.558164) (xy 419.989593 -320.514127) (xy 420.025845 -320.475056) (xy 420.067516 -320.441825)
			(xy 420.113674 -320.415176) (xy 420.163288 -320.395704) (xy 420.21525 -320.383844) (xy 420.2684 -320.379861)
			(xy 420.32155 -320.383844) (xy 420.373512 -320.395704) (xy 420.423126 -320.415176) (xy 420.469284 -320.441825)
			(xy 420.510955 -320.475056) (xy 420.547207 -320.514127) (xy 420.576954 -320.557758) (xy 426.695997 -320.557758)
			(xy 426.701477 -320.503878) (xy 426.715053 -320.45145) (xy 426.736411 -320.401682) (xy 426.765059 -320.355721)
			(xy 426.800337 -320.314629) (xy 426.84143 -320.279353) (xy 426.88739 -320.250706) (xy 426.937159 -320.229349)
			(xy 426.989588 -320.215775) (xy 427.043468 -320.210296) (xy 427.097556 -320.21304) (xy 427.150605 -320.223942)
			(xy 427.201392 -320.242751) (xy 427.248744 -320.269034) (xy 427.291571 -320.302184) (xy 427.328884 -320.341437)
			(xy 427.359822 -320.385887) (xy 427.383673 -320.43451) (xy 427.399887 -320.486184) (xy 427.408088 -320.539717)
			(xy 427.408594 -320.566796) (xy 427.408158 -320.591572) (xy 427.407895 -320.593445) (xy 432.024272 -320.593445)
			(xy 432.024272 -320.540147) (xy 432.032215 -320.487443) (xy 432.047925 -320.436513) (xy 432.071051 -320.388492)
			(xy 432.101075 -320.344455) (xy 432.137327 -320.305384) (xy 432.178998 -320.272153) (xy 432.225156 -320.245504)
			(xy 432.27477 -320.226032) (xy 432.326732 -320.214172) (xy 432.379882 -320.210189) (xy 432.433032 -320.214172)
			(xy 432.484994 -320.226032) (xy 432.534608 -320.245504) (xy 432.580766 -320.272153) (xy 432.622437 -320.305384)
			(xy 432.658689 -320.344455) (xy 432.688713 -320.388492) (xy 432.711839 -320.436513) (xy 432.727549 -320.487443)
			(xy 432.735492 -320.540147) (xy 432.73599 -320.566796) (xy 432.735492 -320.593445) (xy 434.98261 -320.593445)
			(xy 434.98261 -320.540147) (xy 434.990553 -320.487443) (xy 435.006263 -320.436513) (xy 435.029389 -320.388492)
			(xy 435.059413 -320.344455) (xy 435.095665 -320.305384) (xy 435.137336 -320.272153) (xy 435.183494 -320.245504)
			(xy 435.233108 -320.226032) (xy 435.28507 -320.214172) (xy 435.33822 -320.210189) (xy 435.39137 -320.214172)
			(xy 435.443332 -320.226032) (xy 435.492946 -320.245504) (xy 435.539104 -320.272153) (xy 435.580775 -320.305384)
			(xy 435.617027 -320.344455) (xy 435.647051 -320.388492) (xy 435.670177 -320.436513) (xy 435.685887 -320.487443)
			(xy 435.69383 -320.540147) (xy 435.694328 -320.566796) (xy 435.69383 -320.593445) (xy 435.685887 -320.646149)
			(xy 435.670177 -320.697079) (xy 435.647051 -320.7451) (xy 435.617027 -320.789137) (xy 435.580775 -320.828208)
			(xy 435.539104 -320.861439) (xy 435.492946 -320.888088) (xy 435.443332 -320.90756) (xy 435.39137 -320.91942)
			(xy 435.33822 -320.923404) (xy 435.28507 -320.91942) (xy 435.233108 -320.90756) (xy 435.183494 -320.888088)
			(xy 435.137336 -320.861439) (xy 435.095665 -320.828208) (xy 435.059413 -320.789137) (xy 435.029389 -320.7451)
			(xy 435.006263 -320.697079) (xy 434.990553 -320.646149) (xy 434.98261 -320.593445) (xy 432.735492 -320.593445)
			(xy 432.727549 -320.646149) (xy 432.711839 -320.697079) (xy 432.688713 -320.7451) (xy 432.658689 -320.789137)
			(xy 432.622437 -320.828208) (xy 432.580766 -320.861439) (xy 432.534608 -320.888088) (xy 432.484994 -320.90756)
			(xy 432.433032 -320.91942) (xy 432.379882 -320.923404) (xy 432.326732 -320.91942) (xy 432.27477 -320.90756)
			(xy 432.225156 -320.888088) (xy 432.178998 -320.861439) (xy 432.137327 -320.828208) (xy 432.101075 -320.789137)
			(xy 432.071051 -320.7451) (xy 432.047925 -320.697079) (xy 432.032215 -320.646149) (xy 432.024272 -320.593445)
			(xy 427.407895 -320.593445) (xy 427.401272 -320.640645) (xy 427.394878 -320.664586) (xy 427.39156 -320.677582)
			(xy 427.391105 -320.704391) (xy 427.397655 -320.730391) (xy 427.410755 -320.753786) (xy 427.429501 -320.772956)
			(xy 427.452596 -320.786578) (xy 427.478444 -320.793708) (xy 427.505256 -320.793854) (xy 427.518322 -320.790824)
			(xy 427.540589 -320.78534) (xy 427.586071 -320.779479) (xy 427.609 -320.77914) (xy 427.637001 -320.779701)
			(xy 427.692312 -320.788461) (xy 427.745573 -320.805765) (xy 427.795471 -320.831188) (xy 427.840778 -320.864103)
			(xy 427.880379 -320.903701) (xy 427.913297 -320.949005) (xy 427.9265 -320.973704) (xy 427.933431 -320.986317)
			(xy 427.953124 -321.007293) (xy 427.977879 -321.021954) (xy 428.005739 -321.029141) (xy 428.034497 -321.028283)
			(xy 428.061879 -321.01945) (xy 428.074074 -321.011804) (xy 428.096329 -320.99725) (xy 428.144249 -320.974205)
			(xy 428.195062 -320.958537) (xy 428.24764 -320.950595) (xy 428.274226 -320.950082) (xy 428.300873 -320.950601)
			(xy 428.353572 -320.958548) (xy 428.404498 -320.97426) (xy 428.452514 -320.997386) (xy 428.496547 -321.02741)
			(xy 428.531988 -321.060297) (xy 431.19801 -321.060297) (xy 431.19801 -321.006999) (xy 431.205953 -320.954295)
			(xy 431.221663 -320.903365) (xy 431.244789 -320.855344) (xy 431.274813 -320.811307) (xy 431.311065 -320.772236)
			(xy 431.352736 -320.739005) (xy 431.398894 -320.712356) (xy 431.448508 -320.692884) (xy 431.50047 -320.681024)
			(xy 431.55362 -320.677041) (xy 431.60677 -320.681024) (xy 431.658732 -320.692884) (xy 431.708346 -320.712356)
			(xy 431.754504 -320.739005) (xy 431.796175 -320.772236) (xy 431.832427 -320.811307) (xy 431.862451 -320.855344)
			(xy 431.885577 -320.903365) (xy 431.901287 -320.954295) (xy 431.90923 -321.006999) (xy 431.909728 -321.033648)
			(xy 431.90923 -321.060297) (xy 431.901287 -321.113001) (xy 431.885577 -321.163931) (xy 431.862451 -321.211952)
			(xy 431.832427 -321.255989) (xy 431.796175 -321.29506) (xy 431.754504 -321.328291) (xy 431.708346 -321.35494)
			(xy 431.658732 -321.374412) (xy 431.60677 -321.386272) (xy 431.55362 -321.390256) (xy 431.50047 -321.386272)
			(xy 431.448508 -321.374412) (xy 431.398894 -321.35494) (xy 431.352736 -321.328291) (xy 431.311065 -321.29506)
			(xy 431.274813 -321.255989) (xy 431.244789 -321.211952) (xy 431.221663 -321.163931) (xy 431.205953 -321.113001)
			(xy 431.19801 -321.060297) (xy 428.531988 -321.060297) (xy 428.535613 -321.063661) (xy 428.56884 -321.10533)
			(xy 428.595486 -321.151485) (xy 428.614956 -321.201096) (xy 428.626815 -321.253054) (xy 428.630798 -321.3062)
			(xy 428.626815 -321.359346) (xy 428.614956 -321.411304) (xy 428.602388 -321.443329) (xy 432.015636 -321.443329)
			(xy 432.015636 -321.390031) (xy 432.023579 -321.337327) (xy 432.039289 -321.286397) (xy 432.062415 -321.238376)
			(xy 432.092439 -321.194339) (xy 432.128691 -321.155268) (xy 432.170362 -321.122037) (xy 432.21652 -321.095388)
			(xy 432.266134 -321.075916) (xy 432.318096 -321.064056) (xy 432.371246 -321.060073) (xy 432.424396 -321.064056)
			(xy 432.476358 -321.075916) (xy 432.525972 -321.095388) (xy 432.57213 -321.122037) (xy 432.613801 -321.155268)
			(xy 432.650053 -321.194339) (xy 432.680077 -321.238376) (xy 432.703203 -321.286397) (xy 432.718913 -321.337327)
			(xy 432.726856 -321.390031) (xy 432.727354 -321.41668) (xy 432.726856 -321.443329) (xy 435.467496 -321.443329)
			(xy 435.467496 -321.390031) (xy 435.475439 -321.337327) (xy 435.491149 -321.286397) (xy 435.514275 -321.238376)
			(xy 435.544299 -321.194339) (xy 435.580551 -321.155268) (xy 435.622222 -321.122037) (xy 435.66838 -321.095388)
			(xy 435.717994 -321.075916) (xy 435.769956 -321.064056) (xy 435.823106 -321.060073) (xy 435.876256 -321.064056)
			(xy 435.928218 -321.075916) (xy 435.977832 -321.095388) (xy 436.02399 -321.122037) (xy 436.065661 -321.155268)
			(xy 436.101913 -321.194339) (xy 436.131937 -321.238376) (xy 436.155063 -321.286397) (xy 436.170773 -321.337327)
			(xy 436.178716 -321.390031) (xy 436.179214 -321.41668) (xy 436.178716 -321.443329) (xy 436.170773 -321.496033)
			(xy 436.155063 -321.546963) (xy 436.131937 -321.594984) (xy 436.101913 -321.639021) (xy 436.065661 -321.678092)
			(xy 436.02399 -321.711323) (xy 435.977832 -321.737972) (xy 435.928218 -321.757444) (xy 435.876256 -321.769304)
			(xy 435.823106 -321.773288) (xy 435.769956 -321.769304) (xy 435.717994 -321.757444) (xy 435.66838 -321.737972)
			(xy 435.622222 -321.711323) (xy 435.580551 -321.678092) (xy 435.544299 -321.639021) (xy 435.514275 -321.594984)
			(xy 435.491149 -321.546963) (xy 435.475439 -321.496033) (xy 435.467496 -321.443329) (xy 432.726856 -321.443329)
			(xy 432.718913 -321.496033) (xy 432.703203 -321.546963) (xy 432.680077 -321.594984) (xy 432.650053 -321.639021)
			(xy 432.613801 -321.678092) (xy 432.57213 -321.711323) (xy 432.525972 -321.737972) (xy 432.476358 -321.757444)
			(xy 432.424396 -321.769304) (xy 432.371246 -321.773288) (xy 432.318096 -321.769304) (xy 432.266134 -321.757444)
			(xy 432.21652 -321.737972) (xy 432.170362 -321.711323) (xy 432.128691 -321.678092) (xy 432.092439 -321.639021)
			(xy 432.062415 -321.594984) (xy 432.039289 -321.546963) (xy 432.023579 -321.496033) (xy 432.015636 -321.443329)
			(xy 428.602388 -321.443329) (xy 428.595486 -321.460915) (xy 428.56884 -321.50707) (xy 428.535613 -321.548739)
			(xy 428.496547 -321.58499) (xy 428.452514 -321.615014) (xy 428.404498 -321.63814) (xy 428.353572 -321.653852)
			(xy 428.300873 -321.661799) (xy 428.274226 -321.662298) (xy 428.246224 -321.661777) (xy 428.190912 -321.653007)
			(xy 428.137651 -321.635693) (xy 428.087754 -321.610263) (xy 428.042448 -321.577343) (xy 428.002848 -321.537741)
			(xy 427.969929 -321.492434) (xy 427.956726 -321.467734) (xy 427.949755 -321.455144) (xy 427.930074 -321.434164)
			(xy 427.905328 -321.419498) (xy 427.877475 -321.412307) (xy 427.848722 -321.41316) (xy 427.821345 -321.42199)
			(xy 427.809152 -321.429634) (xy 427.786886 -321.44417) (xy 427.73897 -321.467221) (xy 427.68816 -321.482894)
			(xy 427.635586 -321.490841) (xy 427.609 -321.491356) (xy 427.581019 -321.490759) (xy 427.525747 -321.482006)
			(xy 427.472524 -321.464714) (xy 427.422661 -321.43931) (xy 427.377385 -321.406419) (xy 427.337812 -321.366851)
			(xy 427.304915 -321.32158) (xy 427.279504 -321.271721) (xy 427.262206 -321.2185) (xy 427.253445 -321.163229)
			(xy 427.252892 -321.135248) (xy 427.253334 -321.110472) (xy 427.260216 -321.061399) (xy 427.266608 -321.037458)
			(xy 427.269896 -321.024454) (xy 427.27036 -320.997647) (xy 427.263818 -320.971646) (xy 427.250723 -320.94825)
			(xy 427.23198 -320.929078) (xy 427.208886 -320.915457) (xy 427.18304 -320.908329) (xy 427.156229 -320.908188)
			(xy 427.143164 -320.91122) (xy 427.120898 -320.916708) (xy 427.075416 -320.922566) (xy 427.052486 -320.922904)
			(xy 427.025407 -320.922387) (xy 426.971874 -320.914184) (xy 426.920201 -320.89797) (xy 426.871579 -320.874117)
			(xy 426.827129 -320.843177) (xy 426.787877 -320.805863) (xy 426.754728 -320.763036) (xy 426.728447 -320.715682)
			(xy 426.709639 -320.664895) (xy 426.698738 -320.611846) (xy 426.695997 -320.557758) (xy 420.576954 -320.557758)
			(xy 420.577231 -320.558164) (xy 420.600357 -320.606185) (xy 420.616067 -320.657115) (xy 420.62401 -320.709819)
			(xy 420.624508 -320.736468) (xy 420.624216 -320.757824) (xy 420.619118 -320.800231) (xy 420.614348 -320.82105)
			(xy 420.611405 -320.835322) (xy 420.612834 -320.864414) (xy 420.6224 -320.891926) (xy 420.639329 -320.915628)
			(xy 420.662249 -320.933602) (xy 420.689305 -320.944391) (xy 420.703756 -320.946272) (xy 420.729985 -320.949105)
			(xy 420.781257 -320.96153) (xy 420.830133 -320.981386) (xy 420.875543 -321.008238) (xy 420.893355 -321.022705)
			(xy 424.380142 -321.022705) (xy 424.380142 -320.969407) (xy 424.388085 -320.916703) (xy 424.403795 -320.865773)
			(xy 424.426921 -320.817752) (xy 424.456945 -320.773715) (xy 424.493197 -320.734644) (xy 424.534868 -320.701413)
			(xy 424.581026 -320.674764) (xy 424.63064 -320.655292) (xy 424.682602 -320.643432) (xy 424.735752 -320.639449)
			(xy 424.788902 -320.643432) (xy 424.840864 -320.655292) (xy 424.890478 -320.674764) (xy 424.936636 -320.701413)
			(xy 424.978307 -320.734644) (xy 425.014559 -320.773715) (xy 425.044583 -320.817752) (xy 425.067709 -320.865773)
			(xy 425.083419 -320.916703) (xy 425.091362 -320.969407) (xy 425.09186 -320.996056) (xy 425.091362 -321.022705)
			(xy 425.083419 -321.075409) (xy 425.067709 -321.126339) (xy 425.044583 -321.17436) (xy 425.014559 -321.218397)
			(xy 424.978307 -321.257468) (xy 424.936636 -321.290699) (xy 424.890478 -321.317348) (xy 424.840864 -321.33682)
			(xy 424.788902 -321.34868) (xy 424.735752 -321.352664) (xy 424.682602 -321.34868) (xy 424.63064 -321.33682)
			(xy 424.581026 -321.317348) (xy 424.534868 -321.290699) (xy 424.493197 -321.257468) (xy 424.456945 -321.218397)
			(xy 424.426921 -321.17436) (xy 424.403795 -321.126339) (xy 424.388085 -321.075409) (xy 424.380142 -321.022705)
			(xy 420.893355 -321.022705) (xy 420.916493 -321.041498) (xy 420.952085 -321.080438) (xy 420.981541 -321.124205)
			(xy 421.004214 -321.17184) (xy 421.019608 -321.222299) (xy 421.027386 -321.274478) (xy 421.02786 -321.300856)
			(xy 421.027362 -321.327505) (xy 421.019419 -321.380209) (xy 421.003709 -321.431139) (xy 420.980583 -321.47916)
			(xy 420.950559 -321.523197) (xy 420.914307 -321.562268) (xy 420.872636 -321.595499) (xy 420.826478 -321.622148)
			(xy 420.776864 -321.64162) (xy 420.724902 -321.65348) (xy 420.671752 -321.657464) (xy 420.618602 -321.65348)
			(xy 420.56664 -321.64162) (xy 420.517026 -321.622148) (xy 420.470868 -321.595499) (xy 420.429197 -321.562268)
			(xy 420.392945 -321.523197) (xy 420.362921 -321.47916) (xy 420.339795 -321.431139) (xy 420.324085 -321.380209)
			(xy 420.316142 -321.327505) (xy 420.315644 -321.300856) (xy 420.315939 -321.2795) (xy 420.321035 -321.237093)
			(xy 420.325804 -321.216274) (xy 420.328815 -321.202009) (xy 420.327392 -321.172896) (xy 420.317821 -321.145365)
			(xy 420.300879 -321.121647) (xy 420.27794 -321.103665) (xy 420.250862 -321.092877) (xy 420.236396 -321.091052)
			(xy 420.210175 -321.088152) (xy 420.158906 -321.075736) (xy 420.110032 -321.055888) (xy 420.064622 -321.029044)
			(xy 420.023672 -320.995791) (xy 419.988079 -320.956859) (xy 419.958622 -320.913099) (xy 419.935946 -320.865471)
			(xy 419.920549 -320.815017) (xy 419.912768 -320.762843) (xy 419.912292 -320.736468) (xy 417.605059 -320.736468)
			(xy 417.598953 -320.748808) (xy 417.567598 -320.793417) (xy 417.549076 -320.81343) (xy 417.5392 -320.824463)
			(xy 417.525616 -320.850754) (xy 417.520157 -320.87984) (xy 417.523283 -320.909267) (xy 417.534731 -320.936557)
			(xy 417.543742 -320.948304) (xy 417.558896 -320.967477) (xy 417.584382 -321.009176) (xy 417.603928 -321.053967)
			(xy 417.617168 -321.10101) (xy 417.623854 -321.149421) (xy 417.62426 -321.173856) (xy 417.623762 -321.200505)
			(xy 417.615819 -321.253209) (xy 417.600109 -321.304139) (xy 417.576983 -321.35216) (xy 417.546959 -321.396197)
			(xy 417.510707 -321.435268) (xy 417.469036 -321.468499) (xy 417.422878 -321.495148) (xy 417.373264 -321.51462)
			(xy 417.321302 -321.52648) (xy 417.268152 -321.530464) (xy 417.215002 -321.52648) (xy 417.16304 -321.51462)
			(xy 417.113426 -321.495148) (xy 417.067268 -321.468499) (xy 417.025597 -321.435268) (xy 416.989345 -321.396197)
			(xy 416.959321 -321.35216) (xy 416.936195 -321.304139) (xy 416.920485 -321.253209) (xy 416.912542 -321.200505)
			(xy 416.912044 -321.173856) (xy 408.76185 -321.173856) (xy 408.761381 -321.197546) (xy 408.752284 -321.253849)
			(xy 408.734329 -321.307981) (xy 408.707974 -321.358559) (xy 408.673893 -321.404289) (xy 408.632959 -321.444001)
			(xy 408.586217 -321.47668) (xy 408.560778 -321.489578) (xy 408.548515 -321.496033) (xy 408.527744 -321.51436)
			(xy 408.512659 -321.537593) (xy 408.50437 -321.564024) (xy 408.503485 -321.59171) (xy 408.51007 -321.618616)
			(xy 408.523641 -321.642765) (xy 408.533092 -321.6529) (xy 408.665405 -321.785213) (xy 412.579556 -321.785213)
			(xy 412.579556 -321.731915) (xy 412.587499 -321.679211) (xy 412.603209 -321.628281) (xy 412.626335 -321.58026)
			(xy 412.656359 -321.536223) (xy 412.692611 -321.497152) (xy 412.734282 -321.463921) (xy 412.78044 -321.437272)
			(xy 412.830054 -321.4178) (xy 412.882016 -321.40594) (xy 412.935166 -321.401957) (xy 412.988316 -321.40594)
			(xy 413.040278 -321.4178) (xy 413.089892 -321.437272) (xy 413.13605 -321.463921) (xy 413.177721 -321.497152)
			(xy 413.213973 -321.536223) (xy 413.243997 -321.58026) (xy 413.267123 -321.628281) (xy 413.282833 -321.679211)
			(xy 413.290776 -321.731915) (xy 413.291274 -321.758564) (xy 413.290776 -321.785213) (xy 413.282833 -321.837917)
			(xy 413.267123 -321.888847) (xy 413.243997 -321.936868) (xy 413.213973 -321.980905) (xy 413.177721 -322.019976)
			(xy 413.13605 -322.053207) (xy 413.089892 -322.079856) (xy 413.040278 -322.099328) (xy 412.988316 -322.111188)
			(xy 412.935166 -322.115172) (xy 412.882016 -322.111188) (xy 412.830054 -322.099328) (xy 412.78044 -322.079856)
			(xy 412.734282 -322.053207) (xy 412.692611 -322.019976) (xy 412.656359 -321.980905) (xy 412.626335 -321.936868)
			(xy 412.603209 -321.888847) (xy 412.587499 -321.837917) (xy 412.579556 -321.785213) (xy 408.665405 -321.785213)
			(xy 409.249941 -322.369749) (xy 415.741388 -322.369749) (xy 415.741388 -322.315251) (xy 415.749143 -322.261309)
			(xy 415.764496 -322.209019) (xy 415.787133 -322.159446) (xy 415.816595 -322.113599) (xy 415.852281 -322.072411)
			(xy 415.893465 -322.03672) (xy 415.939309 -322.007254) (xy 415.988879 -321.984611) (xy 416.041168 -321.969252)
			(xy 416.095109 -321.961491) (xy 416.122358 -321.961002) (xy 416.149857 -321.961476) (xy 416.204285 -321.969388)
			(xy 416.257014 -321.985025) (xy 416.306955 -322.008064) (xy 416.353075 -322.038029) (xy 416.394419 -322.0743)
			(xy 416.430133 -322.116126) (xy 416.459478 -322.162642) (xy 416.4711 -322.18757) (xy 416.476995 -322.199647)
			(xy 416.493947 -322.220485) (xy 416.515741 -322.236189) (xy 416.540873 -322.245674) (xy 416.567608 -322.248287)
			(xy 416.594101 -322.243847) (xy 416.606482 -322.238624) (xy 416.63165 -322.227563) (xy 416.684358 -322.211948)
			(xy 416.738762 -322.204055) (xy 416.766248 -322.203572) (xy 416.793496 -322.204102) (xy 416.847435 -322.211863)
			(xy 416.899721 -322.227222) (xy 416.94929 -322.249864) (xy 416.995132 -322.27933) (xy 417.036314 -322.31502)
			(xy 417.071999 -322.356207) (xy 417.101459 -322.402052) (xy 417.124095 -322.451624) (xy 417.139447 -322.503912)
			(xy 417.147202 -322.557852) (xy 417.147202 -322.612348) (xy 417.139447 -322.666288) (xy 417.124095 -322.718576)
			(xy 417.101459 -322.768148) (xy 417.071999 -322.813993) (xy 417.036314 -322.85518) (xy 416.995132 -322.89087)
			(xy 416.94929 -322.920336) (xy 416.899721 -322.942978) (xy 416.847435 -322.958337) (xy 416.793496 -322.966098)
			(xy 416.766248 -322.966588) (xy 416.738748 -322.966115) (xy 416.684321 -322.958204) (xy 416.631591 -322.942567)
			(xy 416.58165 -322.919527) (xy 416.53553 -322.889562) (xy 416.494186 -322.853292) (xy 416.458472 -322.811465)
			(xy 416.429128 -322.764948) (xy 416.417506 -322.74002) (xy 416.411719 -322.727884) (xy 416.394745 -322.707041)
			(xy 416.372927 -322.691339) (xy 416.347772 -322.681863) (xy 416.321017 -322.679267) (xy 416.294509 -322.68373)
			(xy 416.282124 -322.688966) (xy 416.256955 -322.700024) (xy 416.204247 -322.715641) (xy 416.149844 -322.723535)
			(xy 416.122358 -322.724018) (xy 416.095109 -322.723509) (xy 416.041168 -322.715748) (xy 415.988879 -322.700389)
			(xy 415.939309 -322.677746) (xy 415.893465 -322.64828) (xy 415.852281 -322.612589) (xy 415.816595 -322.571401)
			(xy 415.787133 -322.525554) (xy 415.764496 -322.475981) (xy 415.749143 -322.423691) (xy 415.741388 -322.369749)
			(xy 409.249941 -322.369749) (xy 410.074618 -323.194426) (xy 410.084657 -323.203846) (xy 410.108589 -323.217431)
			(xy 410.135279 -323.224136) (xy 410.16279 -323.223475) (xy 410.189126 -323.215494) (xy 410.212377 -323.200774)
			(xy 410.221938 -323.19087) (xy 410.238901 -323.172715) (xy 410.27699 -323.14081) (xy 410.319143 -323.114509)
			(xy 410.364542 -323.094321) (xy 410.412307 -323.080638) (xy 410.461509 -323.073726) (xy 410.486352 -323.073268)
			(xy 410.512759 -323.073751) (xy 410.564994 -323.081559) (xy 410.615503 -323.096996) (xy 410.663178 -323.119722)
			(xy 410.706974 -323.149241) (xy 410.74593 -323.184904) (xy 410.762958 -323.205094) (xy 410.772895 -323.216487)
			(xy 410.797948 -323.233378) (xy 410.826844 -323.242209) (xy 410.85706 -323.242209) (xy 410.885956 -323.233378)
			(xy 410.911009 -323.216487) (xy 410.920946 -323.205094) (xy 410.937953 -323.184887) (xy 410.976916 -323.149233)
			(xy 411.020718 -323.119725) (xy 411.068397 -323.09701) (xy 411.118909 -323.081586) (xy 411.171145 -323.073793)
			(xy 411.197552 -323.073268) (xy 411.224207 -323.073738) (xy 411.276923 -323.081677) (xy 411.327867 -323.097385)
			(xy 411.3759 -323.120511) (xy 411.41995 -323.150538) (xy 411.459032 -323.186796) (xy 411.492273 -323.228473)
			(xy 411.51893 -323.27464) (xy 411.538408 -323.324265) (xy 411.550272 -323.376239) (xy 411.554256 -323.4294)
			(xy 413.609568 -323.4294) (xy 413.613551 -323.376251) (xy 413.62541 -323.32429) (xy 413.64488 -323.274676)
			(xy 413.671527 -323.228517) (xy 413.704755 -323.186846) (xy 413.743822 -323.150591) (xy 413.787856 -323.120564)
			(xy 413.835874 -323.097434) (xy 413.886802 -323.081719) (xy 413.939503 -323.073769) (xy 413.966152 -323.073268)
			(xy 413.992559 -323.07379) (xy 414.044795 -323.081584) (xy 414.095307 -323.097008) (xy 414.142987 -323.119723)
			(xy 414.186788 -323.149232) (xy 414.225751 -323.184887) (xy 414.242758 -323.205094) (xy 414.252695 -323.216487)
			(xy 414.277748 -323.233378) (xy 414.306644 -323.242209) (xy 414.33686 -323.242209) (xy 414.365756 -323.233378)
			(xy 414.390809 -323.216487) (xy 414.400746 -323.205094) (xy 414.417772 -323.184902) (xy 414.456729 -323.149239)
			(xy 414.500525 -323.119721) (xy 414.5482 -323.096994) (xy 414.59871 -323.081558) (xy 414.650944 -323.073751)
			(xy 414.677352 -323.073268) (xy 414.704004 -323.073786) (xy 414.756713 -323.081724) (xy 414.807649 -323.09743)
			(xy 414.855676 -323.120552) (xy 414.89972 -323.150576) (xy 414.938797 -323.186828) (xy 414.972033 -323.2285)
			(xy 414.998687 -323.274661) (xy 415.018162 -323.324279) (xy 415.030024 -323.376246) (xy 415.034008 -323.4294)
			(xy 417.673568 -323.4294) (xy 417.677551 -323.376251) (xy 417.68941 -323.32429) (xy 417.70888 -323.274676)
			(xy 417.735527 -323.228517) (xy 417.768755 -323.186846) (xy 417.807822 -323.150591) (xy 417.851856 -323.120564)
			(xy 417.899874 -323.097434) (xy 417.950802 -323.081719) (xy 418.003503 -323.073769) (xy 418.030152 -323.073268)
			(xy 418.056559 -323.07379) (xy 418.108795 -323.081584) (xy 418.159307 -323.097008) (xy 418.206987 -323.119723)
			(xy 418.250788 -323.149232) (xy 418.289751 -323.184887) (xy 418.306758 -323.205094) (xy 418.316695 -323.216487)
			(xy 418.341748 -323.233378) (xy 418.370644 -323.242209) (xy 418.40086 -323.242209) (xy 418.429756 -323.233378)
			(xy 418.454809 -323.216487) (xy 418.464746 -323.205094) (xy 418.481772 -323.184902) (xy 418.520729 -323.149239)
			(xy 418.564525 -323.119721) (xy 418.6122 -323.096994) (xy 418.66271 -323.081558) (xy 418.714944 -323.073751)
			(xy 418.741352 -323.073268) (xy 418.768004 -323.073786) (xy 418.820713 -323.081724) (xy 418.871649 -323.09743)
			(xy 418.919676 -323.120552) (xy 418.96372 -323.150576) (xy 419.002797 -323.186828) (xy 419.036033 -323.2285)
			(xy 419.062687 -323.274661) (xy 419.082162 -323.324279) (xy 419.094024 -323.376246) (xy 419.098008 -323.4294)
			(xy 421.153368 -323.4294) (xy 421.157351 -323.376251) (xy 421.16921 -323.32429) (xy 421.18868 -323.274676)
			(xy 421.215327 -323.228517) (xy 421.248555 -323.186846) (xy 421.287622 -323.150591) (xy 421.331656 -323.120564)
			(xy 421.379674 -323.097434) (xy 421.430602 -323.081719) (xy 421.483303 -323.073769) (xy 421.509952 -323.073268)
			(xy 421.536359 -323.07379) (xy 421.588595 -323.081584) (xy 421.639107 -323.097008) (xy 421.686787 -323.119723)
			(xy 421.730588 -323.149232) (xy 421.769551 -323.184887) (xy 421.786558 -323.205094) (xy 421.796495 -323.216487)
			(xy 421.821548 -323.233378) (xy 421.850444 -323.242209) (xy 421.88066 -323.242209) (xy 421.909556 -323.233378)
			(xy 421.934609 -323.216487) (xy 421.944546 -323.205094) (xy 421.961572 -323.184902) (xy 422.000529 -323.149239)
			(xy 422.044325 -323.119721) (xy 422.092 -323.096994) (xy 422.14251 -323.081558) (xy 422.194744 -323.073751)
			(xy 422.221152 -323.073268) (xy 422.247804 -323.073786) (xy 422.300513 -323.081724) (xy 422.351449 -323.09743)
			(xy 422.399476 -323.120552) (xy 422.44352 -323.150576) (xy 422.482597 -323.186828) (xy 422.515833 -323.2285)
			(xy 422.542487 -323.274661) (xy 422.561962 -323.324279) (xy 422.573824 -323.376246) (xy 422.577808 -323.4294)
			(xy 425.217368 -323.4294) (xy 425.221351 -323.376251) (xy 425.23321 -323.32429) (xy 425.25268 -323.274676)
			(xy 425.279327 -323.228517) (xy 425.312555 -323.186846) (xy 425.351622 -323.150591) (xy 425.395656 -323.120564)
			(xy 425.443674 -323.097434) (xy 425.494602 -323.081719) (xy 425.547303 -323.073769) (xy 425.573952 -323.073268)
			(xy 425.600359 -323.07379) (xy 425.652595 -323.081584) (xy 425.703107 -323.097008) (xy 425.750787 -323.119723)
			(xy 425.794588 -323.149232) (xy 425.833551 -323.184887) (xy 425.850558 -323.205094) (xy 425.860495 -323.216487)
			(xy 425.885548 -323.233378) (xy 425.914444 -323.242209) (xy 425.94466 -323.242209) (xy 425.973556 -323.233378)
			(xy 425.998609 -323.216487) (xy 426.008546 -323.205094) (xy 426.025572 -323.184902) (xy 426.064529 -323.149239)
			(xy 426.108325 -323.119721) (xy 426.156 -323.096994) (xy 426.20651 -323.081558) (xy 426.258744 -323.073751)
			(xy 426.285152 -323.073268) (xy 426.311804 -323.073786) (xy 426.364513 -323.081724) (xy 426.415449 -323.09743)
			(xy 426.463476 -323.120552) (xy 426.50752 -323.150576) (xy 426.546597 -323.186828) (xy 426.579833 -323.2285)
			(xy 426.606487 -323.274661) (xy 426.625962 -323.324279) (xy 426.637824 -323.376246) (xy 426.641808 -323.4294)
			(xy 428.697168 -323.4294) (xy 428.701151 -323.376251) (xy 428.71301 -323.32429) (xy 428.73248 -323.274676)
			(xy 428.759127 -323.228517) (xy 428.792355 -323.186846) (xy 428.831422 -323.150591) (xy 428.875456 -323.120564)
			(xy 428.923474 -323.097434) (xy 428.974402 -323.081719) (xy 429.027103 -323.073769) (xy 429.053752 -323.073268)
			(xy 429.080159 -323.07379) (xy 429.132395 -323.081584) (xy 429.182907 -323.097008) (xy 429.230587 -323.119723)
			(xy 429.274388 -323.149232) (xy 429.313351 -323.184887) (xy 429.330358 -323.205094) (xy 429.340295 -323.216487)
			(xy 429.365348 -323.233378) (xy 429.394244 -323.242209) (xy 429.42446 -323.242209) (xy 429.453356 -323.233378)
			(xy 429.478409 -323.216487) (xy 429.488346 -323.205094) (xy 429.505372 -323.184902) (xy 429.544329 -323.149239)
			(xy 429.588125 -323.119721) (xy 429.6358 -323.096994) (xy 429.68631 -323.081558) (xy 429.738544 -323.073751)
			(xy 429.764952 -323.073268) (xy 429.791604 -323.073786) (xy 429.844313 -323.081724) (xy 429.895249 -323.09743)
			(xy 429.943276 -323.120552) (xy 429.98732 -323.150576) (xy 430.026397 -323.186828) (xy 430.059633 -323.2285)
			(xy 430.086287 -323.274661) (xy 430.105762 -323.324279) (xy 430.117624 -323.376246) (xy 430.121608 -323.4294)
			(xy 432.761168 -323.4294) (xy 432.765151 -323.376251) (xy 432.77701 -323.32429) (xy 432.79648 -323.274676)
			(xy 432.823127 -323.228517) (xy 432.856355 -323.186846) (xy 432.895422 -323.150591) (xy 432.939456 -323.120564)
			(xy 432.987474 -323.097434) (xy 433.038402 -323.081719) (xy 433.091103 -323.073769) (xy 433.117752 -323.073268)
			(xy 433.144314 -323.073727) (xy 433.196845 -323.081638) (xy 433.24762 -323.097261) (xy 433.295512 -323.12025)
			(xy 433.339459 -323.150096) (xy 433.359306 -323.167756) (xy 433.370108 -323.177123) (xy 433.395674 -323.189907)
			(xy 433.423782 -323.195102) (xy 433.452228 -323.192301) (xy 433.478783 -323.181724) (xy 433.49037 -323.173344)
			(xy 433.513938 -323.155803) (xy 433.565646 -323.127918) (xy 433.62123 -323.1089) (xy 433.679182 -323.099265)
			(xy 433.708556 -323.098668) (xy 433.735208 -323.099186) (xy 433.787916 -323.107125) (xy 433.838852 -323.122831)
			(xy 433.886879 -323.145954) (xy 433.930922 -323.175977) (xy 433.969998 -323.21223) (xy 434.003234 -323.253902)
			(xy 434.029887 -323.300062) (xy 434.049362 -323.34968) (xy 434.061224 -323.401646) (xy 434.065208 -323.4548)
			(xy 434.061224 -323.507954) (xy 434.049362 -323.55992) (xy 434.029887 -323.609538) (xy 434.003234 -323.655698)
			(xy 433.969998 -323.69737) (xy 433.930922 -323.733623) (xy 433.886879 -323.763646) (xy 433.838852 -323.786769)
			(xy 433.787916 -323.802475) (xy 433.735208 -323.810414) (xy 433.708556 -323.810884) (xy 433.681995 -323.810406)
			(xy 433.629465 -323.802498) (xy 433.578691 -323.786878) (xy 433.530799 -323.763894) (xy 433.48685 -323.734053)
			(xy 433.467002 -323.716396) (xy 433.456194 -323.707037) (xy 433.430629 -323.694259) (xy 433.402524 -323.689065)
			(xy 433.374081 -323.691863) (xy 433.347526 -323.702432) (xy 433.335938 -323.710808) (xy 433.312372 -323.728352)
			(xy 433.260663 -323.756235) (xy 433.205078 -323.775251) (xy 433.147126 -323.784886) (xy 433.117752 -323.785484)
			(xy 433.091103 -323.785031) (xy 433.038402 -323.777081) (xy 432.987474 -323.761366) (xy 432.939456 -323.738236)
			(xy 432.895422 -323.708209) (xy 432.856355 -323.671954) (xy 432.823127 -323.630283) (xy 432.79648 -323.584124)
			(xy 432.77701 -323.53451) (xy 432.765151 -323.482549) (xy 432.761168 -323.4294) (xy 430.121608 -323.4294)
			(xy 430.117624 -323.482554) (xy 430.105762 -323.534521) (xy 430.086287 -323.584139) (xy 430.059633 -323.6303)
			(xy 430.026397 -323.671972) (xy 429.98732 -323.708224) (xy 429.943276 -323.738248) (xy 429.895249 -323.76137)
			(xy 429.844313 -323.777076) (xy 429.791604 -323.785014) (xy 429.764952 -323.785484) (xy 429.738544 -323.784977)
			(xy 429.686307 -323.777182) (xy 429.635794 -323.761757) (xy 429.588114 -323.739038) (xy 429.544313 -323.709526)
			(xy 429.505352 -323.673867) (xy 429.488346 -323.653658) (xy 429.478409 -323.642265) (xy 429.453356 -323.625374)
			(xy 429.42446 -323.616543) (xy 429.394244 -323.616543) (xy 429.365348 -323.625374) (xy 429.340295 -323.642265)
			(xy 429.330358 -323.653658) (xy 429.313318 -323.673838) (xy 429.274366 -323.709504) (xy 429.230573 -323.739025)
			(xy 429.1829 -323.761754) (xy 429.132392 -323.777192) (xy 429.080159 -323.785) (xy 429.053752 -323.785484)
			(xy 429.027103 -323.785031) (xy 428.974402 -323.777081) (xy 428.923474 -323.761366) (xy 428.875456 -323.738236)
			(xy 428.831422 -323.708209) (xy 428.792355 -323.671954) (xy 428.759127 -323.630283) (xy 428.73248 -323.584124)
			(xy 428.71301 -323.53451) (xy 428.701151 -323.482549) (xy 428.697168 -323.4294) (xy 426.641808 -323.4294)
			(xy 426.637824 -323.482554) (xy 426.625962 -323.534521) (xy 426.606487 -323.584139) (xy 426.579833 -323.6303)
			(xy 426.546597 -323.671972) (xy 426.50752 -323.708224) (xy 426.463476 -323.738248) (xy 426.415449 -323.76137)
			(xy 426.364513 -323.777076) (xy 426.311804 -323.785014) (xy 426.285152 -323.785484) (xy 426.258744 -323.784977)
			(xy 426.206507 -323.777182) (xy 426.155994 -323.761757) (xy 426.108314 -323.739038) (xy 426.064513 -323.709526)
			(xy 426.025552 -323.673867) (xy 426.008546 -323.653658) (xy 425.998609 -323.642265) (xy 425.973556 -323.625374)
			(xy 425.94466 -323.616543) (xy 425.914444 -323.616543) (xy 425.885548 -323.625374) (xy 425.860495 -323.642265)
			(xy 425.850558 -323.653658) (xy 425.833518 -323.673838) (xy 425.794566 -323.709504) (xy 425.750773 -323.739025)
			(xy 425.7031 -323.761754) (xy 425.652592 -323.777192) (xy 425.600359 -323.785) (xy 425.573952 -323.785484)
			(xy 425.547303 -323.785031) (xy 425.494602 -323.777081) (xy 425.443674 -323.761366) (xy 425.395656 -323.738236)
			(xy 425.351622 -323.708209) (xy 425.312555 -323.671954) (xy 425.279327 -323.630283) (xy 425.25268 -323.584124)
			(xy 425.23321 -323.53451) (xy 425.221351 -323.482549) (xy 425.217368 -323.4294) (xy 422.577808 -323.4294)
			(xy 422.573824 -323.482554) (xy 422.561962 -323.534521) (xy 422.542487 -323.584139) (xy 422.515833 -323.6303)
			(xy 422.482597 -323.671972) (xy 422.44352 -323.708224) (xy 422.399476 -323.738248) (xy 422.351449 -323.76137)
			(xy 422.300513 -323.777076) (xy 422.247804 -323.785014) (xy 422.221152 -323.785484) (xy 422.194744 -323.784977)
			(xy 422.142507 -323.777182) (xy 422.091994 -323.761757) (xy 422.044314 -323.739038) (xy 422.000513 -323.709526)
			(xy 421.961552 -323.673867) (xy 421.944546 -323.653658) (xy 421.934609 -323.642265) (xy 421.909556 -323.625374)
			(xy 421.88066 -323.616543) (xy 421.850444 -323.616543) (xy 421.821548 -323.625374) (xy 421.796495 -323.642265)
			(xy 421.786558 -323.653658) (xy 421.769518 -323.673838) (xy 421.730566 -323.709504) (xy 421.686773 -323.739025)
			(xy 421.6391 -323.761754) (xy 421.588592 -323.777192) (xy 421.536359 -323.785) (xy 421.509952 -323.785484)
			(xy 421.483303 -323.785031) (xy 421.430602 -323.777081) (xy 421.379674 -323.761366) (xy 421.331656 -323.738236)
			(xy 421.287622 -323.708209) (xy 421.248555 -323.671954) (xy 421.215327 -323.630283) (xy 421.18868 -323.584124)
			(xy 421.16921 -323.53451) (xy 421.157351 -323.482549) (xy 421.153368 -323.4294) (xy 419.098008 -323.4294)
			(xy 419.094024 -323.482554) (xy 419.082162 -323.534521) (xy 419.062687 -323.584139) (xy 419.036033 -323.6303)
			(xy 419.002797 -323.671972) (xy 418.96372 -323.708224) (xy 418.919676 -323.738248) (xy 418.871649 -323.76137)
			(xy 418.820713 -323.777076) (xy 418.768004 -323.785014) (xy 418.741352 -323.785484) (xy 418.714944 -323.784977)
			(xy 418.662707 -323.777182) (xy 418.612194 -323.761757) (xy 418.564514 -323.739038) (xy 418.520713 -323.709526)
			(xy 418.481752 -323.673867) (xy 418.464746 -323.653658) (xy 418.454809 -323.642265) (xy 418.429756 -323.625374)
			(xy 418.40086 -323.616543) (xy 418.370644 -323.616543) (xy 418.341748 -323.625374) (xy 418.316695 -323.642265)
			(xy 418.306758 -323.653658) (xy 418.289718 -323.673838) (xy 418.250766 -323.709504) (xy 418.206973 -323.739025)
			(xy 418.1593 -323.761754) (xy 418.108792 -323.777192) (xy 418.056559 -323.785) (xy 418.030152 -323.785484)
			(xy 418.003503 -323.785031) (xy 417.950802 -323.777081) (xy 417.899874 -323.761366) (xy 417.851856 -323.738236)
			(xy 417.807822 -323.708209) (xy 417.768755 -323.671954) (xy 417.735527 -323.630283) (xy 417.70888 -323.584124)
			(xy 417.68941 -323.53451) (xy 417.677551 -323.482549) (xy 417.673568 -323.4294) (xy 415.034008 -323.4294)
			(xy 415.030024 -323.482554) (xy 415.018162 -323.534521) (xy 414.998687 -323.584139) (xy 414.972033 -323.6303)
			(xy 414.938797 -323.671972) (xy 414.89972 -323.708224) (xy 414.855676 -323.738248) (xy 414.807649 -323.76137)
			(xy 414.756713 -323.777076) (xy 414.704004 -323.785014) (xy 414.677352 -323.785484) (xy 414.650944 -323.784977)
			(xy 414.598707 -323.777182) (xy 414.548194 -323.761757) (xy 414.500514 -323.739038) (xy 414.456713 -323.709526)
			(xy 414.417752 -323.673867) (xy 414.400746 -323.653658) (xy 414.390809 -323.642265) (xy 414.365756 -323.625374)
			(xy 414.33686 -323.616543) (xy 414.306644 -323.616543) (xy 414.277748 -323.625374) (xy 414.252695 -323.642265)
			(xy 414.242758 -323.653658) (xy 414.225718 -323.673838) (xy 414.186766 -323.709504) (xy 414.142973 -323.739025)
			(xy 414.0953 -323.761754) (xy 414.044792 -323.777192) (xy 413.992559 -323.785) (xy 413.966152 -323.785484)
			(xy 413.939503 -323.785031) (xy 413.886802 -323.777081) (xy 413.835874 -323.761366) (xy 413.787856 -323.738236)
			(xy 413.743822 -323.708209) (xy 413.704755 -323.671954) (xy 413.671527 -323.630283) (xy 413.64488 -323.584124)
			(xy 413.62541 -323.53451) (xy 413.613551 -323.482549) (xy 413.609568 -323.4294) (xy 411.554256 -323.4294)
			(xy 411.550272 -323.482561) (xy 411.538408 -323.534535) (xy 411.51893 -323.58416) (xy 411.492273 -323.630327)
			(xy 411.459032 -323.672004) (xy 411.41995 -323.708262) (xy 411.3759 -323.738289) (xy 411.327867 -323.761415)
			(xy 411.276923 -323.777123) (xy 411.224207 -323.785062) (xy 411.197552 -323.785484) (xy 411.171145 -323.785)
			(xy 411.118911 -323.777192) (xy 411.068404 -323.761755) (xy 411.02073 -323.739026) (xy 410.976937 -323.709506)
			(xy 410.937984 -323.67384) (xy 410.920946 -323.653658) (xy 410.911009 -323.642265) (xy 410.885956 -323.625374)
			(xy 410.85706 -323.616543) (xy 410.826844 -323.616543) (xy 410.797948 -323.625374) (xy 410.772895 -323.642265)
			(xy 410.762958 -323.653658) (xy 410.754134 -323.664335) (xy 410.735064 -323.684426) (xy 410.724858 -323.69379)
			(xy 410.714936 -323.703345) (xy 410.700164 -323.72658) (xy 410.692155 -323.752923) (xy 410.691496 -323.780449)
			(xy 410.698236 -323.807145) (xy 410.71188 -323.83106) (xy 410.721302 -323.84111) (xy 411.03169 -324.151498)
			(xy 411.03169 -327.10898) (xy 414.810321 -327.10898) (xy 414.810321 -327.02442) (xy 414.818124 -326.94022)
			(xy 414.833662 -326.857099) (xy 414.856804 -326.775767) (xy 414.887352 -326.696917) (xy 414.925045 -326.621222)
			(xy 414.969562 -326.549328) (xy 415.020523 -326.481848) (xy 415.077492 -326.419358) (xy 415.139985 -326.362392)
			(xy 415.207467 -326.311435) (xy 415.279364 -326.266922) (xy 415.355061 -326.229233) (xy 415.433912 -326.198689)
			(xy 415.515246 -326.175551) (xy 415.598367 -326.160017) (xy 415.682568 -326.152219) (xy 415.724848 -326.151748)
			(xy 416.969448 -326.151748) (xy 417.011721 -326.152326) (xy 417.095905 -326.160131) (xy 417.17901 -326.17567)
			(xy 417.260327 -326.198811) (xy 417.339162 -326.229355) (xy 417.414843 -326.267043) (xy 417.486723 -326.311553)
			(xy 417.554191 -326.362505) (xy 417.616669 -326.419465) (xy 417.673625 -326.481946) (xy 417.724574 -326.549416)
			(xy 417.76908 -326.621299) (xy 417.806764 -326.696982) (xy 417.837304 -326.775818) (xy 417.860441 -326.857136)
			(xy 417.875975 -326.940242) (xy 417.883776 -327.024427) (xy 417.883776 -327.108973) (xy 417.883775 -327.10898)
			(xy 422.354121 -327.10898) (xy 422.354121 -327.02442) (xy 422.361924 -326.94022) (xy 422.377462 -326.857099)
			(xy 422.400604 -326.775767) (xy 422.431152 -326.696917) (xy 422.468845 -326.621222) (xy 422.513362 -326.549328)
			(xy 422.564323 -326.481848) (xy 422.621292 -326.419358) (xy 422.683785 -326.362392) (xy 422.751267 -326.311435)
			(xy 422.823164 -326.266922) (xy 422.898861 -326.229233) (xy 422.977712 -326.198689) (xy 423.059046 -326.175551)
			(xy 423.142167 -326.160017) (xy 423.226368 -326.152219) (xy 423.268648 -326.151748) (xy 424.513248 -326.151748)
			(xy 424.555521 -326.152326) (xy 424.639705 -326.160131) (xy 424.72281 -326.17567) (xy 424.804127 -326.198811)
			(xy 424.882962 -326.229355) (xy 424.958643 -326.267043) (xy 425.030523 -326.311553) (xy 425.097991 -326.362505)
			(xy 425.160469 -326.419465) (xy 425.217425 -326.481946) (xy 425.268374 -326.549416) (xy 425.31288 -326.621299)
			(xy 425.350564 -326.696982) (xy 425.381104 -326.775818) (xy 425.404241 -326.857136) (xy 425.419775 -326.940242)
			(xy 425.427576 -327.024427) (xy 425.427576 -327.108973) (xy 425.427575 -327.10898) (xy 429.897921 -327.10898)
			(xy 429.897921 -327.02442) (xy 429.905724 -326.94022) (xy 429.921262 -326.857099) (xy 429.944404 -326.775767)
			(xy 429.974952 -326.696917) (xy 430.012645 -326.621222) (xy 430.057162 -326.549328) (xy 430.108123 -326.481848)
			(xy 430.165092 -326.419358) (xy 430.227585 -326.362392) (xy 430.295067 -326.311435) (xy 430.366964 -326.266922)
			(xy 430.442661 -326.229233) (xy 430.521512 -326.198689) (xy 430.602846 -326.175551) (xy 430.685967 -326.160017)
			(xy 430.770168 -326.152219) (xy 430.812448 -326.151748) (xy 432.057048 -326.151748) (xy 432.099321 -326.152326)
			(xy 432.183505 -326.160131) (xy 432.26661 -326.17567) (xy 432.347927 -326.198811) (xy 432.426762 -326.229355)
			(xy 432.502443 -326.267043) (xy 432.574323 -326.311553) (xy 432.641791 -326.362505) (xy 432.704269 -326.419465)
			(xy 432.761225 -326.481946) (xy 432.812174 -326.549416) (xy 432.85668 -326.621299) (xy 432.894364 -326.696982)
			(xy 432.924904 -326.775818) (xy 432.948041 -326.857136) (xy 432.963575 -326.940242) (xy 432.971376 -327.024427)
			(xy 432.971376 -327.108973) (xy 432.963575 -327.193158) (xy 432.948041 -327.276264) (xy 432.924904 -327.357582)
			(xy 432.894364 -327.436418) (xy 432.85668 -327.512101) (xy 432.812174 -327.583984) (xy 432.761225 -327.651454)
			(xy 432.704269 -327.713935) (xy 432.641791 -327.770895) (xy 432.574324 -327.821847) (xy 432.502443 -327.866357)
			(xy 432.426762 -327.904045) (xy 432.347927 -327.934589) (xy 432.26661 -327.95773) (xy 432.183505 -327.973269)
			(xy 432.099321 -327.981074) (xy 432.057048 -327.981564) (xy 430.812448 -327.981564) (xy 430.770168 -327.981181)
			(xy 430.685967 -327.973383) (xy 430.602846 -327.957849) (xy 430.521512 -327.934711) (xy 430.442661 -327.904167)
			(xy 430.366964 -327.866478) (xy 430.295067 -327.821965) (xy 430.227585 -327.771008) (xy 430.165092 -327.714042)
			(xy 430.108123 -327.651552) (xy 430.057162 -327.584072) (xy 430.012645 -327.512178) (xy 429.974952 -327.436483)
			(xy 429.944404 -327.357633) (xy 429.921262 -327.276301) (xy 429.905724 -327.19318) (xy 429.897921 -327.10898)
			(xy 425.427575 -327.10898) (xy 425.419775 -327.193158) (xy 425.404241 -327.276264) (xy 425.381104 -327.357582)
			(xy 425.350564 -327.436418) (xy 425.31288 -327.512101) (xy 425.268374 -327.583984) (xy 425.217425 -327.651454)
			(xy 425.160469 -327.713935) (xy 425.097991 -327.770895) (xy 425.030524 -327.821847) (xy 424.958643 -327.866357)
			(xy 424.882962 -327.904045) (xy 424.804127 -327.934589) (xy 424.72281 -327.95773) (xy 424.639705 -327.973269)
			(xy 424.555521 -327.981074) (xy 424.513248 -327.981564) (xy 423.268648 -327.981564) (xy 423.226368 -327.981181)
			(xy 423.142167 -327.973383) (xy 423.059046 -327.957849) (xy 422.977712 -327.934711) (xy 422.898861 -327.904167)
			(xy 422.823164 -327.866478) (xy 422.751267 -327.821965) (xy 422.683785 -327.771008) (xy 422.621292 -327.714042)
			(xy 422.564323 -327.651552) (xy 422.513362 -327.584072) (xy 422.468845 -327.512178) (xy 422.431152 -327.436483)
			(xy 422.400604 -327.357633) (xy 422.377462 -327.276301) (xy 422.361924 -327.19318) (xy 422.354121 -327.10898)
			(xy 417.883775 -327.10898) (xy 417.875975 -327.193158) (xy 417.860441 -327.276264) (xy 417.837304 -327.357582)
			(xy 417.806764 -327.436418) (xy 417.76908 -327.512101) (xy 417.724574 -327.583984) (xy 417.673625 -327.651454)
			(xy 417.616669 -327.713935) (xy 417.554191 -327.770895) (xy 417.486724 -327.821847) (xy 417.414843 -327.866357)
			(xy 417.339162 -327.904045) (xy 417.260327 -327.934589) (xy 417.17901 -327.95773) (xy 417.095905 -327.973269)
			(xy 417.011721 -327.981074) (xy 416.969448 -327.981564) (xy 415.724848 -327.981564) (xy 415.682568 -327.981181)
			(xy 415.598367 -327.973383) (xy 415.515246 -327.957849) (xy 415.433912 -327.934711) (xy 415.355061 -327.904167)
			(xy 415.279364 -327.866478) (xy 415.207467 -327.821965) (xy 415.139985 -327.771008) (xy 415.077492 -327.714042)
			(xy 415.020523 -327.651552) (xy 414.969562 -327.584072) (xy 414.925045 -327.512178) (xy 414.887352 -327.436483)
			(xy 414.856804 -327.357633) (xy 414.833662 -327.276301) (xy 414.818124 -327.19318) (xy 414.810321 -327.10898)
			(xy 411.03169 -327.10898) (xy 411.03169 -332.744318) (xy 414.816798 -336.529426) (xy 426.254418 -336.529426)
			(xy 432.39817 -342.673178) (xy 432.39817 -372.18112) (xy 427.703234 -376.876056) (xy 424.718226 -376.876056)
			(xy 423.880534 -377.713748) (xy 426.520862 -377.713748) (xy 426.524933 -377.658126) (xy 426.537059 -377.603689)
			(xy 426.556982 -377.551598) (xy 426.584278 -377.502963) (xy 426.618364 -377.45882) (xy 426.658513 -377.420111)
			(xy 426.703871 -377.38766) (xy 426.753471 -377.362159) (xy 426.806255 -377.344152) (xy 426.861098 -377.334022)
			(xy 426.916832 -377.331985) (xy 426.972269 -377.338085) (xy 427.026226 -377.352191) (xy 427.077555 -377.374003)
			(xy 427.125161 -377.403057) (xy 427.168029 -377.438732) (xy 427.205246 -377.480269) (xy 427.236019 -377.526782)
			(xy 427.259691 -377.577279) (xy 427.275759 -377.630686) (xy 427.283879 -377.685862) (xy 427.284388 -377.713748)
			(xy 427.283879 -377.741634) (xy 427.275759 -377.79681) (xy 427.259691 -377.850217) (xy 427.236019 -377.900714)
			(xy 427.205246 -377.947227) (xy 427.168029 -377.988764) (xy 427.125161 -378.024439) (xy 427.077555 -378.053493)
			(xy 427.026226 -378.075305) (xy 426.972269 -378.089411) (xy 426.916832 -378.095511) (xy 426.861098 -378.093474)
			(xy 426.806255 -378.083344) (xy 426.753471 -378.065337) (xy 426.703871 -378.039836) (xy 426.658513 -378.007385)
			(xy 426.618364 -377.968676) (xy 426.584278 -377.924533) (xy 426.556982 -377.875898) (xy 426.537059 -377.823807)
			(xy 426.524933 -377.76937) (xy 426.520862 -377.713748) (xy 423.880534 -377.713748) (xy 422.085008 -379.509274)
			(xy 422.085008 -380.329948) (xy 422.813224 -380.329948) (xy 422.817295 -380.274326) (xy 422.829421 -380.219889)
			(xy 422.849344 -380.167798) (xy 422.87664 -380.119163) (xy 422.910726 -380.07502) (xy 422.950875 -380.036311)
			(xy 422.996233 -380.00386) (xy 423.045833 -379.978359) (xy 423.098617 -379.960352) (xy 423.15346 -379.950222)
			(xy 423.209194 -379.948185) (xy 423.264631 -379.954285) (xy 423.318588 -379.968391) (xy 423.369917 -379.990203)
			(xy 423.417523 -380.019257) (xy 423.460391 -380.054932) (xy 423.497608 -380.096469) (xy 423.528381 -380.142982)
			(xy 423.552053 -380.193479) (xy 423.568121 -380.246886) (xy 423.576241 -380.302062) (xy 423.57675 -380.329948)
			(xy 423.576241 -380.357834) (xy 423.568121 -380.41301) (xy 423.552053 -380.466417) (xy 423.528381 -380.516914)
			(xy 423.497608 -380.563427) (xy 423.460391 -380.604964) (xy 423.417523 -380.640639) (xy 423.369917 -380.669693)
			(xy 423.318588 -380.691505) (xy 423.264631 -380.705611) (xy 423.209194 -380.711711) (xy 423.15346 -380.709674)
			(xy 423.098617 -380.699544) (xy 423.045833 -380.681537) (xy 422.996233 -380.656036) (xy 422.950875 -380.623585)
			(xy 422.910726 -380.584876) (xy 422.87664 -380.540733) (xy 422.849344 -380.492098) (xy 422.829421 -380.440007)
			(xy 422.817295 -380.38557) (xy 422.813224 -380.329948) (xy 422.085008 -380.329948) (xy 422.085008 -381.218915)
			(xy 425.916426 -381.218915) (xy 425.920614 -381.162495) (xy 425.933089 -381.107313) (xy 425.953578 -381.054578)
			(xy 425.981631 -381.005449) (xy 426.016634 -380.961001) (xy 426.057817 -380.922212) (xy 426.104279 -380.889931)
			(xy 426.154998 -380.864866) (xy 426.181774 -380.855728) (xy 426.195105 -380.851043) (xy 426.21862 -380.835388)
			(xy 426.236949 -380.813892) (xy 426.248689 -380.788197) (xy 426.252943 -380.76027) (xy 426.249385 -380.732245)
			(xy 426.244258 -380.719076) (xy 426.234532 -380.695259) (xy 426.220853 -380.645665) (xy 426.213947 -380.594685)
			(xy 426.213524 -380.568962) (xy 426.21401 -380.541711) (xy 426.221766 -380.487763) (xy 426.237121 -380.435468)
			(xy 426.259763 -380.385891) (xy 426.289229 -380.340041) (xy 426.32492 -380.29885) (xy 426.366111 -380.263159)
			(xy 426.411961 -380.233693) (xy 426.461538 -380.211051) (xy 426.513833 -380.195696) (xy 426.567781 -380.18794)
			(xy 426.622283 -380.18794) (xy 426.676231 -380.195696) (xy 426.728526 -380.211051) (xy 426.778103 -380.233693)
			(xy 426.823953 -380.263159) (xy 426.865144 -380.29885) (xy 426.900835 -380.340041) (xy 426.930301 -380.385891)
			(xy 426.952943 -380.435468) (xy 426.968298 -380.487763) (xy 426.976054 -380.541711) (xy 426.97654 -380.568962)
			(xy 429.382934 -380.568962) (xy 429.387005 -380.51334) (xy 429.399131 -380.458903) (xy 429.419054 -380.406812)
			(xy 429.44635 -380.358177) (xy 429.480436 -380.314034) (xy 429.520585 -380.275325) (xy 429.565943 -380.242874)
			(xy 429.615543 -380.217373) (xy 429.668327 -380.199366) (xy 429.72317 -380.189236) (xy 429.778904 -380.187199)
			(xy 429.834341 -380.193299) (xy 429.888298 -380.207405) (xy 429.939627 -380.229217) (xy 429.987233 -380.258271)
			(xy 430.030101 -380.293946) (xy 430.067318 -380.335483) (xy 430.098091 -380.381996) (xy 430.121763 -380.432493)
			(xy 430.137831 -380.4859) (xy 430.145951 -380.541076) (xy 430.14646 -380.568962) (xy 430.145951 -380.596848)
			(xy 430.137831 -380.652024) (xy 430.121763 -380.705431) (xy 430.098091 -380.755928) (xy 430.067318 -380.802441)
			(xy 430.030101 -380.843978) (xy 429.987233 -380.879653) (xy 429.939627 -380.908707) (xy 429.888298 -380.930519)
			(xy 429.834341 -380.944625) (xy 429.778904 -380.950725) (xy 429.72317 -380.948688) (xy 429.668327 -380.938558)
			(xy 429.615543 -380.920551) (xy 429.565943 -380.89505) (xy 429.520585 -380.862599) (xy 429.480436 -380.82389)
			(xy 429.44635 -380.779747) (xy 429.419054 -380.731112) (xy 429.399131 -380.679021) (xy 429.387005 -380.624584)
			(xy 429.382934 -380.568962) (xy 426.97654 -380.568962) (xy 426.976089 -380.595682) (xy 426.968623 -380.648599)
			(xy 426.953845 -380.699956) (xy 426.932046 -380.748749) (xy 426.903652 -380.794022) (xy 426.869217 -380.83489)
			(xy 426.829417 -380.870553) (xy 426.785029 -380.900313) (xy 426.736923 -380.923588) (xy 426.711618 -380.932182)
			(xy 426.69833 -380.936971) (xy 426.674825 -380.952608) (xy 426.6565 -380.974083) (xy 426.644754 -380.999754)
			(xy 426.640486 -381.027661) (xy 426.644021 -381.055669) (xy 426.649134 -381.068834) (xy 426.658862 -381.09265)
			(xy 426.672541 -381.142244) (xy 426.679446 -381.193225) (xy 426.679868 -381.218948) (xy 426.679466 -381.244673)
			(xy 426.672571 -381.295657) (xy 426.658871 -381.345248) (xy 426.649134 -381.369062) (xy 426.643973 -381.382214)
			(xy 426.640436 -381.410237) (xy 426.644706 -381.438158) (xy 426.656457 -381.463842) (xy 426.674791 -381.485328)
			(xy 426.698307 -381.500973) (xy 426.711618 -381.505714) (xy 426.736932 -381.514285) (xy 426.785045 -381.537555)
			(xy 426.829438 -381.567314) (xy 426.869242 -381.602978) (xy 426.903678 -381.64385) (xy 426.932072 -381.689128)
			(xy 426.953868 -381.737926) (xy 426.968638 -381.78929) (xy 426.976093 -381.842212) (xy 426.97654 -381.868934)
			(xy 426.976054 -381.896185) (xy 426.968298 -381.950133) (xy 426.952943 -382.002428) (xy 426.930301 -382.052005)
			(xy 426.900835 -382.097855) (xy 426.865144 -382.139046) (xy 426.823953 -382.174737) (xy 426.778103 -382.204203)
			(xy 426.728526 -382.226845) (xy 426.676231 -382.2422) (xy 426.622283 -382.249956) (xy 426.567781 -382.249956)
			(xy 426.513833 -382.2422) (xy 426.461538 -382.226845) (xy 426.411961 -382.204203) (xy 426.366111 -382.174737)
			(xy 426.32492 -382.139046) (xy 426.289229 -382.097855) (xy 426.259763 -382.052005) (xy 426.237121 -382.002428)
			(xy 426.221766 -381.950133) (xy 426.21401 -381.896185) (xy 426.213524 -381.868934) (xy 426.21392 -381.843209)
			(xy 426.220818 -381.792225) (xy 426.23452 -381.742634) (xy 426.244258 -381.71882) (xy 426.249444 -381.705677)
			(xy 426.252979 -381.677649) (xy 426.248705 -381.649725) (xy 426.236949 -381.624039) (xy 426.218609 -381.602552)
			(xy 426.195087 -381.586908) (xy 426.181774 -381.582168) (xy 426.155026 -381.572945) (xy 426.104304 -381.547884)
			(xy 426.05784 -381.515607) (xy 426.016654 -381.47682) (xy 425.981648 -381.432376) (xy 425.953591 -381.383248)
			(xy 425.933097 -381.330515) (xy 425.920618 -381.275334) (xy 425.916426 -381.218915) (xy 422.085008 -381.218915)
			(xy 422.085008 -382.184148) (xy 422.809922 -382.184148) (xy 422.813993 -382.128526) (xy 422.826119 -382.074089)
			(xy 422.846042 -382.021998) (xy 422.873338 -381.973363) (xy 422.907424 -381.92922) (xy 422.947573 -381.890511)
			(xy 422.992931 -381.85806) (xy 423.042531 -381.832559) (xy 423.095315 -381.814552) (xy 423.150158 -381.804422)
			(xy 423.205892 -381.802385) (xy 423.261329 -381.808485) (xy 423.315286 -381.822591) (xy 423.366615 -381.844403)
			(xy 423.414221 -381.873457) (xy 423.457089 -381.909132) (xy 423.494306 -381.950669) (xy 423.525079 -381.997182)
			(xy 423.548751 -382.047679) (xy 423.564819 -382.101086) (xy 423.572939 -382.156262) (xy 423.573448 -382.184148)
			(xy 423.572939 -382.212034) (xy 423.564819 -382.26721) (xy 423.548751 -382.320617) (xy 423.525079 -382.371114)
			(xy 423.494306 -382.417627) (xy 423.457089 -382.459164) (xy 423.414221 -382.494839) (xy 423.366615 -382.523893)
			(xy 423.315286 -382.545705) (xy 423.261329 -382.559811) (xy 423.205892 -382.565911) (xy 423.150158 -382.563874)
			(xy 423.095315 -382.553744) (xy 423.042531 -382.535737) (xy 422.992931 -382.510236) (xy 422.947573 -382.477785)
			(xy 422.907424 -382.439076) (xy 422.873338 -382.394933) (xy 422.846042 -382.346298) (xy 422.826119 -382.294207)
			(xy 422.813993 -382.23977) (xy 422.809922 -382.184148) (xy 422.085008 -382.184148) (xy 422.085008 -382.663446)
			(xy 423.072306 -383.650744) (xy 432.644804 -383.650744)
		)
		(stroke
			(width 0)
			(type solid)
		)
		(fill yes)
		(layer "In15.Cu")
		(net "P3V3_AUX")
	)
	(gr_poly
		(pts
			(xy 310.15432 -439.49112) (xy 310.15432 -426.301408) (xy 313.5376 -422.918128) (xy 355.6 -422.918128)
			(xy 355.981 -422.537128) (xy 355.981 -420.842948) (xy 356.362 -420.461948) (xy 363.093 -420.461948)
			(xy 363.474 -420.842948) (xy 363.474 -421.447468) (xy 366.03508 -421.447468) (xy 366.039151 -421.391846)
			(xy 366.051277 -421.337409) (xy 366.0712 -421.285318) (xy 366.098496 -421.236683) (xy 366.132582 -421.19254)
			(xy 366.172731 -421.153831) (xy 366.218089 -421.12138) (xy 366.267689 -421.095879) (xy 366.320473 -421.077872)
			(xy 366.375316 -421.067742) (xy 366.43105 -421.065705) (xy 366.486487 -421.071805) (xy 366.540444 -421.085911)
			(xy 366.591773 -421.107723) (xy 366.620731 -421.125396) (xy 374.666762 -421.125396) (xy 374.670833 -421.069774)
			(xy 374.682959 -421.015337) (xy 374.702882 -420.963246) (xy 374.730178 -420.914611) (xy 374.764264 -420.870468)
			(xy 374.804413 -420.831759) (xy 374.849771 -420.799308) (xy 374.899371 -420.773807) (xy 374.952155 -420.7558)
			(xy 375.006998 -420.74567) (xy 375.062732 -420.743633) (xy 375.118169 -420.749733) (xy 375.172126 -420.763839)
			(xy 375.223455 -420.785651) (xy 375.271061 -420.814705) (xy 375.313929 -420.85038) (xy 375.351146 -420.891917)
			(xy 375.381919 -420.93843) (xy 375.405591 -420.988927) (xy 375.421659 -421.042334) (xy 375.429779 -421.09751)
			(xy 375.430288 -421.125396) (xy 375.429779 -421.153282) (xy 375.421659 -421.208458) (xy 375.405591 -421.261865)
			(xy 375.381919 -421.312362) (xy 375.351146 -421.358875) (xy 375.313929 -421.400412) (xy 375.271061 -421.436087)
			(xy 375.223455 -421.465141) (xy 375.172126 -421.486953) (xy 375.118169 -421.501059) (xy 375.062732 -421.507159)
			(xy 375.006998 -421.505122) (xy 374.952155 -421.494992) (xy 374.899371 -421.476985) (xy 374.849771 -421.451484)
			(xy 374.804413 -421.419033) (xy 374.764264 -421.380324) (xy 374.730178 -421.336181) (xy 374.702882 -421.287546)
			(xy 374.682959 -421.235455) (xy 374.670833 -421.181018) (xy 374.666762 -421.125396) (xy 366.620731 -421.125396)
			(xy 366.639379 -421.136777) (xy 366.682247 -421.172452) (xy 366.719464 -421.213989) (xy 366.750237 -421.260502)
			(xy 366.773909 -421.310999) (xy 366.789977 -421.364406) (xy 366.798097 -421.419582) (xy 366.798606 -421.447468)
			(xy 366.798097 -421.475354) (xy 366.789977 -421.53053) (xy 366.773909 -421.583937) (xy 366.750237 -421.634434)
			(xy 366.719464 -421.680947) (xy 366.682247 -421.722484) (xy 366.639379 -421.758159) (xy 366.591773 -421.787213)
			(xy 366.540444 -421.809025) (xy 366.486487 -421.823131) (xy 366.43105 -421.829231) (xy 366.375316 -421.827194)
			(xy 366.320473 -421.817064) (xy 366.267689 -421.799057) (xy 366.218089 -421.773556) (xy 366.172731 -421.741105)
			(xy 366.132582 -421.702396) (xy 366.098496 -421.658253) (xy 366.0712 -421.609618) (xy 366.051277 -421.557527)
			(xy 366.039151 -421.50309) (xy 366.03508 -421.447468) (xy 363.474 -421.447468) (xy 363.474 -422.537128)
			(xy 363.855 -422.918128) (xy 375.717308 -422.918128) (xy 375.730948 -422.917689) (xy 375.757255 -422.910463)
			(xy 375.780709 -422.89653) (xy 375.799637 -422.876883) (xy 375.812687 -422.852926) (xy 375.818928 -422.826368)
			(xy 375.817913 -422.799106) (xy 375.809716 -422.773086) (xy 375.802652 -422.76141) (xy 375.7882 -422.738171)
			(xy 375.765388 -422.688428) (xy 375.749933 -422.635931) (xy 375.742154 -422.581763) (xy 375.741692 -422.5544)
			(xy 375.742178 -422.527149) (xy 375.749934 -422.473201) (xy 375.765289 -422.420906) (xy 375.787931 -422.371329)
			(xy 375.817397 -422.325479) (xy 375.853088 -422.284288) (xy 375.894279 -422.248597) (xy 375.940129 -422.219131)
			(xy 375.989706 -422.196489) (xy 376.042001 -422.181134) (xy 376.095949 -422.173378) (xy 376.150451 -422.173378)
			(xy 376.204399 -422.181134) (xy 376.256694 -422.196489) (xy 376.306271 -422.219131) (xy 376.352121 -422.248597)
			(xy 376.393312 -422.284288) (xy 376.429003 -422.325479) (xy 376.458469 -422.371329) (xy 376.481111 -422.420906)
			(xy 376.496466 -422.473201) (xy 376.504222 -422.527149) (xy 376.504708 -422.5544) (xy 376.504234 -422.58176)
			(xy 376.49642 -422.635919) (xy 376.480966 -422.688412) (xy 376.458188 -422.738166) (xy 376.443748 -422.76141)
			(xy 376.436721 -422.773103) (xy 376.428528 -422.799113) (xy 376.427514 -422.826364) (xy 376.433751 -422.852911)
			(xy 376.446796 -422.876859) (xy 376.465716 -422.896497) (xy 376.489161 -422.910425) (xy 376.515457 -422.917648)
			(xy 376.529092 -422.918128) (xy 413.57804 -422.918128) (xy 415.12998 -424.470068) (xy 421.270176 -424.470068)
			(xy 421.270176 -417.770056) (xy 421.270681 -417.664527) (xy 421.278765 -417.453623) (xy 421.294922 -417.243184)
			(xy 421.319127 -417.033518) (xy 421.351345 -416.824934) (xy 421.391528 -416.617736) (xy 421.439619 -416.412229)
			(xy 421.495545 -416.208716) (xy 421.559226 -416.007493) (xy 421.630567 -415.808858) (xy 421.709464 -415.613101)
			(xy 421.795802 -415.420509) (xy 421.889452 -415.231366) (xy 421.990279 -415.045949) (xy 422.098134 -414.864529)
			(xy 422.212858 -414.687374) (xy 422.334284 -414.514743) (xy 422.462233 -414.34689) (xy 422.596517 -414.184061)
			(xy 422.73694 -414.026495) (xy 422.883295 -413.874423) (xy 423.035367 -413.728068) (xy 423.192933 -413.587645)
			(xy 423.355762 -413.453361) (xy 423.523615 -413.325412) (xy 423.696246 -413.203986) (xy 423.873401 -413.089262)
			(xy 424.054821 -412.981407) (xy 424.240238 -412.88058) (xy 424.429381 -412.78693) (xy 424.621973 -412.700592)
			(xy 424.81773 -412.621695) (xy 425.016365 -412.550354) (xy 425.217588 -412.486673) (xy 425.421101 -412.430747)
			(xy 425.626608 -412.382656) (xy 425.833806 -412.342473) (xy 426.04239 -412.310255) (xy 426.252056 -412.28605)
			(xy 426.462495 -412.269893) (xy 426.673399 -412.261809) (xy 426.884457 -412.261809) (xy 427.095361 -412.269893)
			(xy 427.3058 -412.28605) (xy 427.515466 -412.310255) (xy 427.72405 -412.342473) (xy 427.931248 -412.382656)
			(xy 428.136755 -412.430747) (xy 428.340268 -412.486673) (xy 428.541491 -412.550354) (xy 428.740126 -412.621695)
			(xy 428.935883 -412.700592) (xy 429.128475 -412.78693) (xy 429.317618 -412.88058) (xy 429.503035 -412.981407)
			(xy 429.684455 -413.089262) (xy 429.86161 -413.203986) (xy 430.034241 -413.325412) (xy 430.202094 -413.453361)
			(xy 430.364923 -413.587645) (xy 430.522489 -413.728068) (xy 430.674561 -413.874423) (xy 430.820916 -414.026495)
			(xy 430.961339 -414.184061) (xy 431.095623 -414.34689) (xy 431.223572 -414.514743) (xy 431.344998 -414.687374)
			(xy 431.459722 -414.864529) (xy 431.567577 -415.045949) (xy 431.668404 -415.231366) (xy 431.762054 -415.420509)
			(xy 431.848392 -415.613101) (xy 431.927289 -415.808858) (xy 431.99863 -416.007493) (xy 432.062311 -416.208716)
			(xy 432.118237 -416.412229) (xy 432.166328 -416.617736) (xy 432.206511 -416.824934) (xy 432.238729 -417.033518)
			(xy 432.262934 -417.243184) (xy 432.279091 -417.453623) (xy 432.287175 -417.664527) (xy 432.28768 -417.770056)
			(xy 432.28768 -424.470068) (xy 432.287175 -424.575597) (xy 432.279091 -424.786501) (xy 432.262934 -424.99694)
			(xy 432.238729 -425.206606) (xy 432.206511 -425.41519) (xy 432.166328 -425.622388) (xy 432.118237 -425.827895)
			(xy 432.062311 -426.031408) (xy 431.99863 -426.232631) (xy 431.927289 -426.431266) (xy 431.848392 -426.627023)
			(xy 431.762054 -426.819615) (xy 431.668404 -427.008758) (xy 431.567577 -427.194175) (xy 431.459722 -427.375595)
			(xy 431.344998 -427.55275) (xy 431.223572 -427.725381) (xy 431.095623 -427.893234) (xy 430.961339 -428.056063)
			(xy 430.820916 -428.213629) (xy 430.674561 -428.365701) (xy 430.522489 -428.512056) (xy 430.364923 -428.652479)
			(xy 430.202094 -428.786763) (xy 430.034241 -428.914712) (xy 429.86161 -429.036138) (xy 429.684455 -429.150862)
			(xy 429.503035 -429.258717) (xy 429.317618 -429.359544) (xy 429.128475 -429.453194) (xy 428.935883 -429.539532)
			(xy 428.740126 -429.618429) (xy 428.541491 -429.68977) (xy 428.340268 -429.753451) (xy 428.136755 -429.809377)
			(xy 427.931248 -429.857468) (xy 427.72405 -429.897651) (xy 427.515466 -429.929869) (xy 427.3058 -429.954074)
			(xy 427.095361 -429.970231) (xy 426.884457 -429.978315) (xy 426.673399 -429.978315) (xy 426.462495 -429.970231)
			(xy 426.252056 -429.954074) (xy 426.04239 -429.929869) (xy 425.833806 -429.897651) (xy 425.626608 -429.857468)
			(xy 425.421101 -429.809377) (xy 425.217588 -429.753451) (xy 425.016365 -429.68977) (xy 424.81773 -429.618429)
			(xy 424.621973 -429.539532) (xy 424.429381 -429.453194) (xy 424.240238 -429.359544) (xy 424.054821 -429.258717)
			(xy 423.873401 -429.150862) (xy 423.696246 -429.036138) (xy 423.523615 -428.914712) (xy 423.355762 -428.786763)
			(xy 423.192933 -428.652479) (xy 423.035367 -428.512056) (xy 422.883295 -428.365701) (xy 422.73694 -428.213629)
			(xy 422.596517 -428.056063) (xy 422.462233 -427.893234) (xy 422.334284 -427.725381) (xy 422.212858 -427.55275)
			(xy 422.098134 -427.375595) (xy 421.990279 -427.194175) (xy 421.889452 -427.008758) (xy 421.795802 -426.819615)
			(xy 421.709464 -426.627023) (xy 421.630567 -426.431266) (xy 421.559226 -426.232631) (xy 421.495545 -426.031408)
			(xy 421.439619 -425.827895) (xy 421.391528 -425.622388) (xy 421.351345 -425.41519) (xy 421.319127 -425.206606)
			(xy 421.294922 -424.99694) (xy 421.278765 -424.786501) (xy 421.270681 -424.575597) (xy 421.270176 -424.470068)
			(xy 415.12998 -424.470068) (xy 415.48304 -424.823128) (xy 415.48304 -431.935128) (xy 417.38804 -433.840128)
			(xy 431.48504 -433.840128) (xy 434.15204 -431.173128) (xy 434.15204 -393.84097) (xy 433.493672 -393.182856)
			(xy 433.493672 -385.444238) (xy 434.15204 -384.786124) (xy 434.15204 -379.484128) (xy 431.86604 -377.198128)
			(xy 424.37304 -377.198128) (xy 423.85742 -377.713748) (xy 426.520862 -377.713748) (xy 426.524933 -377.658126)
			(xy 426.537059 -377.603689) (xy 426.556982 -377.551598) (xy 426.584278 -377.502963) (xy 426.618364 -377.45882)
			(xy 426.658513 -377.420111) (xy 426.703871 -377.38766) (xy 426.753471 -377.362159) (xy 426.806255 -377.344152)
			(xy 426.861098 -377.334022) (xy 426.916832 -377.331985) (xy 426.972269 -377.338085) (xy 427.026226 -377.352191)
			(xy 427.077555 -377.374003) (xy 427.125161 -377.403057) (xy 427.168029 -377.438732) (xy 427.205246 -377.480269)
			(xy 427.236019 -377.526782) (xy 427.259691 -377.577279) (xy 427.275759 -377.630686) (xy 427.283879 -377.685862)
			(xy 427.284388 -377.713748) (xy 427.283879 -377.741634) (xy 427.275759 -377.79681) (xy 427.259691 -377.850217)
			(xy 427.236019 -377.900714) (xy 427.205246 -377.947227) (xy 427.168029 -377.988764) (xy 427.125161 -378.024439)
			(xy 427.077555 -378.053493) (xy 427.026226 -378.075305) (xy 426.972269 -378.089411) (xy 426.916832 -378.095511)
			(xy 426.861098 -378.093474) (xy 426.806255 -378.083344) (xy 426.753471 -378.065337) (xy 426.703871 -378.039836)
			(xy 426.658513 -378.007385) (xy 426.618364 -377.968676) (xy 426.584278 -377.924533) (xy 426.556982 -377.875898)
			(xy 426.537059 -377.823807) (xy 426.524933 -377.76937) (xy 426.520862 -377.713748) (xy 423.85742 -377.713748)
			(xy 421.24122 -380.329948) (xy 422.813224 -380.329948) (xy 422.817295 -380.274326) (xy 422.829421 -380.219889)
			(xy 422.849344 -380.167798) (xy 422.87664 -380.119163) (xy 422.910726 -380.07502) (xy 422.950875 -380.036311)
			(xy 422.996233 -380.00386) (xy 423.045833 -379.978359) (xy 423.098617 -379.960352) (xy 423.15346 -379.950222)
			(xy 423.209194 -379.948185) (xy 423.264631 -379.954285) (xy 423.318588 -379.968391) (xy 423.369917 -379.990203)
			(xy 423.417523 -380.019257) (xy 423.460391 -380.054932) (xy 423.497608 -380.096469) (xy 423.528381 -380.142982)
			(xy 423.552053 -380.193479) (xy 423.568121 -380.246886) (xy 423.576241 -380.302062) (xy 423.57675 -380.329948)
			(xy 423.576241 -380.357834) (xy 423.568121 -380.41301) (xy 423.552053 -380.466417) (xy 423.528381 -380.516914)
			(xy 423.497608 -380.563427) (xy 423.460391 -380.604964) (xy 423.417523 -380.640639) (xy 423.369917 -380.669693)
			(xy 423.318588 -380.691505) (xy 423.264631 -380.705611) (xy 423.209194 -380.711711) (xy 423.15346 -380.709674)
			(xy 423.098617 -380.699544) (xy 423.045833 -380.681537) (xy 422.996233 -380.656036) (xy 422.950875 -380.623585)
			(xy 422.910726 -380.584876) (xy 422.87664 -380.540733) (xy 422.849344 -380.492098) (xy 422.829421 -380.440007)
			(xy 422.817295 -380.38557) (xy 422.813224 -380.329948) (xy 421.24122 -380.329948) (xy 421.07104 -380.500128)
			(xy 421.07104 -381.218915) (xy 425.916426 -381.218915) (xy 425.920614 -381.162495) (xy 425.933089 -381.107313)
			(xy 425.953578 -381.054578) (xy 425.981631 -381.005449) (xy 426.016634 -380.961001) (xy 426.057817 -380.922212)
			(xy 426.104279 -380.889931) (xy 426.154998 -380.864866) (xy 426.181774 -380.855728) (xy 426.195105 -380.851043)
			(xy 426.21862 -380.835388) (xy 426.236949 -380.813892) (xy 426.248689 -380.788197) (xy 426.252943 -380.76027)
			(xy 426.249385 -380.732245) (xy 426.244258 -380.719076) (xy 426.234532 -380.695259) (xy 426.220853 -380.645665)
			(xy 426.213947 -380.594685) (xy 426.213524 -380.568962) (xy 426.21401 -380.541711) (xy 426.221766 -380.487763)
			(xy 426.237121 -380.435468) (xy 426.259763 -380.385891) (xy 426.289229 -380.340041) (xy 426.32492 -380.29885)
			(xy 426.366111 -380.263159) (xy 426.411961 -380.233693) (xy 426.461538 -380.211051) (xy 426.513833 -380.195696)
			(xy 426.567781 -380.18794) (xy 426.622283 -380.18794) (xy 426.676231 -380.195696) (xy 426.728526 -380.211051)
			(xy 426.778103 -380.233693) (xy 426.823953 -380.263159) (xy 426.865144 -380.29885) (xy 426.900835 -380.340041)
			(xy 426.930301 -380.385891) (xy 426.952943 -380.435468) (xy 426.968298 -380.487763) (xy 426.976054 -380.541711)
			(xy 426.97654 -380.568962) (xy 429.382934 -380.568962) (xy 429.387005 -380.51334) (xy 429.399131 -380.458903)
			(xy 429.419054 -380.406812) (xy 429.44635 -380.358177) (xy 429.480436 -380.314034) (xy 429.520585 -380.275325)
			(xy 429.565943 -380.242874) (xy 429.615543 -380.217373) (xy 429.668327 -380.199366) (xy 429.72317 -380.189236)
			(xy 429.778904 -380.187199) (xy 429.834341 -380.193299) (xy 429.888298 -380.207405) (xy 429.939627 -380.229217)
			(xy 429.987233 -380.258271) (xy 430.030101 -380.293946) (xy 430.067318 -380.335483) (xy 430.098091 -380.381996)
			(xy 430.121763 -380.432493) (xy 430.137831 -380.4859) (xy 430.145951 -380.541076) (xy 430.14646 -380.568962)
			(xy 430.145951 -380.596848) (xy 430.137831 -380.652024) (xy 430.121763 -380.705431) (xy 430.098091 -380.755928)
			(xy 430.067318 -380.802441) (xy 430.030101 -380.843978) (xy 429.987233 -380.879653) (xy 429.939627 -380.908707)
			(xy 429.888298 -380.930519) (xy 429.834341 -380.944625) (xy 429.778904 -380.950725) (xy 429.72317 -380.948688)
			(xy 429.668327 -380.938558) (xy 429.615543 -380.920551) (xy 429.565943 -380.89505) (xy 429.520585 -380.862599)
			(xy 429.480436 -380.82389) (xy 429.44635 -380.779747) (xy 429.419054 -380.731112) (xy 429.399131 -380.679021)
			(xy 429.387005 -380.624584) (xy 429.382934 -380.568962) (xy 426.97654 -380.568962) (xy 426.976089 -380.595682)
			(xy 426.968623 -380.648599) (xy 426.953845 -380.699956) (xy 426.932046 -380.748749) (xy 426.903652 -380.794022)
			(xy 426.869217 -380.83489) (xy 426.829417 -380.870553) (xy 426.785029 -380.900313) (xy 426.736923 -380.923588)
			(xy 426.711618 -380.932182) (xy 426.69833 -380.936971) (xy 426.674825 -380.952608) (xy 426.6565 -380.974083)
			(xy 426.644754 -380.999754) (xy 426.640486 -381.027661) (xy 426.644021 -381.055669) (xy 426.649134 -381.068834)
			(xy 426.658862 -381.09265) (xy 426.672541 -381.142244) (xy 426.679446 -381.193225) (xy 426.679868 -381.218948)
			(xy 426.679466 -381.244673) (xy 426.672571 -381.295657) (xy 426.658871 -381.345248) (xy 426.649134 -381.369062)
			(xy 426.643973 -381.382214) (xy 426.640436 -381.410237) (xy 426.644706 -381.438158) (xy 426.656457 -381.463842)
			(xy 426.674791 -381.485328) (xy 426.698307 -381.500973) (xy 426.711618 -381.505714) (xy 426.736932 -381.514285)
			(xy 426.785045 -381.537555) (xy 426.829438 -381.567314) (xy 426.869242 -381.602978) (xy 426.903678 -381.64385)
			(xy 426.932072 -381.689128) (xy 426.953868 -381.737926) (xy 426.968638 -381.78929) (xy 426.976093 -381.842212)
			(xy 426.97654 -381.868934) (xy 426.976054 -381.896185) (xy 426.968298 -381.950133) (xy 426.952943 -382.002428)
			(xy 426.930301 -382.052005) (xy 426.900835 -382.097855) (xy 426.865144 -382.139046) (xy 426.823953 -382.174737)
			(xy 426.778103 -382.204203) (xy 426.728526 -382.226845) (xy 426.676231 -382.2422) (xy 426.622283 -382.249956)
			(xy 426.567781 -382.249956) (xy 426.513833 -382.2422) (xy 426.461538 -382.226845) (xy 426.411961 -382.204203)
			(xy 426.366111 -382.174737) (xy 426.32492 -382.139046) (xy 426.289229 -382.097855) (xy 426.259763 -382.052005)
			(xy 426.237121 -382.002428) (xy 426.221766 -381.950133) (xy 426.21401 -381.896185) (xy 426.213524 -381.868934)
			(xy 426.21392 -381.843209) (xy 426.220818 -381.792225) (xy 426.23452 -381.742634) (xy 426.244258 -381.71882)
			(xy 426.249444 -381.705677) (xy 426.252979 -381.677649) (xy 426.248705 -381.649725) (xy 426.236949 -381.624039)
			(xy 426.218609 -381.602552) (xy 426.195087 -381.586908) (xy 426.181774 -381.582168) (xy 426.155026 -381.572945)
			(xy 426.104304 -381.547884) (xy 426.05784 -381.515607) (xy 426.016654 -381.47682) (xy 425.981648 -381.432376)
			(xy 425.953591 -381.383248) (xy 425.933097 -381.330515) (xy 425.920618 -381.275334) (xy 425.916426 -381.218915)
			(xy 421.07104 -381.218915) (xy 421.07104 -382.184148) (xy 422.809922 -382.184148) (xy 422.813993 -382.128526)
			(xy 422.826119 -382.074089) (xy 422.846042 -382.021998) (xy 422.873338 -381.973363) (xy 422.907424 -381.92922)
			(xy 422.947573 -381.890511) (xy 422.992931 -381.85806) (xy 423.042531 -381.832559) (xy 423.095315 -381.814552)
			(xy 423.150158 -381.804422) (xy 423.205892 -381.802385) (xy 423.261329 -381.808485) (xy 423.315286 -381.822591)
			(xy 423.366615 -381.844403) (xy 423.414221 -381.873457) (xy 423.457089 -381.909132) (xy 423.494306 -381.950669)
			(xy 423.525079 -381.997182) (xy 423.548751 -382.047679) (xy 423.564819 -382.101086) (xy 423.572939 -382.156262)
			(xy 423.573448 -382.184148) (xy 423.572939 -382.212034) (xy 423.564819 -382.26721) (xy 423.548751 -382.320617)
			(xy 423.525079 -382.371114) (xy 423.494306 -382.417627) (xy 423.457089 -382.459164) (xy 423.414221 -382.494839)
			(xy 423.366615 -382.523893) (xy 423.315286 -382.545705) (xy 423.261329 -382.559811) (xy 423.205892 -382.565911)
			(xy 423.150158 -382.563874) (xy 423.095315 -382.553744) (xy 423.042531 -382.535737) (xy 422.992931 -382.510236)
			(xy 422.947573 -382.477785) (xy 422.907424 -382.439076) (xy 422.873338 -382.394933) (xy 422.846042 -382.346298)
			(xy 422.826119 -382.294207) (xy 422.813993 -382.23977) (xy 422.809922 -382.184148) (xy 421.07104 -382.184148)
			(xy 421.07104 -384.266948) (xy 422.766742 -384.266948) (xy 422.770813 -384.211326) (xy 422.782939 -384.156889)
			(xy 422.802862 -384.104798) (xy 422.830158 -384.056163) (xy 422.864244 -384.01202) (xy 422.904393 -383.973311)
			(xy 422.949751 -383.94086) (xy 422.999351 -383.915359) (xy 423.052135 -383.897352) (xy 423.106978 -383.887222)
			(xy 423.162712 -383.885185) (xy 423.218149 -383.891285) (xy 423.272106 -383.905391) (xy 423.323435 -383.927203)
			(xy 423.371041 -383.956257) (xy 423.413909 -383.991932) (xy 423.451126 -384.033469) (xy 423.481899 -384.079982)
			(xy 423.505571 -384.130479) (xy 423.521639 -384.183886) (xy 423.529759 -384.239062) (xy 423.530268 -384.266948)
			(xy 423.529759 -384.294834) (xy 423.521639 -384.35001) (xy 423.505571 -384.403417) (xy 423.481899 -384.453914)
			(xy 423.451126 -384.500427) (xy 423.413909 -384.541964) (xy 423.371041 -384.577639) (xy 423.323435 -384.606693)
			(xy 423.272106 -384.628505) (xy 423.218149 -384.642611) (xy 423.162712 -384.648711) (xy 423.106978 -384.646674)
			(xy 423.052135 -384.636544) (xy 422.999351 -384.618537) (xy 422.949751 -384.593036) (xy 422.904393 -384.560585)
			(xy 422.864244 -384.521876) (xy 422.830158 -384.477733) (xy 422.802862 -384.429098) (xy 422.782939 -384.377007)
			(xy 422.770813 -384.32257) (xy 422.766742 -384.266948) (xy 421.07104 -384.266948) (xy 421.07104 -386.143966)
			(xy 425.813166 -386.143966) (xy 425.82132 -386.088687) (xy 425.837454 -386.03519) (xy 425.861222 -385.98462)
			(xy 425.892116 -385.93806) (xy 425.929475 -385.896508) (xy 425.972497 -385.860852) (xy 426.020262 -385.831856)
			(xy 426.071748 -385.810142) (xy 426.125851 -385.796174) (xy 426.15358 -385.792726) (xy 426.168912 -385.790459)
			(xy 426.197313 -385.778106) (xy 426.220712 -385.757816) (xy 426.236964 -385.731451) (xy 426.244576 -385.701429)
			(xy 426.24285 -385.670506) (xy 426.237908 -385.65582) (xy 426.226531 -385.623532) (xy 426.214263 -385.556188)
			(xy 426.213524 -385.521962) (xy 426.21401 -385.494711) (xy 426.221766 -385.440763) (xy 426.237121 -385.388468)
			(xy 426.259763 -385.338891) (xy 426.289229 -385.293041) (xy 426.32492 -385.25185) (xy 426.366111 -385.216159)
			(xy 426.411961 -385.186693) (xy 426.461538 -385.164051) (xy 426.513833 -385.148696) (xy 426.567781 -385.14094)
			(xy 426.622283 -385.14094) (xy 426.676231 -385.148696) (xy 426.728526 -385.164051) (xy 426.778103 -385.186693)
			(xy 426.823953 -385.216159) (xy 426.865144 -385.25185) (xy 426.900835 -385.293041) (xy 426.930301 -385.338891)
			(xy 426.952943 -385.388468) (xy 426.968298 -385.440763) (xy 426.976054 -385.494711) (xy 426.97654 -385.521962)
			(xy 429.382934 -385.521962) (xy 429.387005 -385.46634) (xy 429.399131 -385.411903) (xy 429.419054 -385.359812)
			(xy 429.44635 -385.311177) (xy 429.480436 -385.267034) (xy 429.520585 -385.228325) (xy 429.565943 -385.195874)
			(xy 429.615543 -385.170373) (xy 429.668327 -385.152366) (xy 429.72317 -385.142236) (xy 429.778904 -385.140199)
			(xy 429.834341 -385.146299) (xy 429.888298 -385.160405) (xy 429.939627 -385.182217) (xy 429.987233 -385.211271)
			(xy 430.030101 -385.246946) (xy 430.067318 -385.288483) (xy 430.098091 -385.334996) (xy 430.121763 -385.385493)
			(xy 430.137831 -385.4389) (xy 430.145951 -385.494076) (xy 430.14646 -385.521962) (xy 430.145951 -385.549848)
			(xy 430.137831 -385.605024) (xy 430.121763 -385.658431) (xy 430.098091 -385.708928) (xy 430.067318 -385.755441)
			(xy 430.030101 -385.796978) (xy 429.987233 -385.832653) (xy 429.939627 -385.861707) (xy 429.888298 -385.883519)
			(xy 429.834341 -385.897625) (xy 429.778904 -385.903725) (xy 429.72317 -385.901688) (xy 429.668327 -385.891558)
			(xy 429.615543 -385.873551) (xy 429.565943 -385.84805) (xy 429.520585 -385.815599) (xy 429.480436 -385.77689)
			(xy 429.44635 -385.732747) (xy 429.419054 -385.684112) (xy 429.399131 -385.632021) (xy 429.387005 -385.577584)
			(xy 429.382934 -385.521962) (xy 426.97654 -385.521962) (xy 426.976045 -385.549904) (xy 426.967919 -385.605193)
			(xy 426.951806 -385.658703) (xy 426.928052 -385.709286) (xy 426.897165 -385.755858) (xy 426.859809 -385.797421)
			(xy 426.816784 -385.833082) (xy 426.769012 -385.862078) (xy 426.717518 -385.883788) (xy 426.663405 -385.897744)
			(xy 426.635672 -385.901184) (xy 426.620333 -385.903406) (xy 426.591932 -385.915772) (xy 426.568534 -385.936072)
			(xy 426.552285 -385.962445) (xy 426.544676 -385.992473) (xy 426.546402 -386.023401) (xy 426.551344 -386.03809)
			(xy 426.562722 -386.070378) (xy 426.57499 -386.137722) (xy 426.575728 -386.171948) (xy 426.574933 -386.206168)
			(xy 426.562661 -386.273501) (xy 426.551344 -386.305806) (xy 426.54643 -386.320498) (xy 426.544735 -386.351415)
			(xy 426.552355 -386.381426) (xy 426.568593 -386.40779) (xy 426.591967 -386.428099) (xy 426.62034 -386.440496)
			(xy 426.635672 -386.442712) (xy 426.663397 -386.44618) (xy 426.717492 -386.460164) (xy 426.768969 -386.48189)
			(xy 426.816725 -386.510894) (xy 426.859739 -386.546553) (xy 426.897091 -386.588107) (xy 426.927982 -386.634664)
			(xy 426.95175 -386.685231) (xy 426.967887 -386.738723) (xy 426.976047 -386.793997) (xy 426.97654 -386.821934)
			(xy 426.976054 -386.849185) (xy 426.968298 -386.903133) (xy 426.952943 -386.955428) (xy 426.930301 -387.005005)
			(xy 426.900835 -387.050855) (xy 426.865144 -387.092046) (xy 426.823953 -387.127737) (xy 426.778103 -387.157203)
			(xy 426.728526 -387.179845) (xy 426.676231 -387.1952) (xy 426.622283 -387.202956) (xy 426.567781 -387.202956)
			(xy 426.513833 -387.1952) (xy 426.461538 -387.179845) (xy 426.411961 -387.157203) (xy 426.366111 -387.127737)
			(xy 426.32492 -387.092046) (xy 426.289229 -387.050855) (xy 426.259763 -387.005005) (xy 426.237121 -386.955428)
			(xy 426.221766 -386.903133) (xy 426.21401 -386.849185) (xy 426.213524 -386.821934) (xy 426.214317 -386.787714)
			(xy 426.226591 -386.720381) (xy 426.237908 -386.688076) (xy 426.242883 -386.673401) (xy 426.244576 -386.642471)
			(xy 426.236949 -386.61245) (xy 426.220698 -386.586079) (xy 426.197308 -386.56577) (xy 426.168919 -386.55338)
			(xy 426.15358 -386.55117) (xy 426.125861 -386.547628) (xy 426.071757 -386.533661) (xy 426.020271 -386.511948)
			(xy 425.972505 -386.482954) (xy 425.929482 -386.447299) (xy 425.892123 -386.405748) (xy 425.861227 -386.359189)
			(xy 425.837458 -386.308619) (xy 425.821322 -386.255123) (xy 425.813167 -386.199844) (xy 425.813166 -386.143966)
			(xy 421.07104 -386.143966) (xy 421.07104 -387.314948) (xy 422.813224 -387.314948) (xy 422.817295 -387.259326)
			(xy 422.829421 -387.204889) (xy 422.849344 -387.152798) (xy 422.87664 -387.104163) (xy 422.910726 -387.06002)
			(xy 422.950875 -387.021311) (xy 422.996233 -386.98886) (xy 423.045833 -386.963359) (xy 423.098617 -386.945352)
			(xy 423.15346 -386.935222) (xy 423.209194 -386.933185) (xy 423.264631 -386.939285) (xy 423.318588 -386.953391)
			(xy 423.369917 -386.975203) (xy 423.417523 -387.004257) (xy 423.460391 -387.039932) (xy 423.497608 -387.081469)
			(xy 423.528381 -387.127982) (xy 423.552053 -387.178479) (xy 423.568121 -387.231886) (xy 423.576241 -387.287062)
			(xy 423.57675 -387.314948) (xy 423.576241 -387.342834) (xy 423.568121 -387.39801) (xy 423.552053 -387.451417)
			(xy 423.528381 -387.501914) (xy 423.497608 -387.548427) (xy 423.460391 -387.589964) (xy 423.417523 -387.625639)
			(xy 423.369917 -387.654693) (xy 423.318588 -387.676505) (xy 423.264631 -387.690611) (xy 423.209194 -387.696711)
			(xy 423.15346 -387.694674) (xy 423.098617 -387.684544) (xy 423.045833 -387.666537) (xy 422.996233 -387.641036)
			(xy 422.950875 -387.608585) (xy 422.910726 -387.569876) (xy 422.87664 -387.525733) (xy 422.849344 -387.477098)
			(xy 422.829421 -387.425007) (xy 422.817295 -387.37057) (xy 422.813224 -387.314948) (xy 421.07104 -387.314948)
			(xy 421.07104 -390.616948) (xy 422.813224 -390.616948) (xy 422.817295 -390.561326) (xy 422.829421 -390.506889)
			(xy 422.849344 -390.454798) (xy 422.87664 -390.406163) (xy 422.910726 -390.36202) (xy 422.950875 -390.323311)
			(xy 422.996233 -390.29086) (xy 423.045833 -390.265359) (xy 423.098617 -390.247352) (xy 423.15346 -390.237222)
			(xy 423.209194 -390.235185) (xy 423.264631 -390.241285) (xy 423.318588 -390.255391) (xy 423.369917 -390.277203)
			(xy 423.417523 -390.306257) (xy 423.460391 -390.341932) (xy 423.497608 -390.383469) (xy 423.528381 -390.429982)
			(xy 423.552053 -390.480479) (xy 423.568121 -390.533886) (xy 423.576241 -390.589062) (xy 423.57675 -390.616948)
			(xy 423.576241 -390.644834) (xy 423.568121 -390.70001) (xy 423.552053 -390.753417) (xy 423.528381 -390.803914)
			(xy 423.497608 -390.850427) (xy 423.460391 -390.891964) (xy 423.417523 -390.927639) (xy 423.369917 -390.956693)
			(xy 423.318588 -390.978505) (xy 423.264631 -390.992611) (xy 423.209194 -390.998711) (xy 423.15346 -390.996674)
			(xy 423.098617 -390.986544) (xy 423.045833 -390.968537) (xy 422.996233 -390.943036) (xy 422.950875 -390.910585)
			(xy 422.910726 -390.871876) (xy 422.87664 -390.827733) (xy 422.849344 -390.779098) (xy 422.829421 -390.727007)
			(xy 422.817295 -390.67257) (xy 422.813224 -390.616948) (xy 421.07104 -390.616948) (xy 421.07104 -391.632948)
			(xy 422.813224 -391.632948) (xy 422.817295 -391.577326) (xy 422.829421 -391.522889) (xy 422.849344 -391.470798)
			(xy 422.87664 -391.422163) (xy 422.910726 -391.37802) (xy 422.950875 -391.339311) (xy 422.996233 -391.30686)
			(xy 423.045833 -391.281359) (xy 423.098617 -391.263352) (xy 423.15346 -391.253222) (xy 423.209194 -391.251185)
			(xy 423.264631 -391.257285) (xy 423.318588 -391.271391) (xy 423.369917 -391.293203) (xy 423.417523 -391.322257)
			(xy 423.460391 -391.357932) (xy 423.497608 -391.399469) (xy 423.528381 -391.445982) (xy 423.552053 -391.496479)
			(xy 423.554892 -391.505915) (xy 425.916426 -391.505915) (xy 425.920614 -391.449495) (xy 425.933089 -391.394313)
			(xy 425.953578 -391.341578) (xy 425.981631 -391.292449) (xy 426.016634 -391.248001) (xy 426.057817 -391.209212)
			(xy 426.104279 -391.176931) (xy 426.154998 -391.151866) (xy 426.181774 -391.142728) (xy 426.195105 -391.138043)
			(xy 426.21862 -391.122388) (xy 426.236949 -391.100892) (xy 426.248689 -391.075197) (xy 426.252943 -391.04727)
			(xy 426.249385 -391.019245) (xy 426.244258 -391.006076) (xy 426.234532 -390.982259) (xy 426.220853 -390.932665)
			(xy 426.213947 -390.881685) (xy 426.213524 -390.855962) (xy 426.21401 -390.828711) (xy 426.221766 -390.774763)
			(xy 426.237121 -390.722468) (xy 426.259763 -390.672891) (xy 426.289229 -390.627041) (xy 426.32492 -390.58585)
			(xy 426.366111 -390.550159) (xy 426.411961 -390.520693) (xy 426.461538 -390.498051) (xy 426.513833 -390.482696)
			(xy 426.567781 -390.47494) (xy 426.622283 -390.47494) (xy 426.676231 -390.482696) (xy 426.728526 -390.498051)
			(xy 426.778103 -390.520693) (xy 426.823953 -390.550159) (xy 426.865144 -390.58585) (xy 426.900835 -390.627041)
			(xy 426.930301 -390.672891) (xy 426.952943 -390.722468) (xy 426.968298 -390.774763) (xy 426.976054 -390.828711)
			(xy 426.97654 -390.855962) (xy 429.382934 -390.855962) (xy 429.387005 -390.80034) (xy 429.399131 -390.745903)
			(xy 429.419054 -390.693812) (xy 429.44635 -390.645177) (xy 429.480436 -390.601034) (xy 429.520585 -390.562325)
			(xy 429.565943 -390.529874) (xy 429.615543 -390.504373) (xy 429.668327 -390.486366) (xy 429.72317 -390.476236)
			(xy 429.778904 -390.474199) (xy 429.834341 -390.480299) (xy 429.888298 -390.494405) (xy 429.939627 -390.516217)
			(xy 429.987233 -390.545271) (xy 430.030101 -390.580946) (xy 430.067318 -390.622483) (xy 430.098091 -390.668996)
			(xy 430.121763 -390.719493) (xy 430.137831 -390.7729) (xy 430.145951 -390.828076) (xy 430.14646 -390.855962)
			(xy 430.145951 -390.883848) (xy 430.137831 -390.939024) (xy 430.121763 -390.992431) (xy 430.098091 -391.042928)
			(xy 430.067318 -391.089441) (xy 430.030101 -391.130978) (xy 429.987233 -391.166653) (xy 429.939627 -391.195707)
			(xy 429.888298 -391.217519) (xy 429.834341 -391.231625) (xy 429.778904 -391.237725) (xy 429.72317 -391.235688)
			(xy 429.668327 -391.225558) (xy 429.615543 -391.207551) (xy 429.565943 -391.18205) (xy 429.520585 -391.149599)
			(xy 429.480436 -391.11089) (xy 429.44635 -391.066747) (xy 429.419054 -391.018112) (xy 429.399131 -390.966021)
			(xy 429.387005 -390.911584) (xy 429.382934 -390.855962) (xy 426.97654 -390.855962) (xy 426.976089 -390.882682)
			(xy 426.968623 -390.935599) (xy 426.953845 -390.986956) (xy 426.932046 -391.035749) (xy 426.903652 -391.081022)
			(xy 426.869217 -391.12189) (xy 426.829417 -391.157553) (xy 426.785029 -391.187313) (xy 426.736923 -391.210588)
			(xy 426.711618 -391.219182) (xy 426.69833 -391.223971) (xy 426.674825 -391.239608) (xy 426.6565 -391.261083)
			(xy 426.644754 -391.286754) (xy 426.640486 -391.314661) (xy 426.644021 -391.342669) (xy 426.649134 -391.355834)
			(xy 426.658862 -391.37965) (xy 426.672541 -391.429244) (xy 426.679446 -391.480225) (xy 426.679868 -391.505948)
			(xy 426.679466 -391.531673) (xy 426.672571 -391.582657) (xy 426.658871 -391.632248) (xy 426.649134 -391.656062)
			(xy 426.643973 -391.669214) (xy 426.640436 -391.697237) (xy 426.644706 -391.725158) (xy 426.656457 -391.750842)
			(xy 426.674791 -391.772328) (xy 426.698307 -391.787973) (xy 426.711618 -391.792714) (xy 426.736932 -391.801285)
			(xy 426.785045 -391.824555) (xy 426.829438 -391.854314) (xy 426.869242 -391.889978) (xy 426.903678 -391.93085)
			(xy 426.932072 -391.976128) (xy 426.953868 -392.024926) (xy 426.968638 -392.07629) (xy 426.976093 -392.129212)
			(xy 426.97654 -392.155934) (xy 426.976054 -392.183185) (xy 426.968298 -392.237133) (xy 426.952943 -392.289428)
			(xy 426.930301 -392.339005) (xy 426.900835 -392.384855) (xy 426.865144 -392.426046) (xy 426.823953 -392.461737)
			(xy 426.778103 -392.491203) (xy 426.728526 -392.513845) (xy 426.676231 -392.5292) (xy 426.622283 -392.536956)
			(xy 426.567781 -392.536956) (xy 426.513833 -392.5292) (xy 426.461538 -392.513845) (xy 426.411961 -392.491203)
			(xy 426.366111 -392.461737) (xy 426.32492 -392.426046) (xy 426.289229 -392.384855) (xy 426.259763 -392.339005)
			(xy 426.237121 -392.289428) (xy 426.221766 -392.237133) (xy 426.21401 -392.183185) (xy 426.213524 -392.155934)
			(xy 426.21392 -392.130209) (xy 426.220818 -392.079225) (xy 426.23452 -392.029634) (xy 426.244258 -392.00582)
			(xy 426.249444 -391.992677) (xy 426.252979 -391.964649) (xy 426.248705 -391.936725) (xy 426.236949 -391.911039)
			(xy 426.218609 -391.889552) (xy 426.195087 -391.873908) (xy 426.181774 -391.869168) (xy 426.155026 -391.859945)
			(xy 426.104304 -391.834884) (xy 426.05784 -391.802607) (xy 426.016654 -391.76382) (xy 425.981648 -391.719376)
			(xy 425.953591 -391.670248) (xy 425.933097 -391.617515) (xy 425.920618 -391.562334) (xy 425.916426 -391.505915)
			(xy 423.554892 -391.505915) (xy 423.568121 -391.549886) (xy 423.576241 -391.605062) (xy 423.57675 -391.632948)
			(xy 423.576241 -391.660834) (xy 423.568121 -391.71601) (xy 423.552053 -391.769417) (xy 423.528381 -391.819914)
			(xy 423.497608 -391.866427) (xy 423.460391 -391.907964) (xy 423.417523 -391.943639) (xy 423.369917 -391.972693)
			(xy 423.318588 -391.994505) (xy 423.264631 -392.008611) (xy 423.209194 -392.014711) (xy 423.15346 -392.012674)
			(xy 423.098617 -392.002544) (xy 423.045833 -391.984537) (xy 422.996233 -391.959036) (xy 422.950875 -391.926585)
			(xy 422.910726 -391.887876) (xy 422.87664 -391.843733) (xy 422.849344 -391.795098) (xy 422.829421 -391.743007)
			(xy 422.817295 -391.68857) (xy 422.813224 -391.632948) (xy 421.07104 -391.632948) (xy 421.07104 -393.90701)
			(xy 424.222924 -393.90701) (xy 424.226995 -393.851388) (xy 424.239121 -393.796951) (xy 424.259044 -393.74486)
			(xy 424.28634 -393.696225) (xy 424.320426 -393.652082) (xy 424.360575 -393.613373) (xy 424.405933 -393.580922)
			(xy 424.455533 -393.555421) (xy 424.508317 -393.537414) (xy 424.56316 -393.527284) (xy 424.618894 -393.525247)
			(xy 424.674331 -393.531347) (xy 424.728288 -393.545453) (xy 424.779617 -393.567265) (xy 424.827223 -393.596319)
			(xy 424.870091 -393.631994) (xy 424.907308 -393.673531) (xy 424.938081 -393.720044) (xy 424.961753 -393.770541)
			(xy 424.977821 -393.823948) (xy 424.985941 -393.879124) (xy 424.98645 -393.90701) (xy 424.985941 -393.934896)
			(xy 424.977821 -393.990072) (xy 424.961753 -394.043479) (xy 424.938081 -394.093976) (xy 424.907308 -394.140489)
			(xy 424.870091 -394.182026) (xy 424.827223 -394.217701) (xy 424.779617 -394.246755) (xy 424.728288 -394.268567)
			(xy 424.674331 -394.282673) (xy 424.618894 -394.288773) (xy 424.56316 -394.286736) (xy 424.508317 -394.276606)
			(xy 424.455533 -394.258599) (xy 424.405933 -394.233098) (xy 424.360575 -394.200647) (xy 424.320426 -394.161938)
			(xy 424.28634 -394.117795) (xy 424.259044 -394.06916) (xy 424.239121 -394.017069) (xy 424.226995 -393.962632)
			(xy 424.222924 -393.90701) (xy 421.07104 -393.90701) (xy 421.07104 -394.603478) (xy 422.813224 -394.603478)
			(xy 422.817295 -394.547856) (xy 422.829421 -394.493419) (xy 422.849344 -394.441328) (xy 422.87664 -394.392693)
			(xy 422.910726 -394.34855) (xy 422.950875 -394.309841) (xy 422.996233 -394.27739) (xy 423.045833 -394.251889)
			(xy 423.098617 -394.233882) (xy 423.15346 -394.223752) (xy 423.209194 -394.221715) (xy 423.264631 -394.227815)
			(xy 423.318588 -394.241921) (xy 423.369917 -394.263733) (xy 423.417523 -394.292787) (xy 423.460391 -394.328462)
			(xy 423.497608 -394.369999) (xy 423.528381 -394.416512) (xy 423.552053 -394.467009) (xy 423.568121 -394.520416)
			(xy 423.576241 -394.575592) (xy 423.57675 -394.603478) (xy 423.576241 -394.631364) (xy 423.568121 -394.68654)
			(xy 423.552053 -394.739947) (xy 423.528381 -394.790444) (xy 423.497608 -394.836957) (xy 423.460391 -394.878494)
			(xy 423.417523 -394.914169) (xy 423.369917 -394.943223) (xy 423.318588 -394.965035) (xy 423.264631 -394.979141)
			(xy 423.209194 -394.985241) (xy 423.15346 -394.983204) (xy 423.098617 -394.973074) (xy 423.045833 -394.955067)
			(xy 422.996233 -394.929566) (xy 422.950875 -394.897115) (xy 422.910726 -394.858406) (xy 422.87664 -394.814263)
			(xy 422.849344 -394.765628) (xy 422.829421 -394.713537) (xy 422.817295 -394.6591) (xy 422.813224 -394.603478)
			(xy 421.07104 -394.603478) (xy 421.07104 -395.798548) (xy 429.382934 -395.798548) (xy 429.387005 -395.742926)
			(xy 429.399131 -395.688489) (xy 429.419054 -395.636398) (xy 429.44635 -395.587763) (xy 429.480436 -395.54362)
			(xy 429.520585 -395.504911) (xy 429.565943 -395.47246) (xy 429.615543 -395.446959) (xy 429.668327 -395.428952)
			(xy 429.72317 -395.418822) (xy 429.778904 -395.416785) (xy 429.834341 -395.422885) (xy 429.888298 -395.436991)
			(xy 429.939627 -395.458803) (xy 429.987233 -395.487857) (xy 430.030101 -395.523532) (xy 430.067318 -395.565069)
			(xy 430.098091 -395.611582) (xy 430.121763 -395.662079) (xy 430.137831 -395.715486) (xy 430.145951 -395.770662)
			(xy 430.14646 -395.798548) (xy 430.145951 -395.826434) (xy 430.137831 -395.88161) (xy 430.121763 -395.935017)
			(xy 430.098091 -395.985514) (xy 430.067318 -396.032027) (xy 430.030101 -396.073564) (xy 429.987233 -396.109239)
			(xy 429.939627 -396.138293) (xy 429.888298 -396.160105) (xy 429.834341 -396.174211) (xy 429.778904 -396.180311)
			(xy 429.72317 -396.178274) (xy 429.668327 -396.168144) (xy 429.615543 -396.150137) (xy 429.565943 -396.124636)
			(xy 429.520585 -396.092185) (xy 429.480436 -396.053476) (xy 429.44635 -396.009333) (xy 429.419054 -395.960698)
			(xy 429.399131 -395.908607) (xy 429.387005 -395.85417) (xy 429.382934 -395.798548) (xy 421.07104 -395.798548)
			(xy 421.07104 -397.09852) (xy 426.213014 -397.09852) (xy 426.217085 -397.042898) (xy 426.229211 -396.988461)
			(xy 426.249134 -396.93637) (xy 426.27643 -396.887735) (xy 426.310516 -396.843592) (xy 426.350665 -396.804883)
			(xy 426.396023 -396.772432) (xy 426.445623 -396.746931) (xy 426.498407 -396.728924) (xy 426.55325 -396.718794)
			(xy 426.608984 -396.716757) (xy 426.664421 -396.722857) (xy 426.718378 -396.736963) (xy 426.769707 -396.758775)
			(xy 426.817313 -396.787829) (xy 426.860181 -396.823504) (xy 426.897398 -396.865041) (xy 426.928171 -396.911554)
			(xy 426.951843 -396.962051) (xy 426.967911 -397.015458) (xy 426.976031 -397.070634) (xy 426.97654 -397.09852)
			(xy 426.976031 -397.126406) (xy 426.967911 -397.181582) (xy 426.951843 -397.234989) (xy 426.928171 -397.285486)
			(xy 426.897398 -397.331999) (xy 426.860181 -397.373536) (xy 426.817313 -397.409211) (xy 426.769707 -397.438265)
			(xy 426.718378 -397.460077) (xy 426.664421 -397.474183) (xy 426.608984 -397.480283) (xy 426.55325 -397.478246)
			(xy 426.498407 -397.468116) (xy 426.445623 -397.450109) (xy 426.396023 -397.424608) (xy 426.350665 -397.392157)
			(xy 426.310516 -397.353448) (xy 426.27643 -397.309305) (xy 426.249134 -397.26067) (xy 426.229211 -397.208579)
			(xy 426.217085 -397.154142) (xy 426.213014 -397.09852) (xy 421.07104 -397.09852) (xy 421.07104 -397.651478)
			(xy 422.832274 -397.651478) (xy 422.836345 -397.595856) (xy 422.848471 -397.541419) (xy 422.868394 -397.489328)
			(xy 422.89569 -397.440693) (xy 422.929776 -397.39655) (xy 422.969925 -397.357841) (xy 423.015283 -397.32539)
			(xy 423.064883 -397.299889) (xy 423.117667 -397.281882) (xy 423.17251 -397.271752) (xy 423.228244 -397.269715)
			(xy 423.283681 -397.275815) (xy 423.337638 -397.289921) (xy 423.388967 -397.311733) (xy 423.436573 -397.340787)
			(xy 423.479441 -397.376462) (xy 423.516658 -397.417999) (xy 423.547431 -397.464512) (xy 423.571103 -397.515009)
			(xy 423.587171 -397.568416) (xy 423.595291 -397.623592) (xy 423.5958 -397.651478) (xy 423.595291 -397.679364)
			(xy 423.587171 -397.73454) (xy 423.571103 -397.787947) (xy 423.547431 -397.838444) (xy 423.516658 -397.884957)
			(xy 423.479441 -397.926494) (xy 423.436573 -397.962169) (xy 423.388967 -397.991223) (xy 423.337638 -398.013035)
			(xy 423.283681 -398.027141) (xy 423.228244 -398.033241) (xy 423.17251 -398.031204) (xy 423.117667 -398.021074)
			(xy 423.064883 -398.003067) (xy 423.015283 -397.977566) (xy 422.969925 -397.945115) (xy 422.929776 -397.906406)
			(xy 422.89569 -397.862263) (xy 422.868394 -397.813628) (xy 422.848471 -397.761537) (xy 422.836345 -397.7071)
			(xy 422.832274 -397.651478) (xy 421.07104 -397.651478) (xy 421.07104 -398.630648) (xy 424.219622 -398.630648)
			(xy 424.223693 -398.575026) (xy 424.235819 -398.520589) (xy 424.255742 -398.468498) (xy 424.283038 -398.419863)
			(xy 424.317124 -398.37572) (xy 424.357273 -398.337011) (xy 424.402631 -398.30456) (xy 424.452231 -398.279059)
			(xy 424.505015 -398.261052) (xy 424.559858 -398.250922) (xy 424.615592 -398.248885) (xy 424.671029 -398.254985)
			(xy 424.724986 -398.269091) (xy 424.776315 -398.290903) (xy 424.823921 -398.319957) (xy 424.866789 -398.355632)
			(xy 424.904006 -398.397169) (xy 424.934779 -398.443682) (xy 424.958451 -398.494179) (xy 424.974519 -398.547586)
			(xy 424.982639 -398.602762) (xy 424.983148 -398.630648) (xy 424.982639 -398.658534) (xy 424.974519 -398.71371)
			(xy 424.958451 -398.767117) (xy 424.934779 -398.817614) (xy 424.904006 -398.864127) (xy 424.866789 -398.905664)
			(xy 424.823921 -398.941339) (xy 424.776315 -398.970393) (xy 424.724986 -398.992205) (xy 424.671029 -399.006311)
			(xy 424.615592 -399.012411) (xy 424.559858 -399.010374) (xy 424.505015 -399.000244) (xy 424.452231 -398.982237)
			(xy 424.402631 -398.956736) (xy 424.357273 -398.924285) (xy 424.317124 -398.885576) (xy 424.283038 -398.841433)
			(xy 424.255742 -398.792798) (xy 424.235819 -398.740707) (xy 424.223693 -398.68627) (xy 424.219622 -398.630648)
			(xy 421.07104 -398.630648) (xy 421.07104 -402.671534) (xy 422.832274 -402.671534) (xy 422.836345 -402.615912)
			(xy 422.848471 -402.561475) (xy 422.868394 -402.509384) (xy 422.89569 -402.460749) (xy 422.929776 -402.416606)
			(xy 422.969925 -402.377897) (xy 423.015283 -402.345446) (xy 423.064883 -402.319945) (xy 423.117667 -402.301938)
			(xy 423.17251 -402.291808) (xy 423.228244 -402.289771) (xy 423.283681 -402.295871) (xy 423.337638 -402.309977)
			(xy 423.388967 -402.331789) (xy 423.436573 -402.360843) (xy 423.479441 -402.396518) (xy 423.516658 -402.438055)
			(xy 423.547431 -402.484568) (xy 423.571103 -402.535065) (xy 423.587171 -402.588472) (xy 423.595291 -402.643648)
			(xy 423.5958 -402.671534) (xy 424.869862 -402.671534) (xy 424.873933 -402.615912) (xy 424.886059 -402.561475)
			(xy 424.905982 -402.509384) (xy 424.933278 -402.460749) (xy 424.967364 -402.416606) (xy 425.007513 -402.377897)
			(xy 425.052871 -402.345446) (xy 425.102471 -402.319945) (xy 425.155255 -402.301938) (xy 425.210098 -402.291808)
			(xy 425.265832 -402.289771) (xy 425.321269 -402.295871) (xy 425.358177 -402.30552) (xy 426.213014 -402.30552)
			(xy 426.217085 -402.249898) (xy 426.229211 -402.195461) (xy 426.249134 -402.14337) (xy 426.27643 -402.094735)
			(xy 426.310516 -402.050592) (xy 426.350665 -402.011883) (xy 426.396023 -401.979432) (xy 426.445623 -401.953931)
			(xy 426.498407 -401.935924) (xy 426.55325 -401.925794) (xy 426.608984 -401.923757) (xy 426.664421 -401.929857)
			(xy 426.718378 -401.943963) (xy 426.769707 -401.965775) (xy 426.817313 -401.994829) (xy 426.860181 -402.030504)
			(xy 426.897398 -402.072041) (xy 426.928171 -402.118554) (xy 426.951843 -402.169051) (xy 426.967911 -402.222458)
			(xy 426.976031 -402.277634) (xy 426.976266 -402.290534) (xy 432.871624 -402.290534) (xy 432.875695 -402.234912)
			(xy 432.887821 -402.180475) (xy 432.907744 -402.128384) (xy 432.93504 -402.079749) (xy 432.969126 -402.035606)
			(xy 433.009275 -401.996897) (xy 433.054633 -401.964446) (xy 433.104233 -401.938945) (xy 433.157017 -401.920938)
			(xy 433.21186 -401.910808) (xy 433.267594 -401.908771) (xy 433.323031 -401.914871) (xy 433.376988 -401.928977)
			(xy 433.428317 -401.950789) (xy 433.475923 -401.979843) (xy 433.518791 -402.015518) (xy 433.556008 -402.057055)
			(xy 433.586781 -402.103568) (xy 433.610453 -402.154065) (xy 433.626521 -402.207472) (xy 433.634641 -402.262648)
			(xy 433.63515 -402.290534) (xy 433.634641 -402.31842) (xy 433.626521 -402.373596) (xy 433.610453 -402.427003)
			(xy 433.586781 -402.4775) (xy 433.556008 -402.524013) (xy 433.518791 -402.56555) (xy 433.475923 -402.601225)
			(xy 433.428317 -402.630279) (xy 433.376988 -402.652091) (xy 433.323031 -402.666197) (xy 433.267594 -402.672297)
			(xy 433.21186 -402.67026) (xy 433.157017 -402.66013) (xy 433.104233 -402.642123) (xy 433.054633 -402.616622)
			(xy 433.009275 -402.584171) (xy 432.969126 -402.545462) (xy 432.93504 -402.501319) (xy 432.907744 -402.452684)
			(xy 432.887821 -402.400593) (xy 432.875695 -402.346156) (xy 432.871624 -402.290534) (xy 426.976266 -402.290534)
			(xy 426.97654 -402.30552) (xy 426.976031 -402.333406) (xy 426.967911 -402.388582) (xy 426.951843 -402.441989)
			(xy 426.928171 -402.492486) (xy 426.897398 -402.538999) (xy 426.860181 -402.580536) (xy 426.817313 -402.616211)
			(xy 426.769707 -402.645265) (xy 426.718378 -402.667077) (xy 426.664421 -402.681183) (xy 426.608984 -402.687283)
			(xy 426.55325 -402.685246) (xy 426.498407 -402.675116) (xy 426.445623 -402.657109) (xy 426.396023 -402.631608)
			(xy 426.350665 -402.599157) (xy 426.310516 -402.560448) (xy 426.27643 -402.516305) (xy 426.249134 -402.46767)
			(xy 426.229211 -402.415579) (xy 426.217085 -402.361142) (xy 426.213014 -402.30552) (xy 425.358177 -402.30552)
			(xy 425.375226 -402.309977) (xy 425.426555 -402.331789) (xy 425.474161 -402.360843) (xy 425.517029 -402.396518)
			(xy 425.554246 -402.438055) (xy 425.585019 -402.484568) (xy 425.608691 -402.535065) (xy 425.624759 -402.588472)
			(xy 425.632879 -402.643648) (xy 425.633388 -402.671534) (xy 425.632879 -402.69942) (xy 425.624759 -402.754596)
			(xy 425.608691 -402.808003) (xy 425.585019 -402.8585) (xy 425.554246 -402.905013) (xy 425.517029 -402.94655)
			(xy 425.474161 -402.982225) (xy 425.426555 -403.011279) (xy 425.375226 -403.033091) (xy 425.321269 -403.047197)
			(xy 425.265832 -403.053297) (xy 425.210098 -403.05126) (xy 425.155255 -403.04113) (xy 425.102471 -403.023123)
			(xy 425.052871 -402.997622) (xy 425.007513 -402.965171) (xy 424.967364 -402.926462) (xy 424.933278 -402.882319)
			(xy 424.905982 -402.833684) (xy 424.886059 -402.781593) (xy 424.873933 -402.727156) (xy 424.869862 -402.671534)
			(xy 423.5958 -402.671534) (xy 423.595291 -402.69942) (xy 423.587171 -402.754596) (xy 423.571103 -402.808003)
			(xy 423.547431 -402.8585) (xy 423.516658 -402.905013) (xy 423.479441 -402.94655) (xy 423.436573 -402.982225)
			(xy 423.388967 -403.011279) (xy 423.337638 -403.033091) (xy 423.283681 -403.047197) (xy 423.228244 -403.053297)
			(xy 423.17251 -403.05126) (xy 423.117667 -403.04113) (xy 423.064883 -403.023123) (xy 423.015283 -402.997622)
			(xy 422.969925 -402.965171) (xy 422.929776 -402.926462) (xy 422.89569 -402.882319) (xy 422.868394 -402.833684)
			(xy 422.848471 -402.781593) (xy 422.836345 -402.727156) (xy 422.832274 -402.671534) (xy 421.07104 -402.671534)
			(xy 421.07104 -403.997668) (xy 425.888402 -403.997668) (xy 425.892473 -403.942046) (xy 425.904599 -403.887609)
			(xy 425.924522 -403.835518) (xy 425.951818 -403.786883) (xy 425.985904 -403.74274) (xy 426.026053 -403.704031)
			(xy 426.071411 -403.67158) (xy 426.121011 -403.646079) (xy 426.173795 -403.628072) (xy 426.228638 -403.617942)
			(xy 426.284372 -403.615905) (xy 426.339809 -403.622005) (xy 426.393766 -403.636111) (xy 426.445095 -403.657923)
			(xy 426.492701 -403.686977) (xy 426.535569 -403.722652) (xy 426.572786 -403.764189) (xy 426.603559 -403.810702)
			(xy 426.627231 -403.861199) (xy 426.643299 -403.914606) (xy 426.651419 -403.969782) (xy 426.651928 -403.997668)
			(xy 426.651419 -404.025554) (xy 426.643299 -404.08073) (xy 426.627231 -404.134137) (xy 426.603559 -404.184634)
			(xy 426.572786 -404.231147) (xy 426.535569 -404.272684) (xy 426.492701 -404.308359) (xy 426.445095 -404.337413)
			(xy 426.393766 -404.359225) (xy 426.339809 -404.373331) (xy 426.284372 -404.379431) (xy 426.228638 -404.377394)
			(xy 426.173795 -404.367264) (xy 426.121011 -404.349257) (xy 426.071411 -404.323756) (xy 426.026053 -404.291305)
			(xy 425.985904 -404.252596) (xy 425.951818 -404.208453) (xy 425.924522 -404.159818) (xy 425.904599 -404.107727)
			(xy 425.892473 -404.05329) (xy 425.888402 -403.997668) (xy 421.07104 -403.997668) (xy 421.07104 -409.837128)
			(xy 420.036244 -410.871924) (xy 420.03472 -410.873956) (xy 420.024242 -410.886422) (xy 420.001212 -410.909451)
			(xy 419.988746 -410.91993) (xy 419.986714 -410.921454) (xy 419.67404 -411.234128) (xy 371.62232 -411.234128)
			(xy 370.45138 -410.063188) (xy 370.45138 -401.040346) (xy 370.450618 -401.035774) (xy 370.443113 -400.991772)
			(xy 370.435103 -400.902863) (xy 370.434616 -400.858228) (xy 370.435086 -400.813592) (xy 370.443096 -400.724682)
			(xy 370.450618 -400.680682) (xy 370.45138 -400.67611) (xy 370.45138 -398.00149) (xy 370.450899 -397.986151)
			(xy 370.441881 -397.956831) (xy 370.424569 -397.931507) (xy 370.400523 -397.91246) (xy 370.371908 -397.901406)
			(xy 370.356638 -397.89989) (xy 370.32944 -397.897552) (xy 370.276071 -397.886081) (xy 370.224882 -397.867119)
			(xy 370.176919 -397.841051) (xy 370.133163 -397.808412) (xy 370.094508 -397.769868) (xy 370.061743 -397.726206)
			(xy 370.035538 -397.678319) (xy 370.016428 -397.627185) (xy 370.004803 -397.573849) (xy 370.000902 -397.5194)
			(xy 370.004803 -397.464951) (xy 370.016428 -397.411615) (xy 370.035538 -397.360481) (xy 370.061743 -397.312594)
			(xy 370.094508 -397.268932) (xy 370.133164 -397.230388) (xy 370.17692 -397.197749) (xy 370.224882 -397.171681)
			(xy 370.276071 -397.152719) (xy 370.32944 -397.141248) (xy 370.356638 -397.138906) (xy 370.371905 -397.137352)
			(xy 370.400522 -397.126305) (xy 370.424575 -397.107269) (xy 370.441902 -397.081956) (xy 370.450942 -397.052644)
			(xy 370.45138 -397.037306) (xy 370.45138 -396.73149) (xy 370.450899 -396.716151) (xy 370.441881 -396.686831)
			(xy 370.424569 -396.661507) (xy 370.400523 -396.64246) (xy 370.371908 -396.631406) (xy 370.356638 -396.62989)
			(xy 370.32808 -396.627404) (xy 370.272126 -396.614949) (xy 370.218665 -396.594265) (xy 370.168899 -396.565818)
			(xy 370.123947 -396.530246) (xy 370.084823 -396.488351) (xy 370.052405 -396.441075) (xy 370.027422 -396.389482)
			(xy 370.010439 -396.334733) (xy 370.001835 -396.278059) (xy 370.001292 -396.249398) (xy 370.001778 -396.222147)
			(xy 370.009535 -396.168199) (xy 370.02489 -396.115905) (xy 370.047531 -396.066328) (xy 370.076998 -396.020478)
			(xy 370.112689 -395.979288) (xy 370.153879 -395.943596) (xy 370.19973 -395.91413) (xy 370.249307 -395.891489)
			(xy 370.301601 -395.876134) (xy 370.355549 -395.868378) (xy 370.3828 -395.86789) (xy 370.412349 -395.868444)
			(xy 370.470739 -395.877557) (xy 370.527026 -395.895565) (xy 370.579863 -395.922037) (xy 370.627986 -395.95634)
			(xy 370.6495 -395.976602) (xy 370.659252 -395.985516) (xy 370.682262 -395.998479) (xy 370.707826 -396.005113)
			(xy 370.734237 -396.004975) (xy 370.75973 -395.998073) (xy 370.782603 -395.984869) (xy 370.792248 -395.97584)
			(xy 371.44452 -395.323568) (xy 371.44452 -384.033268) (xy 370.32438 -382.913128) (xy 356.42804 -382.913128)
			(xy 354.166678 -385.17449) (xy 356.068882 -385.17449) (xy 356.072953 -385.118868) (xy 356.085079 -385.064431)
			(xy 356.105002 -385.01234) (xy 356.132298 -384.963705) (xy 356.166384 -384.919562) (xy 356.206533 -384.880853)
			(xy 356.251891 -384.848402) (xy 356.301491 -384.822901) (xy 356.354275 -384.804894) (xy 356.409118 -384.794764)
			(xy 356.464852 -384.792727) (xy 356.520289 -384.798827) (xy 356.574246 -384.812933) (xy 356.625575 -384.834745)
			(xy 356.673181 -384.863799) (xy 356.716049 -384.899474) (xy 356.753266 -384.941011) (xy 356.784039 -384.987524)
			(xy 356.807711 -385.038021) (xy 356.823779 -385.091428) (xy 356.831899 -385.146604) (xy 356.832408 -385.17449)
			(xy 356.831899 -385.202376) (xy 356.823779 -385.257552) (xy 356.807711 -385.310959) (xy 356.784039 -385.361456)
			(xy 356.753266 -385.407969) (xy 356.716049 -385.449506) (xy 356.673181 -385.485181) (xy 356.625575 -385.514235)
			(xy 356.574246 -385.536047) (xy 356.520289 -385.550153) (xy 356.464852 -385.556253) (xy 356.409118 -385.554216)
			(xy 356.354275 -385.544086) (xy 356.301491 -385.526079) (xy 356.251891 -385.500578) (xy 356.206533 -385.468127)
			(xy 356.166384 -385.429418) (xy 356.132298 -385.385275) (xy 356.105002 -385.33664) (xy 356.085079 -385.284549)
			(xy 356.072953 -385.230112) (xy 356.068882 -385.17449) (xy 354.166678 -385.17449) (xy 354.01504 -385.326128)
			(xy 354.01504 -385.790948) (xy 355.273862 -385.790948) (xy 355.277933 -385.735326) (xy 355.290059 -385.680889)
			(xy 355.309982 -385.628798) (xy 355.337278 -385.580163) (xy 355.371364 -385.53602) (xy 355.411513 -385.497311)
			(xy 355.456871 -385.46486) (xy 355.506471 -385.439359) (xy 355.559255 -385.421352) (xy 355.614098 -385.411222)
			(xy 355.669832 -385.409185) (xy 355.725269 -385.415285) (xy 355.779226 -385.429391) (xy 355.830555 -385.451203)
			(xy 355.878161 -385.480257) (xy 355.921029 -385.515932) (xy 355.958246 -385.557469) (xy 355.989019 -385.603982)
			(xy 356.012691 -385.654479) (xy 356.028759 -385.707886) (xy 356.036879 -385.763062) (xy 356.037388 -385.790948)
			(xy 356.036879 -385.818834) (xy 356.028759 -385.87401) (xy 356.012691 -385.927417) (xy 355.989019 -385.977914)
			(xy 355.958246 -386.024427) (xy 355.921029 -386.065964) (xy 355.878161 -386.101639) (xy 355.830555 -386.130693)
			(xy 355.779226 -386.152505) (xy 355.725269 -386.166611) (xy 355.669832 -386.172711) (xy 355.614098 -386.170674)
			(xy 355.559255 -386.160544) (xy 355.506471 -386.142537) (xy 355.456871 -386.117036) (xy 355.411513 -386.084585)
			(xy 355.371364 -386.045876) (xy 355.337278 -386.001733) (xy 355.309982 -385.953098) (xy 355.290059 -385.901007)
			(xy 355.277933 -385.84657) (xy 355.273862 -385.790948) (xy 354.01504 -385.790948) (xy 354.01504 -386.41909)
			(xy 356.068882 -386.41909) (xy 356.072953 -386.363468) (xy 356.085079 -386.309031) (xy 356.105002 -386.25694)
			(xy 356.132298 -386.208305) (xy 356.166384 -386.164162) (xy 356.206533 -386.125453) (xy 356.251891 -386.093002)
			(xy 356.301491 -386.067501) (xy 356.354275 -386.049494) (xy 356.409118 -386.039364) (xy 356.464852 -386.037327)
			(xy 356.520289 -386.043427) (xy 356.574246 -386.057533) (xy 356.625575 -386.079345) (xy 356.673181 -386.108399)
			(xy 356.716049 -386.144074) (xy 356.753266 -386.185611) (xy 356.784039 -386.232124) (xy 356.807711 -386.282621)
			(xy 356.823779 -386.336028) (xy 356.831899 -386.391204) (xy 356.832408 -386.41909) (xy 356.831899 -386.446976)
			(xy 356.828527 -386.46989) (xy 361.827062 -386.46989) (xy 361.831133 -386.414268) (xy 361.843259 -386.359831)
			(xy 361.863182 -386.30774) (xy 361.890478 -386.259105) (xy 361.924564 -386.214962) (xy 361.964713 -386.176253)
			(xy 362.010071 -386.143802) (xy 362.059671 -386.118301) (xy 362.112455 -386.100294) (xy 362.167298 -386.090164)
			(xy 362.223032 -386.088127) (xy 362.278469 -386.094227) (xy 362.332426 -386.108333) (xy 362.383755 -386.130145)
			(xy 362.431361 -386.159199) (xy 362.474229 -386.194874) (xy 362.511446 -386.236411) (xy 362.542219 -386.282924)
			(xy 362.565891 -386.333421) (xy 362.577681 -386.372608) (xy 364.445802 -386.372608) (xy 364.449873 -386.316986)
			(xy 364.461999 -386.262549) (xy 364.481922 -386.210458) (xy 364.509218 -386.161823) (xy 364.543304 -386.11768)
			(xy 364.583453 -386.078971) (xy 364.628811 -386.04652) (xy 364.678411 -386.021019) (xy 364.731195 -386.003012)
			(xy 364.786038 -385.992882) (xy 364.841772 -385.990845) (xy 364.897209 -385.996945) (xy 364.951166 -386.011051)
			(xy 365.002495 -386.032863) (xy 365.050101 -386.061917) (xy 365.092969 -386.097592) (xy 365.130186 -386.139129)
			(xy 365.160959 -386.185642) (xy 365.184631 -386.236139) (xy 365.200699 -386.289546) (xy 365.208819 -386.344722)
			(xy 365.209328 -386.372608) (xy 365.208819 -386.400494) (xy 365.200699 -386.45567) (xy 365.184631 -386.509077)
			(xy 365.160959 -386.559574) (xy 365.130186 -386.606087) (xy 365.092969 -386.647624) (xy 365.050101 -386.683299)
			(xy 365.002495 -386.712353) (xy 364.951166 -386.734165) (xy 364.897209 -386.748271) (xy 364.841772 -386.754371)
			(xy 364.786038 -386.752334) (xy 364.731195 -386.742204) (xy 364.678411 -386.724197) (xy 364.628811 -386.698696)
			(xy 364.583453 -386.666245) (xy 364.543304 -386.627536) (xy 364.509218 -386.583393) (xy 364.481922 -386.534758)
			(xy 364.461999 -386.482667) (xy 364.449873 -386.42823) (xy 364.445802 -386.372608) (xy 362.577681 -386.372608)
			(xy 362.581959 -386.386828) (xy 362.590079 -386.442004) (xy 362.590588 -386.46989) (xy 362.590079 -386.497776)
			(xy 362.581959 -386.552952) (xy 362.565891 -386.606359) (xy 362.542219 -386.656856) (xy 362.511446 -386.703369)
			(xy 362.474229 -386.744906) (xy 362.431361 -386.780581) (xy 362.383755 -386.809635) (xy 362.332426 -386.831447)
			(xy 362.278469 -386.845553) (xy 362.223032 -386.851653) (xy 362.167298 -386.849616) (xy 362.112455 -386.839486)
			(xy 362.059671 -386.821479) (xy 362.010071 -386.795978) (xy 361.964713 -386.763527) (xy 361.924564 -386.724818)
			(xy 361.890478 -386.680675) (xy 361.863182 -386.63204) (xy 361.843259 -386.579949) (xy 361.831133 -386.525512)
			(xy 361.827062 -386.46989) (xy 356.828527 -386.46989) (xy 356.823779 -386.502152) (xy 356.807711 -386.555559)
			(xy 356.784039 -386.606056) (xy 356.753266 -386.652569) (xy 356.716049 -386.694106) (xy 356.673181 -386.729781)
			(xy 356.625575 -386.758835) (xy 356.574246 -386.780647) (xy 356.520289 -386.794753) (xy 356.464852 -386.800853)
			(xy 356.409118 -386.798816) (xy 356.354275 -386.788686) (xy 356.301491 -386.770679) (xy 356.251891 -386.745178)
			(xy 356.206533 -386.712727) (xy 356.166384 -386.674018) (xy 356.132298 -386.629875) (xy 356.105002 -386.58124)
			(xy 356.085079 -386.529149) (xy 356.072953 -386.474712) (xy 356.068882 -386.41909) (xy 354.01504 -386.41909)
			(xy 354.01504 -388.330948) (xy 357.566974 -388.330948) (xy 357.571045 -388.275326) (xy 357.583171 -388.220889)
			(xy 357.603094 -388.168798) (xy 357.63039 -388.120163) (xy 357.664476 -388.07602) (xy 357.704625 -388.037311)
			(xy 357.749983 -388.00486) (xy 357.799583 -387.979359) (xy 357.852367 -387.961352) (xy 357.90721 -387.951222)
			(xy 357.962944 -387.949185) (xy 358.018381 -387.955285) (xy 358.072338 -387.969391) (xy 358.123667 -387.991203)
			(xy 358.171273 -388.020257) (xy 358.214141 -388.055932) (xy 358.251358 -388.097469) (xy 358.282131 -388.143982)
			(xy 358.305803 -388.194479) (xy 358.321871 -388.247886) (xy 358.329991 -388.303062) (xy 358.3305 -388.330948)
			(xy 358.329991 -388.358834) (xy 358.321871 -388.41401) (xy 358.305803 -388.467417) (xy 358.282131 -388.517914)
			(xy 358.251358 -388.564427) (xy 358.214141 -388.605964) (xy 358.171273 -388.641639) (xy 358.123667 -388.670693)
			(xy 358.072338 -388.692505) (xy 358.018381 -388.706611) (xy 357.962944 -388.712711) (xy 357.90721 -388.710674)
			(xy 357.852367 -388.700544) (xy 357.799583 -388.682537) (xy 357.749983 -388.657036) (xy 357.704625 -388.624585)
			(xy 357.664476 -388.585876) (xy 357.63039 -388.541733) (xy 357.603094 -388.493098) (xy 357.583171 -388.441007)
			(xy 357.571045 -388.38657) (xy 357.566974 -388.330948) (xy 354.01504 -388.330948) (xy 354.01504 -389.19277)
			(xy 356.129842 -389.19277) (xy 356.133913 -389.137148) (xy 356.146039 -389.082711) (xy 356.165962 -389.03062)
			(xy 356.193258 -388.981985) (xy 356.227344 -388.937842) (xy 356.267493 -388.899133) (xy 356.312851 -388.866682)
			(xy 356.362451 -388.841181) (xy 356.415235 -388.823174) (xy 356.470078 -388.813044) (xy 356.525812 -388.811007)
			(xy 356.581249 -388.817107) (xy 356.635206 -388.831213) (xy 356.686535 -388.853025) (xy 356.734141 -388.882079)
			(xy 356.777009 -388.917754) (xy 356.814226 -388.959291) (xy 356.844999 -389.005804) (xy 356.868671 -389.056301)
			(xy 356.884739 -389.109708) (xy 356.892859 -389.164884) (xy 356.893368 -389.19277) (xy 356.892859 -389.220656)
			(xy 356.884739 -389.275832) (xy 356.868671 -389.329239) (xy 356.844999 -389.379736) (xy 356.814226 -389.426249)
			(xy 356.777009 -389.467786) (xy 356.734141 -389.503461) (xy 356.686535 -389.532515) (xy 356.635206 -389.554327)
			(xy 356.581249 -389.568433) (xy 356.525812 -389.574533) (xy 356.470078 -389.572496) (xy 356.415235 -389.562366)
			(xy 356.362451 -389.544359) (xy 356.312851 -389.518858) (xy 356.267493 -389.486407) (xy 356.227344 -389.447698)
			(xy 356.193258 -389.403555) (xy 356.165962 -389.35492) (xy 356.146039 -389.302829) (xy 356.133913 -389.248392)
			(xy 356.129842 -389.19277) (xy 354.01504 -389.19277) (xy 354.01504 -390.43737) (xy 356.129842 -390.43737)
			(xy 356.133913 -390.381748) (xy 356.146039 -390.327311) (xy 356.165962 -390.27522) (xy 356.193258 -390.226585)
			(xy 356.227344 -390.182442) (xy 356.267493 -390.143733) (xy 356.312851 -390.111282) (xy 356.362451 -390.085781)
			(xy 356.415235 -390.067774) (xy 356.470078 -390.057644) (xy 356.525812 -390.055607) (xy 356.581249 -390.061707)
			(xy 356.635206 -390.075813) (xy 356.686535 -390.097625) (xy 356.734141 -390.126679) (xy 356.777009 -390.162354)
			(xy 356.814226 -390.203891) (xy 356.844999 -390.250404) (xy 356.868671 -390.300901) (xy 356.884739 -390.354308)
			(xy 356.892859 -390.409484) (xy 356.893368 -390.43737) (xy 356.892859 -390.465256) (xy 356.889487 -390.48817)
			(xy 362.106462 -390.48817) (xy 362.110533 -390.432548) (xy 362.122659 -390.378111) (xy 362.142582 -390.32602)
			(xy 362.169878 -390.277385) (xy 362.203964 -390.233242) (xy 362.244113 -390.194533) (xy 362.289471 -390.162082)
			(xy 362.339071 -390.136581) (xy 362.391855 -390.118574) (xy 362.446698 -390.108444) (xy 362.502432 -390.106407)
			(xy 362.557869 -390.112507) (xy 362.611826 -390.126613) (xy 362.663155 -390.148425) (xy 362.710761 -390.177479)
			(xy 362.753629 -390.213154) (xy 362.790846 -390.254691) (xy 362.821619 -390.301204) (xy 362.845291 -390.351701)
			(xy 362.857081 -390.390888) (xy 364.506762 -390.390888) (xy 364.510833 -390.335266) (xy 364.522959 -390.280829)
			(xy 364.542882 -390.228738) (xy 364.570178 -390.180103) (xy 364.604264 -390.13596) (xy 364.644413 -390.097251)
			(xy 364.689771 -390.0648) (xy 364.739371 -390.039299) (xy 364.792155 -390.021292) (xy 364.846998 -390.011162)
			(xy 364.902732 -390.009125) (xy 364.958169 -390.015225) (xy 365.012126 -390.029331) (xy 365.063455 -390.051143)
			(xy 365.111061 -390.080197) (xy 365.153929 -390.115872) (xy 365.191146 -390.157409) (xy 365.221919 -390.203922)
			(xy 365.245591 -390.254419) (xy 365.261659 -390.307826) (xy 365.269779 -390.363002) (xy 365.270288 -390.390888)
			(xy 365.269779 -390.418774) (xy 365.261659 -390.47395) (xy 365.245591 -390.527357) (xy 365.221919 -390.577854)
			(xy 365.191146 -390.624367) (xy 365.153929 -390.665904) (xy 365.111061 -390.701579) (xy 365.063455 -390.730633)
			(xy 365.012126 -390.752445) (xy 364.958169 -390.766551) (xy 364.902732 -390.772651) (xy 364.846998 -390.770614)
			(xy 364.792155 -390.760484) (xy 364.739371 -390.742477) (xy 364.689771 -390.716976) (xy 364.644413 -390.684525)
			(xy 364.604264 -390.645816) (xy 364.570178 -390.601673) (xy 364.542882 -390.553038) (xy 364.522959 -390.500947)
			(xy 364.510833 -390.44651) (xy 364.506762 -390.390888) (xy 362.857081 -390.390888) (xy 362.861359 -390.405108)
			(xy 362.869479 -390.460284) (xy 362.869988 -390.48817) (xy 362.869479 -390.516056) (xy 362.861359 -390.571232)
			(xy 362.845291 -390.624639) (xy 362.821619 -390.675136) (xy 362.790846 -390.721649) (xy 362.753629 -390.763186)
			(xy 362.710761 -390.798861) (xy 362.663155 -390.827915) (xy 362.611826 -390.849727) (xy 362.557869 -390.863833)
			(xy 362.502432 -390.869933) (xy 362.446698 -390.867896) (xy 362.391855 -390.857766) (xy 362.339071 -390.839759)
			(xy 362.289471 -390.814258) (xy 362.244113 -390.781807) (xy 362.203964 -390.743098) (xy 362.169878 -390.698955)
			(xy 362.142582 -390.65032) (xy 362.122659 -390.598229) (xy 362.110533 -390.543792) (xy 362.106462 -390.48817)
			(xy 356.889487 -390.48817) (xy 356.884739 -390.520432) (xy 356.868671 -390.573839) (xy 356.844999 -390.624336)
			(xy 356.814226 -390.670849) (xy 356.777009 -390.712386) (xy 356.734141 -390.748061) (xy 356.686535 -390.777115)
			(xy 356.635206 -390.798927) (xy 356.581249 -390.813033) (xy 356.525812 -390.819133) (xy 356.470078 -390.817096)
			(xy 356.415235 -390.806966) (xy 356.362451 -390.788959) (xy 356.312851 -390.763458) (xy 356.267493 -390.731007)
			(xy 356.227344 -390.692298) (xy 356.193258 -390.648155) (xy 356.165962 -390.59952) (xy 356.146039 -390.547429)
			(xy 356.133913 -390.492992) (xy 356.129842 -390.43737) (xy 354.01504 -390.43737) (xy 354.01504 -392.008868)
			(xy 355.258622 -392.008868) (xy 355.262693 -391.953246) (xy 355.274819 -391.898809) (xy 355.294742 -391.846718)
			(xy 355.322038 -391.798083) (xy 355.356124 -391.75394) (xy 355.396273 -391.715231) (xy 355.441631 -391.68278)
			(xy 355.491231 -391.657279) (xy 355.544015 -391.639272) (xy 355.598858 -391.629142) (xy 355.654592 -391.627105)
			(xy 355.710029 -391.633205) (xy 355.763986 -391.647311) (xy 355.815315 -391.669123) (xy 355.862921 -391.698177)
			(xy 355.905789 -391.733852) (xy 355.943006 -391.775389) (xy 355.973779 -391.821902) (xy 355.997451 -391.872399)
			(xy 356.013519 -391.925806) (xy 356.021639 -391.980982) (xy 356.022148 -392.008868) (xy 356.021639 -392.036754)
			(xy 356.020771 -392.04265) (xy 356.167942 -392.04265) (xy 356.172013 -391.987028) (xy 356.184139 -391.932591)
			(xy 356.204062 -391.8805) (xy 356.231358 -391.831865) (xy 356.265444 -391.787722) (xy 356.305593 -391.749013)
			(xy 356.350951 -391.716562) (xy 356.400551 -391.691061) (xy 356.453335 -391.673054) (xy 356.508178 -391.662924)
			(xy 356.563912 -391.660887) (xy 356.619349 -391.666987) (xy 356.673306 -391.681093) (xy 356.724635 -391.702905)
			(xy 356.772241 -391.731959) (xy 356.815109 -391.767634) (xy 356.852326 -391.809171) (xy 356.883099 -391.855684)
			(xy 356.906771 -391.906181) (xy 356.922839 -391.959588) (xy 356.930959 -392.014764) (xy 356.931468 -392.04265)
			(xy 356.930959 -392.070536) (xy 356.922839 -392.125712) (xy 356.906771 -392.179119) (xy 356.883099 -392.229616)
			(xy 356.852326 -392.276129) (xy 356.815109 -392.317666) (xy 356.772241 -392.353341) (xy 356.724635 -392.382395)
			(xy 356.673306 -392.404207) (xy 356.619349 -392.418313) (xy 356.563912 -392.424413) (xy 356.508178 -392.422376)
			(xy 356.453335 -392.412246) (xy 356.400551 -392.394239) (xy 356.350951 -392.368738) (xy 356.305593 -392.336287)
			(xy 356.265444 -392.297578) (xy 356.231358 -392.253435) (xy 356.204062 -392.2048) (xy 356.184139 -392.152709)
			(xy 356.172013 -392.098272) (xy 356.167942 -392.04265) (xy 356.020771 -392.04265) (xy 356.013519 -392.09193)
			(xy 355.997451 -392.145337) (xy 355.973779 -392.195834) (xy 355.943006 -392.242347) (xy 355.905789 -392.283884)
			(xy 355.862921 -392.319559) (xy 355.815315 -392.348613) (xy 355.763986 -392.370425) (xy 355.710029 -392.384531)
			(xy 355.654592 -392.390631) (xy 355.598858 -392.388594) (xy 355.544015 -392.378464) (xy 355.491231 -392.360457)
			(xy 355.441631 -392.334956) (xy 355.396273 -392.302505) (xy 355.356124 -392.263796) (xy 355.322038 -392.219653)
			(xy 355.294742 -392.171018) (xy 355.274819 -392.118927) (xy 355.262693 -392.06449) (xy 355.258622 -392.008868)
			(xy 354.01504 -392.008868) (xy 354.01504 -393.28725) (xy 356.167942 -393.28725) (xy 356.172013 -393.231628)
			(xy 356.184139 -393.177191) (xy 356.204062 -393.1251) (xy 356.231358 -393.076465) (xy 356.265444 -393.032322)
			(xy 356.305593 -392.993613) (xy 356.350951 -392.961162) (xy 356.400551 -392.935661) (xy 356.453335 -392.917654)
			(xy 356.508178 -392.907524) (xy 356.563912 -392.905487) (xy 356.619349 -392.911587) (xy 356.673306 -392.925693)
			(xy 356.724635 -392.947505) (xy 356.772241 -392.976559) (xy 356.815109 -393.012234) (xy 356.852326 -393.053771)
			(xy 356.883099 -393.100284) (xy 356.906771 -393.150781) (xy 356.922839 -393.204188) (xy 356.930959 -393.259364)
			(xy 356.931468 -393.28725) (xy 356.930959 -393.315136) (xy 356.927587 -393.33805) (xy 362.157262 -393.33805)
			(xy 362.161333 -393.282428) (xy 362.173459 -393.227991) (xy 362.193382 -393.1759) (xy 362.220678 -393.127265)
			(xy 362.254764 -393.083122) (xy 362.294913 -393.044413) (xy 362.340271 -393.011962) (xy 362.389871 -392.986461)
			(xy 362.442655 -392.968454) (xy 362.497498 -392.958324) (xy 362.553232 -392.956287) (xy 362.608669 -392.962387)
			(xy 362.662626 -392.976493) (xy 362.713955 -392.998305) (xy 362.761561 -393.027359) (xy 362.804429 -393.063034)
			(xy 362.841646 -393.104571) (xy 362.872419 -393.151084) (xy 362.896091 -393.201581) (xy 362.907881 -393.240768)
			(xy 364.544862 -393.240768) (xy 364.548933 -393.185146) (xy 364.561059 -393.130709) (xy 364.580982 -393.078618)
			(xy 364.608278 -393.029983) (xy 364.642364 -392.98584) (xy 364.682513 -392.947131) (xy 364.727871 -392.91468)
			(xy 364.777471 -392.889179) (xy 364.830255 -392.871172) (xy 364.885098 -392.861042) (xy 364.940832 -392.859005)
			(xy 364.996269 -392.865105) (xy 365.050226 -392.879211) (xy 365.101555 -392.901023) (xy 365.149161 -392.930077)
			(xy 365.192029 -392.965752) (xy 365.229246 -393.007289) (xy 365.260019 -393.053802) (xy 365.283691 -393.104299)
			(xy 365.299759 -393.157706) (xy 365.307879 -393.212882) (xy 365.308388 -393.240768) (xy 365.307879 -393.268654)
			(xy 365.299759 -393.32383) (xy 365.283691 -393.377237) (xy 365.260019 -393.427734) (xy 365.229246 -393.474247)
			(xy 365.192029 -393.515784) (xy 365.149161 -393.551459) (xy 365.101555 -393.580513) (xy 365.050226 -393.602325)
			(xy 364.996269 -393.616431) (xy 364.940832 -393.622531) (xy 364.885098 -393.620494) (xy 364.830255 -393.610364)
			(xy 364.777471 -393.592357) (xy 364.727871 -393.566856) (xy 364.682513 -393.534405) (xy 364.642364 -393.495696)
			(xy 364.608278 -393.451553) (xy 364.580982 -393.402918) (xy 364.561059 -393.350827) (xy 364.548933 -393.29639)
			(xy 364.544862 -393.240768) (xy 362.907881 -393.240768) (xy 362.912159 -393.254988) (xy 362.920279 -393.310164)
			(xy 362.920788 -393.33805) (xy 362.920279 -393.365936) (xy 362.912159 -393.421112) (xy 362.896091 -393.474519)
			(xy 362.872419 -393.525016) (xy 362.841646 -393.571529) (xy 362.804429 -393.613066) (xy 362.761561 -393.648741)
			(xy 362.713955 -393.677795) (xy 362.662626 -393.699607) (xy 362.608669 -393.713713) (xy 362.553232 -393.719813)
			(xy 362.497498 -393.717776) (xy 362.442655 -393.707646) (xy 362.389871 -393.689639) (xy 362.340271 -393.664138)
			(xy 362.294913 -393.631687) (xy 362.254764 -393.592978) (xy 362.220678 -393.548835) (xy 362.193382 -393.5002)
			(xy 362.173459 -393.448109) (xy 362.161333 -393.393672) (xy 362.157262 -393.33805) (xy 356.927587 -393.33805)
			(xy 356.922839 -393.370312) (xy 356.906771 -393.423719) (xy 356.883099 -393.474216) (xy 356.852326 -393.520729)
			(xy 356.815109 -393.562266) (xy 356.772241 -393.597941) (xy 356.724635 -393.626995) (xy 356.673306 -393.648807)
			(xy 356.619349 -393.662913) (xy 356.563912 -393.669013) (xy 356.508178 -393.666976) (xy 356.453335 -393.656846)
			(xy 356.400551 -393.638839) (xy 356.350951 -393.613338) (xy 356.305593 -393.580887) (xy 356.265444 -393.542178)
			(xy 356.231358 -393.498035) (xy 356.204062 -393.4494) (xy 356.184139 -393.397309) (xy 356.172013 -393.342872)
			(xy 356.167942 -393.28725) (xy 354.01504 -393.28725) (xy 354.01504 -395.618208) (xy 357.107742 -395.618208)
			(xy 357.111813 -395.562586) (xy 357.123939 -395.508149) (xy 357.143862 -395.456058) (xy 357.171158 -395.407423)
			(xy 357.205244 -395.36328) (xy 357.245393 -395.324571) (xy 357.290751 -395.29212) (xy 357.340351 -395.266619)
			(xy 357.393135 -395.248612) (xy 357.447978 -395.238482) (xy 357.503712 -395.236445) (xy 357.559149 -395.242545)
			(xy 357.613106 -395.256651) (xy 357.664435 -395.278463) (xy 357.712041 -395.307517) (xy 357.754909 -395.343192)
			(xy 357.792126 -395.384729) (xy 357.797034 -395.392148) (xy 361.725462 -395.392148) (xy 361.729533 -395.336526)
			(xy 361.741659 -395.282089) (xy 361.761582 -395.229998) (xy 361.788878 -395.181363) (xy 361.822964 -395.13722)
			(xy 361.863113 -395.098511) (xy 361.908471 -395.06606) (xy 361.958071 -395.040559) (xy 362.010855 -395.022552)
			(xy 362.065698 -395.012422) (xy 362.121432 -395.010385) (xy 362.176869 -395.016485) (xy 362.230826 -395.030591)
			(xy 362.282155 -395.052403) (xy 362.329761 -395.081457) (xy 362.372629 -395.117132) (xy 362.409846 -395.158669)
			(xy 362.440619 -395.205182) (xy 362.464291 -395.255679) (xy 362.46714 -395.265148) (xy 367.567462 -395.265148)
			(xy 367.571533 -395.209526) (xy 367.583659 -395.155089) (xy 367.603582 -395.102998) (xy 367.630878 -395.054363)
			(xy 367.664964 -395.01022) (xy 367.705113 -394.971511) (xy 367.750471 -394.93906) (xy 367.800071 -394.913559)
			(xy 367.852855 -394.895552) (xy 367.907698 -394.885422) (xy 367.963432 -394.883385) (xy 368.018869 -394.889485)
			(xy 368.072826 -394.903591) (xy 368.124155 -394.925403) (xy 368.171761 -394.954457) (xy 368.214629 -394.990132)
			(xy 368.251846 -395.031669) (xy 368.282619 -395.078182) (xy 368.306291 -395.128679) (xy 368.322359 -395.182086)
			(xy 368.330479 -395.237262) (xy 368.330988 -395.265148) (xy 368.330479 -395.293034) (xy 368.322359 -395.34821)
			(xy 368.306291 -395.401617) (xy 368.282619 -395.452114) (xy 368.251846 -395.498627) (xy 368.214629 -395.540164)
			(xy 368.171761 -395.575839) (xy 368.124155 -395.604893) (xy 368.072826 -395.626705) (xy 368.018869 -395.640811)
			(xy 367.963432 -395.646911) (xy 367.907698 -395.644874) (xy 367.852855 -395.634744) (xy 367.800071 -395.616737)
			(xy 367.750471 -395.591236) (xy 367.705113 -395.558785) (xy 367.664964 -395.520076) (xy 367.630878 -395.475933)
			(xy 367.603582 -395.427298) (xy 367.583659 -395.375207) (xy 367.571533 -395.32077) (xy 367.567462 -395.265148)
			(xy 362.46714 -395.265148) (xy 362.480359 -395.309086) (xy 362.488479 -395.364262) (xy 362.488988 -395.392148)
			(xy 362.488479 -395.420034) (xy 362.480359 -395.47521) (xy 362.464291 -395.528617) (xy 362.440619 -395.579114)
			(xy 362.409846 -395.625627) (xy 362.372629 -395.667164) (xy 362.329761 -395.702839) (xy 362.282155 -395.731893)
			(xy 362.230826 -395.753705) (xy 362.176869 -395.767811) (xy 362.121432 -395.773911) (xy 362.065698 -395.771874)
			(xy 362.010855 -395.761744) (xy 361.958071 -395.743737) (xy 361.908471 -395.718236) (xy 361.863113 -395.685785)
			(xy 361.822964 -395.647076) (xy 361.788878 -395.602933) (xy 361.761582 -395.554298) (xy 361.741659 -395.502207)
			(xy 361.729533 -395.44777) (xy 361.725462 -395.392148) (xy 357.797034 -395.392148) (xy 357.822899 -395.431242)
			(xy 357.846571 -395.481739) (xy 357.862639 -395.535146) (xy 357.870759 -395.590322) (xy 357.871268 -395.618208)
			(xy 357.870759 -395.646094) (xy 357.862639 -395.70127) (xy 357.846571 -395.754677) (xy 357.822899 -395.805174)
			(xy 357.792126 -395.851687) (xy 357.754909 -395.893224) (xy 357.712041 -395.928899) (xy 357.664435 -395.957953)
			(xy 357.613106 -395.979765) (xy 357.559149 -395.993871) (xy 357.503712 -395.999971) (xy 357.447978 -395.997934)
			(xy 357.393135 -395.987804) (xy 357.340351 -395.969797) (xy 357.290751 -395.944296) (xy 357.245393 -395.911845)
			(xy 357.205244 -395.873136) (xy 357.171158 -395.828993) (xy 357.143862 -395.780358) (xy 357.123939 -395.728267)
			(xy 357.111813 -395.67383) (xy 357.107742 -395.618208) (xy 354.01504 -395.618208) (xy 354.01504 -397.519398)
			(xy 355.399592 -397.519398) (xy 355.403663 -397.463776) (xy 355.415789 -397.409339) (xy 355.435712 -397.357248)
			(xy 355.463008 -397.308613) (xy 355.497094 -397.26447) (xy 355.537243 -397.225761) (xy 355.582601 -397.19331)
			(xy 355.632201 -397.167809) (xy 355.684985 -397.149802) (xy 355.739828 -397.139672) (xy 355.795562 -397.137635)
			(xy 355.850999 -397.143735) (xy 355.904956 -397.157841) (xy 355.956285 -397.179653) (xy 356.003891 -397.208707)
			(xy 356.046759 -397.244382) (xy 356.083976 -397.285919) (xy 356.114749 -397.332432) (xy 356.138421 -397.382929)
			(xy 356.154489 -397.436336) (xy 356.160171 -397.474948) (xy 359.485182 -397.474948) (xy 359.489253 -397.419326)
			(xy 359.501379 -397.364889) (xy 359.521302 -397.312798) (xy 359.548598 -397.264163) (xy 359.582684 -397.22002)
			(xy 359.622833 -397.181311) (xy 359.668191 -397.14886) (xy 359.717791 -397.123359) (xy 359.770575 -397.105352)
			(xy 359.825418 -397.095222) (xy 359.881152 -397.093185) (xy 359.936589 -397.099285) (xy 359.990546 -397.113391)
			(xy 360.041875 -397.135203) (xy 360.089481 -397.164257) (xy 360.132349 -397.199932) (xy 360.169566 -397.241469)
			(xy 360.200339 -397.287982) (xy 360.224011 -397.338479) (xy 360.240079 -397.391886) (xy 360.248199 -397.447062)
			(xy 360.248708 -397.474948) (xy 360.248199 -397.502834) (xy 360.240079 -397.55801) (xy 360.224011 -397.611417)
			(xy 360.200339 -397.661914) (xy 360.169566 -397.708427) (xy 360.132349 -397.749964) (xy 360.089481 -397.785639)
			(xy 360.041875 -397.814693) (xy 359.990546 -397.836505) (xy 359.936589 -397.850611) (xy 359.881152 -397.856711)
			(xy 359.825418 -397.854674) (xy 359.770575 -397.844544) (xy 359.717791 -397.826537) (xy 359.668191 -397.801036)
			(xy 359.622833 -397.768585) (xy 359.582684 -397.729876) (xy 359.548598 -397.685733) (xy 359.521302 -397.637098)
			(xy 359.501379 -397.585007) (xy 359.489253 -397.53057) (xy 359.485182 -397.474948) (xy 356.160171 -397.474948)
			(xy 356.162609 -397.491512) (xy 356.163118 -397.519398) (xy 356.162609 -397.547284) (xy 356.154489 -397.60246)
			(xy 356.138421 -397.655867) (xy 356.114749 -397.706364) (xy 356.083976 -397.752877) (xy 356.046759 -397.794414)
			(xy 356.003891 -397.830089) (xy 355.956285 -397.859143) (xy 355.904956 -397.880955) (xy 355.850999 -397.895061)
			(xy 355.795562 -397.901161) (xy 355.739828 -397.899124) (xy 355.684985 -397.888994) (xy 355.632201 -397.870987)
			(xy 355.582601 -397.845486) (xy 355.537243 -397.813035) (xy 355.497094 -397.774326) (xy 355.463008 -397.730183)
			(xy 355.435712 -397.681548) (xy 355.415789 -397.629457) (xy 355.403663 -397.57502) (xy 355.399592 -397.519398)
			(xy 354.01504 -397.519398) (xy 354.01504 -398.789398) (xy 355.394512 -398.789398) (xy 355.398583 -398.733776)
			(xy 355.410709 -398.679339) (xy 355.430632 -398.627248) (xy 355.457928 -398.578613) (xy 355.492014 -398.53447)
			(xy 355.532163 -398.495761) (xy 355.577521 -398.46331) (xy 355.627121 -398.437809) (xy 355.679905 -398.419802)
			(xy 355.734748 -398.409672) (xy 355.790482 -398.407635) (xy 355.845919 -398.413735) (xy 355.899876 -398.427841)
			(xy 355.951205 -398.449653) (xy 355.998811 -398.478707) (xy 356.041679 -398.514382) (xy 356.078896 -398.555919)
			(xy 356.109669 -398.602432) (xy 356.133341 -398.652929) (xy 356.149409 -398.706336) (xy 356.151353 -398.719548)
			(xy 363.782862 -398.719548) (xy 363.786933 -398.663926) (xy 363.799059 -398.609489) (xy 363.818982 -398.557398)
			(xy 363.846278 -398.508763) (xy 363.880364 -398.46462) (xy 363.920513 -398.425911) (xy 363.965871 -398.39346)
			(xy 364.015471 -398.367959) (xy 364.068255 -398.349952) (xy 364.123098 -398.339822) (xy 364.178832 -398.337785)
			(xy 364.234269 -398.343885) (xy 364.288226 -398.357991) (xy 364.339555 -398.379803) (xy 364.387161 -398.408857)
			(xy 364.430029 -398.444532) (xy 364.467246 -398.486069) (xy 364.498019 -398.532582) (xy 364.521691 -398.583079)
			(xy 364.537759 -398.636486) (xy 364.545879 -398.691662) (xy 364.546388 -398.719548) (xy 364.545879 -398.747434)
			(xy 364.537759 -398.80261) (xy 364.521691 -398.856017) (xy 364.498019 -398.906514) (xy 364.467246 -398.953027)
			(xy 364.430029 -398.994564) (xy 364.387161 -399.030239) (xy 364.339555 -399.059293) (xy 364.288226 -399.081105)
			(xy 364.234269 -399.095211) (xy 364.178832 -399.101311) (xy 364.123098 -399.099274) (xy 364.068255 -399.089144)
			(xy 364.015471 -399.071137) (xy 363.965871 -399.045636) (xy 363.920513 -399.013185) (xy 363.880364 -398.974476)
			(xy 363.846278 -398.930333) (xy 363.818982 -398.881698) (xy 363.799059 -398.829607) (xy 363.786933 -398.77517)
			(xy 363.782862 -398.719548) (xy 356.151353 -398.719548) (xy 356.157529 -398.761512) (xy 356.158038 -398.789398)
			(xy 356.157529 -398.817284) (xy 356.149409 -398.87246) (xy 356.133341 -398.925867) (xy 356.109669 -398.976364)
			(xy 356.078896 -399.022877) (xy 356.041679 -399.064414) (xy 355.998811 -399.100089) (xy 355.951205 -399.129143)
			(xy 355.899876 -399.150955) (xy 355.845919 -399.165061) (xy 355.790482 -399.171161) (xy 355.734748 -399.169124)
			(xy 355.679905 -399.158994) (xy 355.627121 -399.140987) (xy 355.577521 -399.115486) (xy 355.532163 -399.083035)
			(xy 355.492014 -399.044326) (xy 355.457928 -399.000183) (xy 355.430632 -398.951548) (xy 355.410709 -398.899457)
			(xy 355.398583 -398.84502) (xy 355.394512 -398.789398) (xy 354.01504 -398.789398) (xy 354.01504 -400.131026)
			(xy 354.028108 -400.153476) (xy 354.048717 -400.201158) (xy 354.06267 -400.251194) (xy 354.06971 -400.30266)
			(xy 354.069707 -400.328638) (xy 355.862126 -400.328638) (xy 355.866197 -400.273016) (xy 355.878323 -400.218579)
			(xy 355.898246 -400.166488) (xy 355.925542 -400.117853) (xy 355.959628 -400.07371) (xy 355.999777 -400.035001)
			(xy 356.045135 -400.00255) (xy 356.094735 -399.977049) (xy 356.147519 -399.959042) (xy 356.202362 -399.948912)
			(xy 356.258096 -399.946875) (xy 356.313533 -399.952975) (xy 356.36749 -399.967081) (xy 356.418819 -399.988893)
			(xy 356.466425 -400.017947) (xy 356.481134 -400.030188) (xy 359.297222 -400.030188) (xy 359.301293 -399.974566)
			(xy 359.313419 -399.920129) (xy 359.333342 -399.868038) (xy 359.360638 -399.819403) (xy 359.394724 -399.77526)
			(xy 359.434873 -399.736551) (xy 359.480231 -399.7041) (xy 359.529831 -399.678599) (xy 359.582615 -399.660592)
			(xy 359.637458 -399.650462) (xy 359.693192 -399.648425) (xy 359.748629 -399.654525) (xy 359.802586 -399.668631)
			(xy 359.853915 -399.690443) (xy 359.901521 -399.719497) (xy 359.944389 -399.755172) (xy 359.981606 -399.796709)
			(xy 360.012379 -399.843222) (xy 360.036051 -399.893719) (xy 360.052119 -399.947126) (xy 360.060239 -400.002302)
			(xy 360.060748 -400.030188) (xy 360.060239 -400.058074) (xy 360.052119 -400.11325) (xy 360.043485 -400.141948)
			(xy 360.842812 -400.141948) (xy 360.846883 -400.086326) (xy 360.859009 -400.031889) (xy 360.878932 -399.979798)
			(xy 360.906228 -399.931163) (xy 360.940314 -399.88702) (xy 360.980463 -399.848311) (xy 361.025821 -399.81586)
			(xy 361.075421 -399.790359) (xy 361.128205 -399.772352) (xy 361.183048 -399.762222) (xy 361.238782 -399.760185)
			(xy 361.294219 -399.766285) (xy 361.348176 -399.780391) (xy 361.399505 -399.802203) (xy 361.447111 -399.831257)
			(xy 361.489979 -399.866932) (xy 361.527196 -399.908469) (xy 361.557969 -399.954982) (xy 361.581641 -400.005479)
			(xy 361.597709 -400.058886) (xy 361.605829 -400.114062) (xy 361.606338 -400.141948) (xy 361.605829 -400.169834)
			(xy 361.597709 -400.22501) (xy 361.581641 -400.278417) (xy 361.568219 -400.307048) (xy 364.651542 -400.307048)
			(xy 364.655613 -400.251426) (xy 364.667739 -400.196989) (xy 364.687662 -400.144898) (xy 364.714958 -400.096263)
			(xy 364.749044 -400.05212) (xy 364.789193 -400.013411) (xy 364.834551 -399.98096) (xy 364.884151 -399.955459)
			(xy 364.936935 -399.937452) (xy 364.991778 -399.927322) (xy 365.047512 -399.925285) (xy 365.102949 -399.931385)
			(xy 365.156906 -399.945491) (xy 365.208235 -399.967303) (xy 365.255841 -399.996357) (xy 365.298709 -400.032032)
			(xy 365.335926 -400.073569) (xy 365.366699 -400.120082) (xy 365.390371 -400.170579) (xy 365.406439 -400.223986)
			(xy 365.414559 -400.279162) (xy 365.415068 -400.307048) (xy 365.414559 -400.334934) (xy 365.406439 -400.39011)
			(xy 365.390371 -400.443517) (xy 365.366699 -400.494014) (xy 365.335926 -400.540527) (xy 365.298709 -400.582064)
			(xy 365.255841 -400.617739) (xy 365.208235 -400.646793) (xy 365.156906 -400.668605) (xy 365.102949 -400.682711)
			(xy 365.047512 -400.688811) (xy 364.991778 -400.686774) (xy 364.936935 -400.676644) (xy 364.884151 -400.658637)
			(xy 364.834551 -400.633136) (xy 364.789193 -400.600685) (xy 364.749044 -400.561976) (xy 364.714958 -400.517833)
			(xy 364.687662 -400.469198) (xy 364.667739 -400.417107) (xy 364.655613 -400.36267) (xy 364.651542 -400.307048)
			(xy 361.568219 -400.307048) (xy 361.557969 -400.328914) (xy 361.527196 -400.375427) (xy 361.489979 -400.416964)
			(xy 361.447111 -400.452639) (xy 361.399505 -400.481693) (xy 361.348176 -400.503505) (xy 361.294219 -400.517611)
			(xy 361.238782 -400.523711) (xy 361.183048 -400.521674) (xy 361.128205 -400.511544) (xy 361.075421 -400.493537)
			(xy 361.025821 -400.468036) (xy 360.980463 -400.435585) (xy 360.940314 -400.396876) (xy 360.906228 -400.352733)
			(xy 360.878932 -400.304098) (xy 360.859009 -400.252007) (xy 360.846883 -400.19757) (xy 360.842812 -400.141948)
			(xy 360.043485 -400.141948) (xy 360.036051 -400.166657) (xy 360.012379 -400.217154) (xy 359.981606 -400.263667)
			(xy 359.944389 -400.305204) (xy 359.901521 -400.340879) (xy 359.853915 -400.369933) (xy 359.802586 -400.391745)
			(xy 359.748629 -400.405851) (xy 359.693192 -400.411951) (xy 359.637458 -400.409914) (xy 359.582615 -400.399784)
			(xy 359.529831 -400.381777) (xy 359.480231 -400.356276) (xy 359.434873 -400.323825) (xy 359.394724 -400.285116)
			(xy 359.360638 -400.240973) (xy 359.333342 -400.192338) (xy 359.313419 -400.140247) (xy 359.301293 -400.08581)
			(xy 359.297222 -400.030188) (xy 356.481134 -400.030188) (xy 356.509293 -400.053622) (xy 356.54651 -400.095159)
			(xy 356.577283 -400.141672) (xy 356.600955 -400.192169) (xy 356.617023 -400.245576) (xy 356.625143 -400.300752)
			(xy 356.625652 -400.328638) (xy 356.625143 -400.356524) (xy 356.617023 -400.4117) (xy 356.600955 -400.465107)
			(xy 356.577283 -400.515604) (xy 356.54651 -400.562117) (xy 356.509293 -400.603654) (xy 356.466425 -400.639329)
			(xy 356.418819 -400.668383) (xy 356.36749 -400.690195) (xy 356.313533 -400.704301) (xy 356.258096 -400.710401)
			(xy 356.202362 -400.708364) (xy 356.147519 -400.698234) (xy 356.094735 -400.680227) (xy 356.045135 -400.654726)
			(xy 355.999777 -400.622275) (xy 355.959628 -400.583566) (xy 355.925542 -400.539423) (xy 355.898246 -400.490788)
			(xy 355.878323 -400.438697) (xy 355.866197 -400.38426) (xy 355.862126 -400.328638) (xy 354.069707 -400.328638)
			(xy 354.069705 -400.354605) (xy 354.062657 -400.40607) (xy 354.048695 -400.456104) (xy 354.028078 -400.503782)
			(xy 354.01504 -400.52625) (xy 354.01504 -401.955) (xy 354.354382 -401.955) (xy 354.358453 -401.899378)
			(xy 354.370579 -401.844941) (xy 354.390502 -401.79285) (xy 354.417798 -401.744215) (xy 354.451884 -401.700072)
			(xy 354.492033 -401.661363) (xy 354.537391 -401.628912) (xy 354.586991 -401.603411) (xy 354.639775 -401.585404)
			(xy 354.694618 -401.575274) (xy 354.750352 -401.573237) (xy 354.805789 -401.579337) (xy 354.859746 -401.593443)
			(xy 354.911075 -401.615255) (xy 354.958681 -401.644309) (xy 355.001549 -401.679984) (xy 355.038766 -401.721521)
			(xy 355.069539 -401.768034) (xy 355.093211 -401.818531) (xy 355.109279 -401.871938) (xy 355.117399 -401.927114)
			(xy 355.117908 -401.955) (xy 355.117399 -401.982886) (xy 355.109279 -402.038062) (xy 355.093211 -402.091469)
			(xy 355.069539 -402.141966) (xy 355.038766 -402.188479) (xy 355.033807 -402.194014) (xy 359.851196 -402.194014)
			(xy 359.855267 -402.138392) (xy 359.867393 -402.083955) (xy 359.887316 -402.031864) (xy 359.914612 -401.983229)
			(xy 359.948698 -401.939086) (xy 359.988847 -401.900377) (xy 360.034205 -401.867926) (xy 360.083805 -401.842425)
			(xy 360.136589 -401.824418) (xy 360.191432 -401.814288) (xy 360.247166 -401.812251) (xy 360.302603 -401.818351)
			(xy 360.35656 -401.832457) (xy 360.405844 -401.8534) (xy 360.978702 -401.8534) (xy 360.982773 -401.797778)
			(xy 360.994899 -401.743341) (xy 361.014822 -401.69125) (xy 361.042118 -401.642615) (xy 361.076204 -401.598472)
			(xy 361.116353 -401.559763) (xy 361.161711 -401.527312) (xy 361.211311 -401.501811) (xy 361.264095 -401.483804)
			(xy 361.318938 -401.473674) (xy 361.374672 -401.471637) (xy 361.430109 -401.477737) (xy 361.484066 -401.491843)
			(xy 361.535395 -401.513655) (xy 361.583001 -401.542709) (xy 361.625869 -401.578384) (xy 361.663086 -401.619921)
			(xy 361.693859 -401.666434) (xy 361.695536 -401.670012) (xy 362.432344 -401.670012) (xy 362.436415 -401.61439)
			(xy 362.448541 -401.559953) (xy 362.468464 -401.507862) (xy 362.49576 -401.459227) (xy 362.529846 -401.415084)
			(xy 362.569995 -401.376375) (xy 362.615353 -401.343924) (xy 362.664953 -401.318423) (xy 362.717737 -401.300416)
			(xy 362.77258 -401.290286) (xy 362.828314 -401.288249) (xy 362.883751 -401.294349) (xy 362.937708 -401.308455)
			(xy 362.989037 -401.330267) (xy 363.036643 -401.359321) (xy 363.079511 -401.394996) (xy 363.116728 -401.436533)
			(xy 363.147501 -401.483046) (xy 363.171173 -401.533543) (xy 363.187241 -401.58695) (xy 363.195361 -401.642126)
			(xy 363.19587 -401.670012) (xy 363.195361 -401.697898) (xy 363.187241 -401.753074) (xy 363.171173 -401.806481)
			(xy 363.147501 -401.856978) (xy 363.116728 -401.903491) (xy 363.079511 -401.945028) (xy 363.036643 -401.980703)
			(xy 362.989037 -402.009757) (xy 362.937708 -402.031569) (xy 362.883751 -402.045675) (xy 362.828314 -402.051775)
			(xy 362.77258 -402.049738) (xy 362.717737 -402.039608) (xy 362.664953 -402.021601) (xy 362.615353 -401.9961)
			(xy 362.569995 -401.963649) (xy 362.529846 -401.92494) (xy 362.49576 -401.880797) (xy 362.468464 -401.832162)
			(xy 362.448541 -401.780071) (xy 362.436415 -401.725634) (xy 362.432344 -401.670012) (xy 361.695536 -401.670012)
			(xy 361.717531 -401.716931) (xy 361.733599 -401.770338) (xy 361.741719 -401.825514) (xy 361.742228 -401.8534)
			(xy 361.741719 -401.881286) (xy 361.733599 -401.936462) (xy 361.717531 -401.989869) (xy 361.693859 -402.040366)
			(xy 361.663086 -402.086879) (xy 361.625869 -402.128416) (xy 361.583001 -402.164091) (xy 361.535395 -402.193145)
			(xy 361.484066 -402.214957) (xy 361.430109 -402.229063) (xy 361.374672 -402.235163) (xy 361.318938 -402.233126)
			(xy 361.264095 -402.222996) (xy 361.211311 -402.204989) (xy 361.161711 -402.179488) (xy 361.116353 -402.147037)
			(xy 361.076204 -402.108328) (xy 361.042118 -402.064185) (xy 361.014822 -402.01555) (xy 360.994899 -401.963459)
			(xy 360.982773 -401.909022) (xy 360.978702 -401.8534) (xy 360.405844 -401.8534) (xy 360.407889 -401.854269)
			(xy 360.455495 -401.883323) (xy 360.498363 -401.918998) (xy 360.53558 -401.960535) (xy 360.566353 -402.007048)
			(xy 360.590025 -402.057545) (xy 360.606093 -402.110952) (xy 360.614213 -402.166128) (xy 360.614722 -402.194014)
			(xy 360.614213 -402.2219) (xy 360.606093 -402.277076) (xy 360.590025 -402.330483) (xy 360.566353 -402.38098)
			(xy 360.53558 -402.427493) (xy 360.498363 -402.46903) (xy 360.455495 -402.504705) (xy 360.407889 -402.533759)
			(xy 360.35656 -402.555571) (xy 360.302603 -402.569677) (xy 360.247166 -402.575777) (xy 360.191432 -402.57374)
			(xy 360.136589 -402.56361) (xy 360.083805 -402.545603) (xy 360.034205 -402.520102) (xy 359.988847 -402.487651)
			(xy 359.948698 -402.448942) (xy 359.914612 -402.404799) (xy 359.887316 -402.356164) (xy 359.867393 -402.304073)
			(xy 359.855267 -402.249636) (xy 359.851196 -402.194014) (xy 355.033807 -402.194014) (xy 355.001549 -402.230016)
			(xy 354.958681 -402.265691) (xy 354.911075 -402.294745) (xy 354.859746 -402.316557) (xy 354.805789 -402.330663)
			(xy 354.750352 -402.336763) (xy 354.694618 -402.334726) (xy 354.639775 -402.324596) (xy 354.586991 -402.306589)
			(xy 354.537391 -402.281088) (xy 354.492033 -402.248637) (xy 354.451884 -402.209928) (xy 354.417798 -402.165785)
			(xy 354.390502 -402.11715) (xy 354.370579 -402.065059) (xy 354.358453 -402.010622) (xy 354.354382 -401.955)
			(xy 354.01504 -401.955) (xy 354.01504 -402.910548) (xy 369.472462 -402.910548) (xy 369.476533 -402.854926)
			(xy 369.488659 -402.800489) (xy 369.508582 -402.748398) (xy 369.535878 -402.699763) (xy 369.569964 -402.65562)
			(xy 369.610113 -402.616911) (xy 369.655471 -402.58446) (xy 369.705071 -402.558959) (xy 369.757855 -402.540952)
			(xy 369.812698 -402.530822) (xy 369.868432 -402.528785) (xy 369.923869 -402.534885) (xy 369.977826 -402.548991)
			(xy 370.029155 -402.570803) (xy 370.076761 -402.599857) (xy 370.119629 -402.635532) (xy 370.156846 -402.677069)
			(xy 370.187619 -402.723582) (xy 370.211291 -402.774079) (xy 370.227359 -402.827486) (xy 370.235479 -402.882662)
			(xy 370.235988 -402.910548) (xy 370.235479 -402.938434) (xy 370.227359 -402.99361) (xy 370.211291 -403.047017)
			(xy 370.187619 -403.097514) (xy 370.156846 -403.144027) (xy 370.119629 -403.185564) (xy 370.076761 -403.221239)
			(xy 370.029155 -403.250293) (xy 369.977826 -403.272105) (xy 369.923869 -403.286211) (xy 369.868432 -403.292311)
			(xy 369.812698 -403.290274) (xy 369.757855 -403.280144) (xy 369.705071 -403.262137) (xy 369.655471 -403.236636)
			(xy 369.610113 -403.204185) (xy 369.569964 -403.165476) (xy 369.535878 -403.121333) (xy 369.508582 -403.072698)
			(xy 369.488659 -403.020607) (xy 369.476533 -402.96617) (xy 369.472462 -402.910548) (xy 354.01504 -402.910548)
			(xy 354.01504 -403.607016) (xy 354.039237 -403.621829) (xy 354.083365 -403.657484) (xy 354.121731 -403.699276)
			(xy 354.153489 -403.746286) (xy 354.177941 -403.797479) (xy 354.194548 -403.851726) (xy 354.202943 -403.907834)
			(xy 354.202943 -403.964566) (xy 354.194548 -404.020674) (xy 354.177941 -404.074921) (xy 354.153489 -404.126114)
			(xy 354.121731 -404.173124) (xy 354.083365 -404.214916) (xy 354.082518 -404.2156) (xy 357.046782 -404.2156)
			(xy 357.050853 -404.159978) (xy 357.062979 -404.105541) (xy 357.082902 -404.05345) (xy 357.110198 -404.004815)
			(xy 357.144284 -403.960672) (xy 357.184433 -403.921963) (xy 357.229791 -403.889512) (xy 357.279391 -403.864011)
			(xy 357.332175 -403.846004) (xy 357.387018 -403.835874) (xy 357.442752 -403.833837) (xy 357.498189 -403.839937)
			(xy 357.552146 -403.854043) (xy 357.603475 -403.875855) (xy 357.651081 -403.904909) (xy 357.693949 -403.940584)
			(xy 357.731166 -403.982121) (xy 357.761939 -404.028634) (xy 357.785611 -404.079131) (xy 357.801679 -404.132538)
			(xy 357.809799 -404.187714) (xy 357.810308 -404.2156) (xy 357.809799 -404.243486) (xy 357.801679 -404.298662)
			(xy 357.785611 -404.352069) (xy 357.761939 -404.402566) (xy 357.731166 -404.449079) (xy 357.693949 -404.490616)
			(xy 357.651081 -404.526291) (xy 357.603475 -404.555345) (xy 357.552146 -404.577157) (xy 357.498189 -404.591263)
			(xy 357.442752 -404.597363) (xy 357.387018 -404.595326) (xy 357.332175 -404.585196) (xy 357.279391 -404.567189)
			(xy 357.229791 -404.541688) (xy 357.184433 -404.509237) (xy 357.144284 -404.470528) (xy 357.110198 -404.426385)
			(xy 357.082902 -404.37775) (xy 357.062979 -404.325659) (xy 357.050853 -404.271222) (xy 357.046782 -404.2156)
			(xy 354.082518 -404.2156) (xy 354.039237 -404.250571) (xy 354.01504 -404.265384) (xy 354.01504 -404.876)
			(xy 354.354382 -404.876) (xy 354.358453 -404.820378) (xy 354.370579 -404.765941) (xy 354.390502 -404.71385)
			(xy 354.417798 -404.665215) (xy 354.451884 -404.621072) (xy 354.492033 -404.582363) (xy 354.537391 -404.549912)
			(xy 354.586991 -404.524411) (xy 354.639775 -404.506404) (xy 354.694618 -404.496274) (xy 354.750352 -404.494237)
			(xy 354.805789 -404.500337) (xy 354.859746 -404.514443) (xy 354.911075 -404.536255) (xy 354.958681 -404.565309)
			(xy 355.001549 -404.600984) (xy 355.038766 -404.642521) (xy 355.069539 -404.689034) (xy 355.093211 -404.739531)
			(xy 355.109279 -404.792938) (xy 355.117399 -404.848114) (xy 355.117908 -404.876) (xy 355.117399 -404.903886)
			(xy 355.109279 -404.959062) (xy 355.093211 -405.012469) (xy 355.069539 -405.062966) (xy 355.038766 -405.109479)
			(xy 355.001549 -405.151016) (xy 354.958681 -405.186691) (xy 354.911075 -405.215745) (xy 354.873764 -405.2316)
			(xy 367.054892 -405.2316) (xy 367.055378 -405.204349) (xy 367.063134 -405.150401) (xy 367.078489 -405.098106)
			(xy 367.101131 -405.048529) (xy 367.130597 -405.002679) (xy 367.166288 -404.961488) (xy 367.207479 -404.925797)
			(xy 367.253329 -404.896331) (xy 367.302906 -404.873689) (xy 367.355201 -404.858334) (xy 367.409149 -404.850578)
			(xy 367.463651 -404.850578) (xy 367.517599 -404.858334) (xy 367.569894 -404.873689) (xy 367.619471 -404.896331)
			(xy 367.665321 -404.925797) (xy 367.706512 -404.961488) (xy 367.742203 -405.002679) (xy 367.771669 -405.048529)
			(xy 367.794311 -405.098106) (xy 367.809666 -405.150401) (xy 367.817422 -405.204349) (xy 367.817908 -405.2316)
			(xy 367.817427 -405.259463) (xy 367.811742 -405.298148) (xy 368.832382 -405.298148) (xy 368.836453 -405.242526)
			(xy 368.848579 -405.188089) (xy 368.868502 -405.135998) (xy 368.895798 -405.087363) (xy 368.929884 -405.04322)
			(xy 368.970033 -405.004511) (xy 369.015391 -404.97206) (xy 369.064991 -404.946559) (xy 369.117775 -404.928552)
			(xy 369.172618 -404.918422) (xy 369.228352 -404.916385) (xy 369.283789 -404.922485) (xy 369.337746 -404.936591)
			(xy 369.389075 -404.958403) (xy 369.436681 -404.987457) (xy 369.479549 -405.023132) (xy 369.516766 -405.064669)
			(xy 369.547539 -405.111182) (xy 369.571211 -405.161679) (xy 369.587279 -405.215086) (xy 369.595399 -405.270262)
			(xy 369.595908 -405.298148) (xy 369.595399 -405.326034) (xy 369.587279 -405.38121) (xy 369.571211 -405.434617)
			(xy 369.547539 -405.485114) (xy 369.516766 -405.531627) (xy 369.479549 -405.573164) (xy 369.436681 -405.608839)
			(xy 369.389075 -405.637893) (xy 369.337746 -405.659705) (xy 369.283789 -405.673811) (xy 369.228352 -405.679911)
			(xy 369.172618 -405.677874) (xy 369.117775 -405.667744) (xy 369.064991 -405.649737) (xy 369.015391 -405.624236)
			(xy 368.970033 -405.591785) (xy 368.929884 -405.553076) (xy 368.895798 -405.508933) (xy 368.868502 -405.460298)
			(xy 368.848579 -405.408207) (xy 368.836453 -405.35377) (xy 368.832382 -405.298148) (xy 367.811742 -405.298148)
			(xy 367.809325 -405.314596) (xy 367.793293 -405.367965) (xy 367.769671 -405.418436) (xy 367.738962 -405.464937)
			(xy 367.701818 -405.506478) (xy 367.680748 -405.524716) (xy 367.669232 -405.535019) (xy 367.65246 -405.560952)
			(xy 367.644208 -405.590714) (xy 367.645232 -405.621581) (xy 367.655439 -405.65073) (xy 367.673893 -405.675494)
			(xy 367.686082 -405.68499) (xy 367.706621 -405.700426) (xy 367.743754 -405.735937) (xy 367.775785 -405.776111)
			(xy 367.802135 -405.82022) (xy 367.822326 -405.867466) (xy 367.835993 -405.916995) (xy 367.842889 -405.96791)
			(xy 367.843308 -405.9936) (xy 367.842822 -406.020851) (xy 367.835066 -406.074799) (xy 367.819711 -406.127094)
			(xy 367.797069 -406.176671) (xy 367.767603 -406.222521) (xy 367.731912 -406.263712) (xy 367.690721 -406.299403)
			(xy 367.644871 -406.328869) (xy 367.595294 -406.351511) (xy 367.542999 -406.366866) (xy 367.489051 -406.374622)
			(xy 367.434549 -406.374622) (xy 367.380601 -406.366866) (xy 367.328306 -406.351511) (xy 367.278729 -406.328869)
			(xy 367.232879 -406.299403) (xy 367.191688 -406.263712) (xy 367.155997 -406.222521) (xy 367.126531 -406.176671)
			(xy 367.103889 -406.127094) (xy 367.088534 -406.074799) (xy 367.080778 -406.020851) (xy 367.080292 -405.9936)
			(xy 367.080773 -405.965737) (xy 367.088875 -405.910604) (xy 367.104907 -405.857235) (xy 367.128529 -405.806764)
			(xy 367.159238 -405.760263) (xy 367.196382 -405.718722) (xy 367.217452 -405.700484) (xy 367.228968 -405.690181)
			(xy 367.24574 -405.664248) (xy 367.253992 -405.634486) (xy 367.252968 -405.603619) (xy 367.242761 -405.57447)
			(xy 367.224307 -405.549706) (xy 367.212118 -405.54021) (xy 367.191579 -405.524774) (xy 367.154446 -405.489263)
			(xy 367.122415 -405.449089) (xy 367.096065 -405.40498) (xy 367.075874 -405.357734) (xy 367.062207 -405.308205)
			(xy 367.055311 -405.25729) (xy 367.054892 -405.2316) (xy 354.873764 -405.2316) (xy 354.859746 -405.237557)
			(xy 354.805789 -405.251663) (xy 354.750352 -405.257763) (xy 354.694618 -405.255726) (xy 354.639775 -405.245596)
			(xy 354.586991 -405.227589) (xy 354.537391 -405.202088) (xy 354.492033 -405.169637) (xy 354.451884 -405.130928)
			(xy 354.417798 -405.086785) (xy 354.390502 -405.03815) (xy 354.370579 -404.986059) (xy 354.358453 -404.931622)
			(xy 354.354382 -404.876) (xy 354.01504 -404.876) (xy 354.01504 -405.8412) (xy 354.887782 -405.8412)
			(xy 354.891853 -405.785578) (xy 354.903979 -405.731141) (xy 354.923902 -405.67905) (xy 354.951198 -405.630415)
			(xy 354.985284 -405.586272) (xy 355.025433 -405.547563) (xy 355.070791 -405.515112) (xy 355.120391 -405.489611)
			(xy 355.173175 -405.471604) (xy 355.228018 -405.461474) (xy 355.283752 -405.459437) (xy 355.339189 -405.465537)
			(xy 355.393146 -405.479643) (xy 355.444475 -405.501455) (xy 355.492081 -405.530509) (xy 355.534949 -405.566184)
			(xy 355.572166 -405.607721) (xy 355.602939 -405.654234) (xy 355.626611 -405.704731) (xy 355.642679 -405.758138)
			(xy 355.650799 -405.813314) (xy 355.651308 -405.8412) (xy 355.650799 -405.869086) (xy 355.642679 -405.924262)
			(xy 355.626611 -405.977669) (xy 355.619143 -405.9936) (xy 364.946182 -405.9936) (xy 364.950253 -405.937978)
			(xy 364.962379 -405.883541) (xy 364.982302 -405.83145) (xy 365.009598 -405.782815) (xy 365.043684 -405.738672)
			(xy 365.083833 -405.699963) (xy 365.129191 -405.667512) (xy 365.178791 -405.642011) (xy 365.231575 -405.624004)
			(xy 365.286418 -405.613874) (xy 365.342152 -405.611837) (xy 365.397589 -405.617937) (xy 365.451546 -405.632043)
			(xy 365.502875 -405.653855) (xy 365.550481 -405.682909) (xy 365.593349 -405.718584) (xy 365.630566 -405.760121)
			(xy 365.661339 -405.806634) (xy 365.685011 -405.857131) (xy 365.701079 -405.910538) (xy 365.709199 -405.965714)
			(xy 365.709708 -405.9936) (xy 365.709199 -406.021486) (xy 365.701079 -406.076662) (xy 365.685011 -406.130069)
			(xy 365.661339 -406.180566) (xy 365.630566 -406.227079) (xy 365.593349 -406.268616) (xy 365.550481 -406.304291)
			(xy 365.502875 -406.333345) (xy 365.451546 -406.355157) (xy 365.397589 -406.369263) (xy 365.342152 -406.375363)
			(xy 365.286418 -406.373326) (xy 365.231575 -406.363196) (xy 365.178791 -406.345189) (xy 365.129191 -406.319688)
			(xy 365.083833 -406.287237) (xy 365.043684 -406.248528) (xy 365.009598 -406.204385) (xy 364.982302 -406.15575)
			(xy 364.962379 -406.103659) (xy 364.950253 -406.049222) (xy 364.946182 -405.9936) (xy 355.619143 -405.9936)
			(xy 355.602939 -406.028166) (xy 355.572166 -406.074679) (xy 355.534949 -406.116216) (xy 355.492081 -406.151891)
			(xy 355.444475 -406.180945) (xy 355.393146 -406.202757) (xy 355.339189 -406.216863) (xy 355.283752 -406.222963)
			(xy 355.228018 -406.220926) (xy 355.173175 -406.210796) (xy 355.120391 -406.192789) (xy 355.070791 -406.167288)
			(xy 355.025433 -406.134837) (xy 354.985284 -406.096128) (xy 354.951198 -406.051985) (xy 354.923902 -406.00335)
			(xy 354.903979 -405.951259) (xy 354.891853 -405.896822) (xy 354.887782 -405.8412) (xy 354.01504 -405.8412)
			(xy 354.01504 -407.233628) (xy 358.029762 -407.233628) (xy 358.033833 -407.178006) (xy 358.045959 -407.123569)
			(xy 358.065882 -407.071478) (xy 358.093178 -407.022843) (xy 358.127264 -406.9787) (xy 358.167413 -406.939991)
			(xy 358.212771 -406.90754) (xy 358.262371 -406.882039) (xy 358.315155 -406.864032) (xy 358.369998 -406.853902)
			(xy 358.425732 -406.851865) (xy 358.481169 -406.857965) (xy 358.535126 -406.872071) (xy 358.586455 -406.893883)
			(xy 358.634061 -406.922937) (xy 358.676929 -406.958612) (xy 358.714146 -407.000149) (xy 358.744919 -407.046662)
			(xy 358.768591 -407.097159) (xy 358.784659 -407.150566) (xy 358.792779 -407.205742) (xy 358.793195 -407.228548)
			(xy 361.994702 -407.228548) (xy 361.998773 -407.172926) (xy 362.010899 -407.118489) (xy 362.030822 -407.066398)
			(xy 362.058118 -407.017763) (xy 362.092204 -406.97362) (xy 362.132353 -406.934911) (xy 362.177711 -406.90246)
			(xy 362.227311 -406.876959) (xy 362.280095 -406.858952) (xy 362.334938 -406.848822) (xy 362.390672 -406.846785)
			(xy 362.446109 -406.852885) (xy 362.500066 -406.866991) (xy 362.551395 -406.888803) (xy 362.599001 -406.917857)
			(xy 362.641869 -406.953532) (xy 362.679086 -406.995069) (xy 362.709859 -407.041582) (xy 362.733531 -407.092079)
			(xy 362.749599 -407.145486) (xy 362.757719 -407.200662) (xy 362.758228 -407.228548) (xy 362.757719 -407.256434)
			(xy 362.749599 -407.31161) (xy 362.733531 -407.365017) (xy 362.709859 -407.415514) (xy 362.679086 -407.462027)
			(xy 362.641869 -407.503564) (xy 362.599001 -407.539239) (xy 362.551395 -407.568293) (xy 362.500066 -407.590105)
			(xy 362.446109 -407.604211) (xy 362.390672 -407.610311) (xy 362.334938 -407.608274) (xy 362.280095 -407.598144)
			(xy 362.227311 -407.580137) (xy 362.177711 -407.554636) (xy 362.132353 -407.522185) (xy 362.092204 -407.483476)
			(xy 362.058118 -407.439333) (xy 362.030822 -407.390698) (xy 362.010899 -407.338607) (xy 361.998773 -407.28417)
			(xy 361.994702 -407.228548) (xy 358.793195 -407.228548) (xy 358.793288 -407.233628) (xy 358.792779 -407.261514)
			(xy 358.784659 -407.31669) (xy 358.768591 -407.370097) (xy 358.744919 -407.420594) (xy 358.714146 -407.467107)
			(xy 358.676929 -407.508644) (xy 358.634061 -407.544319) (xy 358.586455 -407.573373) (xy 358.535126 -407.595185)
			(xy 358.481169 -407.609291) (xy 358.425732 -407.615391) (xy 358.369998 -407.613354) (xy 358.315155 -407.603224)
			(xy 358.262371 -407.585217) (xy 358.212771 -407.559716) (xy 358.167413 -407.527265) (xy 358.127264 -407.488556)
			(xy 358.093178 -407.444413) (xy 358.065882 -407.395778) (xy 358.045959 -407.343687) (xy 358.033833 -407.28925)
			(xy 358.029762 -407.233628) (xy 354.01504 -407.233628) (xy 354.01504 -407.761186) (xy 354.015507 -407.775373)
			(xy 354.023313 -407.802652) (xy 354.038326 -407.826728) (xy 354.059387 -407.845742) (xy 354.084868 -407.858225)
			(xy 354.1128 -407.863211) (xy 354.141026 -407.860317) (xy 354.167365 -407.849765) (xy 354.17887 -407.84145)
			(xy 354.198999 -407.826343) (xy 354.242476 -407.800992) (xy 354.288911 -407.78158) (xy 354.337496 -407.768446)
			(xy 354.387386 -407.761818) (xy 354.41255 -407.76144) (xy 354.439802 -407.7619) (xy 354.493751 -407.76965)
			(xy 354.546049 -407.785) (xy 354.595629 -407.807637) (xy 354.641482 -407.8371) (xy 354.682676 -407.872789)
			(xy 354.71837 -407.913978) (xy 354.747839 -407.959827) (xy 354.770483 -408.009405) (xy 354.785839 -408.0617)
			(xy 354.793597 -408.115648) (xy 354.793597 -408.170152) (xy 354.785839 -408.2241) (xy 354.770483 -408.276395)
			(xy 354.747839 -408.325973) (xy 354.71837 -408.371822) (xy 354.682676 -408.413011) (xy 354.641482 -408.4487)
			(xy 354.595629 -408.478163) (xy 354.546049 -408.5008) (xy 354.493751 -408.51615) (xy 354.439802 -408.5239)
			(xy 354.41255 -408.524456) (xy 354.387388 -408.524049) (xy 354.337501 -408.517421) (xy 354.28892 -408.504288)
			(xy 354.24249 -408.484878) (xy 354.199016 -408.459528) (xy 354.17887 -408.444446) (xy 354.167373 -408.436118)
			(xy 354.141029 -408.425564) (xy 354.112799 -408.422669) (xy 354.084862 -408.427657) (xy 354.059377 -408.440141)
			(xy 354.038313 -408.459158) (xy 354.023296 -408.483238) (xy 354.015488 -408.510521) (xy 354.01504 -408.52471)
			(xy 354.01504 -408.544268) (xy 362.901482 -408.544268) (xy 362.905553 -408.488646) (xy 362.917679 -408.434209)
			(xy 362.937602 -408.382118) (xy 362.964898 -408.333483) (xy 362.998984 -408.28934) (xy 363.039133 -408.250631)
			(xy 363.084491 -408.21818) (xy 363.134091 -408.192679) (xy 363.186875 -408.174672) (xy 363.241718 -408.164542)
			(xy 363.297452 -408.162505) (xy 363.352889 -408.168605) (xy 363.406846 -408.182711) (xy 363.458175 -408.204523)
			(xy 363.505781 -408.233577) (xy 363.548649 -408.269252) (xy 363.585866 -408.310789) (xy 363.616639 -408.357302)
			(xy 363.640311 -408.407799) (xy 363.656379 -408.461206) (xy 363.664499 -408.516382) (xy 363.665008 -408.544268)
			(xy 363.664499 -408.572154) (xy 363.656379 -408.62733) (xy 363.640311 -408.680737) (xy 363.616639 -408.731234)
			(xy 363.585866 -408.777747) (xy 363.548649 -408.819284) (xy 363.505781 -408.854959) (xy 363.458175 -408.884013)
			(xy 363.406846 -408.905825) (xy 363.352889 -408.919931) (xy 363.297452 -408.926031) (xy 363.241718 -408.923994)
			(xy 363.186875 -408.913864) (xy 363.134091 -408.895857) (xy 363.084491 -408.870356) (xy 363.039133 -408.837905)
			(xy 362.998984 -408.799196) (xy 362.964898 -408.755053) (xy 362.937602 -408.706418) (xy 362.917679 -408.654327)
			(xy 362.905553 -408.59989) (xy 362.901482 -408.544268) (xy 354.01504 -408.544268) (xy 354.01504 -409.194)
			(xy 364.946182 -409.194) (xy 364.950253 -409.138378) (xy 364.962379 -409.083941) (xy 364.982302 -409.03185)
			(xy 365.009598 -408.983215) (xy 365.043684 -408.939072) (xy 365.083833 -408.900363) (xy 365.129191 -408.867912)
			(xy 365.178791 -408.842411) (xy 365.231575 -408.824404) (xy 365.286418 -408.814274) (xy 365.342152 -408.812237)
			(xy 365.397589 -408.818337) (xy 365.451546 -408.832443) (xy 365.502875 -408.854255) (xy 365.550481 -408.883309)
			(xy 365.593349 -408.918984) (xy 365.630566 -408.960521) (xy 365.661339 -409.007034) (xy 365.685011 -409.057531)
			(xy 365.698482 -409.102306) (xy 367.101626 -409.102306) (xy 367.105697 -409.046684) (xy 367.117823 -408.992247)
			(xy 367.137746 -408.940156) (xy 367.165042 -408.891521) (xy 367.199128 -408.847378) (xy 367.239277 -408.808669)
			(xy 367.284635 -408.776218) (xy 367.334235 -408.750717) (xy 367.387019 -408.73271) (xy 367.441862 -408.72258)
			(xy 367.497596 -408.720543) (xy 367.553033 -408.726643) (xy 367.60699 -408.740749) (xy 367.658319 -408.762561)
			(xy 367.705925 -408.791615) (xy 367.748793 -408.82729) (xy 367.78601 -408.868827) (xy 367.816783 -408.91534)
			(xy 367.840455 -408.965837) (xy 367.856523 -409.019244) (xy 367.864643 -409.07442) (xy 367.865152 -409.102306)
			(xy 367.864643 -409.130192) (xy 367.856523 -409.185368) (xy 367.840455 -409.238775) (xy 367.816783 -409.289272)
			(xy 367.78601 -409.335785) (xy 367.748793 -409.377322) (xy 367.705925 -409.412997) (xy 367.658319 -409.442051)
			(xy 367.60699 -409.463863) (xy 367.553033 -409.477969) (xy 367.497596 -409.484069) (xy 367.441862 -409.482032)
			(xy 367.387019 -409.471902) (xy 367.334235 -409.453895) (xy 367.284635 -409.428394) (xy 367.239277 -409.395943)
			(xy 367.199128 -409.357234) (xy 367.165042 -409.313091) (xy 367.137746 -409.264456) (xy 367.117823 -409.212365)
			(xy 367.105697 -409.157928) (xy 367.101626 -409.102306) (xy 365.698482 -409.102306) (xy 365.701079 -409.110938)
			(xy 365.709199 -409.166114) (xy 365.709708 -409.194) (xy 365.709199 -409.221886) (xy 365.701079 -409.277062)
			(xy 365.685011 -409.330469) (xy 365.661339 -409.380966) (xy 365.630566 -409.427479) (xy 365.593349 -409.469016)
			(xy 365.550481 -409.504691) (xy 365.502875 -409.533745) (xy 365.451546 -409.555557) (xy 365.397589 -409.569663)
			(xy 365.342152 -409.575763) (xy 365.286418 -409.573726) (xy 365.231575 -409.563596) (xy 365.178791 -409.545589)
			(xy 365.129191 -409.520088) (xy 365.083833 -409.487637) (xy 365.043684 -409.448928) (xy 365.009598 -409.404785)
			(xy 364.982302 -409.35615) (xy 364.962379 -409.304059) (xy 364.950253 -409.249622) (xy 364.946182 -409.194)
			(xy 354.01504 -409.194) (xy 354.01504 -410.505148) (xy 353.22002 -411.300168) (xy 303.8983 -411.300168)
			(xy 302.8188 -410.220668) (xy 302.8188 -379.882908) (xy 302.161956 -379.226064) (xy 289.231832 -379.226064)
			(xy 281.795728 -371.78996) (xy 281.795728 -340.499192) (xy 283.225494 -339.069426) (xy 289.14598 -339.069426)
			(xy 289.317684 -339.24113) (xy 295.839134 -339.24113) (xy 300.861476 -334.218788) (xy 300.30674 -329.238356)
			(xy 300.303881 -329.211078) (xy 300.300834 -329.156309) (xy 300.300644 -329.128882) (xy 300.300644 -325.661782)
			(xy 300.301102 -325.618641) (xy 300.308624 -325.532687) (xy 300.32361 -325.447717) (xy 300.345945 -325.364375)
			(xy 300.37546 -325.283298) (xy 300.411929 -325.205102) (xy 300.455075 -325.130383) (xy 300.50457 -325.059708)
			(xy 300.560036 -324.993617) (xy 300.590204 -324.962774) (xy 300.89983 -324.653402) (xy 300.89983 -317.188088)
			(xy 300.766226 -317.054484) (xy 300.756121 -317.045031) (xy 300.732036 -317.031433) (xy 300.705186 -317.024792)
			(xy 300.677538 -317.025594) (xy 300.651119 -317.033782) (xy 300.627863 -317.048754) (xy 300.609474 -317.069415)
			(xy 300.597299 -317.09425) (xy 300.592231 -317.121441) (xy 300.592998 -317.135256) (xy 300.594522 -317.166752)
			(xy 300.594024 -317.193401) (xy 300.586081 -317.246105) (xy 300.570371 -317.297035) (xy 300.547245 -317.345056)
			(xy 300.517221 -317.389093) (xy 300.480969 -317.428164) (xy 300.439298 -317.461395) (xy 300.39314 -317.488044)
			(xy 300.343526 -317.507516) (xy 300.291564 -317.519376) (xy 300.238414 -317.52336) (xy 300.185264 -317.519376)
			(xy 300.133302 -317.507516) (xy 300.083688 -317.488044) (xy 300.03753 -317.461395) (xy 299.995859 -317.428164)
			(xy 299.959607 -317.389093) (xy 299.929583 -317.345056) (xy 299.906457 -317.297035) (xy 299.890747 -317.246105)
			(xy 299.882804 -317.193401) (xy 299.882306 -317.166752) (xy 299.882723 -317.142446) (xy 299.889344 -317.094288)
			(xy 299.902457 -317.047479) (xy 299.921817 -317.002889) (xy 299.947065 -316.961348) (xy 299.962062 -316.942216)
			(xy 299.970711 -316.930773) (xy 299.981868 -316.904361) (xy 299.985248 -316.875889) (xy 299.980584 -316.847599)
			(xy 299.968244 -316.821719) (xy 299.949199 -316.800287) (xy 299.924949 -316.78499) (xy 299.897404 -316.777032)
			(xy 299.883068 -316.776608) (xy 299.343826 -316.776608) (xy 299.3295 -316.777104) (xy 299.30198 -316.785077)
			(xy 299.277753 -316.800374) (xy 299.258724 -316.821794) (xy 299.246387 -316.847654) (xy 299.241713 -316.875922)
			(xy 299.245067 -316.904377) (xy 299.256187 -316.930783) (xy 299.264832 -316.942216) (xy 299.279866 -316.961323)
			(xy 299.305126 -317.002865) (xy 299.324493 -317.047459) (xy 299.337606 -317.094276) (xy 299.34422 -317.142443)
			(xy 299.344588 -317.166752) (xy 299.34409 -317.193401) (xy 299.336147 -317.246105) (xy 299.320437 -317.297035)
			(xy 299.297311 -317.345056) (xy 299.267287 -317.389093) (xy 299.231035 -317.428164) (xy 299.189364 -317.461395)
			(xy 299.143206 -317.488044) (xy 299.093592 -317.507516) (xy 299.04163 -317.519376) (xy 298.98848 -317.52336)
			(xy 298.93533 -317.519376) (xy 298.883368 -317.507516) (xy 298.833754 -317.488044) (xy 298.787596 -317.461395)
			(xy 298.745925 -317.428164) (xy 298.709673 -317.389093) (xy 298.679649 -317.345056) (xy 298.656523 -317.297035)
			(xy 298.640813 -317.246105) (xy 298.63287 -317.193401) (xy 298.632372 -317.166752) (xy 298.632789 -317.142446)
			(xy 298.63941 -317.094287) (xy 298.652521 -317.047477) (xy 298.67188 -317.002887) (xy 298.697126 -316.961345)
			(xy 298.712128 -316.942216) (xy 298.720779 -316.930775) (xy 298.73194 -316.904365) (xy 298.735322 -316.875894)
			(xy 298.730658 -316.847605) (xy 298.718316 -316.821726) (xy 298.699269 -316.800296) (xy 298.675017 -316.785004)
			(xy 298.64747 -316.777054) (xy 298.633134 -316.776608) (xy 295.25976 -316.776608) (xy 295.245431 -316.7771)
			(xy 295.217902 -316.785067) (xy 295.193666 -316.800363) (xy 295.174629 -316.821786) (xy 295.162288 -316.847651)
			(xy 295.157613 -316.875926) (xy 295.16097 -316.904387) (xy 295.172097 -316.930798) (xy 295.180766 -316.942216)
			(xy 295.195799 -316.961324) (xy 295.221056 -317.002866) (xy 295.240421 -317.047461) (xy 295.253533 -317.094277)
			(xy 295.260147 -317.142443) (xy 295.260522 -317.166752) (xy 295.260024 -317.193401) (xy 295.252081 -317.246105)
			(xy 295.236371 -317.297035) (xy 295.213245 -317.345056) (xy 295.183221 -317.389093) (xy 295.146969 -317.428164)
			(xy 295.105298 -317.461395) (xy 295.05914 -317.488044) (xy 295.009526 -317.507516) (xy 294.957564 -317.519376)
			(xy 294.904414 -317.52336) (xy 294.851264 -317.519376) (xy 294.799302 -317.507516) (xy 294.749688 -317.488044)
			(xy 294.70353 -317.461395) (xy 294.661859 -317.428164) (xy 294.625607 -317.389093) (xy 294.595583 -317.345056)
			(xy 294.572457 -317.297035) (xy 294.556747 -317.246105) (xy 294.548804 -317.193401) (xy 294.548306 -317.166752)
			(xy 294.548723 -317.142446) (xy 294.555344 -317.094288) (xy 294.568457 -317.047479) (xy 294.587817 -317.002889)
			(xy 294.613065 -316.961348) (xy 294.628062 -316.942216) (xy 294.636711 -316.930773) (xy 294.647868 -316.904361)
			(xy 294.651248 -316.875889) (xy 294.646584 -316.847599) (xy 294.634244 -316.821719) (xy 294.615199 -316.800287)
			(xy 294.590949 -316.78499) (xy 294.563404 -316.777032) (xy 294.549068 -316.776608) (xy 293.04996 -316.776608)
			(xy 293.035631 -316.7771) (xy 293.008102 -316.785067) (xy 292.983866 -316.800363) (xy 292.964829 -316.821786)
			(xy 292.952488 -316.847651) (xy 292.947813 -316.875926) (xy 292.95117 -316.904387) (xy 292.962297 -316.930798)
			(xy 292.970966 -316.942216) (xy 292.985999 -316.961324) (xy 293.011256 -317.002866) (xy 293.030621 -317.047461)
			(xy 293.043733 -317.094277) (xy 293.050347 -317.142443) (xy 293.050722 -317.166752) (xy 293.050224 -317.193401)
			(xy 293.042281 -317.246105) (xy 293.026571 -317.297035) (xy 293.003445 -317.345056) (xy 292.973421 -317.389093)
			(xy 292.937169 -317.428164) (xy 292.895498 -317.461395) (xy 292.84934 -317.488044) (xy 292.799726 -317.507516)
			(xy 292.747764 -317.519376) (xy 292.694614 -317.52336) (xy 292.641464 -317.519376) (xy 292.589502 -317.507516)
			(xy 292.539888 -317.488044) (xy 292.49373 -317.461395) (xy 292.452059 -317.428164) (xy 292.415807 -317.389093)
			(xy 292.385783 -317.345056) (xy 292.362657 -317.297035) (xy 292.346947 -317.246105) (xy 292.339004 -317.193401)
			(xy 292.338506 -317.166752) (xy 292.338923 -317.142446) (xy 292.345544 -317.094288) (xy 292.358657 -317.047479)
			(xy 292.378017 -317.002889) (xy 292.403265 -316.961348) (xy 292.418262 -316.942216) (xy 292.426911 -316.930773)
			(xy 292.438068 -316.904361) (xy 292.441448 -316.875889) (xy 292.436784 -316.847599) (xy 292.424444 -316.821719)
			(xy 292.405399 -316.800287) (xy 292.381149 -316.78499) (xy 292.353604 -316.777032) (xy 292.339268 -316.776608)
			(xy 291.816028 -316.776608) (xy 291.801702 -316.777104) (xy 291.774181 -316.785076) (xy 291.749954 -316.800373)
			(xy 291.730924 -316.821793) (xy 291.718587 -316.847654) (xy 291.713913 -316.875922) (xy 291.717267 -316.904377)
			(xy 291.728388 -316.930784) (xy 291.737034 -316.942216) (xy 291.752068 -316.961323) (xy 291.777328 -317.002865)
			(xy 291.796694 -317.047459) (xy 291.809807 -317.094276) (xy 291.816422 -317.142443) (xy 291.81679 -317.166752)
			(xy 291.816292 -317.193401) (xy 291.808349 -317.246105) (xy 291.792639 -317.297035) (xy 291.769513 -317.345056)
			(xy 291.739489 -317.389093) (xy 291.703237 -317.428164) (xy 291.661566 -317.461395) (xy 291.615408 -317.488044)
			(xy 291.565794 -317.507516) (xy 291.513832 -317.519376) (xy 291.460682 -317.52336) (xy 291.407532 -317.519376)
			(xy 291.35557 -317.507516) (xy 291.305956 -317.488044) (xy 291.259798 -317.461395) (xy 291.218127 -317.428164)
			(xy 291.181875 -317.389093) (xy 291.151851 -317.345056) (xy 291.128725 -317.297035) (xy 291.113015 -317.246105)
			(xy 291.105072 -317.193401) (xy 291.104574 -317.166752) (xy 291.104991 -317.142446) (xy 291.111612 -317.094287)
			(xy 291.124723 -317.047477) (xy 291.144082 -317.002887) (xy 291.169329 -316.961345) (xy 291.18433 -316.942216)
			(xy 291.192981 -316.930774) (xy 291.204141 -316.904365) (xy 291.207523 -316.875894) (xy 291.20286 -316.847604)
			(xy 291.190518 -316.821725) (xy 291.171471 -316.800296) (xy 291.147219 -316.785003) (xy 291.119672 -316.777053)
			(xy 291.105336 -316.776608) (xy 287.71596 -316.776608) (xy 287.701631 -316.7771) (xy 287.674102 -316.785067)
			(xy 287.649866 -316.800363) (xy 287.630829 -316.821786) (xy 287.618488 -316.847651) (xy 287.613813 -316.875926)
			(xy 287.61717 -316.904387) (xy 287.628297 -316.930798) (xy 287.636966 -316.942216) (xy 287.651999 -316.961324)
			(xy 287.677256 -317.002866) (xy 287.696621 -317.047461) (xy 287.709733 -317.094277) (xy 287.716347 -317.142443)
			(xy 287.716722 -317.166752) (xy 287.716224 -317.193401) (xy 287.708281 -317.246105) (xy 287.692571 -317.297035)
			(xy 287.669445 -317.345056) (xy 287.639421 -317.389093) (xy 287.603169 -317.428164) (xy 287.561498 -317.461395)
			(xy 287.51534 -317.488044) (xy 287.465726 -317.507516) (xy 287.413764 -317.519376) (xy 287.360614 -317.52336)
			(xy 287.307464 -317.519376) (xy 287.255502 -317.507516) (xy 287.205888 -317.488044) (xy 287.15973 -317.461395)
			(xy 287.118059 -317.428164) (xy 287.081807 -317.389093) (xy 287.051783 -317.345056) (xy 287.028657 -317.297035)
			(xy 287.012947 -317.246105) (xy 287.005004 -317.193401) (xy 287.004506 -317.166752) (xy 287.004923 -317.142446)
			(xy 287.011544 -317.094288) (xy 287.024657 -317.047479) (xy 287.044017 -317.002889) (xy 287.069265 -316.961348)
			(xy 287.084262 -316.942216) (xy 287.092911 -316.930773) (xy 287.104068 -316.904361) (xy 287.107448 -316.875889)
			(xy 287.102784 -316.847599) (xy 287.090444 -316.821719) (xy 287.071399 -316.800287) (xy 287.047149 -316.78499)
			(xy 287.019604 -316.777032) (xy 287.005268 -316.776608) (xy 285.50616 -316.776608) (xy 285.491831 -316.7771)
			(xy 285.464302 -316.785067) (xy 285.440066 -316.800363) (xy 285.421029 -316.821786) (xy 285.408688 -316.847651)
			(xy 285.404013 -316.875926) (xy 285.40737 -316.904387) (xy 285.418497 -316.930798) (xy 285.427166 -316.942216)
			(xy 285.442199 -316.961324) (xy 285.467456 -317.002866) (xy 285.486821 -317.047461) (xy 285.499933 -317.094277)
			(xy 285.506547 -317.142443) (xy 285.506922 -317.166752) (xy 285.506424 -317.193401) (xy 285.498481 -317.246105)
			(xy 285.482771 -317.297035) (xy 285.459645 -317.345056) (xy 285.429621 -317.389093) (xy 285.393369 -317.428164)
			(xy 285.351698 -317.461395) (xy 285.30554 -317.488044) (xy 285.255926 -317.507516) (xy 285.203964 -317.519376)
			(xy 285.150814 -317.52336) (xy 285.097664 -317.519376) (xy 285.045702 -317.507516) (xy 284.996088 -317.488044)
			(xy 284.94993 -317.461395) (xy 284.908259 -317.428164) (xy 284.872007 -317.389093) (xy 284.841983 -317.345056)
			(xy 284.818857 -317.297035) (xy 284.803147 -317.246105) (xy 284.795204 -317.193401) (xy 284.794706 -317.166752)
			(xy 284.795123 -317.142446) (xy 284.801744 -317.094288) (xy 284.814857 -317.047479) (xy 284.834217 -317.002889)
			(xy 284.859465 -316.961348) (xy 284.874462 -316.942216) (xy 284.883111 -316.930773) (xy 284.894268 -316.904361)
			(xy 284.897648 -316.875889) (xy 284.892984 -316.847599) (xy 284.880644 -316.821719) (xy 284.861599 -316.800287)
			(xy 284.837349 -316.78499) (xy 284.809804 -316.777032) (xy 284.795468 -316.776608) (xy 284.272228 -316.776608)
			(xy 284.257902 -316.777104) (xy 284.230381 -316.785076) (xy 284.206154 -316.800373) (xy 284.187124 -316.821793)
			(xy 284.174787 -316.847654) (xy 284.170113 -316.875922) (xy 284.173467 -316.904377) (xy 284.184588 -316.930784)
			(xy 284.193234 -316.942216) (xy 284.208268 -316.961323) (xy 284.233528 -317.002865) (xy 284.252894 -317.047459)
			(xy 284.266007 -317.094276) (xy 284.272622 -317.142443) (xy 284.27299 -317.166752) (xy 284.272492 -317.193401)
			(xy 284.264549 -317.246105) (xy 284.248839 -317.297035) (xy 284.225713 -317.345056) (xy 284.195689 -317.389093)
			(xy 284.159437 -317.428164) (xy 284.117766 -317.461395) (xy 284.071608 -317.488044) (xy 284.021994 -317.507516)
			(xy 283.970032 -317.519376) (xy 283.916882 -317.52336) (xy 283.863732 -317.519376) (xy 283.81177 -317.507516)
			(xy 283.762156 -317.488044) (xy 283.715998 -317.461395) (xy 283.674327 -317.428164) (xy 283.638075 -317.389093)
			(xy 283.608051 -317.345056) (xy 283.584925 -317.297035) (xy 283.569215 -317.246105) (xy 283.561272 -317.193401)
			(xy 283.560774 -317.166752) (xy 283.561191 -317.142446) (xy 283.567812 -317.094287) (xy 283.580923 -317.047477)
			(xy 283.600282 -317.002887) (xy 283.625529 -316.961345) (xy 283.64053 -316.942216) (xy 283.649181 -316.930774)
			(xy 283.660341 -316.904365) (xy 283.663723 -316.875894) (xy 283.65906 -316.847604) (xy 283.646718 -316.821725)
			(xy 283.627671 -316.800296) (xy 283.603419 -316.785003) (xy 283.575872 -316.777053) (xy 283.561536 -316.776608)
			(xy 280.17216 -316.776608) (xy 280.157831 -316.7771) (xy 280.130302 -316.785067) (xy 280.106066 -316.800363)
			(xy 280.087029 -316.821786) (xy 280.074688 -316.847651) (xy 280.070013 -316.875926) (xy 280.07337 -316.904387)
			(xy 280.084497 -316.930798) (xy 280.093166 -316.942216) (xy 280.108199 -316.961324) (xy 280.133456 -317.002866)
			(xy 280.152821 -317.047461) (xy 280.165933 -317.094277) (xy 280.172547 -317.142443) (xy 280.172922 -317.166752)
			(xy 280.172424 -317.193401) (xy 280.164481 -317.246105) (xy 280.148771 -317.297035) (xy 280.125645 -317.345056)
			(xy 280.095621 -317.389093) (xy 280.059369 -317.428164) (xy 280.017698 -317.461395) (xy 279.97154 -317.488044)
			(xy 279.921926 -317.507516) (xy 279.869964 -317.519376) (xy 279.816814 -317.52336) (xy 279.763664 -317.519376)
			(xy 279.711702 -317.507516) (xy 279.662088 -317.488044) (xy 279.61593 -317.461395) (xy 279.574259 -317.428164)
			(xy 279.538007 -317.389093) (xy 279.507983 -317.345056) (xy 279.484857 -317.297035) (xy 279.469147 -317.246105)
			(xy 279.461204 -317.193401) (xy 279.460706 -317.166752) (xy 279.461123 -317.142446) (xy 279.467744 -317.094288)
			(xy 279.480857 -317.047479) (xy 279.500217 -317.002889) (xy 279.525465 -316.961348) (xy 279.540462 -316.942216)
			(xy 279.549111 -316.930773) (xy 279.560268 -316.904361) (xy 279.563648 -316.875889) (xy 279.558984 -316.847599)
			(xy 279.546644 -316.821719) (xy 279.527599 -316.800287) (xy 279.503349 -316.78499) (xy 279.475804 -316.777032)
			(xy 279.461468 -316.776608) (xy 277.96236 -316.776608) (xy 277.948031 -316.7771) (xy 277.920502 -316.785067)
			(xy 277.896266 -316.800363) (xy 277.877229 -316.821786) (xy 277.864888 -316.847651) (xy 277.860213 -316.875926)
			(xy 277.86357 -316.904387) (xy 277.874697 -316.930798) (xy 277.883366 -316.942216) (xy 277.898399 -316.961324)
			(xy 277.923656 -317.002866) (xy 277.943021 -317.047461) (xy 277.956133 -317.094277) (xy 277.962747 -317.142443)
			(xy 277.963122 -317.166752) (xy 277.962624 -317.193401) (xy 277.954681 -317.246105) (xy 277.938971 -317.297035)
			(xy 277.915845 -317.345056) (xy 277.885821 -317.389093) (xy 277.849569 -317.428164) (xy 277.807898 -317.461395)
			(xy 277.76174 -317.488044) (xy 277.712126 -317.507516) (xy 277.660164 -317.519376) (xy 277.607014 -317.52336)
			(xy 277.553864 -317.519376) (xy 277.501902 -317.507516) (xy 277.452288 -317.488044) (xy 277.40613 -317.461395)
			(xy 277.364459 -317.428164) (xy 277.328207 -317.389093) (xy 277.298183 -317.345056) (xy 277.275057 -317.297035)
			(xy 277.259347 -317.246105) (xy 277.251404 -317.193401) (xy 277.250906 -317.166752) (xy 277.251338 -317.141663)
			(xy 277.258389 -317.091984) (xy 277.272344 -317.043786) (xy 277.292927 -316.998024) (xy 277.31973 -316.955605)
			(xy 277.352223 -316.917369) (xy 277.389761 -316.884073) (xy 277.410418 -316.869826) (xy 277.433278 -316.854586)
			(xy 277.433278 -316.776608) (xy 277.275798 -316.776608) (xy 277.263606 -316.809882) (xy 277.253772 -316.835186)
			(xy 277.227545 -316.882718) (xy 277.194411 -316.92572) (xy 277.155136 -316.963197) (xy 277.110629 -316.994281)
			(xy 277.061921 -317.018252) (xy 277.01014 -317.034555) (xy 276.956485 -317.042813) (xy 276.929342 -317.043308)
			(xy 276.909747 -317.043026) (xy 276.870796 -317.038701) (xy 276.851618 -317.034672) (xy 276.838317 -317.032139)
			(xy 276.81128 -317.033397) (xy 276.785524 -317.041719) (xy 276.762862 -317.05652) (xy 276.744889 -317.076758)
			(xy 276.732869 -317.101009) (xy 276.727647 -317.127567) (xy 276.728174 -317.141098) (xy 276.72919 -317.166752)
			(xy 276.728692 -317.193401) (xy 276.720749 -317.246105) (xy 276.705039 -317.297035) (xy 276.681913 -317.345056)
			(xy 276.651889 -317.389093) (xy 276.615637 -317.428164) (xy 276.573966 -317.461395) (xy 276.527808 -317.488044)
			(xy 276.478194 -317.507516) (xy 276.426232 -317.519376) (xy 276.373082 -317.52336) (xy 276.319932 -317.519376)
			(xy 276.26797 -317.507516) (xy 276.218356 -317.488044) (xy 276.172198 -317.461395) (xy 276.130527 -317.428164)
			(xy 276.094275 -317.389093) (xy 276.064251 -317.345056) (xy 276.041125 -317.297035) (xy 276.025415 -317.246105)
			(xy 276.017472 -317.193401) (xy 276.016974 -317.166752) (xy 276.017391 -317.142446) (xy 276.024012 -317.094287)
			(xy 276.037123 -317.047477) (xy 276.056482 -317.002887) (xy 276.081729 -316.961345) (xy 276.09673 -316.942216)
			(xy 276.105381 -316.930774) (xy 276.116541 -316.904365) (xy 276.119923 -316.875894) (xy 276.11526 -316.847604)
			(xy 276.102918 -316.821725) (xy 276.083871 -316.800296) (xy 276.059619 -316.785003) (xy 276.032072 -316.777053)
			(xy 276.017736 -316.776608) (xy 272.62836 -316.776608) (xy 272.614031 -316.7771) (xy 272.586502 -316.785067)
			(xy 272.562266 -316.800363) (xy 272.543229 -316.821786) (xy 272.530888 -316.847651) (xy 272.526213 -316.875926)
			(xy 272.52957 -316.904387) (xy 272.540697 -316.930798) (xy 272.549366 -316.942216) (xy 272.564399 -316.961324)
			(xy 272.589656 -317.002866) (xy 272.609021 -317.047461) (xy 272.622133 -317.094277) (xy 272.628747 -317.142443)
			(xy 272.629122 -317.166752) (xy 272.628624 -317.193401) (xy 272.620681 -317.246105) (xy 272.604971 -317.297035)
			(xy 272.581845 -317.345056) (xy 272.551821 -317.389093) (xy 272.515569 -317.428164) (xy 272.473898 -317.461395)
			(xy 272.42774 -317.488044) (xy 272.378126 -317.507516) (xy 272.326164 -317.519376) (xy 272.273014 -317.52336)
			(xy 272.219864 -317.519376) (xy 272.167902 -317.507516) (xy 272.118288 -317.488044) (xy 272.07213 -317.461395)
			(xy 272.030459 -317.428164) (xy 271.994207 -317.389093) (xy 271.964183 -317.345056) (xy 271.941057 -317.297035)
			(xy 271.925347 -317.246105) (xy 271.917404 -317.193401) (xy 271.916906 -317.166752) (xy 271.917323 -317.142446)
			(xy 271.923944 -317.094288) (xy 271.937057 -317.047479) (xy 271.956417 -317.002889) (xy 271.981665 -316.961348)
			(xy 271.996662 -316.942216) (xy 272.005311 -316.930773) (xy 272.016468 -316.904361) (xy 272.019848 -316.875889)
			(xy 272.015184 -316.847599) (xy 272.002844 -316.821719) (xy 271.983799 -316.800287) (xy 271.959549 -316.78499)
			(xy 271.932004 -316.777032) (xy 271.917668 -316.776608) (xy 270.41856 -316.776608) (xy 270.404231 -316.7771)
			(xy 270.376702 -316.785067) (xy 270.352466 -316.800363) (xy 270.333429 -316.821786) (xy 270.321088 -316.847651)
			(xy 270.316413 -316.875926) (xy 270.31977 -316.904387) (xy 270.330897 -316.930798) (xy 270.339566 -316.942216)
			(xy 270.354599 -316.961324) (xy 270.379856 -317.002866) (xy 270.399221 -317.047461) (xy 270.412333 -317.094277)
			(xy 270.418947 -317.142443) (xy 270.419322 -317.166752) (xy 270.418824 -317.193401) (xy 270.410881 -317.246105)
			(xy 270.395171 -317.297035) (xy 270.372045 -317.345056) (xy 270.342021 -317.389093) (xy 270.305769 -317.428164)
			(xy 270.264098 -317.461395) (xy 270.21794 -317.488044) (xy 270.168326 -317.507516) (xy 270.116364 -317.519376)
			(xy 270.063214 -317.52336) (xy 270.010064 -317.519376) (xy 269.958102 -317.507516) (xy 269.908488 -317.488044)
			(xy 269.86233 -317.461395) (xy 269.820659 -317.428164) (xy 269.784407 -317.389093) (xy 269.754383 -317.345056)
			(xy 269.731257 -317.297035) (xy 269.715547 -317.246105) (xy 269.707604 -317.193401) (xy 269.707106 -317.166752)
			(xy 269.707523 -317.142446) (xy 269.714144 -317.094288) (xy 269.727257 -317.047479) (xy 269.746617 -317.002889)
			(xy 269.771865 -316.961348) (xy 269.786862 -316.942216) (xy 269.795511 -316.930773) (xy 269.806668 -316.904361)
			(xy 269.810048 -316.875889) (xy 269.805384 -316.847599) (xy 269.793044 -316.821719) (xy 269.773999 -316.800287)
			(xy 269.749749 -316.78499) (xy 269.722204 -316.777032) (xy 269.707868 -316.776608) (xy 269.184628 -316.776608)
			(xy 269.170302 -316.777104) (xy 269.142781 -316.785076) (xy 269.118554 -316.800373) (xy 269.099524 -316.821793)
			(xy 269.087187 -316.847654) (xy 269.082513 -316.875922) (xy 269.085867 -316.904377) (xy 269.096988 -316.930784)
			(xy 269.105634 -316.942216) (xy 269.120668 -316.961323) (xy 269.145928 -317.002865) (xy 269.165294 -317.047459)
			(xy 269.178407 -317.094276) (xy 269.185022 -317.142443) (xy 269.18539 -317.166752) (xy 269.184892 -317.193401)
			(xy 269.176949 -317.246105) (xy 269.161239 -317.297035) (xy 269.138113 -317.345056) (xy 269.108089 -317.389093)
			(xy 269.071837 -317.428164) (xy 269.030166 -317.461395) (xy 268.984008 -317.488044) (xy 268.934394 -317.507516)
			(xy 268.882432 -317.519376) (xy 268.829282 -317.52336) (xy 268.776132 -317.519376) (xy 268.72417 -317.507516)
			(xy 268.674556 -317.488044) (xy 268.628398 -317.461395) (xy 268.586727 -317.428164) (xy 268.550475 -317.389093)
			(xy 268.520451 -317.345056) (xy 268.497325 -317.297035) (xy 268.481615 -317.246105) (xy 268.473672 -317.193401)
			(xy 268.473174 -317.166752) (xy 268.473591 -317.142446) (xy 268.480212 -317.094287) (xy 268.493323 -317.047477)
			(xy 268.512682 -317.002887) (xy 268.537929 -316.961345) (xy 268.55293 -316.942216) (xy 268.561581 -316.930774)
			(xy 268.572741 -316.904365) (xy 268.576123 -316.875894) (xy 268.57146 -316.847604) (xy 268.559118 -316.821725)
			(xy 268.540071 -316.800296) (xy 268.515819 -316.785003) (xy 268.488272 -316.777053) (xy 268.473936 -316.776608)
			(xy 265.08456 -316.776608) (xy 265.070231 -316.7771) (xy 265.042702 -316.785067) (xy 265.018466 -316.800363)
			(xy 264.999429 -316.821786) (xy 264.987088 -316.847651) (xy 264.982413 -316.875926) (xy 264.98577 -316.904387)
			(xy 264.996897 -316.930798) (xy 265.005566 -316.942216) (xy 265.020599 -316.961324) (xy 265.045856 -317.002866)
			(xy 265.065221 -317.047461) (xy 265.078333 -317.094277) (xy 265.084947 -317.142443) (xy 265.085322 -317.166752)
			(xy 265.084824 -317.193401) (xy 265.076881 -317.246105) (xy 265.061171 -317.297035) (xy 265.038045 -317.345056)
			(xy 265.008021 -317.389093) (xy 264.971769 -317.428164) (xy 264.930098 -317.461395) (xy 264.88394 -317.488044)
			(xy 264.834326 -317.507516) (xy 264.782364 -317.519376) (xy 264.729214 -317.52336) (xy 264.676064 -317.519376)
			(xy 264.624102 -317.507516) (xy 264.574488 -317.488044) (xy 264.52833 -317.461395) (xy 264.486659 -317.428164)
			(xy 264.450407 -317.389093) (xy 264.420383 -317.345056) (xy 264.397257 -317.297035) (xy 264.381547 -317.246105)
			(xy 264.373604 -317.193401) (xy 264.373106 -317.166752) (xy 264.373523 -317.142446) (xy 264.380144 -317.094288)
			(xy 264.393257 -317.047479) (xy 264.412617 -317.002889) (xy 264.437865 -316.961348) (xy 264.452862 -316.942216)
			(xy 264.461511 -316.930773) (xy 264.472668 -316.904361) (xy 264.476048 -316.875889) (xy 264.471384 -316.847599)
			(xy 264.459044 -316.821719) (xy 264.439999 -316.800287) (xy 264.415749 -316.78499) (xy 264.388204 -316.777032)
			(xy 264.373868 -316.776608) (xy 262.87476 -316.776608) (xy 262.860431 -316.7771) (xy 262.832902 -316.785067)
			(xy 262.808666 -316.800363) (xy 262.789629 -316.821786) (xy 262.777288 -316.847651) (xy 262.772613 -316.875926)
			(xy 262.77597 -316.904387) (xy 262.787097 -316.930798) (xy 262.795766 -316.942216) (xy 262.810799 -316.961324)
			(xy 262.836056 -317.002866) (xy 262.855421 -317.047461) (xy 262.868533 -317.094277) (xy 262.875147 -317.142443)
			(xy 262.875522 -317.166752) (xy 262.875024 -317.193401) (xy 262.867081 -317.246105) (xy 262.851371 -317.297035)
			(xy 262.828245 -317.345056) (xy 262.798221 -317.389093) (xy 262.761969 -317.428164) (xy 262.720298 -317.461395)
			(xy 262.67414 -317.488044) (xy 262.624526 -317.507516) (xy 262.572564 -317.519376) (xy 262.519414 -317.52336)
			(xy 262.466264 -317.519376) (xy 262.414302 -317.507516) (xy 262.364688 -317.488044) (xy 262.31853 -317.461395)
			(xy 262.276859 -317.428164) (xy 262.240607 -317.389093) (xy 262.210583 -317.345056) (xy 262.187457 -317.297035)
			(xy 262.171747 -317.246105) (xy 262.163804 -317.193401) (xy 262.163306 -317.166752) (xy 262.163723 -317.142446)
			(xy 262.170344 -317.094288) (xy 262.183457 -317.047479) (xy 262.202817 -317.002889) (xy 262.228065 -316.961348)
			(xy 262.243062 -316.942216) (xy 262.251711 -316.930773) (xy 262.262868 -316.904361) (xy 262.266248 -316.875889)
			(xy 262.261584 -316.847599) (xy 262.249244 -316.821719) (xy 262.230199 -316.800287) (xy 262.205949 -316.78499)
			(xy 262.178404 -316.777032) (xy 262.164068 -316.776608) (xy 259.431028 -316.776608) (xy 259.416702 -316.777104)
			(xy 259.389181 -316.785076) (xy 259.364954 -316.800373) (xy 259.345924 -316.821793) (xy 259.333587 -316.847654)
			(xy 259.328913 -316.875922) (xy 259.332267 -316.904377) (xy 259.343388 -316.930784) (xy 259.352034 -316.942216)
			(xy 259.367068 -316.961323) (xy 259.392328 -317.002865) (xy 259.411694 -317.047459) (xy 259.424807 -317.094276)
			(xy 259.431422 -317.142443) (xy 259.43179 -317.166752) (xy 259.431273 -317.194739) (xy 259.422523 -317.250026)
			(xy 259.405231 -317.303262) (xy 259.379823 -317.353138) (xy 259.346925 -317.398424) (xy 259.307347 -317.438006)
			(xy 259.262063 -317.470908) (xy 259.21219 -317.49632) (xy 259.158955 -317.513616) (xy 259.103669 -317.522371)
			(xy 259.075682 -317.52286) (xy 259.049542 -317.522399) (xy 258.997825 -317.514754) (xy 258.947781 -317.49963)
			(xy 258.900485 -317.477354) (xy 258.856954 -317.448402) (xy 258.818123 -317.413398) (xy 258.784826 -317.373093)
			(xy 258.757779 -317.328354) (xy 258.74726 -317.30442) (xy 258.741258 -317.291353) (xy 258.723222 -317.268973)
			(xy 258.699672 -317.252496) (xy 258.672466 -317.243222) (xy 258.643755 -317.241885) (xy 258.629658 -317.24473)
			(xy 258.609202 -317.249336) (xy 258.567565 -317.254296) (xy 258.5466 -317.254636) (xy 258.518616 -317.254087)
			(xy 258.463337 -317.245332) (xy 258.410108 -317.228038) (xy 258.36024 -317.20263) (xy 258.31496 -317.169735)
			(xy 258.275383 -317.130161) (xy 258.242484 -317.084884) (xy 258.217073 -317.035017) (xy 258.199774 -316.98179)
			(xy 258.191015 -316.926512) (xy 258.190492 -316.898528) (xy 258.190746 -316.88278) (xy 258.190907 -316.869089)
			(xy 258.184807 -316.842407) (xy 258.171841 -316.818303) (xy 258.152938 -316.798509) (xy 258.129457 -316.784447)
			(xy 258.103084 -316.777125) (xy 258.0894 -316.776608) (xy 257.54076 -316.776608) (xy 257.526431 -316.7771)
			(xy 257.498902 -316.785067) (xy 257.474666 -316.800363) (xy 257.455629 -316.821786) (xy 257.443288 -316.847651)
			(xy 257.438613 -316.875926) (xy 257.44197 -316.904387) (xy 257.453097 -316.930798) (xy 257.461766 -316.942216)
			(xy 257.476799 -316.961324) (xy 257.502056 -317.002866) (xy 257.521421 -317.047461) (xy 257.534533 -317.094277)
			(xy 257.541147 -317.142443) (xy 257.541522 -317.166752) (xy 257.541024 -317.193401) (xy 257.533081 -317.246105)
			(xy 257.517371 -317.297035) (xy 257.494245 -317.345056) (xy 257.464221 -317.389093) (xy 257.427969 -317.428164)
			(xy 257.386298 -317.461395) (xy 257.34014 -317.488044) (xy 257.290526 -317.507516) (xy 257.238564 -317.519376)
			(xy 257.185414 -317.52336) (xy 257.132264 -317.519376) (xy 257.080302 -317.507516) (xy 257.030688 -317.488044)
			(xy 256.98453 -317.461395) (xy 256.942859 -317.428164) (xy 256.906607 -317.389093) (xy 256.876583 -317.345056)
			(xy 256.853457 -317.297035) (xy 256.837747 -317.246105) (xy 256.829804 -317.193401) (xy 256.829306 -317.166752)
			(xy 256.829723 -317.142446) (xy 256.836344 -317.094288) (xy 256.849457 -317.047479) (xy 256.868817 -317.002889)
			(xy 256.894065 -316.961348) (xy 256.909062 -316.942216) (xy 256.917711 -316.930773) (xy 256.928868 -316.904361)
			(xy 256.932248 -316.875889) (xy 256.927584 -316.847599) (xy 256.915244 -316.821719) (xy 256.896199 -316.800287)
			(xy 256.871949 -316.78499) (xy 256.844404 -316.777032) (xy 256.830068 -316.776608) (xy 255.226058 -316.776608)
			(xy 252.805946 -314.356496) (xy 252.805946 -197.854824) (xy 252.805504 -197.841717) (xy 252.798758 -197.816383)
			(xy 252.785782 -197.793603) (xy 252.767433 -197.774878) (xy 252.74492 -197.761444) (xy 252.719727 -197.754188)
			(xy 252.706632 -197.753478) (xy 252.678508 -197.752336) (xy 252.623034 -197.742805) (xy 252.569563 -197.725228)
			(xy 252.519254 -197.699987) (xy 252.473199 -197.667629) (xy 252.432397 -197.628856) (xy 252.397733 -197.58451)
			(xy 252.36996 -197.535553) (xy 252.349681 -197.483048) (xy 252.337334 -197.428132) (xy 252.333189 -197.371999)
			(xy 252.337334 -197.315866) (xy 252.349681 -197.260951) (xy 252.369961 -197.208445) (xy 252.397734 -197.159489)
			(xy 252.432398 -197.115143) (xy 252.4732 -197.07637) (xy 252.519255 -197.044013) (xy 252.569565 -197.018772)
			(xy 252.623036 -197.001195) (xy 252.678509 -196.991664) (xy 252.706632 -196.990462) (xy 252.719734 -196.989766)
			(xy 252.744942 -196.982524) (xy 252.76747 -196.969095) (xy 252.785831 -196.950366) (xy 252.79881 -196.927576)
			(xy 252.805551 -196.902229) (xy 252.805946 -196.889116) (xy 252.805946 -196.805296) (xy 252.80547 -196.795348)
			(xy 252.797906 -196.776948) (xy 252.783914 -196.762804) (xy 252.765596 -196.75504) (xy 252.755654 -196.754496)
			(xy 252.72863 -196.753683) (xy 252.675207 -196.745371) (xy 252.623493 -196.729601) (xy 252.574523 -196.706688)
			(xy 252.529278 -196.677091) (xy 252.488665 -196.641404) (xy 252.453496 -196.60034) (xy 252.424477 -196.554723)
			(xy 252.402188 -196.505466) (xy 252.387076 -196.453556) (xy 252.379443 -196.400032) (xy 252.379443 -196.345967)
			(xy 252.387076 -196.292444) (xy 252.402188 -196.240533) (xy 252.424477 -196.191276) (xy 252.453496 -196.145659)
			(xy 252.488665 -196.104596) (xy 252.529279 -196.068909) (xy 252.574523 -196.039312) (xy 252.623493 -196.016399)
			(xy 252.675207 -196.000629) (xy 252.72863 -195.992317) (xy 252.755654 -195.99148) (xy 252.765586 -195.990897)
			(xy 252.783886 -195.983139) (xy 252.797861 -195.969005) (xy 252.805412 -195.950618) (xy 252.805946 -195.94068)
			(xy 252.805946 -194.619372) (xy 256.69621 -190.729108) (xy 256.705802 -190.718905) (xy 256.719497 -190.69449)
			(xy 256.726049 -190.667273) (xy 256.724966 -190.6393) (xy 256.71633 -190.612672) (xy 256.700789 -190.589387)
			(xy 256.679512 -190.571196) (xy 256.654094 -190.559465) (xy 256.64033 -190.556896) (xy 256.611037 -190.551695)
			(xy 256.554429 -190.533402) (xy 256.501353 -190.506531) (xy 256.453099 -190.471737) (xy 256.431542 -190.451232)
			(xy 256.421435 -190.44189) (xy 256.39741 -190.428487) (xy 256.370679 -190.42198) (xy 256.343181 -190.422841)
			(xy 256.31691 -190.431009) (xy 256.293771 -190.445889) (xy 256.284222 -190.455804) (xy 256.266064 -190.475487)
			(xy 256.225181 -190.510075) (xy 256.17986 -190.5386) (xy 256.130992 -190.560502) (xy 256.079541 -190.57535)
			(xy 256.026518 -190.58285) (xy 255.999742 -190.583312) (xy 255.972373 -190.582836) (xy 255.918199 -190.575005)
			(xy 255.8657 -190.559512) (xy 255.815954 -190.536675) (xy 255.769982 -190.506963) (xy 255.749044 -190.489332)
			(xy 255.737716 -190.480096) (xy 255.711159 -190.46792) (xy 255.682242 -190.463747) (xy 255.653325 -190.46792)
			(xy 255.626768 -190.480096) (xy 255.61544 -190.489332) (xy 255.594507 -190.506969) (xy 255.548538 -190.536686)
			(xy 255.498791 -190.559519) (xy 255.446288 -190.575) (xy 255.392111 -190.582809) (xy 255.364742 -190.583312)
			(xy 255.337487 -190.582852) (xy 255.283531 -190.575099) (xy 255.231227 -190.559747) (xy 255.181642 -190.537106)
			(xy 255.135783 -190.507639) (xy 255.094585 -190.471945) (xy 255.058886 -190.430751) (xy 255.029414 -190.384895)
			(xy 255.006768 -190.335312) (xy 254.99141 -190.28301) (xy 254.983651 -190.229055) (xy 254.983651 -190.174545)
			(xy 254.99141 -190.12059) (xy 255.006768 -190.068288) (xy 255.029414 -190.018705) (xy 255.058886 -189.972849)
			(xy 255.094585 -189.931655) (xy 255.135783 -189.895961) (xy 255.181642 -189.866494) (xy 255.231227 -189.843853)
			(xy 255.283531 -189.828501) (xy 255.337487 -189.820748) (xy 255.364742 -189.820296) (xy 255.392111 -189.820771)
			(xy 255.446286 -189.8286) (xy 255.498787 -189.844091) (xy 255.548534 -189.866927) (xy 255.594507 -189.896638)
			(xy 255.61544 -189.914276) (xy 255.626768 -189.923512) (xy 255.653325 -189.935688) (xy 255.682242 -189.939861)
			(xy 255.711159 -189.935688) (xy 255.737716 -189.923512) (xy 255.749044 -189.914276) (xy 255.769977 -189.896637)
			(xy 255.815945 -189.866919) (xy 255.865692 -189.844083) (xy 255.918195 -189.828599) (xy 255.972373 -189.820788)
			(xy 255.999742 -189.820296) (xy 256.029543 -189.820866) (xy 256.08842 -189.830128) (xy 256.145139 -189.848436)
			(xy 256.198321 -189.875344) (xy 256.246669 -189.910196) (xy 256.26822 -189.930786) (xy 256.278328 -189.940132)
			(xy 256.302357 -189.953542) (xy 256.329092 -189.960057) (xy 256.356597 -189.959202) (xy 256.382877 -189.951041)
			(xy 256.406027 -189.936165) (xy 256.41554 -189.926214) (xy 256.436002 -189.904132) (xy 256.482638 -189.866065)
			(xy 256.534674 -189.835795) (xy 256.590818 -189.814072) (xy 256.649676 -189.801437) (xy 256.6797 -189.799214)
			(xy 256.693178 -189.798074) (xy 256.718852 -189.789595) (xy 256.741398 -189.77467) (xy 256.759233 -189.754348)
			(xy 256.771103 -189.730054) (xy 256.776176 -189.703496) (xy 256.774095 -189.676538) (xy 256.765007 -189.651073)
			(xy 256.757678 -189.639702) (xy 256.735282 -189.606829) (xy 256.695626 -189.53787) (xy 256.66211 -189.465726)
			(xy 256.634988 -189.390943) (xy 256.614464 -189.314087) (xy 256.600694 -189.235739) (xy 256.593783 -189.156491)
			(xy 256.59334 -189.116716) (xy 256.593813 -189.074439) (xy 256.601613 -188.990247) (xy 256.617149 -188.907133)
			(xy 256.640287 -188.825808) (xy 256.670831 -188.746965) (xy 256.70852 -188.671276) (xy 256.753032 -188.599388)
			(xy 256.803988 -188.531914) (xy 256.860952 -188.469429) (xy 256.923438 -188.412467) (xy 256.990914 -188.361514)
			(xy 257.062804 -188.317005) (xy 257.138494 -188.279319) (xy 257.217338 -188.248777) (xy 257.298665 -188.225641)
			(xy 257.381779 -188.210109) (xy 257.465971 -188.202311) (xy 257.508248 -188.201808) (xy 258.752848 -188.201808)
			(xy 258.795122 -188.202298) (xy 258.87931 -188.210104) (xy 258.962419 -188.225644) (xy 259.043739 -188.248785)
			(xy 259.122578 -188.279332) (xy 259.198261 -188.317021) (xy 259.270144 -188.361534) (xy 259.337614 -188.412488)
			(xy 259.400094 -188.469451) (xy 259.457053 -188.531935) (xy 259.508003 -188.599408) (xy 259.55251 -188.671295)
			(xy 259.590194 -188.746981) (xy 259.620735 -188.825821) (xy 259.643871 -188.907143) (xy 259.659405 -188.990253)
			(xy 259.667205 -189.074441) (xy 259.667756 -189.116716) (xy 259.667274 -189.15884) (xy 259.659526 -189.24273)
			(xy 259.644097 -189.325552) (xy 259.621117 -189.406604) (xy 259.590783 -189.485201) (xy 259.553349 -189.560675)
			(xy 259.509135 -189.632387) (xy 259.458513 -189.69973) (xy 259.401914 -189.762132) (xy 259.339817 -189.819066)
			(xy 259.306568 -189.844934) (xy 259.295649 -189.853822) (xy 259.278771 -189.876345) (xy 259.268687 -189.902621)
			(xy 259.266163 -189.930653) (xy 259.271392 -189.958308) (xy 259.283976 -189.983483) (xy 259.302958 -190.004263)
			(xy 259.326894 -190.019069) (xy 259.353964 -190.026773) (xy 259.368036 -190.027306) (xy 264.43686 -190.027306)
			(xy 264.450942 -190.026857) (xy 264.478036 -190.019168) (xy 264.501996 -190.004363) (xy 264.520995 -189.983573)
			(xy 264.533586 -189.95838) (xy 264.53881 -189.930704) (xy 264.536268 -189.902655) (xy 264.526154 -189.876369)
			(xy 264.509239 -189.85385) (xy 264.498328 -189.844934) (xy 264.465082 -189.819062) (xy 264.402979 -189.762133)
			(xy 264.346376 -189.699734) (xy 264.295752 -189.632392) (xy 264.251535 -189.560681) (xy 264.214102 -189.485206)
			(xy 264.183769 -189.406609) (xy 264.160793 -189.325555) (xy 264.14537 -189.242731) (xy 264.137629 -189.15884)
			(xy 264.13714 -189.116716) (xy 264.137613 -189.074439) (xy 264.145413 -188.990247) (xy 264.160949 -188.907133)
			(xy 264.184087 -188.825808) (xy 264.214631 -188.746965) (xy 264.25232 -188.671276) (xy 264.296832 -188.599388)
			(xy 264.347788 -188.531914) (xy 264.404752 -188.469429) (xy 264.467238 -188.412467) (xy 264.534714 -188.361514)
			(xy 264.606604 -188.317005) (xy 264.682294 -188.279319) (xy 264.761138 -188.248777) (xy 264.842465 -188.225641)
			(xy 264.925579 -188.210109) (xy 265.009771 -188.202311) (xy 265.052048 -188.201808) (xy 266.296648 -188.201808)
			(xy 266.338922 -188.202298) (xy 266.42311 -188.210104) (xy 266.506219 -188.225644) (xy 266.587539 -188.248785)
			(xy 266.666378 -188.279332) (xy 266.742061 -188.317021) (xy 266.813944 -188.361534) (xy 266.881414 -188.412488)
			(xy 266.943894 -188.469451) (xy 267.000853 -188.531935) (xy 267.017978 -188.554614) (xy 267.269722 -188.554614)
			(xy 267.270208 -188.527363) (xy 267.277964 -188.473415) (xy 267.293319 -188.42112) (xy 267.315961 -188.371543)
			(xy 267.345427 -188.325693) (xy 267.381118 -188.284502) (xy 267.422309 -188.248811) (xy 267.468159 -188.219345)
			(xy 267.517736 -188.196703) (xy 267.570031 -188.181348) (xy 267.623979 -188.173592) (xy 267.678481 -188.173592)
			(xy 267.732429 -188.181348) (xy 267.784724 -188.196703) (xy 267.834301 -188.219345) (xy 267.880151 -188.248811)
			(xy 267.921342 -188.284502) (xy 267.957033 -188.325693) (xy 267.986499 -188.371543) (xy 268.009141 -188.42112)
			(xy 268.024496 -188.473415) (xy 268.032252 -188.527363) (xy 268.032738 -188.554614) (xy 268.032107 -188.587338)
			(xy 268.020989 -188.651833) (xy 268.01064 -188.682884) (xy 268.006133 -188.696927) (xy 268.004602 -188.72637)
			(xy 268.011537 -188.755025) (xy 268.026361 -188.78051) (xy 268.047841 -188.800705) (xy 268.07419 -188.813931)
			(xy 268.088618 -188.816996) (xy 268.114745 -188.822162) (xy 268.165384 -188.838651) (xy 268.213237 -188.862022)
			(xy 268.257375 -188.891823) (xy 268.296938 -188.927473) (xy 268.331158 -188.968279) (xy 268.359369 -189.013449)
			(xy 268.381023 -189.062103) (xy 268.395699 -189.113297) (xy 268.403112 -189.166034) (xy 268.403578 -189.192662)
			(xy 268.403092 -189.219913) (xy 268.395336 -189.273861) (xy 268.379981 -189.326156) (xy 268.357339 -189.375733)
			(xy 268.327873 -189.421583) (xy 268.292182 -189.462774) (xy 268.250991 -189.498465) (xy 268.205141 -189.527931)
			(xy 268.155564 -189.550573) (xy 268.103269 -189.565928) (xy 268.049321 -189.573684) (xy 267.994819 -189.573684)
			(xy 267.940871 -189.565928) (xy 267.888576 -189.550573) (xy 267.838999 -189.527931) (xy 267.793149 -189.498465)
			(xy 267.751958 -189.462774) (xy 267.716267 -189.421583) (xy 267.686801 -189.375733) (xy 267.664159 -189.326156)
			(xy 267.648804 -189.273861) (xy 267.641048 -189.219913) (xy 267.640562 -189.192662) (xy 267.641212 -189.159939)
			(xy 267.652317 -189.095444) (xy 267.66266 -189.064392) (xy 267.66708 -189.050324) (xy 267.668628 -189.020895)
			(xy 267.661711 -188.992247) (xy 267.646904 -188.966767) (xy 267.625439 -188.946573) (xy 267.599103 -188.933346)
			(xy 267.584682 -188.93028) (xy 267.55855 -188.925136) (xy 267.507909 -188.908647) (xy 267.460055 -188.885273)
			(xy 267.415917 -188.85547) (xy 267.376353 -188.819818) (xy 267.342134 -188.779008) (xy 267.313923 -188.733836)
			(xy 267.29227 -188.685179) (xy 267.277596 -188.633982) (xy 267.270186 -188.581243) (xy 267.269722 -188.554614)
			(xy 267.017978 -188.554614) (xy 267.051803 -188.599408) (xy 267.09631 -188.671295) (xy 267.133994 -188.746981)
			(xy 267.164535 -188.825821) (xy 267.187671 -188.907143) (xy 267.203205 -188.990253) (xy 267.211005 -189.074441)
			(xy 267.211556 -189.116716) (xy 267.211074 -189.15884) (xy 267.203326 -189.24273) (xy 267.187897 -189.325552)
			(xy 267.164917 -189.406604) (xy 267.134583 -189.485201) (xy 267.097149 -189.560675) (xy 267.052935 -189.632387)
			(xy 267.002313 -189.69973) (xy 266.945714 -189.762132) (xy 266.883617 -189.819066) (xy 266.850368 -189.844934)
			(xy 266.839449 -189.853822) (xy 266.822571 -189.876345) (xy 266.812487 -189.902621) (xy 266.809963 -189.930653)
			(xy 266.815192 -189.958308) (xy 266.827776 -189.983483) (xy 266.846758 -190.004263) (xy 266.870694 -190.019069)
			(xy 266.897764 -190.026773) (xy 266.911836 -190.027306) (xy 271.98066 -190.027306) (xy 271.994742 -190.026857)
			(xy 272.021836 -190.019168) (xy 272.045796 -190.004363) (xy 272.064795 -189.983573) (xy 272.077386 -189.95838)
			(xy 272.08261 -189.930704) (xy 272.080068 -189.902655) (xy 272.069954 -189.876369) (xy 272.053039 -189.85385)
			(xy 272.042128 -189.844934) (xy 272.008882 -189.819062) (xy 271.946779 -189.762133) (xy 271.890176 -189.699734)
			(xy 271.839552 -189.632392) (xy 271.795335 -189.560681) (xy 271.757902 -189.485206) (xy 271.727569 -189.406609)
			(xy 271.704593 -189.325555) (xy 271.68917 -189.242731) (xy 271.681429 -189.15884) (xy 271.68094 -189.116716)
			(xy 271.681413 -189.074439) (xy 271.689213 -188.990247) (xy 271.704749 -188.907133) (xy 271.727887 -188.825808)
			(xy 271.758431 -188.746965) (xy 271.79612 -188.671276) (xy 271.840632 -188.599388) (xy 271.891588 -188.531914)
			(xy 271.948552 -188.469429) (xy 272.011038 -188.412467) (xy 272.078514 -188.361514) (xy 272.150404 -188.317005)
			(xy 272.226094 -188.279319) (xy 272.304938 -188.248777) (xy 272.386265 -188.225641) (xy 272.469379 -188.210109)
			(xy 272.553571 -188.202311) (xy 272.595848 -188.201808) (xy 273.840448 -188.201808) (xy 273.882722 -188.202298)
			(xy 273.96691 -188.210104) (xy 274.050019 -188.225644) (xy 274.131339 -188.248785) (xy 274.210178 -188.279332)
			(xy 274.285861 -188.317021) (xy 274.357744 -188.361534) (xy 274.425214 -188.412488) (xy 274.487694 -188.469451)
			(xy 274.544653 -188.531935) (xy 274.595603 -188.599408) (xy 274.64011 -188.671295) (xy 274.677794 -188.746981)
			(xy 274.708335 -188.825821) (xy 274.731471 -188.907143) (xy 274.747005 -188.990253) (xy 274.754805 -189.074441)
			(xy 274.755356 -189.116716) (xy 274.755121 -189.13729) (xy 275.11578 -189.13729) (xy 275.119851 -189.081668)
			(xy 275.131977 -189.027231) (xy 275.1519 -188.97514) (xy 275.179196 -188.926505) (xy 275.213282 -188.882362)
			(xy 275.253431 -188.843653) (xy 275.298789 -188.811202) (xy 275.348389 -188.785701) (xy 275.401173 -188.767694)
			(xy 275.456016 -188.757564) (xy 275.51175 -188.755527) (xy 275.567187 -188.761627) (xy 275.621144 -188.775733)
			(xy 275.672473 -188.797545) (xy 275.720079 -188.826599) (xy 275.762947 -188.862274) (xy 275.800164 -188.903811)
			(xy 275.830937 -188.950324) (xy 275.854609 -189.000821) (xy 275.870677 -189.054228) (xy 275.878797 -189.109404)
			(xy 275.879306 -189.13729) (xy 275.878797 -189.165176) (xy 275.878138 -189.169657) (xy 277.367125 -189.169657)
			(xy 277.367125 -189.115143) (xy 277.374884 -189.061185) (xy 277.390243 -189.00888) (xy 277.41289 -188.959293)
			(xy 277.442364 -188.913434) (xy 277.478064 -188.872237) (xy 277.519265 -188.836541) (xy 277.565126 -188.807072)
			(xy 277.614715 -188.784429) (xy 277.667022 -188.769076) (xy 277.720981 -188.761322) (xy 277.748238 -188.760862)
			(xy 277.774158 -188.761316) (xy 277.82552 -188.76835) (xy 277.875457 -188.782271) (xy 277.923051 -188.802822)
			(xy 277.967425 -188.829625) (xy 278.007764 -188.862187) (xy 278.02586 -188.88075) (xy 278.03676 -188.891618)
			(xy 278.063557 -188.906738) (xy 278.09364 -188.913196) (xy 278.124281 -188.910405) (xy 278.152703 -188.89862)
			(xy 278.176328 -188.878909) (xy 278.185118 -188.866272) (xy 278.200277 -188.843757) (xy 278.235954 -188.802853)
			(xy 278.277069 -188.76742) (xy 278.322791 -188.738173) (xy 278.372199 -188.715703) (xy 278.424292 -188.700464)
			(xy 278.47802 -188.692763) (xy 278.505158 -188.692282) (xy 278.532412 -188.692762) (xy 278.586366 -188.700514)
			(xy 278.638668 -188.715866) (xy 278.688252 -188.738506) (xy 278.734109 -188.767972) (xy 278.775306 -188.803665)
			(xy 278.811003 -188.844857) (xy 278.840474 -188.890711) (xy 278.863119 -188.940293) (xy 278.878477 -188.992593)
			(xy 278.886235 -189.046546) (xy 278.886235 -189.101054) (xy 278.878477 -189.155007) (xy 278.863119 -189.207307)
			(xy 278.840474 -189.256889) (xy 278.811003 -189.302743) (xy 278.775306 -189.343935) (xy 278.734109 -189.379628)
			(xy 278.688252 -189.409094) (xy 278.638668 -189.431734) (xy 278.586366 -189.447086) (xy 278.532412 -189.454838)
			(xy 278.505158 -189.455298) (xy 278.479237 -189.454859) (xy 278.427874 -189.447824) (xy 278.377937 -189.433901)
			(xy 278.330343 -189.413347) (xy 278.285969 -189.386541) (xy 278.245631 -189.353975) (xy 278.227536 -189.33541)
			(xy 278.216648 -189.324526) (xy 278.189849 -189.309396) (xy 278.159761 -189.302934) (xy 278.129113 -189.305727)
			(xy 278.100687 -189.31752) (xy 278.077064 -189.337244) (xy 278.068278 -189.349888) (xy 278.053108 -189.372396)
			(xy 278.017435 -189.413302) (xy 277.976322 -189.448737) (xy 277.930601 -189.477986) (xy 277.881196 -189.500457)
			(xy 277.829103 -189.515696) (xy 277.775376 -189.523397) (xy 277.748238 -189.523878) (xy 277.720981 -189.523478)
			(xy 277.667022 -189.515724) (xy 277.614715 -189.500371) (xy 277.565126 -189.477728) (xy 277.519265 -189.448259)
			(xy 277.478064 -189.412563) (xy 277.442364 -189.371366) (xy 277.41289 -189.325507) (xy 277.390243 -189.27592)
			(xy 277.374884 -189.223615) (xy 277.367125 -189.169657) (xy 275.878138 -189.169657) (xy 275.870677 -189.220352)
			(xy 275.854609 -189.273759) (xy 275.830937 -189.324256) (xy 275.800164 -189.370769) (xy 275.762947 -189.412306)
			(xy 275.720079 -189.447981) (xy 275.672473 -189.477035) (xy 275.621144 -189.498847) (xy 275.567187 -189.512953)
			(xy 275.51175 -189.519053) (xy 275.456016 -189.517016) (xy 275.401173 -189.506886) (xy 275.348389 -189.488879)
			(xy 275.298789 -189.463378) (xy 275.253431 -189.430927) (xy 275.213282 -189.392218) (xy 275.179196 -189.348075)
			(xy 275.1519 -189.29944) (xy 275.131977 -189.247349) (xy 275.119851 -189.192912) (xy 275.11578 -189.13729)
			(xy 274.755121 -189.13729) (xy 274.754874 -189.15884) (xy 274.747126 -189.24273) (xy 274.731697 -189.325552)
			(xy 274.708717 -189.406604) (xy 274.678383 -189.485201) (xy 274.640949 -189.560675) (xy 274.596735 -189.632387)
			(xy 274.546113 -189.69973) (xy 274.489514 -189.762132) (xy 274.427417 -189.819066) (xy 274.394168 -189.844934)
			(xy 274.383249 -189.853822) (xy 274.366371 -189.876345) (xy 274.356287 -189.902621) (xy 274.353763 -189.930653)
			(xy 274.358992 -189.958308) (xy 274.371576 -189.983483) (xy 274.390558 -190.004263) (xy 274.414494 -190.019069)
			(xy 274.441564 -190.026773) (xy 274.455636 -190.027306) (xy 279.52446 -190.027306) (xy 279.538542 -190.026857)
			(xy 279.565636 -190.019168) (xy 279.589596 -190.004363) (xy 279.608595 -189.983573) (xy 279.621186 -189.95838)
			(xy 279.62641 -189.930704) (xy 279.623868 -189.902655) (xy 279.613754 -189.876369) (xy 279.596839 -189.85385)
			(xy 279.585928 -189.844934) (xy 279.552682 -189.819062) (xy 279.490579 -189.762133) (xy 279.433976 -189.699734)
			(xy 279.383352 -189.632392) (xy 279.339135 -189.560681) (xy 279.301702 -189.485206) (xy 279.271369 -189.406609)
			(xy 279.248393 -189.325555) (xy 279.23297 -189.242731) (xy 279.225229 -189.15884) (xy 279.22474 -189.116716)
			(xy 279.225213 -189.074439) (xy 279.233013 -188.990247) (xy 279.248549 -188.907133) (xy 279.271687 -188.825808)
			(xy 279.302231 -188.746965) (xy 279.33992 -188.671276) (xy 279.384432 -188.599388) (xy 279.435388 -188.531914)
			(xy 279.492352 -188.469429) (xy 279.554838 -188.412467) (xy 279.622314 -188.361514) (xy 279.694204 -188.317005)
			(xy 279.769894 -188.279319) (xy 279.848738 -188.248777) (xy 279.930065 -188.225641) (xy 280.013179 -188.210109)
			(xy 280.097371 -188.202311) (xy 280.139648 -188.201808) (xy 281.384248 -188.201808) (xy 281.425854 -188.202282)
			(xy 281.50872 -188.209844) (xy 281.590558 -188.224902) (xy 281.670689 -188.247332) (xy 281.748452 -188.276946)
			(xy 281.781787 -188.293248) (xy 284.854902 -188.293248) (xy 284.858973 -188.237626) (xy 284.871099 -188.183189)
			(xy 284.891022 -188.131098) (xy 284.918318 -188.082463) (xy 284.952404 -188.03832) (xy 284.992553 -187.999611)
			(xy 285.037911 -187.96716) (xy 285.087511 -187.941659) (xy 285.140295 -187.923652) (xy 285.195138 -187.913522)
			(xy 285.250872 -187.911485) (xy 285.306309 -187.917585) (xy 285.360266 -187.931691) (xy 285.411595 -187.953503)
			(xy 285.459201 -187.982557) (xy 285.502069 -188.018232) (xy 285.539286 -188.059769) (xy 285.570059 -188.106282)
			(xy 285.593731 -188.156779) (xy 285.609799 -188.210186) (xy 285.617919 -188.265362) (xy 285.618428 -188.293248)
			(xy 285.617919 -188.321134) (xy 285.609799 -188.37631) (xy 285.593731 -188.429717) (xy 285.570059 -188.480214)
			(xy 285.539286 -188.526727) (xy 285.502069 -188.568264) (xy 285.459201 -188.603939) (xy 285.411595 -188.632993)
			(xy 285.360266 -188.654805) (xy 285.306309 -188.668911) (xy 285.250872 -188.675011) (xy 285.195138 -188.672974)
			(xy 285.140295 -188.662844) (xy 285.087511 -188.644837) (xy 285.037911 -188.619336) (xy 284.992553 -188.586885)
			(xy 284.952404 -188.548176) (xy 284.918318 -188.504033) (xy 284.891022 -188.455398) (xy 284.871099 -188.403307)
			(xy 284.858973 -188.34887) (xy 284.854902 -188.293248) (xy 281.781787 -188.293248) (xy 281.823204 -188.313502)
			(xy 281.894326 -188.356696) (xy 281.961231 -188.406172) (xy 282.023365 -188.461521) (xy 282.080215 -188.522284)
			(xy 282.131311 -188.58796) (xy 282.17623 -188.658005) (xy 282.214602 -188.731841) (xy 282.246108 -188.808857)
			(xy 282.25877 -188.848492) (xy 282.263396 -188.862031) (xy 282.27898 -188.88601) (xy 282.300601 -188.90473)
			(xy 282.326563 -188.916723) (xy 282.354833 -188.921049) (xy 282.383193 -188.91737) (xy 282.409423 -188.905974)
			(xy 282.431466 -188.887753) (xy 282.439872 -188.876178) (xy 282.455179 -188.854597) (xy 282.490798 -188.815473)
			(xy 282.531482 -188.781646) (xy 282.576451 -188.753768) (xy 282.624841 -188.732373) (xy 282.675724 -188.717871)
			(xy 282.728123 -188.710542) (xy 282.754578 -188.710062) (xy 282.781834 -188.710523) (xy 282.835792 -188.718278)
			(xy 282.888096 -188.733634) (xy 282.937683 -188.756277) (xy 282.983543 -188.785747) (xy 283.024741 -188.821443)
			(xy 283.06044 -188.86264) (xy 283.089913 -188.908497) (xy 283.112558 -188.958083) (xy 283.127917 -189.010387)
			(xy 283.135675 -189.064344) (xy 283.135675 -189.118856) (xy 283.127917 -189.172813) (xy 283.112558 -189.225117)
			(xy 283.089913 -189.274703) (xy 283.06044 -189.32056) (xy 283.024741 -189.361757) (xy 282.983543 -189.397453)
			(xy 282.937683 -189.426923) (xy 282.888096 -189.449566) (xy 282.835792 -189.464922) (xy 282.781834 -189.472677)
			(xy 282.754578 -189.473078) (xy 282.724876 -189.472516) (xy 282.666189 -189.46331) (xy 282.609642 -189.445109)
			(xy 282.556603 -189.418354) (xy 282.508359 -189.383692) (xy 282.466078 -189.341965) (xy 282.448 -189.318392)
			(xy 282.439106 -189.307235) (xy 282.416422 -189.289946) (xy 282.389845 -189.279596) (xy 282.361443 -189.276992)
			(xy 282.333427 -189.282335) (xy 282.307978 -189.29521) (xy 282.287076 -189.314615) (xy 282.272348 -189.339039)
			(xy 282.268168 -189.352682) (xy 282.256567 -189.394222) (xy 282.226581 -189.475094) (xy 282.189112 -189.552783)
			(xy 282.144495 -189.626599) (xy 282.093126 -189.695886) (xy 282.035461 -189.760028) (xy 281.972012 -189.818456)
			(xy 281.937968 -189.844934) (xy 281.927049 -189.853822) (xy 281.910171 -189.876345) (xy 281.900087 -189.902621)
			(xy 281.897563 -189.930653) (xy 281.902792 -189.958308) (xy 281.915376 -189.983483) (xy 281.934358 -190.004263)
			(xy 281.958294 -190.019069) (xy 281.985364 -190.026773) (xy 281.999436 -190.027306) (xy 286.038036 -190.027306)
			(xy 286.051346 -190.026918) (xy 286.077062 -190.020038) (xy 286.100117 -190.006732) (xy 286.118939 -189.987908)
			(xy 286.132243 -189.964851) (xy 286.139119 -189.939135) (xy 286.139099 -189.912515) (xy 286.13608 -189.899544)
			(xy 286.130127 -189.875472) (xy 286.123761 -189.826294) (xy 286.12338 -189.8015) (xy 286.123866 -189.774248)
			(xy 286.131622 -189.7203) (xy 286.146977 -189.668005) (xy 286.169618 -189.618427) (xy 286.199084 -189.572575)
			(xy 286.234776 -189.531384) (xy 286.275966 -189.495691) (xy 286.321816 -189.466224) (xy 286.371393 -189.443581)
			(xy 286.423688 -189.428225) (xy 286.477636 -189.420467) (xy 286.504888 -189.419992) (xy 286.530756 -189.420438)
			(xy 286.582012 -189.427468) (xy 286.631845 -189.441373) (xy 286.655764 -189.451234) (xy 286.668918 -189.456441)
			(xy 286.696952 -189.460153) (xy 286.724928 -189.456028) (xy 286.750699 -189.444386) (xy 286.772285 -189.426118)
			(xy 286.788029 -189.402627) (xy 286.796723 -189.375718) (xy 286.797699 -189.347457) (xy 286.794702 -189.333632)
			(xy 286.786384 -189.298084) (xy 286.77476 -189.226002) (xy 286.768912 -189.153223) (xy 286.76854 -189.116716)
			(xy 286.769013 -189.074439) (xy 286.776813 -188.990247) (xy 286.792349 -188.907133) (xy 286.815487 -188.825808)
			(xy 286.846031 -188.746965) (xy 286.88372 -188.671276) (xy 286.928232 -188.599388) (xy 286.979188 -188.531914)
			(xy 287.036152 -188.469429) (xy 287.098638 -188.412467) (xy 287.166114 -188.361514) (xy 287.238004 -188.317005)
			(xy 287.313694 -188.279319) (xy 287.392538 -188.248777) (xy 287.473865 -188.225641) (xy 287.556979 -188.210109)
			(xy 287.641171 -188.202311) (xy 287.683448 -188.201808) (xy 288.928048 -188.201808) (xy 288.970322 -188.202298)
			(xy 289.05451 -188.210104) (xy 289.137619 -188.225644) (xy 289.218939 -188.248785) (xy 289.297778 -188.279332)
			(xy 289.373461 -188.317021) (xy 289.445344 -188.361534) (xy 289.512814 -188.412488) (xy 289.575294 -188.469451)
			(xy 289.632253 -188.531935) (xy 289.683203 -188.599408) (xy 289.72771 -188.671295) (xy 289.765394 -188.746981)
			(xy 289.795935 -188.825821) (xy 289.819071 -188.907143) (xy 289.834605 -188.990253) (xy 289.842405 -189.074441)
			(xy 289.842956 -189.116716) (xy 289.842474 -189.15884) (xy 289.834726 -189.24273) (xy 289.819297 -189.325552)
			(xy 289.796317 -189.406604) (xy 289.765983 -189.485201) (xy 289.742264 -189.533022) (xy 293.23233 -189.533022)
			(xy 293.236401 -189.4774) (xy 293.248527 -189.422963) (xy 293.26845 -189.370872) (xy 293.295746 -189.322237)
			(xy 293.329832 -189.278094) (xy 293.369981 -189.239385) (xy 293.415339 -189.206934) (xy 293.464939 -189.181433)
			(xy 293.517723 -189.163426) (xy 293.572566 -189.153296) (xy 293.6283 -189.151259) (xy 293.683737 -189.157359)
			(xy 293.737694 -189.171465) (xy 293.789023 -189.193277) (xy 293.836629 -189.222331) (xy 293.879497 -189.258006)
			(xy 293.916714 -189.299543) (xy 293.947487 -189.346056) (xy 293.971159 -189.396553) (xy 293.987227 -189.44996)
			(xy 293.995347 -189.505136) (xy 293.995856 -189.533022) (xy 293.995347 -189.560908) (xy 293.987227 -189.616084)
			(xy 293.971159 -189.669491) (xy 293.947487 -189.719988) (xy 293.916714 -189.766501) (xy 293.879497 -189.808038)
			(xy 293.836629 -189.843713) (xy 293.789023 -189.872767) (xy 293.737694 -189.894579) (xy 293.683737 -189.908685)
			(xy 293.6283 -189.914785) (xy 293.572566 -189.912748) (xy 293.517723 -189.902618) (xy 293.464939 -189.884611)
			(xy 293.415339 -189.85911) (xy 293.369981 -189.826659) (xy 293.329832 -189.78795) (xy 293.295746 -189.743807)
			(xy 293.26845 -189.695172) (xy 293.248527 -189.643081) (xy 293.236401 -189.588644) (xy 293.23233 -189.533022)
			(xy 289.742264 -189.533022) (xy 289.728549 -189.560675) (xy 289.684335 -189.632387) (xy 289.633713 -189.69973)
			(xy 289.577114 -189.762132) (xy 289.515017 -189.819066) (xy 289.481768 -189.844934) (xy 289.470849 -189.853822)
			(xy 289.453971 -189.876345) (xy 289.443887 -189.902621) (xy 289.441363 -189.930653) (xy 289.446592 -189.958308)
			(xy 289.459176 -189.983483) (xy 289.478158 -190.004263) (xy 289.502094 -190.019069) (xy 289.529164 -190.026773)
			(xy 289.543236 -190.027306) (xy 294.61206 -190.027306) (xy 294.626142 -190.026857) (xy 294.653236 -190.019168)
			(xy 294.677196 -190.004363) (xy 294.696195 -189.983573) (xy 294.708786 -189.95838) (xy 294.71401 -189.930704)
			(xy 294.711468 -189.902655) (xy 294.701354 -189.876369) (xy 294.684439 -189.85385) (xy 294.673528 -189.844934)
			(xy 294.640282 -189.819062) (xy 294.578179 -189.762133) (xy 294.521576 -189.699734) (xy 294.470952 -189.632392)
			(xy 294.426735 -189.560681) (xy 294.389302 -189.485206) (xy 294.358969 -189.406609) (xy 294.335993 -189.325555)
			(xy 294.32057 -189.242731) (xy 294.312829 -189.15884) (xy 294.31234 -189.116716) (xy 294.312813 -189.074439)
			(xy 294.320613 -188.990247) (xy 294.336149 -188.907133) (xy 294.359287 -188.825808) (xy 294.389831 -188.746965)
			(xy 294.42752 -188.671276) (xy 294.472032 -188.599388) (xy 294.522988 -188.531914) (xy 294.579952 -188.469429)
			(xy 294.642438 -188.412467) (xy 294.709914 -188.361514) (xy 294.781804 -188.317005) (xy 294.857494 -188.279319)
			(xy 294.936338 -188.248777) (xy 295.017665 -188.225641) (xy 295.100779 -188.210109) (xy 295.184971 -188.202311)
			(xy 295.227248 -188.201808) (xy 296.471848 -188.201808) (xy 296.514122 -188.202298) (xy 296.59831 -188.210104)
			(xy 296.681419 -188.225644) (xy 296.762739 -188.248785) (xy 296.841578 -188.279332) (xy 296.917261 -188.317021)
			(xy 296.989144 -188.361534) (xy 297.056614 -188.412488) (xy 297.119094 -188.469451) (xy 297.176053 -188.531935)
			(xy 297.227003 -188.599408) (xy 297.27151 -188.671295) (xy 297.309194 -188.746981) (xy 297.339735 -188.825821)
			(xy 297.362871 -188.907143) (xy 297.378405 -188.990253) (xy 297.386205 -189.074441) (xy 297.386756 -189.116716)
			(xy 297.386274 -189.15884) (xy 297.378526 -189.24273) (xy 297.363097 -189.325552) (xy 297.340117 -189.406604)
			(xy 297.312991 -189.476888) (xy 297.565062 -189.476888) (xy 297.569133 -189.421266) (xy 297.581259 -189.366829)
			(xy 297.601182 -189.314738) (xy 297.628478 -189.266103) (xy 297.662564 -189.22196) (xy 297.702713 -189.183251)
			(xy 297.748071 -189.1508) (xy 297.797671 -189.125299) (xy 297.850455 -189.107292) (xy 297.905298 -189.097162)
			(xy 297.961032 -189.095125) (xy 297.974891 -189.09665) (xy 300.78248 -189.09665) (xy 300.786551 -189.041028)
			(xy 300.798677 -188.986591) (xy 300.8186 -188.9345) (xy 300.845896 -188.885865) (xy 300.879982 -188.841722)
			(xy 300.920131 -188.803013) (xy 300.965489 -188.770562) (xy 301.015089 -188.745061) (xy 301.067873 -188.727054)
			(xy 301.122716 -188.716924) (xy 301.17845 -188.714887) (xy 301.233887 -188.720987) (xy 301.287844 -188.735093)
			(xy 301.339173 -188.756905) (xy 301.386779 -188.785959) (xy 301.429647 -188.821634) (xy 301.466864 -188.863171)
			(xy 301.497637 -188.909684) (xy 301.521309 -188.960181) (xy 301.537377 -189.013588) (xy 301.545497 -189.068764)
			(xy 301.546006 -189.09665) (xy 301.545497 -189.124536) (xy 301.540428 -189.158978) (xy 301.856581 -189.158978)
			(xy 301.856581 -189.074422) (xy 301.864383 -188.990228) (xy 301.879921 -188.907113) (xy 301.903061 -188.825786)
			(xy 301.933607 -188.746941) (xy 301.971298 -188.671251) (xy 302.015811 -188.599362) (xy 302.066769 -188.531886)
			(xy 302.123735 -188.469401) (xy 302.186223 -188.412438) (xy 302.253701 -188.361484) (xy 302.325593 -188.316974)
			(xy 302.401285 -188.279288) (xy 302.480131 -188.248746) (xy 302.56146 -188.22561) (xy 302.644576 -188.210077)
			(xy 302.72877 -188.202279) (xy 302.771048 -188.201808) (xy 304.015648 -188.201808) (xy 304.057923 -188.202266)
			(xy 304.142113 -188.210072) (xy 304.225224 -188.225612) (xy 304.306546 -188.248754) (xy 304.385387 -188.279301)
			(xy 304.461072 -188.316991) (xy 304.532957 -188.361504) (xy 304.600429 -188.412459) (xy 304.662911 -188.469423)
			(xy 304.719871 -188.531908) (xy 304.770823 -188.599382) (xy 304.815332 -188.67127) (xy 304.853019 -188.746957)
			(xy 304.883561 -188.825799) (xy 304.906699 -188.907123) (xy 304.922235 -188.990234) (xy 304.930036 -189.074424)
			(xy 304.930036 -189.09157) (xy 306.13426 -189.09157) (xy 306.138331 -189.035948) (xy 306.150457 -188.981511)
			(xy 306.17038 -188.92942) (xy 306.197676 -188.880785) (xy 306.231762 -188.836642) (xy 306.271911 -188.797933)
			(xy 306.317269 -188.765482) (xy 306.366869 -188.739981) (xy 306.419653 -188.721974) (xy 306.474496 -188.711844)
			(xy 306.53023 -188.709807) (xy 306.585667 -188.715907) (xy 306.639624 -188.730013) (xy 306.690953 -188.751825)
			(xy 306.738559 -188.780879) (xy 306.781427 -188.816554) (xy 306.818644 -188.858091) (xy 306.849417 -188.904604)
			(xy 306.873089 -188.955101) (xy 306.889157 -189.008508) (xy 306.894279 -189.04331) (xy 307.28234 -189.04331)
			(xy 307.286411 -188.987688) (xy 307.298537 -188.933251) (xy 307.31846 -188.88116) (xy 307.345756 -188.832525)
			(xy 307.379842 -188.788382) (xy 307.419991 -188.749673) (xy 307.465349 -188.717222) (xy 307.514949 -188.691721)
			(xy 307.567733 -188.673714) (xy 307.622576 -188.663584) (xy 307.67831 -188.661547) (xy 307.733747 -188.667647)
			(xy 307.787704 -188.681753) (xy 307.839033 -188.703565) (xy 307.886639 -188.732619) (xy 307.929507 -188.768294)
			(xy 307.966724 -188.809831) (xy 307.997497 -188.856344) (xy 308.021169 -188.906841) (xy 308.037237 -188.960248)
			(xy 308.045357 -189.015424) (xy 308.045866 -189.04331) (xy 308.045357 -189.071196) (xy 308.037237 -189.126372)
			(xy 308.027427 -189.158978) (xy 309.400381 -189.158978) (xy 309.400381 -189.074422) (xy 309.408183 -188.990228)
			(xy 309.423721 -188.907113) (xy 309.446861 -188.825786) (xy 309.477407 -188.746941) (xy 309.515098 -188.671251)
			(xy 309.559611 -188.599362) (xy 309.610569 -188.531886) (xy 309.667535 -188.469401) (xy 309.730023 -188.412438)
			(xy 309.797501 -188.361484) (xy 309.869393 -188.316974) (xy 309.945085 -188.279288) (xy 310.023931 -188.248746)
			(xy 310.10526 -188.22561) (xy 310.188376 -188.210077) (xy 310.27257 -188.202279) (xy 310.314848 -188.201808)
			(xy 311.559448 -188.201808) (xy 311.601723 -188.202266) (xy 311.685913 -188.210072) (xy 311.769024 -188.225612)
			(xy 311.850346 -188.248754) (xy 311.929187 -188.279301) (xy 312.004872 -188.316991) (xy 312.076757 -188.361504)
			(xy 312.144229 -188.412459) (xy 312.206711 -188.469423) (xy 312.263671 -188.531908) (xy 312.314623 -188.599382)
			(xy 312.359132 -188.67127) (xy 312.396819 -188.746957) (xy 312.427361 -188.825799) (xy 312.450499 -188.907123)
			(xy 312.466035 -188.990234) (xy 312.473836 -189.074424) (xy 312.473836 -189.158976) (xy 312.466035 -189.243166)
			(xy 312.450499 -189.326277) (xy 312.427361 -189.407601) (xy 312.396819 -189.486443) (xy 312.359132 -189.56213)
			(xy 312.314623 -189.634018) (xy 312.263671 -189.701492) (xy 312.206711 -189.763977) (xy 312.144229 -189.820941)
			(xy 312.132302 -189.829948) (xy 318.520572 -189.829948) (xy 318.521058 -189.802697) (xy 318.528814 -189.748749)
			(xy 318.544169 -189.696454) (xy 318.566811 -189.646877) (xy 318.596277 -189.601027) (xy 318.631968 -189.559836)
			(xy 318.673159 -189.524145) (xy 318.719009 -189.494679) (xy 318.768586 -189.472037) (xy 318.820881 -189.456682)
			(xy 318.874829 -189.448926) (xy 318.929331 -189.448926) (xy 318.983279 -189.456682) (xy 319.035574 -189.472037)
			(xy 319.085151 -189.494679) (xy 319.131001 -189.524145) (xy 319.172192 -189.559836) (xy 319.207883 -189.601027)
			(xy 319.237349 -189.646877) (xy 319.259991 -189.696454) (xy 319.275346 -189.748749) (xy 319.283102 -189.802697)
			(xy 319.283588 -189.829948) (xy 319.283311 -189.851861) (xy 319.278344 -189.895403) (xy 319.273682 -189.916816)
			(xy 319.270808 -189.931697) (xy 319.272819 -189.961917) (xy 319.283604 -189.990219) (xy 319.302214 -190.014114)
			(xy 319.327014 -190.031501) (xy 319.341246 -190.036704) (xy 319.36844 -190.046031) (xy 319.419878 -190.071703)
			(xy 319.46688 -190.104806) (xy 319.50838 -190.14459) (xy 319.543438 -190.190152) (xy 319.57126 -190.24046)
			(xy 319.591214 -190.294375) (xy 319.60285 -190.350674) (xy 319.604898 -190.37935) (xy 319.606308 -190.394625)
			(xy 319.616948 -190.423374) (xy 319.63565 -190.447664) (xy 319.660724 -190.4653) (xy 319.689906 -190.474689)
			(xy 319.705228 -190.475362) (xy 319.732299 -190.476138) (xy 319.78583 -190.484333) (xy 319.837664 -190.500016)
			(xy 319.88676 -190.52287) (xy 319.932131 -190.552438) (xy 319.972865 -190.588123) (xy 320.008144 -190.629211)
			(xy 320.037258 -190.674874) (xy 320.059623 -190.724195) (xy 320.074789 -190.776183) (xy 320.082451 -190.829793)
			(xy 320.082926 -190.85687) (xy 320.082417 -190.884121) (xy 320.074664 -190.93807) (xy 320.059313 -190.990366)
			(xy 320.036675 -191.039944) (xy 320.007212 -191.085797) (xy 319.971523 -191.126989) (xy 319.930335 -191.162683)
			(xy 319.884487 -191.192152) (xy 319.834911 -191.214796) (xy 319.782617 -191.230154) (xy 319.728669 -191.237913)
			(xy 319.701418 -191.238378) (xy 319.672453 -191.237885) (xy 319.615187 -191.22913) (xy 319.559904 -191.211818)
			(xy 319.507873 -191.186347) (xy 319.460291 -191.153302) (xy 319.418252 -191.113444) (xy 319.382722 -191.067689)
			(xy 319.354517 -191.017087) (xy 319.334287 -190.962804) (xy 319.322496 -190.906086) (xy 319.320418 -190.87719)
			(xy 319.319136 -190.861898) (xy 319.308469 -190.833135) (xy 319.289737 -190.808841) (xy 319.264632 -190.791212)
			(xy 319.235421 -190.781839) (xy 319.220088 -190.781178) (xy 319.193014 -190.780447) (xy 319.139478 -190.772252)
			(xy 319.08764 -190.756569) (xy 319.03854 -190.733712) (xy 318.993166 -190.70414) (xy 318.95243 -190.668449)
			(xy 318.917151 -190.627356) (xy 318.888039 -190.581687) (xy 318.865677 -190.53236) (xy 318.850517 -190.480365)
			(xy 318.842861 -190.42675) (xy 318.84239 -190.39967) (xy 318.842668 -190.377757) (xy 318.847634 -190.334215)
			(xy 318.852296 -190.312802) (xy 318.855269 -190.297937) (xy 318.853237 -190.267702) (xy 318.842429 -190.239393)
			(xy 318.823795 -190.215496) (xy 318.798974 -190.198113) (xy 318.784732 -190.192914) (xy 318.759472 -190.184323)
			(xy 318.711482 -190.161001) (xy 318.667211 -190.131219) (xy 318.627522 -190.095558) (xy 318.593191 -190.054713)
			(xy 318.564887 -190.009483) (xy 318.543163 -189.960749) (xy 318.528443 -189.909463) (xy 318.521014 -189.856626)
			(xy 318.520572 -189.829948) (xy 312.132302 -189.829948) (xy 312.076757 -189.871896) (xy 312.004872 -189.916409)
			(xy 311.929187 -189.954099) (xy 311.850346 -189.984646) (xy 311.769024 -190.007788) (xy 311.685913 -190.023328)
			(xy 311.601723 -190.031134) (xy 311.559448 -190.031624) (xy 310.314848 -190.031624) (xy 310.27257 -190.031121)
			(xy 310.188376 -190.023323) (xy 310.10526 -190.00779) (xy 310.023931 -189.984654) (xy 309.945085 -189.954112)
			(xy 309.869393 -189.916426) (xy 309.797501 -189.871916) (xy 309.730023 -189.820962) (xy 309.667535 -189.763999)
			(xy 309.610569 -189.701514) (xy 309.559611 -189.634038) (xy 309.515098 -189.562149) (xy 309.477407 -189.486459)
			(xy 309.446861 -189.407614) (xy 309.423721 -189.326287) (xy 309.408183 -189.243172) (xy 309.400381 -189.158978)
			(xy 308.027427 -189.158978) (xy 308.021169 -189.179779) (xy 307.997497 -189.230276) (xy 307.966724 -189.276789)
			(xy 307.929507 -189.318326) (xy 307.886639 -189.354001) (xy 307.839033 -189.383055) (xy 307.787704 -189.404867)
			(xy 307.733747 -189.418973) (xy 307.67831 -189.425073) (xy 307.622576 -189.423036) (xy 307.567733 -189.412906)
			(xy 307.514949 -189.394899) (xy 307.465349 -189.369398) (xy 307.419991 -189.336947) (xy 307.379842 -189.298238)
			(xy 307.345756 -189.254095) (xy 307.31846 -189.20546) (xy 307.298537 -189.153369) (xy 307.286411 -189.098932)
			(xy 307.28234 -189.04331) (xy 306.894279 -189.04331) (xy 306.897277 -189.063684) (xy 306.897786 -189.09157)
			(xy 306.897277 -189.119456) (xy 306.889157 -189.174632) (xy 306.873089 -189.228039) (xy 306.849417 -189.278536)
			(xy 306.818644 -189.325049) (xy 306.781427 -189.366586) (xy 306.738559 -189.402261) (xy 306.690953 -189.431315)
			(xy 306.639624 -189.453127) (xy 306.585667 -189.467233) (xy 306.53023 -189.473333) (xy 306.474496 -189.471296)
			(xy 306.419653 -189.461166) (xy 306.366869 -189.443159) (xy 306.317269 -189.417658) (xy 306.271911 -189.385207)
			(xy 306.231762 -189.346498) (xy 306.197676 -189.302355) (xy 306.17038 -189.25372) (xy 306.150457 -189.201629)
			(xy 306.138331 -189.147192) (xy 306.13426 -189.09157) (xy 304.930036 -189.09157) (xy 304.930036 -189.158976)
			(xy 304.922235 -189.243166) (xy 304.906699 -189.326277) (xy 304.883561 -189.407601) (xy 304.853019 -189.486443)
			(xy 304.815332 -189.56213) (xy 304.770823 -189.634018) (xy 304.719871 -189.701492) (xy 304.662911 -189.763977)
			(xy 304.600429 -189.820941) (xy 304.532957 -189.871896) (xy 304.461072 -189.916409) (xy 304.385387 -189.954099)
			(xy 304.306546 -189.984646) (xy 304.225224 -190.007788) (xy 304.142113 -190.023328) (xy 304.057923 -190.031134)
			(xy 304.015648 -190.031624) (xy 302.771048 -190.031624) (xy 302.72877 -190.031121) (xy 302.644576 -190.023323)
			(xy 302.56146 -190.00779) (xy 302.480131 -189.984654) (xy 302.401285 -189.954112) (xy 302.325593 -189.916426)
			(xy 302.253701 -189.871916) (xy 302.186223 -189.820962) (xy 302.123735 -189.763999) (xy 302.066769 -189.701514)
			(xy 302.015811 -189.634038) (xy 301.971298 -189.562149) (xy 301.933607 -189.486459) (xy 301.903061 -189.407614)
			(xy 301.879921 -189.326287) (xy 301.864383 -189.243172) (xy 301.856581 -189.158978) (xy 301.540428 -189.158978)
			(xy 301.537377 -189.179712) (xy 301.521309 -189.233119) (xy 301.497637 -189.283616) (xy 301.466864 -189.330129)
			(xy 301.429647 -189.371666) (xy 301.386779 -189.407341) (xy 301.339173 -189.436395) (xy 301.287844 -189.458207)
			(xy 301.233887 -189.472313) (xy 301.17845 -189.478413) (xy 301.122716 -189.476376) (xy 301.067873 -189.466246)
			(xy 301.015089 -189.448239) (xy 300.965489 -189.422738) (xy 300.920131 -189.390287) (xy 300.879982 -189.351578)
			(xy 300.845896 -189.307435) (xy 300.8186 -189.2588) (xy 300.798677 -189.206709) (xy 300.786551 -189.152272)
			(xy 300.78248 -189.09665) (xy 297.974891 -189.09665) (xy 298.016469 -189.101225) (xy 298.070426 -189.115331)
			(xy 298.121755 -189.137143) (xy 298.169361 -189.166197) (xy 298.212229 -189.201872) (xy 298.249446 -189.243409)
			(xy 298.280219 -189.289922) (xy 298.303891 -189.340419) (xy 298.319959 -189.393826) (xy 298.328079 -189.449002)
			(xy 298.328588 -189.476888) (xy 298.328079 -189.504774) (xy 298.319959 -189.55995) (xy 298.303891 -189.613357)
			(xy 298.280219 -189.663854) (xy 298.249446 -189.710367) (xy 298.212229 -189.751904) (xy 298.169361 -189.787579)
			(xy 298.121755 -189.816633) (xy 298.070426 -189.838445) (xy 298.016469 -189.852551) (xy 297.961032 -189.858651)
			(xy 297.905298 -189.856614) (xy 297.850455 -189.846484) (xy 297.797671 -189.828477) (xy 297.748071 -189.802976)
			(xy 297.702713 -189.770525) (xy 297.662564 -189.731816) (xy 297.628478 -189.687673) (xy 297.601182 -189.639038)
			(xy 297.581259 -189.586947) (xy 297.569133 -189.53251) (xy 297.565062 -189.476888) (xy 297.312991 -189.476888)
			(xy 297.309783 -189.485201) (xy 297.272349 -189.560675) (xy 297.228135 -189.632387) (xy 297.177513 -189.69973)
			(xy 297.120914 -189.762132) (xy 297.058817 -189.819066) (xy 297.025568 -189.844934) (xy 297.014649 -189.853822)
			(xy 296.997771 -189.876345) (xy 296.987687 -189.902621) (xy 296.985163 -189.930653) (xy 296.990392 -189.958308)
			(xy 297.002976 -189.983483) (xy 297.021958 -190.004263) (xy 297.045894 -190.019069) (xy 297.072964 -190.026773)
			(xy 297.087036 -190.027306) (xy 301.716186 -190.027306) (xy 303.195228 -191.506348) (xy 305.002692 -191.506348)
			(xy 305.0032 -191.479096) (xy 305.01095 -191.425147) (xy 305.0263 -191.37285) (xy 305.048937 -191.32327)
			(xy 305.0784 -191.277417) (xy 305.114089 -191.236223) (xy 305.155278 -191.200529) (xy 305.201128 -191.17106)
			(xy 305.250705 -191.148417) (xy 305.303 -191.133061) (xy 305.356948 -191.125303) (xy 305.3842 -191.12484)
			(xy 305.413141 -191.125355) (xy 305.47036 -191.134091) (xy 305.525605 -191.151361) (xy 305.577611 -191.176771)
			(xy 305.625187 -191.209738) (xy 305.646582 -191.229234) (xy 305.6542 -191.235834) (xy 305.673042 -191.242957)
			(xy 305.693174 -191.242316) (xy 305.711525 -191.23401) (xy 305.718718 -191.226948) (xy 305.739481 -191.205246)
			(xy 305.785927 -191.167165) (xy 305.837149 -191.135802) (xy 305.892184 -191.111749) (xy 305.949993 -191.095458)
			(xy 306.009489 -191.087237) (xy 306.03952 -191.08674) (xy 306.069617 -191.087282) (xy 306.129237 -191.095589)
			(xy 306.187156 -191.111989) (xy 306.24228 -191.136172) (xy 306.293571 -191.167682) (xy 306.340058 -191.205923)
			(xy 306.36083 -191.22771) (xy 306.37153 -191.238445) (xy 306.397697 -191.253703) (xy 306.427189 -191.260616)
			(xy 306.457412 -191.258577) (xy 306.485708 -191.247765) (xy 306.49799 -191.238886) (xy 306.518166 -191.223746)
			(xy 306.561729 -191.198317) (xy 306.608263 -191.178848) (xy 306.656954 -191.165675) (xy 306.706957 -191.15903)
			(xy 306.732178 -191.158622) (xy 306.761834 -191.159169) (xy 306.82043 -191.168358) (xy 306.876899 -191.186502)
			(xy 306.929881 -191.213165) (xy 306.978099 -191.247705) (xy 306.99964 -191.268096) (xy 307.009399 -191.277108)
			(xy 307.032468 -191.290254) (xy 307.058152 -191.296987) (xy 307.084703 -191.296848) (xy 307.110315 -191.289847)
			(xy 307.133245 -191.276461) (xy 307.142896 -191.267334) (xy 307.164493 -191.246428) (xy 307.213062 -191.211017)
			(xy 307.266584 -191.183664) (xy 307.323735 -191.165047) (xy 307.383099 -191.155626) (xy 307.413152 -191.155066)
			(xy 307.440405 -191.155578) (xy 307.494358 -191.163329) (xy 307.546658 -191.17868) (xy 307.596241 -191.201318)
			(xy 307.642097 -191.230783) (xy 307.664935 -191.25057) (xy 321.36664 -191.25057) (xy 321.370711 -191.194948)
			(xy 321.382837 -191.140511) (xy 321.40276 -191.08842) (xy 321.430056 -191.039785) (xy 321.464142 -190.995642)
			(xy 321.504291 -190.956933) (xy 321.549649 -190.924482) (xy 321.599249 -190.898981) (xy 321.652033 -190.880974)
			(xy 321.706876 -190.870844) (xy 321.76261 -190.868807) (xy 321.818047 -190.874907) (xy 321.872004 -190.889013)
			(xy 321.923333 -190.910825) (xy 321.970939 -190.939879) (xy 322.013807 -190.975554) (xy 322.051024 -191.017091)
			(xy 322.081797 -191.063604) (xy 322.105469 -191.114101) (xy 322.121537 -191.167508) (xy 322.129657 -191.222684)
			(xy 322.130166 -191.25057) (xy 322.129657 -191.278456) (xy 322.121537 -191.333632) (xy 322.105469 -191.387039)
			(xy 322.081797 -191.437536) (xy 322.051024 -191.484049) (xy 322.013807 -191.525586) (xy 321.970939 -191.561261)
			(xy 321.923333 -191.590315) (xy 321.872004 -191.612127) (xy 321.818047 -191.626233) (xy 321.76261 -191.632333)
			(xy 321.706876 -191.630296) (xy 321.652033 -191.620166) (xy 321.599249 -191.602159) (xy 321.549649 -191.576658)
			(xy 321.504291 -191.544207) (xy 321.464142 -191.505498) (xy 321.430056 -191.461355) (xy 321.40276 -191.41272)
			(xy 321.382837 -191.360629) (xy 321.370711 -191.306192) (xy 321.36664 -191.25057) (xy 307.664935 -191.25057)
			(xy 307.683292 -191.266474) (xy 307.718989 -191.307665) (xy 307.748459 -191.353517) (xy 307.771103 -191.403097)
			(xy 307.786461 -191.455395) (xy 307.794219 -191.509347) (xy 307.794219 -191.563853) (xy 307.786461 -191.617805)
			(xy 307.771103 -191.670103) (xy 307.748459 -191.719683) (xy 307.718989 -191.765535) (xy 307.683292 -191.806726)
			(xy 307.642097 -191.842417) (xy 307.596241 -191.871882) (xy 307.546658 -191.89452) (xy 307.494358 -191.909871)
			(xy 307.440405 -191.917622) (xy 307.413152 -191.918082) (xy 307.383497 -191.917515) (xy 307.324901 -191.908331)
			(xy 307.268433 -191.890191) (xy 307.215451 -191.863532) (xy 307.167232 -191.828997) (xy 307.14569 -191.808608)
			(xy 307.135905 -191.799626) (xy 307.112844 -191.786477) (xy 307.087167 -191.77974) (xy 307.060621 -191.779874)
			(xy 307.035013 -191.786868) (xy 307.012085 -191.800247) (xy 307.002434 -191.80937) (xy 306.980824 -191.830263)
			(xy 306.932259 -191.865675) (xy 306.87874 -191.89303) (xy 306.821592 -191.911651) (xy 306.762231 -191.921076)
			(xy 306.732178 -191.921638) (xy 306.705184 -191.921191) (xy 306.651735 -191.913582) (xy 306.599892 -191.898518)
			(xy 306.550687 -191.876301) (xy 306.505104 -191.847374) (xy 306.484274 -191.830198) (xy 306.47243 -191.82076)
			(xy 306.444682 -191.808666) (xy 306.414608 -191.805236) (xy 306.38485 -191.810771) (xy 306.358021 -191.824787)
			(xy 306.34686 -191.835024) (xy 306.326336 -191.854689) (xy 306.281101 -191.889109) (xy 306.231786 -191.917376)
			(xy 306.179223 -191.939011) (xy 306.124299 -191.95365) (xy 306.067941 -191.961047) (xy 306.03952 -191.961516)
			(xy 306.007504 -191.960925) (xy 305.944156 -191.951604) (xy 305.882843 -191.933145) (xy 305.824879 -191.905941)
			(xy 305.771501 -191.870575) (xy 305.723851 -191.827803) (xy 305.70297 -191.803528) (xy 305.696216 -191.796031)
			(xy 305.678363 -191.786659) (xy 305.658277 -191.784887) (xy 305.63906 -191.790991) (xy 305.631088 -191.797178)
			(xy 305.603148 -191.818768) (xy 305.591981 -191.827175) (xy 305.574332 -191.848836) (xy 305.563204 -191.874466)
			(xy 305.559428 -191.902151) (xy 305.563286 -191.929824) (xy 305.574489 -191.955421) (xy 305.592202 -191.97703)
			(xy 305.603402 -191.985392) (xy 305.624741 -192.000752) (xy 305.66343 -192.036354) (xy 305.69686 -192.076934)
			(xy 305.724397 -192.121722) (xy 305.74552 -192.169869) (xy 305.759827 -192.220461) (xy 305.767047 -192.27254)
			(xy 305.767486 -192.298828) (xy 305.766921 -192.329292) (xy 305.757226 -192.389443) (xy 305.738087 -192.447286)
			(xy 305.709991 -192.501349) (xy 305.692302 -192.526158) (xy 305.683644 -192.538757) (xy 305.673596 -192.567615)
			(xy 305.672505 -192.598154) (xy 305.680469 -192.627656) (xy 305.69678 -192.653497) (xy 305.70805 -192.663826)
			(xy 305.728684 -192.682015) (xy 305.764949 -192.723374) (xy 305.794904 -192.769508) (xy 305.80192 -192.78473)
			(xy 306.05171 -192.78473) (xy 306.055781 -192.729108) (xy 306.067907 -192.674671) (xy 306.08783 -192.62258)
			(xy 306.115126 -192.573945) (xy 306.149212 -192.529802) (xy 306.189361 -192.491093) (xy 306.234719 -192.458642)
			(xy 306.284319 -192.433141) (xy 306.337103 -192.415134) (xy 306.391946 -192.405004) (xy 306.44768 -192.402967)
			(xy 306.503117 -192.409067) (xy 306.557074 -192.423173) (xy 306.583047 -192.43421) (xy 310.34304 -192.43421)
			(xy 310.347111 -192.378588) (xy 310.359237 -192.324151) (xy 310.37916 -192.27206) (xy 310.406456 -192.223425)
			(xy 310.440542 -192.179282) (xy 310.480691 -192.140573) (xy 310.526049 -192.108122) (xy 310.575649 -192.082621)
			(xy 310.628433 -192.064614) (xy 310.683276 -192.054484) (xy 310.73901 -192.052447) (xy 310.794447 -192.058547)
			(xy 310.848404 -192.072653) (xy 310.899733 -192.094465) (xy 310.947339 -192.123519) (xy 310.990207 -192.159194)
			(xy 311.027424 -192.200731) (xy 311.058197 -192.247244) (xy 311.081869 -192.297741) (xy 311.097937 -192.351148)
			(xy 311.106057 -192.406324) (xy 311.106566 -192.43421) (xy 311.106057 -192.462096) (xy 311.097937 -192.517272)
			(xy 311.081869 -192.570679) (xy 311.058197 -192.621176) (xy 311.027424 -192.667689) (xy 311.012906 -192.683892)
			(xy 311.611262 -192.683892) (xy 311.615333 -192.62827) (xy 311.627459 -192.573833) (xy 311.647382 -192.521742)
			(xy 311.674678 -192.473107) (xy 311.708764 -192.428964) (xy 311.748913 -192.390255) (xy 311.794271 -192.357804)
			(xy 311.843871 -192.332303) (xy 311.896655 -192.314296) (xy 311.951498 -192.304166) (xy 312.007232 -192.302129)
			(xy 312.062669 -192.308229) (xy 312.116626 -192.322335) (xy 312.167955 -192.344147) (xy 312.215561 -192.373201)
			(xy 312.258429 -192.408876) (xy 312.27817 -192.430908) (xy 315.152022 -192.430908) (xy 315.156093 -192.375286)
			(xy 315.168219 -192.320849) (xy 315.188142 -192.268758) (xy 315.215438 -192.220123) (xy 315.249524 -192.17598)
			(xy 315.289673 -192.137271) (xy 315.335031 -192.10482) (xy 315.384631 -192.079319) (xy 315.437415 -192.061312)
			(xy 315.492258 -192.051182) (xy 315.547992 -192.049145) (xy 315.603429 -192.055245) (xy 315.657386 -192.069351)
			(xy 315.708715 -192.091163) (xy 315.756321 -192.120217) (xy 315.799189 -192.155892) (xy 315.836406 -192.197429)
			(xy 315.867179 -192.243942) (xy 315.890851 -192.294439) (xy 315.906919 -192.347846) (xy 315.915039 -192.403022)
			(xy 315.915548 -192.430908) (xy 315.915039 -192.458794) (xy 315.906919 -192.51397) (xy 315.890851 -192.567377)
			(xy 315.867179 -192.617874) (xy 315.836406 -192.664387) (xy 315.799189 -192.705924) (xy 315.756321 -192.741599)
			(xy 315.708715 -192.770653) (xy 315.657386 -192.792465) (xy 315.603429 -192.806571) (xy 315.547992 -192.812671)
			(xy 315.492258 -192.810634) (xy 315.437415 -192.800504) (xy 315.384631 -192.782497) (xy 315.335031 -192.756996)
			(xy 315.289673 -192.724545) (xy 315.249524 -192.685836) (xy 315.215438 -192.641693) (xy 315.188142 -192.593058)
			(xy 315.168219 -192.540967) (xy 315.156093 -192.48653) (xy 315.152022 -192.430908) (xy 312.27817 -192.430908)
			(xy 312.295646 -192.450413) (xy 312.326419 -192.496926) (xy 312.350091 -192.547423) (xy 312.366159 -192.60083)
			(xy 312.374279 -192.656006) (xy 312.374788 -192.683892) (xy 312.374279 -192.711778) (xy 312.366159 -192.766954)
			(xy 312.350091 -192.820361) (xy 312.326419 -192.870858) (xy 312.295646 -192.917371) (xy 312.258429 -192.958908)
			(xy 312.215561 -192.994583) (xy 312.167955 -193.023637) (xy 312.116626 -193.045449) (xy 312.062669 -193.059555)
			(xy 312.007232 -193.065655) (xy 311.951498 -193.063618) (xy 311.896655 -193.053488) (xy 311.843871 -193.035481)
			(xy 311.794271 -193.00998) (xy 311.748913 -192.977529) (xy 311.708764 -192.93882) (xy 311.674678 -192.894677)
			(xy 311.647382 -192.846042) (xy 311.627459 -192.793951) (xy 311.615333 -192.739514) (xy 311.611262 -192.683892)
			(xy 311.012906 -192.683892) (xy 310.990207 -192.709226) (xy 310.947339 -192.744901) (xy 310.899733 -192.773955)
			(xy 310.848404 -192.795767) (xy 310.794447 -192.809873) (xy 310.73901 -192.815973) (xy 310.683276 -192.813936)
			(xy 310.628433 -192.803806) (xy 310.575649 -192.785799) (xy 310.526049 -192.760298) (xy 310.480691 -192.727847)
			(xy 310.440542 -192.689138) (xy 310.406456 -192.644995) (xy 310.37916 -192.59636) (xy 310.359237 -192.544269)
			(xy 310.347111 -192.489832) (xy 310.34304 -192.43421) (xy 306.583047 -192.43421) (xy 306.608403 -192.444985)
			(xy 306.656009 -192.474039) (xy 306.698877 -192.509714) (xy 306.736094 -192.551251) (xy 306.766867 -192.597764)
			(xy 306.790539 -192.648261) (xy 306.806607 -192.701668) (xy 306.814727 -192.756844) (xy 306.815236 -192.78473)
			(xy 306.814727 -192.812616) (xy 306.806607 -192.867792) (xy 306.790539 -192.921199) (xy 306.766867 -192.971696)
			(xy 306.736094 -193.018209) (xy 306.698877 -193.059746) (xy 306.656009 -193.095421) (xy 306.608403 -193.124475)
			(xy 306.557074 -193.146287) (xy 306.503117 -193.160393) (xy 306.44768 -193.166493) (xy 306.391946 -193.164456)
			(xy 306.337103 -193.154326) (xy 306.284319 -193.136319) (xy 306.234719 -193.110818) (xy 306.189361 -193.078367)
			(xy 306.149212 -193.039658) (xy 306.115126 -192.995515) (xy 306.08783 -192.94688) (xy 306.067907 -192.894789)
			(xy 306.055781 -192.840352) (xy 306.05171 -192.78473) (xy 305.80192 -192.78473) (xy 305.817928 -192.819464)
			(xy 305.833545 -192.872207) (xy 305.841431 -192.926645) (xy 305.841908 -192.954148) (xy 305.841422 -192.981399)
			(xy 305.833666 -193.035347) (xy 305.818311 -193.087642) (xy 305.795669 -193.137219) (xy 305.766203 -193.183069)
			(xy 305.730512 -193.22426) (xy 305.689321 -193.259951) (xy 305.643471 -193.289417) (xy 305.593894 -193.312059)
			(xy 305.541599 -193.327414) (xy 305.487651 -193.33517) (xy 305.433149 -193.33517) (xy 305.379201 -193.327414)
			(xy 305.326906 -193.312059) (xy 305.277329 -193.289417) (xy 305.231479 -193.259951) (xy 305.190288 -193.22426)
			(xy 305.154597 -193.183069) (xy 305.125131 -193.137219) (xy 305.102489 -193.087642) (xy 305.087134 -193.035347)
			(xy 305.079378 -192.981399) (xy 305.078892 -192.954148) (xy 305.079501 -192.923686) (xy 305.089183 -192.863537)
			(xy 305.10831 -192.805694) (xy 305.136393 -192.751629) (xy 305.154076 -192.726818) (xy 305.162764 -192.714237)
			(xy 305.172811 -192.685371) (xy 305.173896 -192.654826) (xy 305.165924 -192.62532) (xy 305.149604 -192.599478)
			(xy 305.138328 -192.58915) (xy 305.117746 -192.570904) (xy 305.081474 -192.529559) (xy 305.051511 -192.483437)
			(xy 305.028477 -192.433492) (xy 305.01285 -192.380759) (xy 305.004952 -192.326328) (xy 305.00447 -192.298828)
			(xy 305.004936 -192.27267) (xy 305.012081 -192.220845) (xy 305.02624 -192.170483) (xy 305.047148 -192.122528)
			(xy 305.074413 -192.077879) (xy 305.107523 -192.037375) (xy 305.145858 -192.001775) (xy 305.16703 -191.986408)
			(xy 305.178214 -191.978026) (xy 305.19585 -191.956354) (xy 305.206967 -191.930721) (xy 305.210737 -191.903035)
			(xy 305.206878 -191.875363) (xy 305.195678 -191.849765) (xy 305.177973 -191.82815) (xy 305.166776 -191.819784)
			(xy 305.145421 -191.804445) (xy 305.106734 -191.768839) (xy 305.073305 -191.728255) (xy 305.04577 -191.683464)
			(xy 305.02465 -191.635313) (xy 305.010346 -191.584718) (xy 305.003129 -191.532637) (xy 305.002692 -191.506348)
			(xy 303.195228 -191.506348) (xy 305.57597 -193.88709) (xy 322.782692 -193.88709) (xy 327.929494 -188.740288)
			(xy 327.929494 -186.511438) (xy 327.928983 -186.497204) (xy 327.921052 -186.46986) (xy 327.90588 -186.445768)
			(xy 327.884646 -186.426802) (xy 327.859001 -186.414435) (xy 327.830939 -186.409628) (xy 327.80264 -186.412757)
			(xy 327.789286 -186.417712) (xy 327.766117 -186.426823) (xy 327.718007 -186.439631) (xy 327.668637 -186.446053)
			(xy 327.643744 -186.446414) (xy 327.616489 -186.445954) (xy 327.562532 -186.438202) (xy 327.510228 -186.422849)
			(xy 327.460642 -186.400209) (xy 327.414782 -186.370742) (xy 327.373584 -186.335047) (xy 327.337885 -186.293853)
			(xy 327.308412 -186.247997) (xy 327.285766 -186.198413) (xy 327.270408 -186.146111) (xy 327.262649 -186.092155)
			(xy 327.262649 -186.037645) (xy 327.270408 -185.983689) (xy 327.285766 -185.931387) (xy 327.308412 -185.881803)
			(xy 327.337885 -185.835947) (xy 327.373584 -185.794753) (xy 327.414782 -185.759058) (xy 327.460642 -185.729591)
			(xy 327.510228 -185.706951) (xy 327.562532 -185.691598) (xy 327.616489 -185.683846) (xy 327.643744 -185.683398)
			(xy 327.668635 -185.683787) (xy 327.717999 -185.690224) (xy 327.766111 -185.703008) (xy 327.789286 -185.7121)
			(xy 327.802637 -185.717071) (xy 327.830941 -185.720199) (xy 327.859008 -185.715392) (xy 327.884658 -185.703024)
			(xy 327.905897 -185.684054) (xy 327.921074 -185.659959) (xy 327.929009 -185.632611) (xy 327.929494 -185.618374)
			(xy 327.929494 -172.179742) (xy 326.642476 -170.892724) (xy 318.233806 -170.892724) (xy 312.055764 -164.714682)
			(xy 312.055764 -155.791154) (xy 317.547244 -150.299674) (xy 390.782048 -150.299674) (xy 390.795912 -150.299199)
			(xy 390.822612 -150.291722) (xy 390.846315 -150.277335) (xy 390.865269 -150.257098) (xy 390.878077 -150.232505)
			(xy 390.883792 -150.205373) (xy 390.881993 -150.177704) (xy 390.872811 -150.15154) (xy 390.856926 -150.128814)
			(xy 390.846564 -150.119588) (xy 390.823932 -150.100237) (xy 390.784375 -150.055731) (xy 390.752213 -150.005621)
			(xy 390.728226 -149.951123) (xy 390.720072 -149.922484) (xy 390.715661 -149.907801) (xy 390.699419 -149.881815)
			(xy 390.676206 -149.861808) (xy 390.648108 -149.849577) (xy 390.617648 -149.846219) (xy 390.587561 -149.852037)
			(xy 390.560548 -149.866508) (xy 390.549384 -149.877018) (xy 390.527736 -149.898126) (xy 390.479006 -149.933916)
			(xy 390.425243 -149.961576) (xy 390.367791 -149.980412) (xy 390.308088 -149.989954) (xy 390.277858 -149.990556)
			(xy 390.250605 -149.990067) (xy 390.196655 -149.982305) (xy 390.144359 -149.966944) (xy 390.094781 -149.944298)
			(xy 390.04893 -149.914827) (xy 390.00774 -149.879131) (xy 389.972048 -149.837936) (xy 389.942582 -149.792082)
			(xy 389.919941 -149.742502) (xy 389.904586 -149.690204) (xy 389.89683 -149.636253) (xy 389.89683 -149.581747)
			(xy 389.904586 -149.527796) (xy 389.919941 -149.475498) (xy 389.942582 -149.425918) (xy 389.972048 -149.380064)
			(xy 390.00774 -149.338869) (xy 390.04893 -149.303173) (xy 390.094781 -149.273702) (xy 390.144359 -149.251056)
			(xy 390.196655 -149.235695) (xy 390.250605 -149.227933) (xy 390.277858 -149.22754) (xy 390.305684 -149.228042)
			(xy 390.360747 -149.236123) (xy 390.414052 -149.252119) (xy 390.464466 -149.275692) (xy 390.510919 -149.30634)
			(xy 390.552426 -149.343413) (xy 390.588105 -149.386124) (xy 390.617199 -149.433566) (xy 390.639091 -149.484732)
			(xy 390.646666 -149.511512) (xy 390.651076 -149.526203) (xy 390.667321 -149.552205) (xy 390.690539 -149.572228)
			(xy 390.718647 -149.584473) (xy 390.749121 -149.587842) (xy 390.779225 -149.582031) (xy 390.806256 -149.567564)
			(xy 390.817354 -149.556978) (xy 390.839001 -149.535866) (xy 390.887729 -149.500069) (xy 390.941491 -149.472401)
			(xy 390.998944 -149.453556) (xy 391.058648 -149.444004) (xy 391.08888 -149.44344) (xy 391.116133 -149.443902)
			(xy 391.170083 -149.451657) (xy 391.222381 -149.467012) (xy 391.27196 -149.489654) (xy 391.317812 -149.519122)
			(xy 391.359003 -149.554816) (xy 391.394695 -149.59601) (xy 391.42416 -149.641864) (xy 391.446798 -149.691446)
			(xy 391.462149 -149.743744) (xy 391.4699 -149.797695) (xy 391.470388 -149.824948) (xy 394.008862 -149.824948)
			(xy 394.012933 -149.769326) (xy 394.025059 -149.714889) (xy 394.044982 -149.662798) (xy 394.072278 -149.614163)
			(xy 394.106364 -149.57002) (xy 394.146513 -149.531311) (xy 394.191871 -149.49886) (xy 394.241471 -149.473359)
			(xy 394.294255 -149.455352) (xy 394.349098 -149.445222) (xy 394.404832 -149.443185) (xy 394.460269 -149.449285)
			(xy 394.514226 -149.463391) (xy 394.565555 -149.485203) (xy 394.613161 -149.514257) (xy 394.656029 -149.549932)
			(xy 394.693246 -149.591469) (xy 394.724019 -149.637982) (xy 394.747691 -149.688479) (xy 394.748859 -149.69236)
			(xy 395.70228 -149.69236) (xy 395.706351 -149.636738) (xy 395.718477 -149.582301) (xy 395.7384 -149.53021)
			(xy 395.765696 -149.481575) (xy 395.799782 -149.437432) (xy 395.839931 -149.398723) (xy 395.885289 -149.366272)
			(xy 395.934889 -149.340771) (xy 395.987673 -149.322764) (xy 396.042516 -149.312634) (xy 396.09825 -149.310597)
			(xy 396.153687 -149.316697) (xy 396.207644 -149.330803) (xy 396.258973 -149.352615) (xy 396.306579 -149.381669)
			(xy 396.349447 -149.417344) (xy 396.386664 -149.458881) (xy 396.417437 -149.505394) (xy 396.441109 -149.555891)
			(xy 396.457177 -149.609298) (xy 396.465297 -149.664474) (xy 396.465806 -149.69236) (xy 396.465297 -149.720246)
			(xy 396.457177 -149.775422) (xy 396.441109 -149.828829) (xy 396.417437 -149.879326) (xy 396.386664 -149.925839)
			(xy 396.349447 -149.967376) (xy 396.306579 -150.003051) (xy 396.258973 -150.032105) (xy 396.207644 -150.053917)
			(xy 396.153687 -150.068023) (xy 396.09825 -150.074123) (xy 396.042516 -150.072086) (xy 395.987673 -150.061956)
			(xy 395.934889 -150.043949) (xy 395.885289 -150.018448) (xy 395.839931 -149.985997) (xy 395.799782 -149.947288)
			(xy 395.765696 -149.903145) (xy 395.7384 -149.85451) (xy 395.718477 -149.802419) (xy 395.706351 -149.747982)
			(xy 395.70228 -149.69236) (xy 394.748859 -149.69236) (xy 394.763759 -149.741886) (xy 394.771879 -149.797062)
			(xy 394.772388 -149.824948) (xy 394.771879 -149.852834) (xy 394.763759 -149.90801) (xy 394.747691 -149.961417)
			(xy 394.724019 -150.011914) (xy 394.693246 -150.058427) (xy 394.656029 -150.099964) (xy 394.613161 -150.135639)
			(xy 394.565555 -150.164693) (xy 394.514226 -150.186505) (xy 394.460269 -150.200611) (xy 394.404832 -150.206711)
			(xy 394.349098 -150.204674) (xy 394.294255 -150.194544) (xy 394.241471 -150.176537) (xy 394.191871 -150.151036)
			(xy 394.146513 -150.118585) (xy 394.106364 -150.079876) (xy 394.072278 -150.035733) (xy 394.044982 -149.987098)
			(xy 394.025059 -149.935007) (xy 394.012933 -149.88057) (xy 394.008862 -149.824948) (xy 391.470388 -149.824948)
			(xy 391.469893 -149.85302) (xy 391.46167 -149.90856) (xy 391.445392 -149.962293) (xy 391.421413 -150.01306)
			(xy 391.39025 -150.059762) (xy 391.352577 -150.101391) (xy 391.331196 -150.119588) (xy 391.320774 -150.128759)
			(xy 391.304868 -150.151498) (xy 391.295674 -150.17768) (xy 391.29387 -150.205371) (xy 391.29959 -150.232524)
			(xy 391.312411 -150.257135) (xy 391.331385 -150.277383) (xy 391.355112 -150.291774) (xy 391.381837 -150.299243)
			(xy 391.395712 -150.299674) (xy 393.227052 -150.299674) (xy 394.599922 -151.672544) (xy 395.88694 -151.672544)
			(xy 398.375124 -149.18436) (xy 398.375124 -145.915888) (xy 398.374592 -145.900906) (xy 398.365898 -145.872231)
			(xy 398.349262 -145.84731) (xy 398.326113 -145.828285) (xy 398.298441 -145.816792) (xy 398.268625 -145.813818)
			(xy 398.239228 -145.81962) (xy 398.225772 -145.826226) (xy 398.198072 -145.84024) (xy 398.139252 -145.860072)
			(xy 398.077993 -145.8701) (xy 398.046956 -145.870676) (xy 398.020578 -145.870228) (xy 397.968324 -145.86296)
			(xy 397.917569 -145.848568) (xy 397.869278 -145.827327) (xy 397.82437 -145.79964) (xy 397.783701 -145.766035)
			(xy 397.748045 -145.727152) (xy 397.718081 -145.683731) (xy 397.705834 -145.660364) (xy 397.699132 -145.648005)
			(xy 397.680157 -145.627277) (xy 397.656243 -145.612515) (xy 397.629207 -145.604843) (xy 397.601105 -145.604843)
			(xy 397.574069 -145.612515) (xy 397.550155 -145.627277) (xy 397.53118 -145.648005) (xy 397.524478 -145.660364)
			(xy 397.512236 -145.683737) (xy 397.482282 -145.727171) (xy 397.446631 -145.766065) (xy 397.405963 -145.799679)
			(xy 397.361053 -145.827371) (xy 397.312758 -145.848614) (xy 397.261996 -145.863003) (xy 397.209737 -145.870264)
			(xy 397.183356 -145.870676) (xy 397.156109 -145.870187) (xy 397.102171 -145.862426) (xy 397.049886 -145.847068)
			(xy 397.000318 -145.824427) (xy 396.954477 -145.794962) (xy 396.913296 -145.759273) (xy 396.877612 -145.718087)
			(xy 396.848152 -145.672243) (xy 396.825516 -145.622673) (xy 396.810165 -145.570386) (xy 396.80241 -145.516447)
			(xy 396.80241 -145.461953) (xy 396.810165 -145.408014) (xy 396.825516 -145.355727) (xy 396.848152 -145.306157)
			(xy 396.877612 -145.260313) (xy 396.913296 -145.219127) (xy 396.954477 -145.183438) (xy 397.000318 -145.153973)
			(xy 397.049886 -145.131332) (xy 397.102171 -145.115974) (xy 397.156109 -145.108213) (xy 397.183356 -145.10766)
			(xy 397.209733 -145.108109) (xy 397.261985 -145.115379) (xy 397.312738 -145.129773) (xy 397.361026 -145.151016)
			(xy 397.40593 -145.178705) (xy 397.446595 -145.212311) (xy 397.482247 -145.251196) (xy 397.512206 -145.294619)
			(xy 397.524478 -145.317972) (xy 397.53118 -145.330331) (xy 397.550155 -145.351059) (xy 397.574069 -145.365821)
			(xy 397.601105 -145.373493) (xy 397.629207 -145.373493) (xy 397.656243 -145.365821) (xy 397.680157 -145.351059)
			(xy 397.699132 -145.330331) (xy 397.705834 -145.317972) (xy 397.718078 -145.294603) (xy 397.748037 -145.251177)
			(xy 397.78369 -145.21229) (xy 397.824359 -145.178683) (xy 397.869268 -145.150997) (xy 397.917563 -145.129759)
			(xy 397.968321 -145.115375) (xy 398.020577 -145.108117) (xy 398.046956 -145.10766) (xy 398.077991 -145.108269)
			(xy 398.139244 -145.118304) (xy 398.198072 -145.138102) (xy 398.225772 -145.15211) (xy 398.239243 -145.158677)
			(xy 398.268631 -145.164474) (xy 398.298437 -145.161501) (xy 398.3261 -145.150013) (xy 398.349245 -145.130997)
			(xy 398.365881 -145.106088) (xy 398.37458 -145.077425) (xy 398.375124 -145.062448) (xy 398.375124 -130.821938)
			(xy 395.972792 -128.419606) (xy 363.88167 -128.419606) (xy 361.822492 -130.478784) (xy 344.061034 -130.478784)
			(xy 341.658448 -128.076198) (xy 291.205158 -128.076198) (xy 289.395408 -129.885948) (xy 318.621662 -129.885948)
			(xy 318.625733 -129.830326) (xy 318.637859 -129.775889) (xy 318.657782 -129.723798) (xy 318.685078 -129.675163)
			(xy 318.719164 -129.63102) (xy 318.759313 -129.592311) (xy 318.804671 -129.55986) (xy 318.854271 -129.534359)
			(xy 318.907055 -129.516352) (xy 318.961898 -129.506222) (xy 319.017632 -129.504185) (xy 319.073069 -129.510285)
			(xy 319.127026 -129.524391) (xy 319.178355 -129.546203) (xy 319.225961 -129.575257) (xy 319.268829 -129.610932)
			(xy 319.306046 -129.652469) (xy 319.336819 -129.698982) (xy 319.360491 -129.749479) (xy 319.376559 -129.802886)
			(xy 319.384679 -129.858062) (xy 319.385188 -129.885948) (xy 319.384679 -129.913834) (xy 319.376559 -129.96901)
			(xy 319.360491 -130.022417) (xy 319.336819 -130.072914) (xy 319.306046 -130.119427) (xy 319.268829 -130.160964)
			(xy 319.225961 -130.196639) (xy 319.178355 -130.225693) (xy 319.127026 -130.247505) (xy 319.073069 -130.261611)
			(xy 319.017632 -130.267711) (xy 318.961898 -130.265674) (xy 318.907055 -130.255544) (xy 318.854271 -130.237537)
			(xy 318.804671 -130.212036) (xy 318.759313 -130.179585) (xy 318.719164 -130.140876) (xy 318.685078 -130.096733)
			(xy 318.657782 -130.048098) (xy 318.637859 -129.996007) (xy 318.625733 -129.94157) (xy 318.621662 -129.885948)
			(xy 289.395408 -129.885948) (xy 285.415906 -133.86545) (xy 296.085266 -133.86545) (xy 296.085266 -133.81095)
			(xy 296.093021 -133.757004) (xy 296.108375 -133.704711) (xy 296.131014 -133.655134) (xy 296.160477 -133.609285)
			(xy 296.196166 -133.568094) (xy 296.237352 -133.532401) (xy 296.283199 -133.502933) (xy 296.332773 -133.480289)
			(xy 296.385065 -133.46493) (xy 296.43901 -133.457169) (xy 296.46626 -133.45668) (xy 296.49363 -133.45715)
			(xy 296.54781 -133.464964) (xy 296.600314 -133.480451) (xy 296.650061 -133.503292) (xy 296.696027 -133.533018)
			(xy 296.716958 -133.55066) (xy 296.728286 -133.559896) (xy 296.754843 -133.572072) (xy 296.78376 -133.576245)
			(xy 296.812677 -133.572072) (xy 296.839234 -133.559896) (xy 296.850562 -133.55066) (xy 296.871492 -133.533019)
			(xy 296.917466 -133.503308) (xy 296.967214 -133.480473) (xy 297.019715 -133.464983) (xy 297.073891 -133.457154)
			(xy 297.10126 -133.45668) (xy 297.128559 -133.457122) (xy 297.182598 -133.464912) (xy 297.234975 -133.480326)
			(xy 297.284619 -133.503049) (xy 297.330519 -133.532615) (xy 297.371735 -133.568422) (xy 297.407426 -133.609738)
			(xy 297.436864 -133.65572) (xy 297.459447 -133.705428) (xy 297.467528 -133.731508) (xy 297.472013 -133.745125)
			(xy 297.487407 -133.769299) (xy 297.508911 -133.788244) (xy 297.534833 -133.800467) (xy 297.56313 -133.805008)
			(xy 297.591574 -133.801507) (xy 297.617925 -133.790241) (xy 297.629326 -133.781546) (xy 297.649871 -133.765342)
			(xy 297.694541 -133.738093) (xy 297.742511 -133.717192) (xy 297.792884 -133.703032) (xy 297.844718 -133.695877)
			(xy 297.87088 -133.69544) (xy 297.898137 -133.695806) (xy 297.952097 -133.703561) (xy 298.004404 -133.718917)
			(xy 298.053993 -133.741562) (xy 298.099854 -133.771033) (xy 298.141055 -133.806731) (xy 298.176755 -133.84793)
			(xy 298.206229 -133.893789) (xy 298.228876 -133.943377) (xy 298.244235 -133.995683) (xy 298.251993 -134.049643)
			(xy 298.251993 -134.104157) (xy 298.244235 -134.158117) (xy 298.228876 -134.210423) (xy 298.206229 -134.260011)
			(xy 298.176755 -134.30587) (xy 298.141055 -134.347069) (xy 298.099854 -134.382767) (xy 298.053993 -134.412238)
			(xy 298.004404 -134.434883) (xy 297.952097 -134.450239) (xy 297.898137 -134.457994) (xy 297.87088 -134.458456)
			(xy 297.843584 -134.457953) (xy 297.789548 -134.450169) (xy 297.737174 -134.434762) (xy 297.687531 -134.412047)
			(xy 297.641633 -134.382488) (xy 297.600416 -134.346689) (xy 297.564723 -134.30538) (xy 297.535282 -134.259406)
			(xy 297.512695 -134.209704) (xy 297.504612 -134.183628) (xy 297.500091 -134.170027) (xy 297.484695 -134.145867)
			(xy 297.463196 -134.126932) (xy 297.437285 -134.114713) (xy 297.408999 -134.110169) (xy 297.380564 -134.113658)
			(xy 297.354216 -134.124906) (xy 297.342814 -134.13359) (xy 297.322259 -134.149781) (xy 297.277591 -134.177031)
			(xy 297.229624 -134.197933) (xy 297.179253 -134.212097) (xy 297.127422 -134.219256) (xy 297.10126 -134.219696)
			(xy 297.073891 -134.219196) (xy 297.019713 -134.211386) (xy 296.967211 -134.195905) (xy 296.917463 -134.173071)
			(xy 296.871495 -134.143354) (xy 296.850562 -134.125716) (xy 296.839234 -134.11648) (xy 296.812677 -134.104304)
			(xy 296.78376 -134.100131) (xy 296.754843 -134.104304) (xy 296.728286 -134.11648) (xy 296.716958 -134.125716)
			(xy 296.696017 -134.143344) (xy 296.650046 -134.173057) (xy 296.600301 -134.195895) (xy 296.547803 -134.211388)
			(xy 296.493629 -134.21922) (xy 296.46626 -134.219696) (xy 296.43901 -134.219231) (xy 296.385065 -134.21147)
			(xy 296.332773 -134.196111) (xy 296.283199 -134.173467) (xy 296.237352 -134.143999) (xy 296.196166 -134.108306)
			(xy 296.160477 -134.067115) (xy 296.131014 -134.021266) (xy 296.108375 -133.971689) (xy 296.093021 -133.919396)
			(xy 296.085266 -133.86545) (xy 285.415906 -133.86545) (xy 284.683962 -134.597394) (xy 268.123924 -134.597394)
			(xy 265.521672 -137.199646) (xy 336.829724 -137.199646) (xy 336.829724 -137.145154) (xy 336.837478 -137.091217)
			(xy 336.852829 -137.038932) (xy 336.875464 -136.989364) (xy 336.904923 -136.943522) (xy 336.940605 -136.902338)
			(xy 336.981785 -136.86665) (xy 337.027624 -136.837186) (xy 337.077189 -136.814545) (xy 337.129472 -136.799188)
			(xy 337.183408 -136.791427) (xy 337.210654 -136.790938) (xy 337.238024 -136.791422) (xy 337.292202 -136.799234)
			(xy 337.344706 -136.814718) (xy 337.394453 -136.837556) (xy 337.44042 -136.867278) (xy 337.461352 -136.884918)
			(xy 337.472702 -136.894057) (xy 337.499199 -136.906145) (xy 337.528027 -136.910286) (xy 337.556855 -136.906145)
			(xy 337.583352 -136.894057) (xy 337.594702 -136.884918) (xy 337.615667 -136.867267) (xy 337.661677 -136.837496)
			(xy 337.711469 -136.814603) (xy 337.76402 -136.799058) (xy 337.818253 -136.79118) (xy 337.845654 -136.790684)
			(xy 338.618322 -136.790684) (xy 338.64569 -136.791189) (xy 338.699866 -136.799006) (xy 338.752366 -136.814488)
			(xy 338.802114 -136.83732) (xy 338.848085 -136.86703) (xy 338.86902 -136.884664) (xy 338.880339 -136.89392)
			(xy 338.906895 -136.906127) (xy 338.935822 -136.91031) (xy 338.964749 -136.906127) (xy 338.991305 -136.89392)
			(xy 339.002624 -136.884664) (xy 339.023569 -136.867041) (xy 339.069539 -136.837328) (xy 339.119283 -136.81449)
			(xy 339.171781 -136.798995) (xy 339.225954 -136.791161) (xy 339.253322 -136.790684) (xy 339.280572 -136.791187)
			(xy 339.334516 -136.798946) (xy 339.386807 -136.814303) (xy 339.43638 -136.836945) (xy 339.482227 -136.866411)
			(xy 339.523414 -136.902102) (xy 339.559102 -136.943291) (xy 339.588566 -136.989139) (xy 339.611205 -137.038714)
			(xy 339.626559 -137.091006) (xy 339.634314 -137.14495) (xy 339.634314 -137.19945) (xy 339.626559 -137.253394)
			(xy 339.611205 -137.305686) (xy 339.588566 -137.355261) (xy 339.559102 -137.401109) (xy 339.523414 -137.442298)
			(xy 339.482227 -137.477989) (xy 339.43638 -137.507455) (xy 339.386807 -137.530097) (xy 339.334516 -137.545454)
			(xy 339.280572 -137.553213) (xy 339.253322 -137.5537) (xy 339.225988 -137.553245) (xy 339.17188 -137.545432)
			(xy 339.119441 -137.529979) (xy 339.069744 -137.507201) (xy 339.023805 -137.477565) (xy 339.002878 -137.459974)
			(xy 338.991559 -137.450718) (xy 338.965003 -137.438511) (xy 338.936076 -137.434328) (xy 338.907149 -137.438511)
			(xy 338.880593 -137.450718) (xy 338.869274 -137.459974) (xy 338.848317 -137.477635) (xy 338.802305 -137.507405)
			(xy 338.752511 -137.530296) (xy 338.699958 -137.545838) (xy 338.645723 -137.553713) (xy 338.618322 -137.554208)
			(xy 337.845654 -137.554208) (xy 337.81825 -137.553726) (xy 337.764008 -137.545874) (xy 337.711448 -137.53034)
			(xy 337.661652 -137.507441) (xy 337.615648 -137.477651) (xy 337.594702 -137.459974) (xy 337.583402 -137.450741)
			(xy 337.556896 -137.438564) (xy 337.528027 -137.434392) (xy 337.499158 -137.438564) (xy 337.472652 -137.450741)
			(xy 337.461352 -137.459974) (xy 337.440408 -137.477598) (xy 337.394439 -137.507313) (xy 337.344694 -137.530152)
			(xy 337.292196 -137.545647) (xy 337.238022 -137.553478) (xy 337.210654 -137.553954) (xy 337.183408 -137.553373)
			(xy 337.129472 -137.545612) (xy 337.077189 -137.530255) (xy 337.027624 -137.507614) (xy 336.981785 -137.47815)
			(xy 336.940605 -137.442462) (xy 336.904923 -137.401278) (xy 336.875464 -137.355436) (xy 336.852829 -137.305868)
			(xy 336.837478 -137.253583) (xy 336.829724 -137.199646) (xy 265.521672 -137.199646) (xy 264.622162 -138.099156)
			(xy 339.636515 -138.099156) (xy 339.636515 -138.044644) (xy 339.644273 -137.990687) (xy 339.659631 -137.938383)
			(xy 339.682277 -137.888797) (xy 339.711748 -137.842938) (xy 339.747447 -137.801741) (xy 339.788645 -137.766044)
			(xy 339.834504 -137.736573) (xy 339.88409 -137.713928) (xy 339.936394 -137.698571) (xy 339.990352 -137.690814)
			(xy 340.017608 -137.690352) (xy 340.032594 -137.690606) (xy 340.043139 -137.690521) (xy 340.062758 -137.682842)
			(xy 340.077653 -137.667942) (xy 340.085324 -137.64832) (xy 340.085426 -137.637774) (xy 340.085172 -137.622788)
			(xy 340.085172 -136.759188) (xy 340.085426 -136.744202) (xy 340.085323 -136.733658) (xy 340.077647 -136.714044)
			(xy 340.062753 -136.699151) (xy 340.043138 -136.691476) (xy 340.032594 -136.69137) (xy 340.017608 -136.691624)
			(xy 339.990356 -136.691129) (xy 339.936406 -136.683374) (xy 339.88411 -136.668019) (xy 339.834531 -136.645378)
			(xy 339.788679 -136.615911) (xy 339.747487 -136.580219) (xy 339.711794 -136.539028) (xy 339.682326 -136.493176)
			(xy 339.659684 -136.443598) (xy 339.644328 -136.391301) (xy 339.636571 -136.337352) (xy 339.636571 -136.282848)
			(xy 339.644328 -136.228899) (xy 339.659684 -136.176602) (xy 339.682326 -136.127024) (xy 339.711794 -136.081172)
			(xy 339.747487 -136.039981) (xy 339.788679 -136.004289) (xy 339.834531 -135.974822) (xy 339.88411 -135.952181)
			(xy 339.936406 -135.936826) (xy 339.990356 -135.929071) (xy 340.017608 -135.928608) (xy 340.04627 -135.929127)
			(xy 340.102946 -135.937732) (xy 340.157697 -135.954719) (xy 340.209291 -135.979703) (xy 340.256567 -136.012124)
			(xy 340.298462 -136.051251) (xy 340.334033 -136.096205) (xy 340.36248 -136.145974) (xy 340.383162 -136.199438)
			(xy 340.395615 -136.255395) (xy 340.3981 -136.283954) (xy 340.399525 -136.29851) (xy 340.409682 -136.325927)
			(xy 340.427189 -136.349343) (xy 340.450613 -136.36684) (xy 340.478034 -136.376985) (xy 340.492588 -136.378442)
			(xy 340.521178 -136.380868) (xy 340.577192 -136.393303) (xy 340.630713 -136.413984) (xy 340.680534 -136.442445)
			(xy 340.725533 -136.478045) (xy 340.764694 -136.519981) (xy 340.797135 -136.567307) (xy 340.822125 -136.618957)
			(xy 340.8391 -136.673766) (xy 340.847678 -136.730499) (xy 340.848188 -136.759188) (xy 340.848188 -137.622788)
			(xy 340.847611 -137.651468) (xy 340.839003 -137.708178) (xy 340.82201 -137.762963) (xy 340.797013 -137.81459)
			(xy 340.764575 -137.861897) (xy 340.725426 -137.90382) (xy 340.680447 -137.939416) (xy 340.630649 -137.967883)
			(xy 340.577154 -137.988582) (xy 340.521165 -138.001046) (xy 340.492588 -138.003534) (xy 340.478046 -138.005051)
			(xy 340.450638 -138.015189) (xy 340.427225 -138.032675) (xy 340.409723 -138.056076) (xy 340.399566 -138.083477)
			(xy 340.3981 -138.098022) (xy 340.395621 -138.126587) (xy 340.383202 -138.182561) (xy 340.362542 -138.236044)
			(xy 340.334106 -138.28583) (xy 340.298536 -138.330798) (xy 340.256634 -138.369932) (xy 340.209345 -138.402351)
			(xy 340.157734 -138.427324) (xy 340.102966 -138.444287) (xy 340.046276 -138.452858) (xy 340.017608 -138.453368)
			(xy 339.990352 -138.452986) (xy 339.936394 -138.445229) (xy 339.88409 -138.429872) (xy 339.834504 -138.407227)
			(xy 339.788645 -138.377756) (xy 339.747447 -138.342059) (xy 339.711748 -138.300862) (xy 339.682277 -138.255003)
			(xy 339.659631 -138.205417) (xy 339.644273 -138.153113) (xy 339.636515 -138.099156) (xy 264.622162 -138.099156)
			(xy 262.030718 -140.6906) (xy 334.161382 -140.6906) (xy 334.165453 -140.634978) (xy 334.177579 -140.580541)
			(xy 334.197502 -140.52845) (xy 334.224798 -140.479815) (xy 334.258884 -140.435672) (xy 334.299033 -140.396963)
			(xy 334.344391 -140.364512) (xy 334.393991 -140.339011) (xy 334.446775 -140.321004) (xy 334.501618 -140.310874)
			(xy 334.557352 -140.308837) (xy 334.612789 -140.314937) (xy 334.666746 -140.329043) (xy 334.718075 -140.350855)
			(xy 334.765681 -140.379909) (xy 334.808549 -140.415584) (xy 334.845766 -140.457121) (xy 334.876539 -140.503634)
			(xy 334.900211 -140.554131) (xy 334.916279 -140.607538) (xy 334.924399 -140.662714) (xy 334.924908 -140.6906)
			(xy 334.924399 -140.718486) (xy 334.916279 -140.773662) (xy 334.900211 -140.827069) (xy 334.876539 -140.877566)
			(xy 334.845766 -140.924079) (xy 334.808549 -140.965616) (xy 334.765681 -141.001291) (xy 334.718075 -141.030345)
			(xy 334.666746 -141.052157) (xy 334.612789 -141.066263) (xy 334.557352 -141.072363) (xy 334.501618 -141.070326)
			(xy 334.446775 -141.060196) (xy 334.393991 -141.042189) (xy 334.344391 -141.016688) (xy 334.299033 -140.984237)
			(xy 334.258884 -140.945528) (xy 334.224798 -140.901385) (xy 334.197502 -140.85275) (xy 334.177579 -140.800659)
			(xy 334.165453 -140.746222) (xy 334.161382 -140.6906) (xy 262.030718 -140.6906) (xy 260.573012 -142.148306)
			(xy 249.188478 -142.148306) (xy 248.976134 -142.36065) (xy 248.95815 -142.378005) (xy 248.917737 -142.407406)
			(xy 248.873219 -142.430114) (xy 248.825692 -142.445569) (xy 248.776332 -142.453388) (xy 248.751344 -142.453868)
			(xy 228.262688 -142.453868) (xy 224.279931 -146.436588) (xy 391.01598 -146.436588) (xy 391.020051 -146.380966)
			(xy 391.032177 -146.326529) (xy 391.0521 -146.274438) (xy 391.079396 -146.225803) (xy 391.113482 -146.18166)
			(xy 391.153631 -146.142951) (xy 391.198989 -146.1105) (xy 391.248589 -146.084999) (xy 391.301373 -146.066992)
			(xy 391.356216 -146.056862) (xy 391.41195 -146.054825) (xy 391.467387 -146.060925) (xy 391.521344 -146.075031)
			(xy 391.572673 -146.096843) (xy 391.620279 -146.125897) (xy 391.663147 -146.161572) (xy 391.700364 -146.203109)
			(xy 391.731137 -146.249622) (xy 391.754809 -146.300119) (xy 391.770877 -146.353526) (xy 391.778997 -146.408702)
			(xy 391.779506 -146.436588) (xy 391.778997 -146.464474) (xy 391.770877 -146.51965) (xy 391.754809 -146.573057)
			(xy 391.731137 -146.623554) (xy 391.700364 -146.670067) (xy 391.663147 -146.711604) (xy 391.620279 -146.747279)
			(xy 391.572673 -146.776333) (xy 391.521344 -146.798145) (xy 391.467387 -146.812251) (xy 391.41195 -146.818351)
			(xy 391.356216 -146.816314) (xy 391.301373 -146.806184) (xy 391.248589 -146.788177) (xy 391.198989 -146.762676)
			(xy 391.153631 -146.730225) (xy 391.113482 -146.691516) (xy 391.079396 -146.647373) (xy 391.0521 -146.598738)
			(xy 391.032177 -146.546647) (xy 391.020051 -146.49221) (xy 391.01598 -146.436588) (xy 224.279931 -146.436588)
			(xy 223.630193 -147.08632) (xy 392.63523 -147.08632) (xy 392.639301 -147.030698) (xy 392.651427 -146.976261)
			(xy 392.67135 -146.92417) (xy 392.698646 -146.875535) (xy 392.732732 -146.831392) (xy 392.772881 -146.792683)
			(xy 392.818239 -146.760232) (xy 392.867839 -146.734731) (xy 392.920623 -146.716724) (xy 392.975466 -146.706594)
			(xy 393.0312 -146.704557) (xy 393.086637 -146.710657) (xy 393.140594 -146.724763) (xy 393.191923 -146.746575)
			(xy 393.239529 -146.775629) (xy 393.282397 -146.811304) (xy 393.319614 -146.852841) (xy 393.350387 -146.899354)
			(xy 393.374059 -146.949851) (xy 393.390127 -147.003258) (xy 393.398247 -147.058434) (xy 393.398756 -147.08632)
			(xy 393.398247 -147.114206) (xy 393.390127 -147.169382) (xy 393.374059 -147.222789) (xy 393.350387 -147.273286)
			(xy 393.319614 -147.319799) (xy 393.282397 -147.361336) (xy 393.239529 -147.397011) (xy 393.191923 -147.426065)
			(xy 393.140594 -147.447877) (xy 393.086637 -147.461983) (xy 393.0312 -147.468083) (xy 392.975466 -147.466046)
			(xy 392.920623 -147.455916) (xy 392.867839 -147.437909) (xy 392.818239 -147.412408) (xy 392.772881 -147.379957)
			(xy 392.732732 -147.341248) (xy 392.698646 -147.297105) (xy 392.67135 -147.24847) (xy 392.651427 -147.196379)
			(xy 392.639301 -147.141942) (xy 392.63523 -147.08632) (xy 223.630193 -147.08632) (xy 222.776237 -147.940268)
			(xy 225.121722 -147.940268) (xy 225.125793 -147.884646) (xy 225.137919 -147.830209) (xy 225.157842 -147.778118)
			(xy 225.185138 -147.729483) (xy 225.219224 -147.68534) (xy 225.259373 -147.646631) (xy 225.304731 -147.61418)
			(xy 225.354331 -147.588679) (xy 225.407115 -147.570672) (xy 225.461958 -147.560542) (xy 225.517692 -147.558505)
			(xy 225.573129 -147.564605) (xy 225.627086 -147.578711) (xy 225.678415 -147.600523) (xy 225.726021 -147.629577)
			(xy 225.768889 -147.665252) (xy 225.806106 -147.706789) (xy 225.836879 -147.753302) (xy 225.860551 -147.803799)
			(xy 225.876619 -147.857206) (xy 225.884739 -147.912382) (xy 225.885248 -147.940268) (xy 225.884739 -147.968154)
			(xy 225.876619 -148.02333) (xy 225.869513 -148.046948) (xy 242.751862 -148.046948) (xy 242.755933 -147.991326)
			(xy 242.768059 -147.936889) (xy 242.787982 -147.884798) (xy 242.815278 -147.836163) (xy 242.849364 -147.79202)
			(xy 242.889513 -147.753311) (xy 242.934871 -147.72086) (xy 242.984471 -147.695359) (xy 243.037255 -147.677352)
			(xy 243.092098 -147.667222) (xy 243.147832 -147.665185) (xy 243.203269 -147.671285) (xy 243.257226 -147.685391)
			(xy 243.308555 -147.707203) (xy 243.356161 -147.736257) (xy 243.399029 -147.771932) (xy 243.436246 -147.813469)
			(xy 243.467019 -147.859982) (xy 243.490691 -147.910479) (xy 243.491247 -147.912328) (xy 272.223482 -147.912328)
			(xy 272.227553 -147.856706) (xy 272.239679 -147.802269) (xy 272.259602 -147.750178) (xy 272.286898 -147.701543)
			(xy 272.320984 -147.6574) (xy 272.361133 -147.618691) (xy 272.406491 -147.58624) (xy 272.456091 -147.560739)
			(xy 272.508875 -147.542732) (xy 272.563718 -147.532602) (xy 272.619452 -147.530565) (xy 272.674889 -147.536665)
			(xy 272.728846 -147.550771) (xy 272.780175 -147.572583) (xy 272.827781 -147.601637) (xy 272.870649 -147.637312)
			(xy 272.907866 -147.678849) (xy 272.938639 -147.725362) (xy 272.962311 -147.775859) (xy 272.967452 -147.792948)
			(xy 344.097862 -147.792948) (xy 344.101933 -147.737326) (xy 344.114059 -147.682889) (xy 344.133982 -147.630798)
			(xy 344.161278 -147.582163) (xy 344.195364 -147.53802) (xy 344.235513 -147.499311) (xy 344.280871 -147.46686)
			(xy 344.330471 -147.441359) (xy 344.383255 -147.423352) (xy 344.438098 -147.413222) (xy 344.493832 -147.411185)
			(xy 344.549269 -147.417285) (xy 344.603226 -147.431391) (xy 344.654555 -147.453203) (xy 344.702161 -147.482257)
			(xy 344.745029 -147.517932) (xy 344.782246 -147.559469) (xy 344.813019 -147.605982) (xy 344.836691 -147.656479)
			(xy 344.852759 -147.709886) (xy 344.860879 -147.765062) (xy 344.861388 -147.792948) (xy 390.706862 -147.792948)
			(xy 390.710933 -147.737326) (xy 390.723059 -147.682889) (xy 390.742982 -147.630798) (xy 390.770278 -147.582163)
			(xy 390.804364 -147.53802) (xy 390.844513 -147.499311) (xy 390.889871 -147.46686) (xy 390.939471 -147.441359)
			(xy 390.992255 -147.423352) (xy 391.047098 -147.413222) (xy 391.102832 -147.411185) (xy 391.158269 -147.417285)
			(xy 391.212226 -147.431391) (xy 391.263555 -147.453203) (xy 391.311161 -147.482257) (xy 391.354029 -147.517932)
			(xy 391.391246 -147.559469) (xy 391.422019 -147.605982) (xy 391.445691 -147.656479) (xy 391.461759 -147.709886)
			(xy 391.469879 -147.765062) (xy 391.470388 -147.792948) (xy 394.008862 -147.792948) (xy 394.012933 -147.737326)
			(xy 394.025059 -147.682889) (xy 394.044982 -147.630798) (xy 394.072278 -147.582163) (xy 394.106364 -147.53802)
			(xy 394.146513 -147.499311) (xy 394.191871 -147.46686) (xy 394.241471 -147.441359) (xy 394.294255 -147.423352)
			(xy 394.349098 -147.413222) (xy 394.404832 -147.411185) (xy 394.460269 -147.417285) (xy 394.514226 -147.431391)
			(xy 394.565555 -147.453203) (xy 394.613161 -147.482257) (xy 394.656029 -147.517932) (xy 394.693246 -147.559469)
			(xy 394.724019 -147.605982) (xy 394.747691 -147.656479) (xy 394.763759 -147.709886) (xy 394.771879 -147.765062)
			(xy 394.772388 -147.792948) (xy 394.771879 -147.820834) (xy 394.763759 -147.87601) (xy 394.747691 -147.929417)
			(xy 394.724019 -147.979914) (xy 394.693246 -148.026427) (xy 394.656029 -148.067964) (xy 394.613161 -148.103639)
			(xy 394.565555 -148.132693) (xy 394.514226 -148.154505) (xy 394.460269 -148.168611) (xy 394.404832 -148.174711)
			(xy 394.349098 -148.172674) (xy 394.294255 -148.162544) (xy 394.241471 -148.144537) (xy 394.191871 -148.119036)
			(xy 394.146513 -148.086585) (xy 394.106364 -148.047876) (xy 394.072278 -148.003733) (xy 394.044982 -147.955098)
			(xy 394.025059 -147.903007) (xy 394.012933 -147.84857) (xy 394.008862 -147.792948) (xy 391.470388 -147.792948)
			(xy 391.469879 -147.820834) (xy 391.461759 -147.87601) (xy 391.445691 -147.929417) (xy 391.422019 -147.979914)
			(xy 391.391246 -148.026427) (xy 391.354029 -148.067964) (xy 391.311161 -148.103639) (xy 391.263555 -148.132693)
			(xy 391.212226 -148.154505) (xy 391.158269 -148.168611) (xy 391.102832 -148.174711) (xy 391.047098 -148.172674)
			(xy 390.992255 -148.162544) (xy 390.939471 -148.144537) (xy 390.889871 -148.119036) (xy 390.844513 -148.086585)
			(xy 390.804364 -148.047876) (xy 390.770278 -148.003733) (xy 390.742982 -147.955098) (xy 390.723059 -147.903007)
			(xy 390.710933 -147.84857) (xy 390.706862 -147.792948) (xy 344.861388 -147.792948) (xy 344.860879 -147.820834)
			(xy 344.852759 -147.87601) (xy 344.836691 -147.929417) (xy 344.813019 -147.979914) (xy 344.782246 -148.026427)
			(xy 344.745029 -148.067964) (xy 344.702161 -148.103639) (xy 344.654555 -148.132693) (xy 344.603226 -148.154505)
			(xy 344.549269 -148.168611) (xy 344.493832 -148.174711) (xy 344.438098 -148.172674) (xy 344.383255 -148.162544)
			(xy 344.330471 -148.144537) (xy 344.280871 -148.119036) (xy 344.235513 -148.086585) (xy 344.195364 -148.047876)
			(xy 344.161278 -148.003733) (xy 344.133982 -147.955098) (xy 344.114059 -147.903007) (xy 344.101933 -147.84857)
			(xy 344.097862 -147.792948) (xy 272.967452 -147.792948) (xy 272.978379 -147.829266) (xy 272.986499 -147.884442)
			(xy 272.987008 -147.912328) (xy 272.986499 -147.940214) (xy 272.978379 -147.99539) (xy 272.962311 -148.048797)
			(xy 272.938639 -148.099294) (xy 272.907866 -148.145807) (xy 272.870649 -148.187344) (xy 272.827781 -148.223019)
			(xy 272.780175 -148.252073) (xy 272.728846 -148.273885) (xy 272.674889 -148.287991) (xy 272.619452 -148.294091)
			(xy 272.563718 -148.292054) (xy 272.508875 -148.281924) (xy 272.456091 -148.263917) (xy 272.406491 -148.238416)
			(xy 272.361133 -148.205965) (xy 272.320984 -148.167256) (xy 272.286898 -148.123113) (xy 272.259602 -148.074478)
			(xy 272.239679 -148.022387) (xy 272.227553 -147.96795) (xy 272.223482 -147.912328) (xy 243.491247 -147.912328)
			(xy 243.506759 -147.963886) (xy 243.514879 -148.019062) (xy 243.515388 -148.046948) (xy 243.514879 -148.074834)
			(xy 243.506759 -148.13001) (xy 243.490691 -148.183417) (xy 243.467019 -148.233914) (xy 243.436246 -148.280427)
			(xy 243.399029 -148.321964) (xy 243.356161 -148.357639) (xy 243.308555 -148.386693) (xy 243.257226 -148.408505)
			(xy 243.203269 -148.422611) (xy 243.147832 -148.428711) (xy 243.092098 -148.426674) (xy 243.037255 -148.416544)
			(xy 242.984471 -148.398537) (xy 242.934871 -148.373036) (xy 242.889513 -148.340585) (xy 242.849364 -148.301876)
			(xy 242.815278 -148.257733) (xy 242.787982 -148.209098) (xy 242.768059 -148.157007) (xy 242.755933 -148.10257)
			(xy 242.751862 -148.046948) (xy 225.869513 -148.046948) (xy 225.860551 -148.076737) (xy 225.836879 -148.127234)
			(xy 225.806106 -148.173747) (xy 225.768889 -148.215284) (xy 225.726021 -148.250959) (xy 225.678415 -148.280013)
			(xy 225.627086 -148.301825) (xy 225.573129 -148.315931) (xy 225.517692 -148.322031) (xy 225.461958 -148.319994)
			(xy 225.407115 -148.309864) (xy 225.354331 -148.291857) (xy 225.304731 -148.266356) (xy 225.259373 -148.233905)
			(xy 225.219224 -148.195196) (xy 225.185138 -148.151053) (xy 225.157842 -148.102418) (xy 225.137919 -148.050327)
			(xy 225.125793 -147.99589) (xy 225.121722 -147.940268) (xy 222.776237 -147.940268) (xy 221.880349 -148.836147)
			(xy 268.406926 -148.836147) (xy 268.406926 -148.781653) (xy 268.414681 -148.727714) (xy 268.430033 -148.675427)
			(xy 268.45267 -148.625858) (xy 268.482131 -148.580014) (xy 268.517816 -148.53883) (xy 268.558998 -148.503143)
			(xy 268.60484 -148.47368) (xy 268.654409 -148.45104) (xy 268.706694 -148.435685) (xy 268.760633 -148.427928)
			(xy 268.78788 -148.42744) (xy 268.815799 -148.427915) (xy 268.871041 -148.436053) (xy 268.924507 -148.452156)
			(xy 268.975054 -148.475882) (xy 269.021603 -148.506723) (xy 269.063157 -148.544021) (xy 269.098831 -148.586978)
			(xy 269.113762 -148.610574) (xy 269.121935 -148.623068) (xy 269.144108 -148.643041) (xy 269.171108 -148.65575)
			(xy 269.20063 -148.660111) (xy 269.230152 -148.65575) (xy 269.257152 -148.643041) (xy 269.279325 -148.623068)
			(xy 269.287498 -148.610574) (xy 269.302429 -148.586979) (xy 269.338107 -148.544028) (xy 269.379664 -148.506735)
			(xy 269.426212 -148.475897) (xy 269.476758 -148.452173) (xy 269.530222 -148.436068) (xy 269.585462 -148.427928)
			(xy 269.61338 -148.42744) (xy 269.640637 -148.427806) (xy 269.694597 -148.435561) (xy 269.746904 -148.450917)
			(xy 269.796493 -148.473562) (xy 269.842354 -148.503033) (xy 269.883555 -148.538731) (xy 269.919255 -148.57993)
			(xy 269.948729 -148.625789) (xy 269.971376 -148.675377) (xy 269.986735 -148.727683) (xy 269.994493 -148.781643)
			(xy 269.994493 -148.836157) (xy 269.986735 -148.890117) (xy 269.971376 -148.942423) (xy 269.948729 -148.992011)
			(xy 269.919255 -149.03787) (xy 269.883555 -149.079069) (xy 269.842354 -149.114767) (xy 269.796493 -149.144238)
			(xy 269.746904 -149.166883) (xy 269.694597 -149.182239) (xy 269.640637 -149.189994) (xy 269.61338 -149.190456)
			(xy 269.58546 -149.190014) (xy 269.530216 -149.181871) (xy 269.476749 -149.165762) (xy 269.426202 -149.14203)
			(xy 269.379654 -149.111184) (xy 269.3381 -149.073882) (xy 269.302428 -149.03092) (xy 269.287498 -149.007322)
			(xy 269.279325 -148.994828) (xy 269.257152 -148.974855) (xy 269.230152 -148.962146) (xy 269.20063 -148.957785)
			(xy 269.171108 -148.962146) (xy 269.144108 -148.974855) (xy 269.121935 -148.994828) (xy 269.113762 -149.007322)
			(xy 269.098857 -149.030934) (xy 269.063175 -149.073886) (xy 269.021613 -149.111177) (xy 268.975061 -149.142013)
			(xy 268.924511 -149.165735) (xy 268.871043 -149.181835) (xy 268.8158 -149.189971) (xy 268.78788 -149.190456)
			(xy 268.760633 -149.189872) (xy 268.706694 -149.182115) (xy 268.654409 -149.16676) (xy 268.60484 -149.14412)
			(xy 268.558998 -149.114657) (xy 268.517816 -149.07897) (xy 268.482131 -149.037786) (xy 268.45267 -148.991942)
			(xy 268.430033 -148.942373) (xy 268.414681 -148.890086) (xy 268.406926 -148.836147) (xy 221.880349 -148.836147)
			(xy 220.910034 -149.806453) (xy 255.793183 -149.806453) (xy 255.793183 -149.751947) (xy 255.800941 -149.697997)
			(xy 255.816298 -149.6457) (xy 255.838942 -149.59612) (xy 255.868411 -149.550269) (xy 255.904106 -149.509078)
			(xy 255.945301 -149.473387) (xy 255.991156 -149.443922) (xy 256.040737 -149.421284) (xy 256.093036 -149.405932)
			(xy 256.146987 -149.398181) (xy 256.17424 -149.39772) (xy 256.202445 -149.398235) (xy 256.258237 -149.406558)
			(xy 256.312196 -149.423002) (xy 256.363148 -149.447209) (xy 256.409982 -149.478651) (xy 256.451678 -149.516644)
			(xy 256.469896 -149.538182) (xy 256.479353 -149.54904) (xy 256.502979 -149.565474) (xy 256.530256 -149.57465)
			(xy 256.55901 -149.575838) (xy 256.586951 -149.568944) (xy 256.611852 -149.554515) (xy 256.631729 -149.533703)
			(xy 256.638806 -149.521164) (xy 256.651265 -149.498367) (xy 256.681357 -149.45602) (xy 256.716918 -149.418148)
			(xy 256.757289 -149.385454) (xy 256.801724 -149.35854) (xy 256.8494 -149.337906) (xy 256.899436 -149.323933)
			(xy 256.950905 -149.31688) (xy 256.97688 -149.31644) (xy 257.004137 -149.316806) (xy 257.058097 -149.324561)
			(xy 257.110404 -149.339917) (xy 257.159993 -149.362562) (xy 257.205854 -149.392033) (xy 257.247055 -149.427731)
			(xy 257.282755 -149.46893) (xy 257.312229 -149.514789) (xy 257.334876 -149.564377) (xy 257.350235 -149.616683)
			(xy 257.357993 -149.670643) (xy 257.357993 -149.725157) (xy 257.350235 -149.779117) (xy 257.334876 -149.831423)
			(xy 257.312229 -149.881011) (xy 257.282755 -149.92687) (xy 257.247055 -149.968069) (xy 257.205854 -150.003767)
			(xy 257.159993 -150.033238) (xy 257.110404 -150.055883) (xy 257.058097 -150.071239) (xy 257.004137 -150.078994)
			(xy 256.97688 -150.079456) (xy 256.948675 -150.078936) (xy 256.892883 -150.070615) (xy 256.838923 -150.054173)
			(xy 256.787971 -150.029967) (xy 256.741137 -149.998525) (xy 256.699442 -149.960532) (xy 256.681224 -149.938994)
			(xy 256.67174 -149.928162) (xy 256.64812 -149.911733) (xy 256.62085 -149.902558) (xy 256.592103 -149.901367)
			(xy 256.564168 -149.908256) (xy 256.53927 -149.922676) (xy 256.519393 -149.943478) (xy 256.512314 -149.956012)
			(xy 256.499873 -149.978819) (xy 256.469775 -150.021162) (xy 256.43421 -150.059031) (xy 256.393835 -150.091723)
			(xy 256.370018 -150.106147) (xy 257.738926 -150.106147) (xy 257.738926 -150.051653) (xy 257.746681 -149.997714)
			(xy 257.762033 -149.945427) (xy 257.78467 -149.895858) (xy 257.814131 -149.850014) (xy 257.849816 -149.80883)
			(xy 257.890998 -149.773143) (xy 257.93684 -149.74368) (xy 257.986409 -149.72104) (xy 258.038694 -149.705685)
			(xy 258.092633 -149.697928) (xy 258.11988 -149.69744) (xy 258.14686 -149.697913) (xy 258.200279 -149.705534)
			(xy 258.252093 -149.720599) (xy 258.301271 -149.742809) (xy 258.346832 -149.771721) (xy 258.387869 -149.806758)
			(xy 258.423566 -149.847223) (xy 258.426788 -149.852123) (xy 263.326873 -149.852123) (xy 263.326877 -149.797619)
			(xy 263.334638 -149.743671) (xy 263.349998 -149.691376) (xy 263.372644 -149.641799) (xy 263.402115 -149.595951)
			(xy 263.437811 -149.554763) (xy 263.479005 -149.519074) (xy 263.524859 -149.489611) (xy 263.57444 -149.466974)
			(xy 263.626737 -149.451624) (xy 263.680687 -149.443873) (xy 263.73519 -149.443878) (xy 263.789139 -149.45164)
			(xy 263.841433 -149.467001) (xy 263.891009 -149.489648) (xy 263.936857 -149.51912) (xy 263.978044 -149.554817)
			(xy 264.013732 -149.596013) (xy 264.043193 -149.641867) (xy 264.065829 -149.691448) (xy 264.075712 -149.725123)
			(xy 264.723873 -149.725123) (xy 264.723877 -149.670619) (xy 264.731638 -149.616671) (xy 264.746998 -149.564376)
			(xy 264.769644 -149.514799) (xy 264.799115 -149.468951) (xy 264.834811 -149.427763) (xy 264.876005 -149.392074)
			(xy 264.921859 -149.362611) (xy 264.97144 -149.339974) (xy 265.023737 -149.324624) (xy 265.077687 -149.316873)
			(xy 265.13219 -149.316878) (xy 265.186139 -149.32464) (xy 265.238433 -149.340001) (xy 265.288009 -149.362648)
			(xy 265.333857 -149.39212) (xy 265.375044 -149.427817) (xy 265.410732 -149.469013) (xy 265.440193 -149.514867)
			(xy 265.462829 -149.564448) (xy 265.478178 -149.616746) (xy 265.485928 -149.670696) (xy 265.486388 -149.697948)
			(xy 265.486098 -149.718885) (xy 265.48152 -149.760508) (xy 265.477244 -149.781006) (xy 265.474691 -149.794333)
			(xy 265.475975 -149.821429) (xy 265.484364 -149.847225) (xy 265.499262 -149.869894) (xy 265.519614 -149.887828)
			(xy 265.543976 -149.899757) (xy 265.570623 -149.904834) (xy 265.584178 -149.904196) (xy 265.61288 -149.90318)
			(xy 265.640135 -149.903633) (xy 265.69409 -149.911388) (xy 265.746392 -149.926743) (xy 265.795977 -149.949385)
			(xy 265.841835 -149.978853) (xy 265.883032 -150.014548) (xy 265.918729 -150.055742) (xy 265.948201 -150.101597)
			(xy 265.970847 -150.15118) (xy 265.986205 -150.203481) (xy 265.993964 -150.257436) (xy 265.993966 -150.311945)
			(xy 265.986209 -150.3659) (xy 265.970853 -150.418202) (xy 265.94821 -150.467786) (xy 265.918741 -150.513643)
			(xy 265.883045 -150.554839) (xy 265.84185 -150.590536) (xy 265.795993 -150.620006) (xy 265.74641 -150.64265)
			(xy 265.694108 -150.658008) (xy 265.640153 -150.665765) (xy 265.585644 -150.665765) (xy 265.531689 -150.658007)
			(xy 265.479388 -150.64265) (xy 265.429804 -150.620005) (xy 265.383948 -150.590534) (xy 265.342753 -150.554837)
			(xy 265.307058 -150.513641) (xy 265.277589 -150.467784) (xy 265.254946 -150.4182) (xy 265.23959 -150.365898)
			(xy 265.231834 -150.311943) (xy 265.231372 -150.284688) (xy 265.23165 -150.263751) (xy 265.236236 -150.222127)
			(xy 265.240516 -150.20163) (xy 265.243073 -150.188302) (xy 265.241797 -150.161202) (xy 265.233412 -150.135401)
			(xy 265.218514 -150.112728) (xy 265.198158 -150.094792) (xy 265.17379 -150.082866) (xy 265.147138 -150.077797)
			(xy 265.133582 -150.07844) (xy 265.10488 -150.079456) (xy 265.077628 -150.078923) (xy 265.02368 -150.071164)
			(xy 264.971385 -150.055805) (xy 264.921808 -150.033161) (xy 264.875958 -150.003691) (xy 264.834769 -149.967996)
			(xy 264.79908 -149.926802) (xy 264.769616 -149.880949) (xy 264.746978 -149.831369) (xy 264.731626 -149.779072)
			(xy 264.723873 -149.725123) (xy 264.075712 -149.725123) (xy 264.081178 -149.743746) (xy 264.088928 -149.797696)
			(xy 264.089388 -149.824948) (xy 264.089337 -149.834872) (xy 264.088318 -149.854694) (xy 264.087356 -149.864572)
			(xy 264.086371 -149.879104) (xy 264.091615 -149.907738) (xy 264.104718 -149.933732) (xy 264.124618 -149.954978)
			(xy 264.1497 -149.969752) (xy 264.17793 -149.976855) (xy 264.207018 -149.975712) (xy 264.22096 -149.971506)
			(xy 264.250569 -149.962155) (xy 264.311835 -149.952071) (xy 264.34288 -149.95144) (xy 264.370132 -149.951856)
			(xy 264.424082 -149.95961) (xy 264.47638 -149.974963) (xy 264.52596 -149.997602) (xy 264.571814 -150.027067)
			(xy 264.613008 -150.062757) (xy 264.648704 -150.103946) (xy 264.678174 -150.149796) (xy 264.70082 -150.199374)
			(xy 264.716179 -150.251669) (xy 264.72394 -150.305618) (xy 264.723944 -150.360123) (xy 264.716192 -150.414073)
			(xy 264.70084 -150.466371) (xy 264.678202 -150.515952) (xy 264.648739 -150.561807) (xy 264.61305 -150.603002)
			(xy 264.571861 -150.638698) (xy 264.526012 -150.66817) (xy 264.476435 -150.690817) (xy 264.42414 -150.706177)
			(xy 264.370191 -150.713939) (xy 264.315686 -150.713945) (xy 264.261736 -150.706194) (xy 264.209438 -150.690844)
			(xy 264.159856 -150.668207) (xy 264.114001 -150.638745) (xy 264.072805 -150.603056) (xy 264.037107 -150.561869)
			(xy 264.007635 -150.51602) (xy 263.984987 -150.466444) (xy 263.969625 -150.414149) (xy 263.961861 -150.3602)
			(xy 263.961372 -150.332948) (xy 263.961423 -150.323024) (xy 263.962442 -150.303202) (xy 263.963404 -150.293324)
			(xy 263.964445 -150.278793) (xy 263.959199 -150.25015) (xy 263.946088 -150.224148) (xy 263.926178 -150.202898)
			(xy 263.901084 -150.188124) (xy 263.872843 -150.181025) (xy 263.843745 -150.182178) (xy 263.8298 -150.18639)
			(xy 263.800193 -150.19575) (xy 263.738925 -150.205828) (xy 263.70788 -150.206456) (xy 263.680628 -150.205923)
			(xy 263.62668 -150.198164) (xy 263.574385 -150.182805) (xy 263.524808 -150.160161) (xy 263.478958 -150.130691)
			(xy 263.437769 -150.094996) (xy 263.40208 -150.053802) (xy 263.372616 -150.007949) (xy 263.349978 -149.958369)
			(xy 263.334626 -149.906072) (xy 263.326873 -149.852123) (xy 258.426788 -149.852123) (xy 258.45321 -149.892311)
			(xy 258.476212 -149.941123) (xy 258.492114 -149.992687) (xy 258.496816 -150.019258) (xy 258.499739 -150.03376)
			(xy 258.512573 -150.060392) (xy 258.532497 -150.082233) (xy 258.557841 -150.097452) (xy 258.586483 -150.104776)
			(xy 258.616022 -150.103591) (xy 258.630166 -150.099268) (xy 258.660421 -150.089534) (xy 258.723104 -150.079059)
			(xy 258.75488 -150.07844) (xy 258.782137 -150.078806) (xy 258.836097 -150.086561) (xy 258.888404 -150.101917)
			(xy 258.937993 -150.124562) (xy 258.983854 -150.154033) (xy 259.025055 -150.189731) (xy 259.060755 -150.23093)
			(xy 259.090229 -150.276789) (xy 259.112876 -150.326377) (xy 259.128235 -150.378683) (xy 259.135993 -150.432643)
			(xy 259.135993 -150.487157) (xy 259.128235 -150.541117) (xy 259.112876 -150.593423) (xy 259.105393 -150.609808)
			(xy 262.701532 -150.609808) (xy 262.702018 -150.582557) (xy 262.709774 -150.528609) (xy 262.725129 -150.476314)
			(xy 262.747771 -150.426737) (xy 262.777237 -150.380887) (xy 262.812928 -150.339696) (xy 262.854119 -150.304005)
			(xy 262.899969 -150.274539) (xy 262.949546 -150.251897) (xy 263.001841 -150.236542) (xy 263.055789 -150.228786)
			(xy 263.110291 -150.228786) (xy 263.164239 -150.236542) (xy 263.216534 -150.251897) (xy 263.266111 -150.274539)
			(xy 263.311961 -150.304005) (xy 263.353152 -150.339696) (xy 263.388843 -150.380887) (xy 263.418309 -150.426737)
			(xy 263.440951 -150.476314) (xy 263.456306 -150.528609) (xy 263.464062 -150.582557) (xy 263.464548 -150.609808)
			(xy 263.464054 -150.638138) (xy 263.455678 -150.694175) (xy 263.439113 -150.748359) (xy 263.414721 -150.7995)
			(xy 263.383038 -150.846474) (xy 263.344761 -150.888249) (xy 263.32307 -150.90648) (xy 263.312431 -150.915666)
			(xy 263.296202 -150.9386) (xy 263.286845 -150.965091) (xy 263.285068 -150.99313) (xy 263.291007 -151.02059)
			(xy 263.304212 -151.045389) (xy 263.32368 -151.065646) (xy 263.347935 -151.079824) (xy 263.361424 -151.083772)
			(xy 263.388348 -151.091262) (xy 263.439835 -151.112987) (xy 263.487602 -151.141992) (xy 263.530625 -151.177656)
			(xy 263.567984 -151.219216) (xy 263.598878 -151.265783) (xy 263.622648 -151.316359) (xy 263.638783 -151.369862)
			(xy 263.646939 -151.425146) (xy 263.647428 -151.453088) (xy 265.241022 -151.453088) (xy 265.245093 -151.397466)
			(xy 265.257219 -151.343029) (xy 265.277142 -151.290938) (xy 265.304438 -151.242303) (xy 265.338524 -151.19816)
			(xy 265.378673 -151.159451) (xy 265.424031 -151.127) (xy 265.473631 -151.101499) (xy 265.526415 -151.083492)
			(xy 265.581258 -151.073362) (xy 265.636992 -151.071325) (xy 265.692429 -151.077425) (xy 265.746386 -151.091531)
			(xy 265.797715 -151.113343) (xy 265.845321 -151.142397) (xy 265.888189 -151.178072) (xy 265.925406 -151.219609)
			(xy 265.956179 -151.266122) (xy 265.979851 -151.316619) (xy 265.995919 -151.370026) (xy 266.004039 -151.425202)
			(xy 266.004548 -151.453088) (xy 266.004039 -151.480974) (xy 265.995919 -151.53615) (xy 265.979851 -151.589557)
			(xy 265.956179 -151.640054) (xy 265.925406 -151.686567) (xy 265.888189 -151.728104) (xy 265.845321 -151.763779)
			(xy 265.797715 -151.792833) (xy 265.746386 -151.814645) (xy 265.692429 -151.828751) (xy 265.636992 -151.834851)
			(xy 265.581258 -151.832814) (xy 265.526415 -151.822684) (xy 265.473631 -151.804677) (xy 265.424031 -151.779176)
			(xy 265.378673 -151.746725) (xy 265.338524 -151.708016) (xy 265.304438 -151.663873) (xy 265.277142 -151.615238)
			(xy 265.257219 -151.563147) (xy 265.245093 -151.50871) (xy 265.241022 -151.453088) (xy 263.647428 -151.453088)
			(xy 263.646942 -151.480339) (xy 263.639186 -151.534287) (xy 263.623831 -151.586582) (xy 263.601189 -151.636159)
			(xy 263.571723 -151.682009) (xy 263.536032 -151.7232) (xy 263.494841 -151.758891) (xy 263.448991 -151.788357)
			(xy 263.399414 -151.810999) (xy 263.347119 -151.826354) (xy 263.293171 -151.83411) (xy 263.238669 -151.83411)
			(xy 263.184721 -151.826354) (xy 263.132426 -151.810999) (xy 263.082849 -151.788357) (xy 263.036999 -151.758891)
			(xy 262.995808 -151.7232) (xy 262.960117 -151.682009) (xy 262.930651 -151.636159) (xy 262.908009 -151.586582)
			(xy 262.892654 -151.534287) (xy 262.884898 -151.480339) (xy 262.884412 -151.453088) (xy 262.884881 -151.424757)
			(xy 262.893259 -151.368717) (xy 262.909828 -151.314532) (xy 262.934224 -151.263391) (xy 262.965913 -151.216418)
			(xy 263.004196 -151.174645) (xy 263.02589 -151.156416) (xy 263.036512 -151.147216) (xy 263.052728 -151.124283)
			(xy 263.062077 -151.097797) (xy 263.06385 -151.069766) (xy 263.057914 -151.042313) (xy 263.044718 -151.017519)
			(xy 263.025261 -150.997262) (xy 263.001019 -150.983078) (xy 262.987536 -150.979124) (xy 262.960622 -150.971598)
			(xy 262.909134 -150.949881) (xy 262.861366 -150.920882) (xy 262.818341 -150.885224) (xy 262.780981 -150.843668)
			(xy 262.750084 -150.797105) (xy 262.726313 -150.746532) (xy 262.710177 -150.693031) (xy 262.702022 -150.637749)
			(xy 262.701532 -150.609808) (xy 259.105393 -150.609808) (xy 259.090229 -150.643011) (xy 259.060755 -150.68887)
			(xy 259.025055 -150.730069) (xy 258.983854 -150.765767) (xy 258.937993 -150.795238) (xy 258.888404 -150.817883)
			(xy 258.836097 -150.833239) (xy 258.782137 -150.840994) (xy 258.75488 -150.841456) (xy 258.728301 -150.840989)
			(xy 258.675659 -150.833591) (xy 258.649978 -150.826724) (xy 258.636962 -150.823474) (xy 258.610146 -150.823142)
			(xy 258.584167 -150.829798) (xy 258.560815 -150.842984) (xy 258.541698 -150.861792) (xy 258.528133 -150.884927)
			(xy 258.521053 -150.910793) (xy 258.520948 -150.937611) (xy 258.523994 -150.950676) (xy 258.530051 -150.974862)
			(xy 258.536544 -151.024298) (xy 258.536948 -151.049228) (xy 258.536415 -151.076479) (xy 258.528654 -151.130426)
			(xy 258.513295 -151.182719) (xy 258.490651 -151.232294) (xy 258.461181 -151.278142) (xy 258.425486 -151.319329)
			(xy 258.384294 -151.355017) (xy 258.338441 -151.384479) (xy 258.288863 -151.407116) (xy 258.236567 -151.422467)
			(xy 258.182619 -151.430219) (xy 258.128117 -151.430214) (xy 258.07417 -151.422453) (xy 258.021877 -151.407094)
			(xy 257.972302 -151.384449) (xy 257.926455 -151.354979) (xy 257.885268 -151.319284) (xy 257.849581 -151.278091)
			(xy 257.820119 -151.232238) (xy 257.797482 -151.182659) (xy 257.782132 -151.130363) (xy 257.774381 -151.076415)
			(xy 257.774386 -151.021913) (xy 257.782147 -150.967966) (xy 257.797507 -150.915674) (xy 257.820153 -150.866099)
			(xy 257.849624 -150.820252) (xy 257.885319 -150.779065) (xy 257.926513 -150.743378) (xy 257.972366 -150.713917)
			(xy 258.021945 -150.691281) (xy 258.074241 -150.675931) (xy 258.128189 -150.66818) (xy 258.15544 -150.66772)
			(xy 258.182019 -150.6682) (xy 258.23466 -150.675589) (xy 258.260342 -150.682452) (xy 258.273347 -150.685753)
			(xy 258.30017 -150.686082) (xy 258.326155 -150.67942) (xy 258.349512 -150.666227) (xy 258.368632 -150.647411)
			(xy 258.382197 -150.624268) (xy 258.389274 -150.598393) (xy 258.389375 -150.571568) (xy 258.386326 -150.5585)
			(xy 258.383794 -150.548884) (xy 258.379599 -150.529443) (xy 258.377944 -150.519638) (xy 258.375074 -150.505123)
			(xy 258.362231 -150.478485) (xy 258.342297 -150.456641) (xy 258.316942 -150.441422) (xy 258.288289 -150.434104)
			(xy 258.258741 -150.435299) (xy 258.244594 -150.439628) (xy 258.214342 -150.449371) (xy 258.151657 -150.459841)
			(xy 258.11988 -150.460456) (xy 258.092633 -150.459872) (xy 258.038694 -150.452115) (xy 257.986409 -150.43676)
			(xy 257.93684 -150.41412) (xy 257.890998 -150.384657) (xy 257.849816 -150.34897) (xy 257.814131 -150.307786)
			(xy 257.78467 -150.261942) (xy 257.762033 -150.212373) (xy 257.746681 -150.160086) (xy 257.738926 -150.106147)
			(xy 256.370018 -150.106147) (xy 256.349399 -150.118634) (xy 256.301721 -150.139268) (xy 256.251685 -150.153241)
			(xy 256.200215 -150.160295) (xy 256.17424 -150.160736) (xy 256.146987 -150.160219) (xy 256.093036 -150.152468)
			(xy 256.040737 -150.137116) (xy 255.991156 -150.114478) (xy 255.945301 -150.085013) (xy 255.904106 -150.049322)
			(xy 255.868411 -150.008131) (xy 255.838942 -149.96228) (xy 255.816298 -149.9127) (xy 255.800941 -149.860403)
			(xy 255.793183 -149.806453) (xy 220.910034 -149.806453) (xy 219.637423 -151.079052) (xy 254.289546 -151.079052)
			(xy 254.289546 -151.024548) (xy 254.297302 -150.9706) (xy 254.312656 -150.918304) (xy 254.335296 -150.868725)
			(xy 254.364761 -150.822873) (xy 254.400452 -150.78168) (xy 254.441641 -150.745985) (xy 254.48749 -150.716516)
			(xy 254.537066 -150.69387) (xy 254.58936 -150.67851) (xy 254.643308 -150.670749) (xy 254.67056 -150.67026)
			(xy 254.699411 -150.670761) (xy 254.756456 -150.679433) (xy 254.811544 -150.6966) (xy 254.863418 -150.72187)
			(xy 254.910892 -150.754666) (xy 254.952884 -150.794239) (xy 254.988435 -150.839687) (xy 255.003046 -150.86457)
			(xy 255.010082 -150.8761) (xy 255.028993 -150.895366) (xy 255.0523 -150.908989) (xy 255.078367 -150.916011)
			(xy 255.105364 -150.91594) (xy 255.131393 -150.908781) (xy 255.154629 -150.895036) (xy 255.173438 -150.875671)
			(xy 255.180338 -150.864062) (xy 255.194909 -150.838974) (xy 255.230406 -150.793089) (xy 255.272445 -150.753111)
			(xy 255.320055 -150.719963) (xy 255.372137 -150.69441) (xy 255.427489 -150.677042) (xy 255.484833 -150.668259)
			(xy 255.51384 -150.66772) (xy 255.541091 -150.668153) (xy 255.595039 -150.675914) (xy 255.647333 -150.691274)
			(xy 255.696908 -150.713919) (xy 255.742757 -150.743389) (xy 255.783946 -150.779083) (xy 255.819635 -150.820275)
			(xy 255.8491 -150.866127) (xy 255.87174 -150.915705) (xy 255.887094 -150.968) (xy 255.89485 -151.021949)
			(xy 255.89485 -151.049228) (xy 256.452622 -151.049228) (xy 256.456693 -150.993606) (xy 256.468819 -150.939169)
			(xy 256.488742 -150.887078) (xy 256.516038 -150.838443) (xy 256.550124 -150.7943) (xy 256.590273 -150.755591)
			(xy 256.635631 -150.72314) (xy 256.685231 -150.697639) (xy 256.738015 -150.679632) (xy 256.792858 -150.669502)
			(xy 256.848592 -150.667465) (xy 256.904029 -150.673565) (xy 256.957986 -150.687671) (xy 257.009315 -150.709483)
			(xy 257.056921 -150.738537) (xy 257.099789 -150.774212) (xy 257.137006 -150.815749) (xy 257.167779 -150.862262)
			(xy 257.191451 -150.912759) (xy 257.207519 -150.966166) (xy 257.215639 -151.021342) (xy 257.216148 -151.049228)
			(xy 257.215639 -151.077114) (xy 257.207519 -151.13229) (xy 257.191451 -151.185697) (xy 257.167779 -151.236194)
			(xy 257.137006 -151.282707) (xy 257.099789 -151.324244) (xy 257.056921 -151.359919) (xy 257.009315 -151.388973)
			(xy 256.957986 -151.410785) (xy 256.904029 -151.424891) (xy 256.848592 -151.430991) (xy 256.792858 -151.428954)
			(xy 256.738015 -151.418824) (xy 256.685231 -151.400817) (xy 256.635631 -151.375316) (xy 256.590273 -151.342865)
			(xy 256.550124 -151.304156) (xy 256.516038 -151.260013) (xy 256.488742 -151.211378) (xy 256.468819 -151.159287)
			(xy 256.456693 -151.10485) (xy 256.452622 -151.049228) (xy 255.89485 -151.049228) (xy 255.89485 -151.076451)
			(xy 255.887094 -151.1304) (xy 255.87174 -151.182695) (xy 255.8491 -151.232273) (xy 255.819635 -151.278125)
			(xy 255.783946 -151.319317) (xy 255.742757 -151.355011) (xy 255.696908 -151.384481) (xy 255.647333 -151.407126)
			(xy 255.595039 -151.422486) (xy 255.541091 -151.430247) (xy 255.51384 -151.430736) (xy 255.484989 -151.430237)
			(xy 255.427943 -151.421565) (xy 255.372855 -151.404398) (xy 255.320982 -151.379128) (xy 255.273507 -151.346332)
			(xy 255.231516 -151.306757) (xy 255.195965 -151.261309) (xy 255.181354 -151.236426) (xy 255.174317 -151.224896)
			(xy 255.155406 -151.205631) (xy 255.132099 -151.192009) (xy 255.106032 -151.184987) (xy 255.079037 -151.185058)
			(xy 255.053007 -151.192217) (xy 255.029772 -151.205961) (xy 255.010962 -151.225326) (xy 255.004062 -151.236934)
			(xy 254.98949 -151.262021) (xy 254.953993 -151.307906) (xy 254.911954 -151.347884) (xy 254.864345 -151.381033)
			(xy 254.812263 -151.406586) (xy 254.756911 -151.423954) (xy 254.699566 -151.432737) (xy 254.67056 -151.433276)
			(xy 254.643308 -151.432851) (xy 254.58936 -151.42509) (xy 254.537066 -151.40973) (xy 254.48749 -151.387084)
			(xy 254.441641 -151.357615) (xy 254.400452 -151.32192) (xy 254.364761 -151.280727) (xy 254.335296 -151.234875)
			(xy 254.312656 -151.185296) (xy 254.297302 -151.133) (xy 254.289546 -151.079052) (xy 219.637423 -151.079052)
			(xy 219.266623 -151.449849) (xy 259.648986 -151.449849) (xy 259.648986 -151.395351) (xy 259.656741 -151.341408)
			(xy 259.672094 -151.289118) (xy 259.694731 -151.239544) (xy 259.724193 -151.193697) (xy 259.75988 -151.152508)
			(xy 259.801064 -151.116817) (xy 259.846909 -151.087351) (xy 259.89648 -151.064708) (xy 259.948769 -151.049349)
			(xy 260.002711 -151.041588) (xy 260.02996 -151.0411) (xy 260.057729 -151.041624) (xy 260.112681 -151.049671)
			(xy 260.165884 -151.065602) (xy 260.216216 -151.08908) (xy 260.262611 -151.119608) (xy 260.304088 -151.156541)
			(xy 260.322314 -151.177498) (xy 260.332222 -151.188474) (xy 260.35694 -151.204675) (xy 260.38526 -151.21313)
			(xy 260.414816 -151.21313) (xy 260.443136 -151.204675) (xy 260.467854 -151.188474) (xy 260.477762 -151.177498)
			(xy 260.495982 -151.156535) (xy 260.53746 -151.119598) (xy 260.583855 -151.089067) (xy 260.634187 -151.065585)
			(xy 260.687392 -151.049651) (xy 260.742346 -151.0416) (xy 260.770116 -151.0411) (xy 260.797367 -151.041571)
			(xy 260.851314 -151.049329) (xy 260.903608 -151.064686) (xy 260.953184 -151.087329) (xy 260.999034 -151.116796)
			(xy 261.040223 -151.152488) (xy 261.075913 -151.193679) (xy 261.105379 -151.23953) (xy 261.128019 -151.289107)
			(xy 261.143374 -151.341401) (xy 261.15113 -151.395349) (xy 261.15113 -151.449851) (xy 261.143374 -151.503799)
			(xy 261.128019 -151.556093) (xy 261.105379 -151.60567) (xy 261.075913 -151.651521) (xy 261.040223 -151.692712)
			(xy 260.999034 -151.728404) (xy 260.953184 -151.757871) (xy 260.903608 -151.780514) (xy 260.851314 -151.795871)
			(xy 260.797367 -151.803629) (xy 260.770116 -151.804116) (xy 260.742347 -151.803603) (xy 260.687395 -151.795553)
			(xy 260.634191 -151.779619) (xy 260.58386 -151.756139) (xy 260.537465 -151.72561) (xy 260.495988 -151.688675)
			(xy 260.477762 -151.667718) (xy 260.467854 -151.656742) (xy 260.443136 -151.640541) (xy 260.414816 -151.632086)
			(xy 260.38526 -151.632086) (xy 260.35694 -151.640541) (xy 260.332222 -151.656742) (xy 260.322314 -151.667718)
			(xy 260.304111 -151.688696) (xy 260.262629 -151.725631) (xy 260.21623 -151.75616) (xy 260.165895 -151.779639)
			(xy 260.112687 -151.79557) (xy 260.057731 -151.803618) (xy 260.02996 -151.804116) (xy 260.002711 -151.803612)
			(xy 259.948769 -151.795851) (xy 259.89648 -151.780492) (xy 259.846909 -151.757849) (xy 259.801064 -151.728383)
			(xy 259.75988 -151.692692) (xy 259.724193 -151.651503) (xy 259.694731 -151.605656) (xy 259.672094 -151.556082)
			(xy 259.656741 -151.503792) (xy 259.648986 -151.449849) (xy 219.266623 -151.449849) (xy 218.024506 -152.691954)
			(xy 258.444946 -152.691954) (xy 258.444946 -152.637446) (xy 258.452703 -152.583494) (xy 258.468059 -152.531195)
			(xy 258.490702 -152.481614) (xy 258.520171 -152.435759) (xy 258.555866 -152.394566) (xy 258.597059 -152.358871)
			(xy 258.642914 -152.329402) (xy 258.692495 -152.306759) (xy 258.744794 -152.291403) (xy 258.798746 -152.283646)
			(xy 258.826 -152.28316) (xy 258.853093 -152.283592) (xy 258.906732 -152.291272) (xy 258.958745 -152.306462)
			(xy 259.008087 -152.328857) (xy 259.053764 -152.358007) (xy 259.094858 -152.393325) (xy 259.130543 -152.434102)
			(xy 259.1601 -152.479516) (xy 259.171948 -152.503886) (xy 259.178344 -152.516699) (xy 259.197114 -152.538318)
			(xy 259.221146 -152.553878) (xy 259.248552 -152.562158) (xy 259.27718 -152.562508) (xy 259.30478 -152.554899)
			(xy 259.317236 -152.547828) (xy 259.339853 -152.534451) (xy 259.387986 -152.51337) (xy 259.438556 -152.499089)
			(xy 259.490606 -152.491879) (xy 259.51688 -152.49144) (xy 259.545257 -152.491953) (xy 259.601385 -152.500369)
			(xy 259.655647 -152.517004) (xy 259.681472 -152.528778) (xy 259.695109 -152.534618) (xy 259.724422 -152.539082)
			(xy 259.753782 -152.53495) (xy 259.780724 -152.522571) (xy 259.802984 -152.502984) (xy 259.811266 -152.490678)
			(xy 259.826305 -152.467496) (xy 259.862024 -152.425336) (xy 259.903447 -152.388765) (xy 259.94971 -152.358547)
			(xy 259.999846 -152.335314) (xy 260.052807 -152.319551) (xy 260.107487 -152.311588) (xy 260.135116 -152.3111)
			(xy 260.162367 -152.311571) (xy 260.216314 -152.319329) (xy 260.268608 -152.334686) (xy 260.318184 -152.357329)
			(xy 260.364034 -152.386796) (xy 260.405223 -152.422488) (xy 260.440913 -152.463679) (xy 260.470379 -152.50953)
			(xy 260.493019 -152.559107) (xy 260.508374 -152.611401) (xy 260.51613 -152.665349) (xy 260.51613 -152.718008)
			(xy 261.144512 -152.718008) (xy 261.145122 -152.689513) (xy 261.153606 -152.633157) (xy 261.170374 -152.578688)
			(xy 261.195051 -152.527317) (xy 261.22709 -152.480184) (xy 261.265779 -152.438337) (xy 261.310258 -152.402706)
			(xy 261.359539 -152.374083) (xy 261.412528 -152.353102) (xy 261.440168 -152.346152) (xy 261.454169 -152.342422)
			(xy 261.479418 -152.328229) (xy 261.499673 -152.307525) (xy 261.513309 -152.281972) (xy 261.519231 -152.25362)
			(xy 261.516966 -152.224745) (xy 261.512304 -152.211024) (xy 261.504413 -152.189292) (xy 261.493337 -152.144403)
			(xy 261.487752 -152.098506) (xy 261.487412 -152.075388) (xy 261.487898 -152.048137) (xy 261.495654 -151.994189)
			(xy 261.511009 -151.941894) (xy 261.533651 -151.892317) (xy 261.563117 -151.846467) (xy 261.598808 -151.805276)
			(xy 261.639999 -151.769585) (xy 261.685849 -151.740119) (xy 261.735426 -151.717477) (xy 261.787721 -151.702122)
			(xy 261.841669 -151.694366) (xy 261.896171 -151.694366) (xy 261.950119 -151.702122) (xy 262.002414 -151.717477)
			(xy 262.051991 -151.740119) (xy 262.097841 -151.769585) (xy 262.139032 -151.805276) (xy 262.174723 -151.846467)
			(xy 262.204189 -151.892317) (xy 262.211236 -151.907748) (xy 266.368782 -151.907748) (xy 266.372853 -151.852126)
			(xy 266.384979 -151.797689) (xy 266.404902 -151.745598) (xy 266.432198 -151.696963) (xy 266.466284 -151.65282)
			(xy 266.506433 -151.614111) (xy 266.551791 -151.58166) (xy 266.601391 -151.556159) (xy 266.654175 -151.538152)
			(xy 266.709018 -151.528022) (xy 266.764752 -151.525985) (xy 266.820189 -151.532085) (xy 266.874146 -151.546191)
			(xy 266.925475 -151.568003) (xy 266.973081 -151.597057) (xy 267.015949 -151.632732) (xy 267.053166 -151.674269)
			(xy 267.083939 -151.720782) (xy 267.107611 -151.771279) (xy 267.123679 -151.824686) (xy 267.131799 -151.879862)
			(xy 267.132308 -151.907748) (xy 267.131799 -151.935634) (xy 267.123679 -151.99081) (xy 267.107611 -152.044217)
			(xy 267.083939 -152.094714) (xy 267.053166 -152.141227) (xy 267.015949 -152.182764) (xy 266.973081 -152.218439)
			(xy 266.925475 -152.247493) (xy 266.874146 -152.269305) (xy 266.820189 -152.283411) (xy 266.764752 -152.289511)
			(xy 266.709018 -152.287474) (xy 266.654175 -152.277344) (xy 266.601391 -152.259337) (xy 266.551791 -152.233836)
			(xy 266.506433 -152.201385) (xy 266.466284 -152.162676) (xy 266.432198 -152.118533) (xy 266.404902 -152.069898)
			(xy 266.384979 -152.017807) (xy 266.372853 -151.96337) (xy 266.368782 -151.907748) (xy 262.211236 -151.907748)
			(xy 262.226831 -151.941894) (xy 262.242186 -151.994189) (xy 262.249942 -152.048137) (xy 262.250428 -152.075388)
			(xy 262.249951 -152.103888) (xy 262.241451 -152.160252) (xy 262.224667 -152.214727) (xy 262.199974 -152.266101)
			(xy 262.167918 -152.313235) (xy 262.129212 -152.35508) (xy 262.084717 -152.390707) (xy 262.035421 -152.419326)
			(xy 261.982418 -152.440299) (xy 261.954772 -152.447244) (xy 261.940778 -152.451002) (xy 261.915528 -152.465185)
			(xy 261.89527 -152.485883) (xy 261.881631 -152.511431) (xy 261.875707 -152.53978) (xy 261.877974 -152.568653)
			(xy 261.882636 -152.582372) (xy 261.890524 -152.604105) (xy 261.901602 -152.648994) (xy 261.907187 -152.69489)
			(xy 261.907528 -152.718008) (xy 261.907437 -152.723088) (xy 262.066022 -152.723088) (xy 262.070093 -152.667466)
			(xy 262.082219 -152.613029) (xy 262.102142 -152.560938) (xy 262.129438 -152.512303) (xy 262.163524 -152.46816)
			(xy 262.203673 -152.429451) (xy 262.249031 -152.397) (xy 262.298631 -152.371499) (xy 262.351415 -152.353492)
			(xy 262.406258 -152.343362) (xy 262.461992 -152.341325) (xy 262.517429 -152.347425) (xy 262.571386 -152.361531)
			(xy 262.622715 -152.383343) (xy 262.670321 -152.412397) (xy 262.713189 -152.448072) (xy 262.750406 -152.489609)
			(xy 262.781179 -152.536122) (xy 262.804851 -152.586619) (xy 262.820919 -152.640026) (xy 262.829039 -152.695202)
			(xy 262.829548 -152.723088) (xy 263.336022 -152.723088) (xy 263.340093 -152.667466) (xy 263.352219 -152.613029)
			(xy 263.372142 -152.560938) (xy 263.399438 -152.512303) (xy 263.433524 -152.46816) (xy 263.473673 -152.429451)
			(xy 263.519031 -152.397) (xy 263.568631 -152.371499) (xy 263.621415 -152.353492) (xy 263.676258 -152.343362)
			(xy 263.731992 -152.341325) (xy 263.787429 -152.347425) (xy 263.841386 -152.361531) (xy 263.892715 -152.383343)
			(xy 263.940321 -152.412397) (xy 263.983189 -152.448072) (xy 264.020406 -152.489609) (xy 264.051179 -152.536122)
			(xy 264.074851 -152.586619) (xy 264.090919 -152.640026) (xy 264.099039 -152.695202) (xy 264.099548 -152.723088)
			(xy 264.606022 -152.723088) (xy 264.610093 -152.667466) (xy 264.622219 -152.613029) (xy 264.642142 -152.560938)
			(xy 264.669438 -152.512303) (xy 264.703524 -152.46816) (xy 264.743673 -152.429451) (xy 264.789031 -152.397)
			(xy 264.838631 -152.371499) (xy 264.891415 -152.353492) (xy 264.946258 -152.343362) (xy 265.001992 -152.341325)
			(xy 265.057429 -152.347425) (xy 265.111386 -152.361531) (xy 265.162715 -152.383343) (xy 265.210321 -152.412397)
			(xy 265.253189 -152.448072) (xy 265.290406 -152.489609) (xy 265.321179 -152.536122) (xy 265.344851 -152.586619)
			(xy 265.360919 -152.640026) (xy 265.369039 -152.695202) (xy 265.369548 -152.723088) (xy 265.876022 -152.723088)
			(xy 265.880093 -152.667466) (xy 265.892219 -152.613029) (xy 265.912142 -152.560938) (xy 265.939438 -152.512303)
			(xy 265.973524 -152.46816) (xy 266.013673 -152.429451) (xy 266.059031 -152.397) (xy 266.108631 -152.371499)
			(xy 266.161415 -152.353492) (xy 266.216258 -152.343362) (xy 266.271992 -152.341325) (xy 266.327429 -152.347425)
			(xy 266.381386 -152.361531) (xy 266.432715 -152.383343) (xy 266.480321 -152.412397) (xy 266.523189 -152.448072)
			(xy 266.560406 -152.489609) (xy 266.591179 -152.536122) (xy 266.614851 -152.586619) (xy 266.630919 -152.640026)
			(xy 266.639039 -152.695202) (xy 266.639363 -152.712928) (xy 267.913102 -152.712928) (xy 267.917173 -152.657306)
			(xy 267.929299 -152.602869) (xy 267.949222 -152.550778) (xy 267.976518 -152.502143) (xy 268.010604 -152.458)
			(xy 268.050753 -152.419291) (xy 268.096111 -152.38684) (xy 268.145711 -152.361339) (xy 268.198495 -152.343332)
			(xy 268.253338 -152.333202) (xy 268.309072 -152.331165) (xy 268.364509 -152.337265) (xy 268.418466 -152.351371)
			(xy 268.469795 -152.373183) (xy 268.517401 -152.402237) (xy 268.560269 -152.437912) (xy 268.597486 -152.479449)
			(xy 268.628259 -152.525962) (xy 268.651931 -152.576459) (xy 268.667999 -152.629866) (xy 268.676119 -152.685042)
			(xy 268.676628 -152.712928) (xy 268.676119 -152.740814) (xy 268.667999 -152.79599) (xy 268.651931 -152.849397)
			(xy 268.628259 -152.899894) (xy 268.597486 -152.946407) (xy 268.560269 -152.987944) (xy 268.517401 -153.023619)
			(xy 268.469795 -153.052673) (xy 268.418466 -153.074485) (xy 268.364509 -153.088591) (xy 268.309072 -153.094691)
			(xy 268.253338 -153.092654) (xy 268.198495 -153.082524) (xy 268.145711 -153.064517) (xy 268.096111 -153.039016)
			(xy 268.050753 -153.006565) (xy 268.010604 -152.967856) (xy 267.976518 -152.923713) (xy 267.949222 -152.875078)
			(xy 267.929299 -152.822987) (xy 267.917173 -152.76855) (xy 267.913102 -152.712928) (xy 266.639363 -152.712928)
			(xy 266.639548 -152.723088) (xy 266.639039 -152.750974) (xy 266.630919 -152.80615) (xy 266.614851 -152.859557)
			(xy 266.591179 -152.910054) (xy 266.560406 -152.956567) (xy 266.523189 -152.998104) (xy 266.480321 -153.033779)
			(xy 266.432715 -153.062833) (xy 266.381386 -153.084645) (xy 266.327429 -153.098751) (xy 266.271992 -153.104851)
			(xy 266.216258 -153.102814) (xy 266.161415 -153.092684) (xy 266.108631 -153.074677) (xy 266.059031 -153.049176)
			(xy 266.013673 -153.016725) (xy 265.973524 -152.978016) (xy 265.939438 -152.933873) (xy 265.912142 -152.885238)
			(xy 265.892219 -152.833147) (xy 265.880093 -152.77871) (xy 265.876022 -152.723088) (xy 265.369548 -152.723088)
			(xy 265.369039 -152.750974) (xy 265.360919 -152.80615) (xy 265.344851 -152.859557) (xy 265.321179 -152.910054)
			(xy 265.290406 -152.956567) (xy 265.253189 -152.998104) (xy 265.210321 -153.033779) (xy 265.162715 -153.062833)
			(xy 265.111386 -153.084645) (xy 265.057429 -153.098751) (xy 265.001992 -153.104851) (xy 264.946258 -153.102814)
			(xy 264.891415 -153.092684) (xy 264.838631 -153.074677) (xy 264.789031 -153.049176) (xy 264.743673 -153.016725)
			(xy 264.703524 -152.978016) (xy 264.669438 -152.933873) (xy 264.642142 -152.885238) (xy 264.622219 -152.833147)
			(xy 264.610093 -152.77871) (xy 264.606022 -152.723088) (xy 264.099548 -152.723088) (xy 264.099039 -152.750974)
			(xy 264.090919 -152.80615) (xy 264.074851 -152.859557) (xy 264.051179 -152.910054) (xy 264.020406 -152.956567)
			(xy 263.983189 -152.998104) (xy 263.940321 -153.033779) (xy 263.892715 -153.062833) (xy 263.841386 -153.084645)
			(xy 263.787429 -153.098751) (xy 263.731992 -153.104851) (xy 263.676258 -153.102814) (xy 263.621415 -153.092684)
			(xy 263.568631 -153.074677) (xy 263.519031 -153.049176) (xy 263.473673 -153.016725) (xy 263.433524 -152.978016)
			(xy 263.399438 -152.933873) (xy 263.372142 -152.885238) (xy 263.352219 -152.833147) (xy 263.340093 -152.77871)
			(xy 263.336022 -152.723088) (xy 262.829548 -152.723088) (xy 262.829039 -152.750974) (xy 262.820919 -152.80615)
			(xy 262.804851 -152.859557) (xy 262.781179 -152.910054) (xy 262.750406 -152.956567) (xy 262.713189 -152.998104)
			(xy 262.670321 -153.033779) (xy 262.622715 -153.062833) (xy 262.571386 -153.084645) (xy 262.517429 -153.098751)
			(xy 262.461992 -153.104851) (xy 262.406258 -153.102814) (xy 262.351415 -153.092684) (xy 262.298631 -153.074677)
			(xy 262.249031 -153.049176) (xy 262.203673 -153.016725) (xy 262.163524 -152.978016) (xy 262.129438 -152.933873)
			(xy 262.102142 -152.885238) (xy 262.082219 -152.833147) (xy 262.070093 -152.77871) (xy 262.066022 -152.723088)
			(xy 261.907437 -152.723088) (xy 261.907042 -152.745259) (xy 261.899286 -152.799207) (xy 261.883931 -152.851502)
			(xy 261.861289 -152.901079) (xy 261.831823 -152.946929) (xy 261.796132 -152.98812) (xy 261.754941 -153.023811)
			(xy 261.709091 -153.053277) (xy 261.659514 -153.075919) (xy 261.607219 -153.091274) (xy 261.553271 -153.09903)
			(xy 261.498769 -153.09903) (xy 261.444821 -153.091274) (xy 261.392526 -153.075919) (xy 261.342949 -153.053277)
			(xy 261.297099 -153.023811) (xy 261.255908 -152.98812) (xy 261.220217 -152.946929) (xy 261.190751 -152.901079)
			(xy 261.168109 -152.851502) (xy 261.152754 -152.799207) (xy 261.144998 -152.745259) (xy 261.144512 -152.718008)
			(xy 260.51613 -152.718008) (xy 260.51613 -152.719851) (xy 260.508374 -152.773799) (xy 260.493019 -152.826093)
			(xy 260.470379 -152.87567) (xy 260.440913 -152.921521) (xy 260.405223 -152.962712) (xy 260.364034 -152.998404)
			(xy 260.318184 -153.027871) (xy 260.268608 -153.050514) (xy 260.216314 -153.065871) (xy 260.162367 -153.073629)
			(xy 260.135116 -153.074116) (xy 260.106738 -153.073609) (xy 260.050611 -153.065191) (xy 259.996348 -153.048554)
			(xy 259.970524 -153.036778) (xy 259.956896 -153.030911) (xy 259.927578 -153.026445) (xy 259.898211 -153.030579)
			(xy 259.871266 -153.042967) (xy 259.849008 -153.062565) (xy 259.84073 -153.074878) (xy 259.825713 -153.098074)
			(xy 259.789988 -153.140232) (xy 259.74856 -153.1768) (xy 259.702293 -153.207015) (xy 259.652155 -153.230245)
			(xy 259.599191 -153.246006) (xy 259.544509 -153.253968) (xy 259.51688 -153.254456) (xy 259.48979 -153.253948)
			(xy 259.436154 -153.24628) (xy 259.384143 -153.231101) (xy 259.334803 -153.208717) (xy 259.289125 -153.179577)
			(xy 259.24803 -153.144269) (xy 259.212343 -153.103502) (xy 259.182782 -153.058096) (xy 259.170932 -153.03373)
			(xy 259.164436 -153.020972) (xy 259.145688 -152.999358) (xy 259.121679 -152.983795) (xy 259.094294 -152.975505)
			(xy 259.065684 -152.975141) (xy 259.038097 -152.982729) (xy 259.025644 -152.989788) (xy 259.003027 -153.003165)
			(xy 258.954894 -153.024248) (xy 258.904324 -153.038529) (xy 258.852274 -153.045738) (xy 258.826 -153.046176)
			(xy 258.798746 -153.045754) (xy 258.744794 -153.037997) (xy 258.692495 -153.022641) (xy 258.642914 -152.999998)
			(xy 258.597059 -152.970529) (xy 258.555866 -152.934834) (xy 258.520171 -152.893641) (xy 258.490702 -152.847786)
			(xy 258.468059 -152.798205) (xy 258.452703 -152.745906) (xy 258.444946 -152.691954) (xy 218.024506 -152.691954)
			(xy 217.256765 -153.459688) (xy 266.417042 -153.459688) (xy 266.421113 -153.404066) (xy 266.433239 -153.349629)
			(xy 266.453162 -153.297538) (xy 266.480458 -153.248903) (xy 266.514544 -153.20476) (xy 266.554693 -153.166051)
			(xy 266.600051 -153.1336) (xy 266.649651 -153.108099) (xy 266.702435 -153.090092) (xy 266.757278 -153.079962)
			(xy 266.813012 -153.077925) (xy 266.868449 -153.084025) (xy 266.922406 -153.098131) (xy 266.973735 -153.119943)
			(xy 267.021341 -153.148997) (xy 267.064209 -153.184672) (xy 267.101426 -153.226209) (xy 267.132199 -153.272722)
			(xy 267.155871 -153.323219) (xy 267.171939 -153.376626) (xy 267.180059 -153.431802) (xy 267.180568 -153.459688)
			(xy 267.180059 -153.487574) (xy 267.171939 -153.54275) (xy 267.155871 -153.596157) (xy 267.132199 -153.646654)
			(xy 267.108015 -153.683208) (xy 267.897862 -153.683208) (xy 267.901933 -153.627586) (xy 267.914059 -153.573149)
			(xy 267.933982 -153.521058) (xy 267.961278 -153.472423) (xy 267.995364 -153.42828) (xy 268.035513 -153.389571)
			(xy 268.080871 -153.35712) (xy 268.130471 -153.331619) (xy 268.183255 -153.313612) (xy 268.238098 -153.303482)
			(xy 268.293832 -153.301445) (xy 268.349269 -153.307545) (xy 268.403226 -153.321651) (xy 268.454555 -153.343463)
			(xy 268.502161 -153.372517) (xy 268.545029 -153.408192) (xy 268.582246 -153.449729) (xy 268.613019 -153.496242)
			(xy 268.636691 -153.546739) (xy 268.652759 -153.600146) (xy 268.660879 -153.655322) (xy 268.661388 -153.683208)
			(xy 268.660879 -153.711094) (xy 268.652797 -153.766012) (xy 272.385799 -153.766012) (xy 272.389792 -153.556271)
			(xy 272.401768 -153.346834) (xy 272.421709 -153.138005) (xy 272.449586 -152.930086) (xy 272.485358 -152.723379)
			(xy 272.528973 -152.518184) (xy 272.580369 -152.314799) (xy 272.639471 -152.113517) (xy 272.706193 -151.914631)
			(xy 272.780438 -151.71843) (xy 272.862098 -151.525198) (xy 272.951056 -151.335214) (xy 273.047183 -151.148755)
			(xy 273.150338 -150.966091) (xy 273.260373 -150.787486) (xy 273.377127 -150.6132) (xy 273.500432 -150.443485)
			(xy 273.630109 -150.278587) (xy 273.76597 -150.118746) (xy 273.907817 -149.964193) (xy 274.055446 -149.815153)
			(xy 274.208641 -149.67184) (xy 274.367182 -149.534464) (xy 274.530837 -149.403223) (xy 274.699371 -149.278308)
			(xy 274.872537 -149.1599) (xy 275.050087 -149.04817) (xy 275.231761 -148.94328) (xy 275.417296 -148.845383)
			(xy 275.606424 -148.754621) (xy 275.798871 -148.671124) (xy 275.994356 -148.595014) (xy 276.192598 -148.526402)
			(xy 276.393308 -148.465387) (xy 276.596195 -148.412058) (xy 276.800965 -148.366491) (xy 277.007322 -148.328752)
			(xy 277.214966 -148.298898) (xy 277.423596 -148.27697) (xy 277.632909 -148.263001) (xy 277.842603 -148.25701)
			(xy 278.052372 -148.259007) (xy 278.261914 -148.268989) (xy 278.470924 -148.286941) (xy 278.679098 -148.312837)
			(xy 278.886136 -148.346639) (xy 279.091737 -148.388299) (xy 279.295603 -148.437757) (xy 279.497438 -148.49494)
			(xy 279.69695 -148.559765) (xy 279.893849 -148.632139) (xy 280.08785 -148.711956) (xy 280.278672 -148.799102)
			(xy 280.466038 -148.893449) (xy 280.542996 -148.935948) (xy 288.796982 -148.935948) (xy 288.801053 -148.880326)
			(xy 288.813179 -148.825889) (xy 288.833102 -148.773798) (xy 288.860398 -148.725163) (xy 288.894484 -148.68102)
			(xy 288.934633 -148.642311) (xy 288.979991 -148.60986) (xy 289.029591 -148.584359) (xy 289.082375 -148.566352)
			(xy 289.137218 -148.556222) (xy 289.192952 -148.554185) (xy 289.248389 -148.560285) (xy 289.302346 -148.574391)
			(xy 289.353675 -148.596203) (xy 289.401281 -148.625257) (xy 289.444149 -148.660932) (xy 289.481366 -148.702469)
			(xy 289.512139 -148.748982) (xy 289.535811 -148.799479) (xy 289.551879 -148.852886) (xy 289.559999 -148.908062)
			(xy 289.560508 -148.935948) (xy 289.560044 -148.961348) (xy 292.5986 -148.961348) (xy 292.602671 -148.905726)
			(xy 292.614797 -148.851289) (xy 292.63472 -148.799198) (xy 292.662016 -148.750563) (xy 292.696102 -148.70642)
			(xy 292.736251 -148.667711) (xy 292.781609 -148.63526) (xy 292.831209 -148.609759) (xy 292.883993 -148.591752)
			(xy 292.938836 -148.581622) (xy 292.99457 -148.579585) (xy 293.050007 -148.585685) (xy 293.103964 -148.599791)
			(xy 293.155293 -148.621603) (xy 293.202899 -148.650657) (xy 293.245767 -148.686332) (xy 293.282984 -148.727869)
			(xy 293.313757 -148.774382) (xy 293.329961 -148.808948) (xy 293.826182 -148.808948) (xy 293.830253 -148.753326)
			(xy 293.842379 -148.698889) (xy 293.862302 -148.646798) (xy 293.889598 -148.598163) (xy 293.923684 -148.55402)
			(xy 293.963833 -148.515311) (xy 294.009191 -148.48286) (xy 294.058791 -148.457359) (xy 294.111575 -148.439352)
			(xy 294.166418 -148.429222) (xy 294.222152 -148.427185) (xy 294.277589 -148.433285) (xy 294.331546 -148.447391)
			(xy 294.382875 -148.469203) (xy 294.430481 -148.498257) (xy 294.439726 -148.505951) (xy 297.385703 -148.505951)
			(xy 297.385703 -148.451449) (xy 297.39346 -148.397501) (xy 297.408816 -148.345207) (xy 297.431459 -148.29563)
			(xy 297.460927 -148.249781) (xy 297.496621 -148.208592) (xy 297.537813 -148.172903) (xy 297.583665 -148.14344)
			(xy 297.633244 -148.120802) (xy 297.68554 -148.105452) (xy 297.739489 -148.0977) (xy 297.76674 -148.09724)
			(xy 297.793004 -148.097656) (xy 297.845037 -148.104855) (xy 297.89559 -148.119125) (xy 297.943708 -148.140197)
			(xy 297.988479 -148.16767) (xy 298.029057 -148.201027) (xy 298.064674 -148.239636) (xy 298.094658 -148.282766)
			(xy 298.11844 -148.329603) (xy 298.12742 -148.354288) (xy 298.132607 -148.367872) (xy 298.149459 -148.391554)
			(xy 298.1723 -148.409529) (xy 298.19928 -148.420343) (xy 298.228213 -148.423119) (xy 298.256757 -148.417631)
			(xy 298.269914 -148.411438) (xy 298.297124 -148.398058) (xy 298.354729 -148.379137) (xy 298.414603 -148.369581)
			(xy 298.44492 -148.36902) (xy 298.472172 -148.369451) (xy 298.526122 -148.377211) (xy 298.578418 -148.392569)
			(xy 298.627996 -148.415213) (xy 298.673848 -148.444682) (xy 298.715038 -148.480376) (xy 298.75073 -148.521568)
			(xy 298.755858 -148.529548) (xy 299.668182 -148.529548) (xy 299.672253 -148.473926) (xy 299.684379 -148.419489)
			(xy 299.704302 -148.367398) (xy 299.731598 -148.318763) (xy 299.765684 -148.27462) (xy 299.805833 -148.235911)
			(xy 299.851191 -148.20346) (xy 299.900791 -148.177959) (xy 299.953575 -148.159952) (xy 300.008418 -148.149822)
			(xy 300.064152 -148.147785) (xy 300.119589 -148.153885) (xy 300.173546 -148.167991) (xy 300.224875 -148.189803)
			(xy 300.272481 -148.218857) (xy 300.315349 -148.254532) (xy 300.352566 -148.296069) (xy 300.383339 -148.342582)
			(xy 300.407011 -148.393079) (xy 300.412152 -148.410168) (xy 396.237458 -148.410168) (xy 396.241529 -148.354546)
			(xy 396.253655 -148.300109) (xy 396.273578 -148.248018) (xy 396.300874 -148.199383) (xy 396.33496 -148.15524)
			(xy 396.375109 -148.116531) (xy 396.420467 -148.08408) (xy 396.470067 -148.058579) (xy 396.522851 -148.040572)
			(xy 396.577694 -148.030442) (xy 396.633428 -148.028405) (xy 396.688865 -148.034505) (xy 396.742822 -148.048611)
			(xy 396.794151 -148.070423) (xy 396.841757 -148.099477) (xy 396.884625 -148.135152) (xy 396.921842 -148.176689)
			(xy 396.952615 -148.223202) (xy 396.976287 -148.273699) (xy 396.992355 -148.327106) (xy 397.000475 -148.382282)
			(xy 397.000984 -148.410168) (xy 397.000475 -148.438054) (xy 396.992355 -148.49323) (xy 396.976287 -148.546637)
			(xy 396.952615 -148.597134) (xy 396.921842 -148.643647) (xy 396.884625 -148.685184) (xy 396.841757 -148.720859)
			(xy 396.794151 -148.749913) (xy 396.742822 -148.771725) (xy 396.688865 -148.785831) (xy 396.633428 -148.791931)
			(xy 396.577694 -148.789894) (xy 396.522851 -148.779764) (xy 396.470067 -148.761757) (xy 396.420467 -148.736256)
			(xy 396.375109 -148.703805) (xy 396.33496 -148.665096) (xy 396.300874 -148.620953) (xy 396.273578 -148.572318)
			(xy 396.253655 -148.520227) (xy 396.241529 -148.46579) (xy 396.237458 -148.410168) (xy 300.412152 -148.410168)
			(xy 300.423079 -148.446486) (xy 300.431199 -148.501662) (xy 300.431708 -148.529548) (xy 300.431199 -148.557434)
			(xy 300.423079 -148.61261) (xy 300.407011 -148.666017) (xy 300.383339 -148.716514) (xy 300.352566 -148.763027)
			(xy 300.315349 -148.804564) (xy 300.272481 -148.840239) (xy 300.224875 -148.869293) (xy 300.173546 -148.891105)
			(xy 300.119589 -148.905211) (xy 300.064152 -148.911311) (xy 300.008418 -148.909274) (xy 299.953575 -148.899144)
			(xy 299.900791 -148.881137) (xy 299.851191 -148.855636) (xy 299.805833 -148.823185) (xy 299.765684 -148.784476)
			(xy 299.731598 -148.740333) (xy 299.704302 -148.691698) (xy 299.684379 -148.639607) (xy 299.672253 -148.58517)
			(xy 299.668182 -148.529548) (xy 298.755858 -148.529548) (xy 298.780197 -148.567421) (xy 298.802838 -148.617001)
			(xy 298.818194 -148.669298) (xy 298.82595 -148.723248) (xy 298.82595 -148.777752) (xy 298.818194 -148.831702)
			(xy 298.802838 -148.883999) (xy 298.780197 -148.933579) (xy 298.75073 -148.979432) (xy 298.715038 -149.020624)
			(xy 298.673848 -149.056318) (xy 298.627996 -149.085787) (xy 298.578418 -149.108431) (xy 298.526122 -149.123789)
			(xy 298.472172 -149.131549) (xy 298.44492 -149.132036) (xy 298.418657 -149.131583) (xy 298.366625 -149.124391)
			(xy 298.316072 -149.110128) (xy 298.267954 -149.089062) (xy 298.223182 -149.061593) (xy 298.182604 -149.02824)
			(xy 298.146985 -148.989635) (xy 298.117002 -148.946507) (xy 298.09322 -148.899672) (xy 298.08424 -148.874988)
			(xy 298.078993 -148.861425) (xy 298.06216 -148.83773) (xy 298.039331 -148.819739) (xy 298.012357 -148.808911)
			(xy 297.983426 -148.806124) (xy 297.954881 -148.811602) (xy 297.941746 -148.817838) (xy 297.914542 -148.83123)
			(xy 297.856934 -148.850147) (xy 297.797057 -148.859698) (xy 297.76674 -148.860256) (xy 297.739489 -148.8597)
			(xy 297.68554 -148.851948) (xy 297.633244 -148.836598) (xy 297.583665 -148.81396) (xy 297.537813 -148.784497)
			(xy 297.496621 -148.748808) (xy 297.460927 -148.707619) (xy 297.431459 -148.66177) (xy 297.408816 -148.612193)
			(xy 297.39346 -148.559899) (xy 297.385703 -148.505951) (xy 294.439726 -148.505951) (xy 294.473349 -148.533932)
			(xy 294.510566 -148.575469) (xy 294.541339 -148.621982) (xy 294.565011 -148.672479) (xy 294.581079 -148.725886)
			(xy 294.589199 -148.781062) (xy 294.589708 -148.808948) (xy 294.589199 -148.836834) (xy 294.581079 -148.89201)
			(xy 294.565011 -148.945417) (xy 294.541339 -148.995914) (xy 294.510566 -149.042427) (xy 294.473349 -149.083964)
			(xy 294.430481 -149.119639) (xy 294.382875 -149.148693) (xy 294.331546 -149.170505) (xy 294.277589 -149.184611)
			(xy 294.222152 -149.190711) (xy 294.166418 -149.188674) (xy 294.111575 -149.178544) (xy 294.058791 -149.160537)
			(xy 294.009191 -149.135036) (xy 293.963833 -149.102585) (xy 293.923684 -149.063876) (xy 293.889598 -149.019733)
			(xy 293.862302 -148.971098) (xy 293.842379 -148.919007) (xy 293.830253 -148.86457) (xy 293.826182 -148.808948)
			(xy 293.329961 -148.808948) (xy 293.337429 -148.824879) (xy 293.353497 -148.878286) (xy 293.361617 -148.933462)
			(xy 293.362126 -148.961348) (xy 293.361617 -148.989234) (xy 293.353497 -149.04441) (xy 293.337429 -149.097817)
			(xy 293.313757 -149.148314) (xy 293.282984 -149.194827) (xy 293.245767 -149.236364) (xy 293.202899 -149.272039)
			(xy 293.155293 -149.301093) (xy 293.103964 -149.322905) (xy 293.050007 -149.337011) (xy 292.99457 -149.343111)
			(xy 292.938836 -149.341074) (xy 292.883993 -149.330944) (xy 292.831209 -149.312937) (xy 292.781609 -149.287436)
			(xy 292.736251 -149.254985) (xy 292.696102 -149.216276) (xy 292.662016 -149.172133) (xy 292.63472 -149.123498)
			(xy 292.614797 -149.071407) (xy 292.602671 -149.01697) (xy 292.5986 -148.961348) (xy 289.560044 -148.961348)
			(xy 289.559999 -148.963834) (xy 289.551879 -149.01901) (xy 289.535811 -149.072417) (xy 289.512139 -149.122914)
			(xy 289.481366 -149.169427) (xy 289.444149 -149.210964) (xy 289.401281 -149.246639) (xy 289.353675 -149.275693)
			(xy 289.302346 -149.297505) (xy 289.248389 -149.311611) (xy 289.192952 -149.317711) (xy 289.137218 -149.315674)
			(xy 289.082375 -149.305544) (xy 289.029591 -149.287537) (xy 288.979991 -149.262036) (xy 288.934633 -149.229585)
			(xy 288.894484 -149.190876) (xy 288.860398 -149.146733) (xy 288.833102 -149.098098) (xy 288.813179 -149.046007)
			(xy 288.801053 -148.99157) (xy 288.796982 -148.935948) (xy 280.542996 -148.935948) (xy 280.649676 -148.99486)
			(xy 280.82932 -149.10319) (xy 281.00471 -149.21828) (xy 281.175591 -149.339964) (xy 281.341715 -149.468065)
			(xy 281.420029 -149.533356) (xy 304.17084 -149.533356) (xy 304.174911 -149.477734) (xy 304.187037 -149.423297)
			(xy 304.20696 -149.371206) (xy 304.234256 -149.322571) (xy 304.268342 -149.278428) (xy 304.308491 -149.239719)
			(xy 304.353849 -149.207268) (xy 304.403449 -149.181767) (xy 304.456233 -149.16376) (xy 304.511076 -149.15363)
			(xy 304.56681 -149.151593) (xy 304.622247 -149.157693) (xy 304.676204 -149.171799) (xy 304.727533 -149.193611)
			(xy 304.775139 -149.222665) (xy 304.818007 -149.25834) (xy 304.855224 -149.299877) (xy 304.885997 -149.34639)
			(xy 304.909669 -149.396887) (xy 304.925737 -149.450294) (xy 304.933857 -149.50547) (xy 304.934366 -149.533356)
			(xy 304.933857 -149.561242) (xy 304.925737 -149.616418) (xy 304.909669 -149.669825) (xy 304.885997 -149.720322)
			(xy 304.855224 -149.766835) (xy 304.818007 -149.808372) (xy 304.775139 -149.844047) (xy 304.727533 -149.873101)
			(xy 304.676204 -149.894913) (xy 304.622247 -149.909019) (xy 304.56681 -149.915119) (xy 304.511076 -149.913082)
			(xy 304.456233 -149.902952) (xy 304.403449 -149.884945) (xy 304.353849 -149.859444) (xy 304.308491 -149.826993)
			(xy 304.268342 -149.788284) (xy 304.234256 -149.744141) (xy 304.20696 -149.695506) (xy 304.187037 -149.643415)
			(xy 304.174911 -149.588978) (xy 304.17084 -149.533356) (xy 281.420029 -149.533356) (xy 281.502842 -149.602398)
			(xy 281.658739 -149.742767) (xy 281.809178 -149.88897) (xy 281.953942 -150.040794) (xy 282.092821 -150.19802)
			(xy 282.225614 -150.360419) (xy 282.249973 -150.392638) (xy 289.9316 -150.392638) (xy 289.935671 -150.337016)
			(xy 289.947797 -150.282579) (xy 289.96772 -150.230488) (xy 289.995016 -150.181853) (xy 290.029102 -150.13771)
			(xy 290.069251 -150.099001) (xy 290.114609 -150.06655) (xy 290.164209 -150.041049) (xy 290.216993 -150.023042)
			(xy 290.271836 -150.012912) (xy 290.32757 -150.010875) (xy 290.383007 -150.016975) (xy 290.436964 -150.031081)
			(xy 290.488293 -150.052893) (xy 290.535899 -150.081947) (xy 290.578767 -150.117622) (xy 290.615984 -150.159159)
			(xy 290.646757 -150.205672) (xy 290.670429 -150.256169) (xy 290.686497 -150.309576) (xy 290.694617 -150.364752)
			(xy 290.695126 -150.392638) (xy 290.694617 -150.420524) (xy 290.686497 -150.4757) (xy 290.670429 -150.529107)
			(xy 290.668319 -150.533608) (xy 298.038012 -150.533608) (xy 298.038498 -150.506357) (xy 298.046254 -150.452409)
			(xy 298.061609 -150.400114) (xy 298.084251 -150.350537) (xy 298.113717 -150.304687) (xy 298.149408 -150.263496)
			(xy 298.190599 -150.227805) (xy 298.236449 -150.198339) (xy 298.286026 -150.175697) (xy 298.338321 -150.160342)
			(xy 298.392269 -150.152586) (xy 298.446771 -150.152586) (xy 298.500719 -150.160342) (xy 298.553014 -150.175697)
			(xy 298.602591 -150.198339) (xy 298.648441 -150.227805) (xy 298.689632 -150.263496) (xy 298.725323 -150.304687)
			(xy 298.754789 -150.350537) (xy 298.777431 -150.400114) (xy 298.792786 -150.452409) (xy 298.800542 -150.506357)
			(xy 298.801028 -150.533608) (xy 298.800571 -150.560883) (xy 298.792793 -150.614876) (xy 298.77741 -150.667212)
			(xy 298.754737 -150.716827) (xy 298.725233 -150.76271) (xy 298.689501 -150.803928) (xy 298.669202 -150.822152)
			(xy 298.658826 -150.831645) (xy 298.643332 -150.855105) (xy 298.634838 -150.881905) (xy 298.63399 -150.910006)
			(xy 298.640852 -150.93727) (xy 298.654903 -150.961621) (xy 298.675074 -150.981205) (xy 298.687236 -150.988268)
			(xy 298.71268 -151.002729) (xy 298.759232 -151.038197) (xy 298.799823 -151.080355) (xy 298.833503 -151.128216)
			(xy 298.859481 -151.180658) (xy 298.877148 -151.23645) (xy 298.88609 -151.294286) (xy 298.886626 -151.323548)
			(xy 298.88614 -151.350799) (xy 298.878384 -151.404747) (xy 298.863029 -151.457042) (xy 298.840387 -151.506619)
			(xy 298.810921 -151.552469) (xy 298.77523 -151.59366) (xy 298.734039 -151.629351) (xy 298.688189 -151.658817)
			(xy 298.638612 -151.681459) (xy 298.586317 -151.696814) (xy 298.532369 -151.70457) (xy 298.477867 -151.70457)
			(xy 298.423919 -151.696814) (xy 298.371624 -151.681459) (xy 298.322047 -151.658817) (xy 298.276197 -151.629351)
			(xy 298.235006 -151.59366) (xy 298.199315 -151.552469) (xy 298.169849 -151.506619) (xy 298.147207 -151.457042)
			(xy 298.131852 -151.404747) (xy 298.124096 -151.350799) (xy 298.12361 -151.323548) (xy 298.124127 -151.296275)
			(xy 298.131896 -151.242286) (xy 298.147268 -151.189952) (xy 298.16993 -151.140337) (xy 298.199422 -151.094453)
			(xy 298.235143 -151.053231) (xy 298.255436 -151.035004) (xy 298.265764 -151.025459) (xy 298.281271 -151.002015)
			(xy 298.289777 -150.975225) (xy 298.290635 -150.94713) (xy 298.283779 -150.919871) (xy 298.269732 -150.895525)
			(xy 298.249563 -150.875947) (xy 298.237402 -150.868888) (xy 298.211924 -150.854483) (xy 298.165375 -150.819004)
			(xy 298.124788 -150.776835) (xy 298.091113 -150.728964) (xy 298.065141 -150.676514) (xy 298.04748 -150.620714)
			(xy 298.038544 -150.562872) (xy 298.038012 -150.533608) (xy 290.668319 -150.533608) (xy 290.646757 -150.579604)
			(xy 290.615984 -150.626117) (xy 290.578767 -150.667654) (xy 290.535899 -150.703329) (xy 290.488293 -150.732383)
			(xy 290.436964 -150.754195) (xy 290.383007 -150.768301) (xy 290.32757 -150.774401) (xy 290.271836 -150.772364)
			(xy 290.216993 -150.762234) (xy 290.164209 -150.744227) (xy 290.114609 -150.718726) (xy 290.069251 -150.686275)
			(xy 290.029102 -150.647566) (xy 289.995016 -150.603423) (xy 289.96772 -150.554788) (xy 289.947797 -150.502697)
			(xy 289.935671 -150.44826) (xy 289.9316 -150.392638) (xy 282.249973 -150.392638) (xy 282.352128 -150.527755)
			(xy 282.47218 -150.699787) (xy 282.585595 -150.876264) (xy 282.692209 -151.056932) (xy 282.791868 -151.241527)
			(xy 282.884427 -151.429782) (xy 282.969752 -151.621425) (xy 283.047719 -151.816177) (xy 283.116642 -152.009348)
			(xy 306.698902 -152.009348) (xy 306.702973 -151.953726) (xy 306.715099 -151.899289) (xy 306.735022 -151.847198)
			(xy 306.762318 -151.798563) (xy 306.796404 -151.75442) (xy 306.836553 -151.715711) (xy 306.881911 -151.68326)
			(xy 306.931511 -151.657759) (xy 306.984295 -151.639752) (xy 307.039138 -151.629622) (xy 307.094872 -151.627585)
			(xy 307.150309 -151.633685) (xy 307.204266 -151.647791) (xy 307.255595 -151.669603) (xy 307.303201 -151.698657)
			(xy 307.346069 -151.734332) (xy 307.383286 -151.775869) (xy 307.414059 -151.822382) (xy 307.437731 -151.872879)
			(xy 307.453799 -151.926286) (xy 307.461919 -151.981462) (xy 307.462428 -152.009348) (xy 307.461919 -152.037234)
			(xy 307.453799 -152.09241) (xy 307.437731 -152.145817) (xy 307.414059 -152.196314) (xy 307.403319 -152.212548)
			(xy 307.973982 -152.212548) (xy 307.978053 -152.156926) (xy 307.990179 -152.102489) (xy 308.010102 -152.050398)
			(xy 308.037398 -152.001763) (xy 308.071484 -151.95762) (xy 308.111633 -151.918911) (xy 308.156991 -151.88646)
			(xy 308.206591 -151.860959) (xy 308.259375 -151.842952) (xy 308.314218 -151.832822) (xy 308.369952 -151.830785)
			(xy 308.425389 -151.836885) (xy 308.479346 -151.850991) (xy 308.530675 -151.872803) (xy 308.578281 -151.901857)
			(xy 308.621149 -151.937532) (xy 308.658366 -151.979069) (xy 308.689139 -152.025582) (xy 308.712811 -152.076079)
			(xy 308.728879 -152.129486) (xy 308.736999 -152.184662) (xy 308.737508 -152.212548) (xy 308.736999 -152.240434)
			(xy 308.728879 -152.29561) (xy 308.712811 -152.349017) (xy 308.689139 -152.399514) (xy 308.658366 -152.446027)
			(xy 308.621149 -152.487564) (xy 308.578281 -152.523239) (xy 308.530675 -152.552293) (xy 308.479346 -152.574105)
			(xy 308.425389 -152.588211) (xy 308.369952 -152.594311) (xy 308.314218 -152.592274) (xy 308.259375 -152.582144)
			(xy 308.206591 -152.564137) (xy 308.156991 -152.538636) (xy 308.111633 -152.506185) (xy 308.071484 -152.467476)
			(xy 308.037398 -152.423333) (xy 308.010102 -152.374698) (xy 307.990179 -152.322607) (xy 307.978053 -152.26817)
			(xy 307.973982 -152.212548) (xy 307.403319 -152.212548) (xy 307.383286 -152.242827) (xy 307.346069 -152.284364)
			(xy 307.303201 -152.320039) (xy 307.255595 -152.349093) (xy 307.204266 -152.370905) (xy 307.150309 -152.385011)
			(xy 307.094872 -152.391111) (xy 307.039138 -152.389074) (xy 306.984295 -152.378944) (xy 306.931511 -152.360937)
			(xy 306.881911 -152.335436) (xy 306.836553 -152.302985) (xy 306.796404 -152.264276) (xy 306.762318 -152.220133)
			(xy 306.735022 -152.171498) (xy 306.715099 -152.119407) (xy 306.702973 -152.06497) (xy 306.698902 -152.009348)
			(xy 283.116642 -152.009348) (xy 283.118215 -152.013757) (xy 283.181138 -152.213876) (xy 283.236397 -152.416247)
			(xy 283.283911 -152.620574) (xy 283.323612 -152.826562) (xy 283.345439 -152.968747) (xy 296.987006 -152.968747)
			(xy 296.987006 -152.914253) (xy 296.994761 -152.860312) (xy 297.010113 -152.808025) (xy 297.032749 -152.758454)
			(xy 297.06221 -152.712609) (xy 297.097894 -152.671423) (xy 297.139077 -152.635734) (xy 297.184919 -152.606269)
			(xy 297.234487 -152.583627) (xy 297.286773 -152.568269) (xy 297.340713 -152.560509) (xy 297.36796 -152.56002)
			(xy 297.396411 -152.560486) (xy 297.452681 -152.568933) (xy 297.507073 -152.585645) (xy 297.558378 -152.610252)
			(xy 297.605459 -152.642208) (xy 297.64727 -152.680803) (xy 297.682884 -152.725181) (xy 297.697652 -152.749504)
			(xy 297.705584 -152.762119) (xy 297.727392 -152.782409) (xy 297.754128 -152.795541) (xy 297.783516 -152.8004)
			(xy 297.813056 -152.796571) (xy 297.840234 -152.78438) (xy 297.862738 -152.764865) (xy 297.871134 -152.752552)
			(xy 297.88622 -152.729637) (xy 297.921923 -152.687982) (xy 297.963225 -152.65187) (xy 298.009273 -152.622047)
			(xy 298.059117 -152.599126) (xy 298.111731 -152.583581) (xy 298.166029 -152.575731) (xy 298.19346 -152.57526)
			(xy 298.220712 -152.575785) (xy 298.274663 -152.583536) (xy 298.326961 -152.598888) (xy 298.376542 -152.621526)
			(xy 298.422397 -152.65099) (xy 298.463591 -152.686681) (xy 298.499286 -152.727871) (xy 298.528755 -152.773722)
			(xy 298.551398 -152.823301) (xy 298.566755 -152.875598) (xy 298.573314 -152.921208) (xy 298.720762 -152.921208)
			(xy 298.724833 -152.865586) (xy 298.736959 -152.811149) (xy 298.756882 -152.759058) (xy 298.784178 -152.710423)
			(xy 298.818264 -152.66628) (xy 298.858413 -152.627571) (xy 298.903771 -152.59512) (xy 298.953371 -152.569619)
			(xy 299.006155 -152.551612) (xy 299.060998 -152.541482) (xy 299.116732 -152.539445) (xy 299.172169 -152.545545)
			(xy 299.226126 -152.559651) (xy 299.277455 -152.581463) (xy 299.325061 -152.610517) (xy 299.367929 -152.646192)
			(xy 299.405146 -152.687729) (xy 299.435919 -152.734242) (xy 299.459591 -152.784739) (xy 299.475659 -152.838146)
			(xy 299.483779 -152.893322) (xy 299.484288 -152.921208) (xy 299.483779 -152.949094) (xy 299.475659 -153.00427)
			(xy 299.459591 -153.057677) (xy 299.435919 -153.108174) (xy 299.405146 -153.154687) (xy 299.367929 -153.196224)
			(xy 299.325061 -153.231899) (xy 299.277455 -153.260953) (xy 299.226126 -153.282765) (xy 299.172169 -153.296871)
			(xy 299.116732 -153.302971) (xy 299.060998 -153.300934) (xy 299.006155 -153.290804) (xy 298.953371 -153.272797)
			(xy 298.903771 -153.247296) (xy 298.858413 -153.214845) (xy 298.818264 -153.176136) (xy 298.784178 -153.131993)
			(xy 298.756882 -153.083358) (xy 298.736959 -153.031267) (xy 298.724833 -152.97683) (xy 298.720762 -152.921208)
			(xy 298.573314 -152.921208) (xy 298.574513 -152.929548) (xy 298.574513 -152.984052) (xy 298.566755 -153.038002)
			(xy 298.551398 -153.090299) (xy 298.528755 -153.139878) (xy 298.499286 -153.185729) (xy 298.463591 -153.226919)
			(xy 298.422397 -153.26261) (xy 298.376542 -153.292074) (xy 298.326961 -153.314712) (xy 298.274663 -153.330064)
			(xy 298.220712 -153.337815) (xy 298.19346 -153.338276) (xy 298.165012 -153.337747) (xy 298.108746 -153.329306)
			(xy 298.054359 -153.312601) (xy 298.003055 -153.288003) (xy 297.955974 -153.256058) (xy 297.91416 -153.217475)
			(xy 297.87854 -153.173109) (xy 297.863768 -153.148792) (xy 297.855809 -153.136196) (xy 297.834006 -153.115908)
			(xy 297.807276 -153.102776) (xy 297.777894 -153.097915) (xy 297.748359 -153.10174) (xy 297.721184 -153.113926)
			(xy 297.698682 -153.133435) (xy 297.690286 -153.145744) (xy 297.675185 -153.168649) (xy 297.639485 -153.210304)
			(xy 297.598186 -153.246417) (xy 297.55214 -153.276242) (xy 297.502298 -153.299164) (xy 297.449686 -153.314712)
			(xy 297.39539 -153.322563) (xy 297.36796 -153.323036) (xy 297.340713 -153.322491) (xy 297.286773 -153.314731)
			(xy 297.234487 -153.299373) (xy 297.184919 -153.276731) (xy 297.139077 -153.247266) (xy 297.097894 -153.211577)
			(xy 297.06221 -153.170391) (xy 297.032749 -153.124546) (xy 297.010113 -153.074975) (xy 296.994761 -153.022688)
			(xy 296.987006 -152.968747) (xy 283.345439 -152.968747) (xy 283.355442 -153.033913) (xy 283.379355 -153.242324)
			(xy 283.395316 -153.451495) (xy 283.403303 -153.661122) (xy 283.403802 -153.766012) (xy 283.403303 -153.870902)
			(xy 283.395316 -154.080529) (xy 283.379355 -154.2897) (xy 283.355442 -154.498111) (xy 283.34007 -154.598252)
			(xy 289.355916 -154.598252) (xy 289.363674 -154.544293) (xy 289.379031 -154.491988) (xy 289.401677 -154.4424)
			(xy 289.431149 -154.39654) (xy 289.466849 -154.355342) (xy 289.508048 -154.319643) (xy 289.553909 -154.290172)
			(xy 289.603497 -154.267528) (xy 289.655803 -154.252171) (xy 289.709762 -154.244416) (xy 289.764276 -154.244418)
			(xy 289.818235 -154.25218) (xy 289.848464 -154.261058) (xy 296.88358 -154.261058) (xy 296.887651 -154.205436)
			(xy 296.899777 -154.150999) (xy 296.9197 -154.098908) (xy 296.946996 -154.050273) (xy 296.981082 -154.00613)
			(xy 297.021231 -153.967421) (xy 297.066589 -153.93497) (xy 297.116189 -153.909469) (xy 297.168973 -153.891462)
			(xy 297.223816 -153.881332) (xy 297.27955 -153.879295) (xy 297.334987 -153.885395) (xy 297.388944 -153.899501)
			(xy 297.440273 -153.921313) (xy 297.487879 -153.950367) (xy 297.530747 -153.986042) (xy 297.567964 -154.027579)
			(xy 297.598737 -154.074092) (xy 297.622409 -154.124589) (xy 297.638477 -154.177996) (xy 297.646597 -154.233172)
			(xy 297.647106 -154.261058) (xy 297.646597 -154.288944) (xy 297.638477 -154.34412) (xy 297.622409 -154.397527)
			(xy 297.598737 -154.448024) (xy 297.567964 -154.494537) (xy 297.530747 -154.536074) (xy 297.487879 -154.571749)
			(xy 297.440273 -154.600803) (xy 297.388944 -154.622615) (xy 297.334987 -154.636721) (xy 297.27955 -154.642821)
			(xy 297.223816 -154.640784) (xy 297.168973 -154.630654) (xy 297.116189 -154.612647) (xy 297.066589 -154.587146)
			(xy 297.021231 -154.554695) (xy 296.981082 -154.515986) (xy 296.946996 -154.471843) (xy 296.9197 -154.423208)
			(xy 296.899777 -154.371117) (xy 296.887651 -154.31668) (xy 296.88358 -154.261058) (xy 289.848464 -154.261058)
			(xy 289.870539 -154.267541) (xy 289.920125 -154.290191) (xy 289.965983 -154.319667) (xy 290.007179 -154.355369)
			(xy 290.042874 -154.396571) (xy 290.072342 -154.442434) (xy 290.094982 -154.492024) (xy 290.110335 -154.544331)
			(xy 290.118086 -154.598291) (xy 290.118546 -154.625548) (xy 290.118155 -154.649627) (xy 290.112043 -154.697397)
			(xy 290.106354 -154.720798) (xy 290.103321 -154.734709) (xy 290.10409 -154.763153) (xy 290.112685 -154.790279)
			(xy 290.128436 -154.813977) (xy 290.15012 -154.832402) (xy 290.176049 -154.844123) (xy 290.204206 -154.848227)
			(xy 290.218368 -154.846782) (xy 290.230882 -154.845221) (xy 290.256049 -154.843571) (xy 290.26866 -154.84348)
			(xy 290.295911 -154.843992) (xy 290.34986 -154.851744) (xy 290.402156 -154.867094) (xy 290.451735 -154.889731)
			(xy 290.497588 -154.919194) (xy 290.538781 -154.954882) (xy 290.574475 -154.99607) (xy 290.603944 -155.041919)
			(xy 290.611812 -155.059146) (xy 291.754626 -155.059146) (xy 291.754626 -155.004654) (xy 291.762381 -154.950717)
			(xy 291.777732 -154.898432) (xy 291.800367 -154.848863) (xy 291.829826 -154.803021) (xy 291.865509 -154.761837)
			(xy 291.906689 -154.72615) (xy 291.952528 -154.696686) (xy 292.002094 -154.674046) (xy 292.054378 -154.658689)
			(xy 292.108314 -154.650929) (xy 292.13556 -154.65044) (xy 292.16461 -154.650942) (xy 292.222041 -154.65974)
			(xy 292.27747 -154.677153) (xy 292.329614 -154.702779) (xy 292.377264 -154.736022) (xy 292.419316 -154.776113)
			(xy 292.454795 -154.822123) (xy 292.469316 -154.84729) (xy 292.476305 -154.859102) (xy 292.495517 -154.878692)
			(xy 292.51925 -154.892463) (xy 292.545791 -154.899422) (xy 292.573228 -154.899067) (xy 292.599581 -154.891424)
			(xy 292.622949 -154.877044) (xy 292.641649 -154.856963) (xy 292.648386 -154.845004) (xy 292.660834 -154.822201)
			(xy 292.690931 -154.779857) (xy 292.726494 -154.741988) (xy 292.766867 -154.709295) (xy 292.811303 -154.682383)
			(xy 292.85898 -154.661749) (xy 292.909016 -154.647776) (xy 292.960485 -154.640721) (xy 292.98646 -154.64028)
			(xy 293.013714 -154.640765) (xy 293.067667 -154.648517) (xy 293.119968 -154.663869) (xy 293.169552 -154.686508)
			(xy 293.215409 -154.715974) (xy 293.256605 -154.751667) (xy 293.292302 -154.792859) (xy 293.321773 -154.838713)
			(xy 293.344417 -154.888294) (xy 293.359775 -154.940593) (xy 293.367533 -154.994546) (xy 293.367533 -155.049054)
			(xy 293.359775 -155.103007) (xy 293.344417 -155.155306) (xy 293.321773 -155.204887) (xy 293.292302 -155.250741)
			(xy 293.256605 -155.291933) (xy 293.215409 -155.327626) (xy 293.169552 -155.357092) (xy 293.119968 -155.379731)
			(xy 293.067667 -155.395083) (xy 293.013714 -155.402835) (xy 292.98646 -155.403296) (xy 292.957411 -155.40276)
			(xy 292.899983 -155.393966) (xy 292.844555 -155.376557) (xy 292.792412 -155.350937) (xy 292.744762 -155.317699)
			(xy 292.702708 -155.277614) (xy 292.667227 -155.23161) (xy 292.652704 -155.206446) (xy 292.64569 -155.194648)
			(xy 292.626485 -155.175053) (xy 292.602757 -155.161277) (xy 292.576218 -155.154314) (xy 292.548782 -155.154666)
			(xy 292.522431 -155.162309) (xy 292.499064 -155.17669) (xy 292.480369 -155.196772) (xy 292.473634 -155.208732)
			(xy 292.461218 -155.231554) (xy 292.43112 -155.273902) (xy 292.395554 -155.311773) (xy 292.355176 -155.344466)
			(xy 292.310735 -155.371377) (xy 292.263052 -155.392007) (xy 292.213011 -155.405974) (xy 292.161537 -155.41302)
			(xy 292.13556 -155.413456) (xy 292.108314 -155.412871) (xy 292.054378 -155.405111) (xy 292.002094 -155.389754)
			(xy 291.952528 -155.367114) (xy 291.906689 -155.33765) (xy 291.865509 -155.301963) (xy 291.829826 -155.260779)
			(xy 291.800367 -155.214937) (xy 291.777732 -155.165368) (xy 291.762381 -155.113083) (xy 291.754626 -155.059146)
			(xy 290.611812 -155.059146) (xy 290.626588 -155.091495) (xy 290.641945 -155.143789) (xy 290.649704 -155.197737)
			(xy 290.650168 -155.224988) (xy 290.649789 -155.251079) (xy 290.64273 -155.30278) (xy 290.628673 -155.353033)
			(xy 290.618672 -155.377134) (xy 290.613766 -155.38972) (xy 290.609889 -155.416437) (xy 290.613156 -155.443236)
			(xy 290.623338 -155.468239) (xy 290.639722 -155.489696) (xy 290.661161 -155.506105) (xy 290.686152 -155.516315)
			(xy 290.712947 -155.519612) (xy 290.726368 -155.518104) (xy 290.740133 -155.516211) (xy 290.767846 -155.514176)
			(xy 290.78174 -155.51404) (xy 290.808987 -155.514521) (xy 290.862926 -155.522282) (xy 290.915211 -155.537639)
			(xy 290.964778 -155.560281) (xy 291.01062 -155.589746) (xy 291.051801 -155.625435) (xy 291.087484 -155.666621)
			(xy 291.116943 -155.712466) (xy 291.139579 -155.762037) (xy 291.154929 -155.814324) (xy 291.162683 -155.868264)
			(xy 291.162681 -155.922758) (xy 291.154925 -155.976697) (xy 291.139571 -156.028983) (xy 291.116933 -156.078553)
			(xy 291.087472 -156.124396) (xy 291.051786 -156.16558) (xy 291.010602 -156.201267) (xy 290.96476 -156.230729)
			(xy 290.915191 -156.253368) (xy 290.862905 -156.268723) (xy 290.808966 -156.276481) (xy 290.754472 -156.276483)
			(xy 290.700532 -156.268731) (xy 290.648244 -156.253381) (xy 290.598673 -156.230747) (xy 290.552827 -156.201289)
			(xy 290.511641 -156.165607) (xy 290.475951 -156.124426) (xy 290.446485 -156.078586) (xy 290.423842 -156.029018)
			(xy 290.408483 -155.976733) (xy 290.400722 -155.922795) (xy 290.400232 -155.895548) (xy 290.400623 -155.869457)
			(xy 290.407678 -155.817756) (xy 290.421729 -155.767504) (xy 290.431728 -155.743402) (xy 290.43671 -155.730845)
			(xy 290.440575 -155.704117) (xy 290.437296 -155.677312) (xy 290.427103 -155.652304) (xy 290.410708 -155.630844)
			(xy 290.38926 -155.614434) (xy 290.36426 -155.604223) (xy 290.337457 -155.600924) (xy 290.324032 -155.602432)
			(xy 290.310267 -155.604325) (xy 290.282554 -155.60636) (xy 290.26866 -155.606496) (xy 290.241407 -155.606059)
			(xy 290.187457 -155.598297) (xy 290.135161 -155.582936) (xy 290.085583 -155.56029) (xy 290.039732 -155.530818)
			(xy 289.998542 -155.495121) (xy 289.962851 -155.453927) (xy 289.933385 -155.408072) (xy 289.910746 -155.35849)
			(xy 289.895392 -155.306192) (xy 289.887637 -155.252241) (xy 289.887152 -155.224988) (xy 289.887531 -155.200908)
			(xy 289.893652 -155.153139) (xy 289.899344 -155.129738) (xy 289.902449 -155.115842) (xy 289.901665 -155.08739)
			(xy 289.893057 -155.06026) (xy 289.877293 -155.036561) (xy 289.855599 -155.018134) (xy 289.829661 -155.006414)
			(xy 289.801496 -155.002309) (xy 289.78733 -155.003754) (xy 289.774816 -155.005315) (xy 289.749649 -155.006965)
			(xy 289.737038 -155.007056) (xy 289.709781 -155.006586) (xy 289.655821 -154.998833) (xy 289.603514 -154.983479)
			(xy 289.553925 -154.960837) (xy 289.508063 -154.931368) (xy 289.466862 -154.895672) (xy 289.431161 -154.854475)
			(xy 289.401686 -154.808616) (xy 289.379038 -154.75903) (xy 289.363678 -154.706725) (xy 289.355918 -154.652766)
			(xy 289.355916 -154.598252) (xy 283.34007 -154.598252) (xy 283.323612 -154.705462) (xy 283.283911 -154.91145)
			(xy 283.236397 -155.115777) (xy 283.181138 -155.318148) (xy 283.118215 -155.518267) (xy 283.047719 -155.715847)
			(xy 282.969752 -155.910599) (xy 282.884427 -156.102242) (xy 282.791868 -156.290497) (xy 282.692209 -156.475092)
			(xy 282.585595 -156.65576) (xy 282.47218 -156.832237) (xy 282.352128 -157.004269) (xy 282.225614 -157.171605)
			(xy 282.092821 -157.334004) (xy 281.953942 -157.49123) (xy 281.809178 -157.643054) (xy 281.658739 -157.789257)
			(xy 281.502842 -157.929626) (xy 281.341715 -158.063959) (xy 281.175591 -158.19206) (xy 281.00471 -158.313744)
			(xy 280.82932 -158.428834) (xy 280.649676 -158.537164) (xy 280.466038 -158.638575) (xy 280.278672 -158.732922)
			(xy 280.08785 -158.820068) (xy 279.893849 -158.899885) (xy 279.69695 -158.972259) (xy 279.497438 -159.037084)
			(xy 279.295603 -159.094267) (xy 279.091737 -159.143725) (xy 278.886136 -159.185385) (xy 278.679098 -159.219187)
			(xy 278.470924 -159.245083) (xy 278.261914 -159.263035) (xy 278.052372 -159.273017) (xy 277.842603 -159.275014)
			(xy 277.632909 -159.269023) (xy 277.423596 -159.255054) (xy 277.214966 -159.233126) (xy 277.007322 -159.203272)
			(xy 276.800965 -159.165533) (xy 276.596195 -159.119966) (xy 276.393308 -159.066637) (xy 276.192598 -159.005622)
			(xy 275.994356 -158.93701) (xy 275.798871 -158.8609) (xy 275.606424 -158.777403) (xy 275.417296 -158.686641)
			(xy 275.231761 -158.588744) (xy 275.050087 -158.483854) (xy 274.872537 -158.372124) (xy 274.699371 -158.253716)
			(xy 274.530837 -158.128801) (xy 274.367182 -157.99756) (xy 274.208641 -157.860184) (xy 274.055446 -157.716871)
			(xy 273.907817 -157.567831) (xy 273.76597 -157.413278) (xy 273.630109 -157.253437) (xy 273.500432 -157.088539)
			(xy 273.377127 -156.918824) (xy 273.260373 -156.744538) (xy 273.150338 -156.565933) (xy 273.047183 -156.383269)
			(xy 272.951056 -156.19681) (xy 272.862098 -156.006826) (xy 272.780438 -155.813594) (xy 272.706193 -155.617393)
			(xy 272.639471 -155.418507) (xy 272.580369 -155.217225) (xy 272.528973 -155.01384) (xy 272.485358 -154.808645)
			(xy 272.449586 -154.601938) (xy 272.421709 -154.394019) (xy 272.401768 -154.18519) (xy 272.389792 -153.975753)
			(xy 272.385799 -153.766012) (xy 268.652797 -153.766012) (xy 268.652759 -153.76627) (xy 268.636691 -153.819677)
			(xy 268.613019 -153.870174) (xy 268.582246 -153.916687) (xy 268.545029 -153.958224) (xy 268.502161 -153.993899)
			(xy 268.454555 -154.022953) (xy 268.403226 -154.044765) (xy 268.349269 -154.058871) (xy 268.293832 -154.064971)
			(xy 268.238098 -154.062934) (xy 268.183255 -154.052804) (xy 268.130471 -154.034797) (xy 268.080871 -154.009296)
			(xy 268.035513 -153.976845) (xy 267.995364 -153.938136) (xy 267.961278 -153.893993) (xy 267.933982 -153.845358)
			(xy 267.914059 -153.793267) (xy 267.901933 -153.73883) (xy 267.897862 -153.683208) (xy 267.108015 -153.683208)
			(xy 267.101426 -153.693167) (xy 267.064209 -153.734704) (xy 267.021341 -153.770379) (xy 266.973735 -153.799433)
			(xy 266.922406 -153.821245) (xy 266.868449 -153.835351) (xy 266.813012 -153.841451) (xy 266.757278 -153.839414)
			(xy 266.702435 -153.829284) (xy 266.649651 -153.811277) (xy 266.600051 -153.785776) (xy 266.554693 -153.753325)
			(xy 266.514544 -153.714616) (xy 266.480458 -153.670473) (xy 266.453162 -153.621838) (xy 266.433239 -153.569747)
			(xy 266.421113 -153.51531) (xy 266.417042 -153.459688) (xy 217.256765 -153.459688) (xy 216.71574 -154.000708)
			(xy 259.118098 -154.000708) (xy 259.122169 -153.945086) (xy 259.134295 -153.890649) (xy 259.154218 -153.838558)
			(xy 259.181514 -153.789923) (xy 259.2156 -153.74578) (xy 259.255749 -153.707071) (xy 259.301107 -153.67462)
			(xy 259.350707 -153.649119) (xy 259.403491 -153.631112) (xy 259.458334 -153.620982) (xy 259.514068 -153.618945)
			(xy 259.569505 -153.625045) (xy 259.623462 -153.639151) (xy 259.674791 -153.660963) (xy 259.722397 -153.690017)
			(xy 259.765265 -153.725692) (xy 259.802482 -153.767229) (xy 259.833255 -153.813742) (xy 259.856927 -153.864239)
			(xy 259.872995 -153.917646) (xy 259.881115 -153.972822) (xy 259.881624 -154.000708) (xy 259.881115 -154.028594)
			(xy 259.872995 -154.08377) (xy 259.856927 -154.137177) (xy 259.833255 -154.187674) (xy 259.802482 -154.234187)
			(xy 259.765265 -154.275724) (xy 259.722397 -154.311399) (xy 259.674791 -154.340453) (xy 259.623462 -154.362265)
			(xy 259.569505 -154.376371) (xy 259.514068 -154.382471) (xy 259.458334 -154.380434) (xy 259.403491 -154.370304)
			(xy 259.350707 -154.352297) (xy 259.301107 -154.326796) (xy 259.255749 -154.294345) (xy 259.2156 -154.255636)
			(xy 259.181514 -154.211493) (xy 259.154218 -154.162858) (xy 259.134295 -154.110767) (xy 259.122169 -154.05633)
			(xy 259.118098 -154.000708) (xy 216.71574 -154.000708) (xy 214.56434 -156.152088) (xy 266.745212 -156.152088)
			(xy 266.745685 -156.124518) (xy 266.753625 -156.069954) (xy 266.769337 -156.0171) (xy 266.792495 -155.96706)
			(xy 266.822615 -155.920874) (xy 266.859071 -155.879506) (xy 266.901102 -155.843817) (xy 266.947833 -155.81455)
			(xy 266.998291 -155.792316) (xy 267.051424 -155.777578) (xy 267.078714 -155.773628) (xy 267.091903 -155.771555)
			(xy 267.116613 -155.761467) (xy 267.137864 -155.745319) (xy 267.154204 -155.724216) (xy 267.164516 -155.699598)
			(xy 267.168095 -155.67315) (xy 267.164697 -155.646677) (xy 267.159994 -155.634182) (xy 267.150928 -155.611088)
			(xy 267.138166 -155.563145) (xy 267.131708 -155.513954) (xy 267.131292 -155.489148) (xy 267.131778 -155.461897)
			(xy 267.139534 -155.407949) (xy 267.154889 -155.355654) (xy 267.177531 -155.306077) (xy 267.206997 -155.260227)
			(xy 267.242688 -155.219036) (xy 267.283879 -155.183345) (xy 267.329729 -155.153879) (xy 267.379306 -155.131237)
			(xy 267.431601 -155.115882) (xy 267.485549 -155.108126) (xy 267.540051 -155.108126) (xy 267.593999 -155.115882)
			(xy 267.646294 -155.131237) (xy 267.695871 -155.153879) (xy 267.741721 -155.183345) (xy 267.782912 -155.219036)
			(xy 267.818603 -155.260227) (xy 267.848069 -155.306077) (xy 267.870711 -155.355654) (xy 267.886066 -155.407949)
			(xy 267.893822 -155.461897) (xy 267.894308 -155.489148) (xy 267.893851 -155.516718) (xy 267.885907 -155.571282)
			(xy 267.870191 -155.624135) (xy 267.84703 -155.674175) (xy 267.816908 -155.72036) (xy 267.780451 -155.761727)
			(xy 267.738419 -155.797416) (xy 267.691687 -155.826683) (xy 267.641229 -155.848918) (xy 267.588096 -155.863657)
			(xy 267.560806 -155.867608) (xy 267.547598 -155.86958) (xy 267.522885 -155.87969) (xy 267.501635 -155.895857)
			(xy 267.485298 -155.916977) (xy 267.474991 -155.941609) (xy 267.471417 -155.96807) (xy 267.47482 -155.994554)
			(xy 267.479526 -156.007054) (xy 267.488574 -156.030154) (xy 267.501343 -156.078094) (xy 267.507808 -156.127283)
			(xy 267.508228 -156.152088) (xy 267.507742 -156.179339) (xy 267.499986 -156.233287) (xy 267.484631 -156.285582)
			(xy 267.461989 -156.335159) (xy 267.432523 -156.381009) (xy 267.396832 -156.4222) (xy 267.355641 -156.457891)
			(xy 267.309791 -156.487357) (xy 267.260214 -156.509999) (xy 267.207919 -156.525354) (xy 267.153971 -156.53311)
			(xy 267.099469 -156.53311) (xy 267.045521 -156.525354) (xy 266.993226 -156.509999) (xy 266.943649 -156.487357)
			(xy 266.897799 -156.457891) (xy 266.856608 -156.4222) (xy 266.820917 -156.381009) (xy 266.791451 -156.335159)
			(xy 266.768809 -156.285582) (xy 266.753454 -156.233287) (xy 266.745698 -156.179339) (xy 266.745212 -156.152088)
			(xy 214.56434 -156.152088) (xy 209.092827 -161.623549) (xy 295.966402 -161.623549) (xy 295.966402 -161.569051)
			(xy 295.974158 -161.515108) (xy 295.989511 -161.462817) (xy 296.01215 -161.413244) (xy 296.041614 -161.367397)
			(xy 296.077301 -161.32621) (xy 296.118488 -161.290521) (xy 296.164334 -161.261056) (xy 296.213906 -161.238416)
			(xy 296.266196 -161.22306) (xy 296.320139 -161.215303) (xy 296.347388 -161.214816) (xy 296.376127 -161.215302)
			(xy 296.432955 -161.223918) (xy 296.487849 -161.240957) (xy 296.539568 -161.266033) (xy 296.586942 -161.29858)
			(xy 296.628902 -161.337862) (xy 296.647108 -161.360104) (xy 296.656031 -161.370708) (xy 296.67838 -161.387078)
			(xy 296.70431 -161.396829) (xy 296.731907 -161.39924) (xy 296.759135 -161.394133) (xy 296.783984 -161.381886)
			(xy 296.804618 -161.363402) (xy 296.812462 -161.351976) (xy 296.827568 -161.329164) (xy 296.863283 -161.287717)
			(xy 296.904553 -161.251798) (xy 296.950533 -161.222145) (xy 297.000278 -161.199366) (xy 297.052767 -161.183929)
			(xy 297.106924 -161.176151) (xy 297.13428 -161.1757) (xy 297.99788 -161.1757) (xy 298.024574 -161.176184)
			(xy 298.077443 -161.18362) (xy 298.128759 -161.19835) (xy 298.177523 -161.220085) (xy 298.222783 -161.248403)
			(xy 298.263656 -161.282751) (xy 298.299344 -161.322459) (xy 298.314618 -161.344356) (xy 298.322889 -161.355825)
			(xy 298.34446 -161.374092) (xy 298.370207 -161.385753) (xy 298.398164 -161.389917) (xy 298.426193 -161.386265)
			(xy 298.45215 -161.375078) (xy 298.474051 -161.357209) (xy 298.482512 -161.34588) (xy 298.497854 -161.324528)
			(xy 298.53346 -161.28584) (xy 298.574043 -161.252412) (xy 298.618834 -161.224876) (xy 298.666984 -161.203755)
			(xy 298.717578 -161.189451) (xy 298.769659 -161.182233) (xy 298.795948 -161.181796) (xy 298.823197 -161.182277)
			(xy 298.87714 -161.190039) (xy 298.92943 -161.205399) (xy 298.979002 -161.228043) (xy 299.024847 -161.257511)
			(xy 299.066031 -161.293203) (xy 299.101718 -161.334392) (xy 299.13118 -161.380241) (xy 299.153818 -161.429815)
			(xy 299.169171 -161.482107) (xy 299.176926 -161.536051) (xy 299.176926 -161.590549) (xy 299.169171 -161.644493)
			(xy 299.153818 -161.696785) (xy 299.13118 -161.746359) (xy 299.101718 -161.792208) (xy 299.066031 -161.833397)
			(xy 299.024847 -161.869089) (xy 298.979002 -161.898557) (xy 298.92943 -161.921201) (xy 298.87714 -161.936561)
			(xy 298.823197 -161.944323) (xy 298.795948 -161.944812) (xy 298.76924 -161.944399) (xy 298.716349 -161.936929)
			(xy 298.665017 -161.922158) (xy 298.616245 -161.900374) (xy 298.570988 -161.872001) (xy 298.530128 -161.837595)
			(xy 298.494466 -161.797828) (xy 298.47921 -161.775902) (xy 298.470917 -161.764436) (xy 298.449338 -161.746153)
			(xy 298.423569 -161.734495) (xy 298.395589 -161.730359) (xy 298.367549 -161.734062) (xy 298.341603 -161.745319)
			(xy 298.319743 -161.763266) (xy 298.311316 -161.774632) (xy 298.29596 -161.795974) (xy 298.260356 -161.834661)
			(xy 298.219775 -161.86809) (xy 298.174987 -161.895627) (xy 298.126839 -161.916749) (xy 298.076247 -161.931056)
			(xy 298.024168 -161.938277) (xy 297.99788 -161.938716) (xy 297.13428 -161.938716) (xy 297.105544 -161.938169)
			(xy 297.048719 -161.929564) (xy 296.993827 -161.912537) (xy 296.942108 -161.887472) (xy 296.894731 -161.854936)
			(xy 296.852769 -161.815665) (xy 296.83456 -161.793428) (xy 296.825568 -161.78286) (xy 296.803197 -161.766477)
			(xy 296.777242 -161.756715) (xy 296.749618 -161.754295) (xy 296.722362 -161.759395) (xy 296.697482 -161.771639)
			(xy 296.676813 -161.790125) (xy 296.668952 -161.801556) (xy 296.653825 -161.824331) (xy 296.618146 -161.865758)
			(xy 296.576916 -161.901665) (xy 296.530981 -161.931316) (xy 296.481282 -161.954102) (xy 296.428838 -161.969557)
			(xy 296.374725 -161.977363) (xy 296.347388 -161.977832) (xy 296.320139 -161.977297) (xy 296.266196 -161.96954)
			(xy 296.213906 -161.954184) (xy 296.164334 -161.931544) (xy 296.118488 -161.902079) (xy 296.077301 -161.86639)
			(xy 296.041614 -161.825203) (xy 296.01215 -161.779356) (xy 295.989511 -161.729783) (xy 295.974158 -161.677492)
			(xy 295.966402 -161.623549) (xy 209.092827 -161.623549) (xy 208.549219 -162.167152) (xy 291.788062 -162.167152)
			(xy 291.788062 -162.112648) (xy 291.795818 -162.058699) (xy 291.811173 -162.006403) (xy 291.833815 -161.956825)
			(xy 291.863281 -161.910973) (xy 291.898973 -161.869781) (xy 291.940163 -161.834088) (xy 291.986014 -161.80462)
			(xy 292.035592 -161.781978) (xy 292.087887 -161.766621) (xy 292.141836 -161.758863) (xy 292.169088 -161.758376)
			(xy 292.197826 -161.758877) (xy 292.254653 -161.767492) (xy 292.309546 -161.784529) (xy 292.361264 -161.809602)
			(xy 292.408639 -161.842146) (xy 292.4506 -161.881424) (xy 292.468808 -161.903664) (xy 292.477727 -161.914274)
			(xy 292.500075 -161.930651) (xy 292.526007 -161.940406) (xy 292.553608 -161.942818) (xy 292.580839 -161.93771)
			(xy 292.605688 -161.925457) (xy 292.626321 -161.906966) (xy 292.634162 -161.895536) (xy 292.649288 -161.872738)
			(xy 292.684997 -161.831287) (xy 292.726263 -161.795365) (xy 292.772239 -161.765709) (xy 292.821982 -161.742928)
			(xy 292.874469 -161.72749) (xy 292.928624 -161.719711) (xy 292.95598 -161.71926) (xy 293.81958 -161.71926)
			(xy 293.846276 -161.719718) (xy 293.899146 -161.727155) (xy 293.950465 -161.741887) (xy 293.999229 -161.763627)
			(xy 294.044489 -161.791949) (xy 294.085361 -161.826302) (xy 294.121046 -161.866016) (xy 294.136318 -161.887916)
			(xy 294.144587 -161.899389) (xy 294.166156 -161.917662) (xy 294.191905 -161.929328) (xy 294.219864 -161.933494)
			(xy 294.247896 -161.929841) (xy 294.273854 -161.918648) (xy 294.295753 -161.900773) (xy 294.304212 -161.88944)
			(xy 294.319542 -161.868079) (xy 294.355151 -161.829393) (xy 294.395737 -161.795967) (xy 294.44053 -161.768433)
			(xy 294.488681 -161.747314) (xy 294.539277 -161.73301) (xy 294.591358 -161.725793) (xy 294.617648 -161.725356)
			(xy 294.644894 -161.725917) (xy 294.698832 -161.733679) (xy 294.751116 -161.749037) (xy 294.800682 -161.771678)
			(xy 294.846522 -161.801143) (xy 294.887703 -161.836831) (xy 294.923386 -161.878016) (xy 294.952845 -161.92386)
			(xy 294.97548 -161.973429) (xy 294.990831 -162.025715) (xy 294.998586 -162.079654) (xy 294.998586 -162.134146)
			(xy 294.990831 -162.188085) (xy 294.97548 -162.240371) (xy 294.952845 -162.28994) (xy 294.923386 -162.335784)
			(xy 294.887703 -162.376969) (xy 294.846522 -162.412657) (xy 294.800682 -162.442122) (xy 294.751116 -162.464763)
			(xy 294.698832 -162.480121) (xy 294.644894 -162.487883) (xy 294.617648 -162.488372) (xy 294.590942 -162.487932)
			(xy 294.538053 -162.480464) (xy 294.486722 -162.465696) (xy 294.437951 -162.443915) (xy 294.392694 -162.415547)
			(xy 294.351833 -162.381147) (xy 294.316168 -162.341386) (xy 294.30091 -162.319462) (xy 294.292615 -162.307999)
			(xy 294.271034 -162.289723) (xy 294.245266 -162.278071) (xy 294.217289 -162.273936) (xy 294.189252 -162.277637)
			(xy 294.163307 -162.28889) (xy 294.141446 -162.30683) (xy 294.133016 -162.318192) (xy 294.117648 -162.339525)
			(xy 294.082048 -162.378214) (xy 294.041469 -162.411645) (xy 293.996683 -162.439184) (xy 293.948537 -162.460307)
			(xy 293.897946 -162.474616) (xy 293.845868 -162.481837) (xy 293.81958 -162.482276) (xy 292.95598 -162.482276)
			(xy 292.927243 -162.481744) (xy 292.870417 -162.473139) (xy 292.815524 -162.456109) (xy 292.763804 -162.431041)
			(xy 292.716428 -162.398502) (xy 292.674467 -162.359227) (xy 292.65626 -162.336988) (xy 292.647264 -162.326426)
			(xy 292.624891 -162.310049) (xy 292.598939 -162.300292) (xy 292.571318 -162.297873) (xy 292.544065 -162.302971)
			(xy 292.519186 -162.315211) (xy 292.498515 -162.333689) (xy 292.490652 -162.345116) (xy 292.475545 -162.367905)
			(xy 292.43986 -162.409329) (xy 292.398626 -162.445233) (xy 292.352687 -162.47488) (xy 292.302986 -162.497664)
			(xy 292.25054 -162.513117) (xy 292.196425 -162.520923) (xy 292.169088 -162.521392) (xy 292.141836 -162.520937)
			(xy 292.087887 -162.513179) (xy 292.035592 -162.497822) (xy 291.986014 -162.47518) (xy 291.940163 -162.445712)
			(xy 291.898973 -162.410019) (xy 291.863281 -162.368827) (xy 291.833815 -162.322975) (xy 291.811173 -162.273397)
			(xy 291.795818 -162.221101) (xy 291.788062 -162.167152) (xy 208.549219 -162.167152) (xy 206.946808 -163.769548)
			(xy 243.691662 -163.769548) (xy 243.695733 -163.713926) (xy 243.707859 -163.659489) (xy 243.727782 -163.607398)
			(xy 243.755078 -163.558763) (xy 243.789164 -163.51462) (xy 243.829313 -163.475911) (xy 243.874671 -163.44346)
			(xy 243.924271 -163.417959) (xy 243.977055 -163.399952) (xy 244.031898 -163.389822) (xy 244.087632 -163.387785)
			(xy 244.143069 -163.393885) (xy 244.197026 -163.407991) (xy 244.248355 -163.429803) (xy 244.295961 -163.458857)
			(xy 244.338829 -163.494532) (xy 244.357659 -163.515548) (xy 285.144462 -163.515548) (xy 285.148533 -163.459926)
			(xy 285.160659 -163.405489) (xy 285.180582 -163.353398) (xy 285.207878 -163.304763) (xy 285.241964 -163.26062)
			(xy 285.282113 -163.221911) (xy 285.327471 -163.18946) (xy 285.377071 -163.163959) (xy 285.429855 -163.145952)
			(xy 285.484698 -163.135822) (xy 285.540432 -163.133785) (xy 285.595869 -163.139885) (xy 285.649826 -163.153991)
			(xy 285.701155 -163.175803) (xy 285.748761 -163.204857) (xy 285.791629 -163.240532) (xy 285.828846 -163.282069)
			(xy 285.859619 -163.328582) (xy 285.883291 -163.379079) (xy 285.899359 -163.432486) (xy 285.907479 -163.487662)
			(xy 285.907988 -163.515548) (xy 285.907479 -163.543434) (xy 285.900369 -163.591748) (xy 286.490662 -163.591748)
			(xy 286.494733 -163.536126) (xy 286.506859 -163.481689) (xy 286.526782 -163.429598) (xy 286.554078 -163.380963)
			(xy 286.588164 -163.33682) (xy 286.628313 -163.298111) (xy 286.673671 -163.26566) (xy 286.723271 -163.240159)
			(xy 286.776055 -163.222152) (xy 286.830898 -163.212022) (xy 286.886632 -163.209985) (xy 286.942069 -163.216085)
			(xy 286.996026 -163.230191) (xy 287.047355 -163.252003) (xy 287.094961 -163.281057) (xy 287.134723 -163.314147)
			(xy 287.583926 -163.314147) (xy 287.583926 -163.259653) (xy 287.591681 -163.205714) (xy 287.607033 -163.153427)
			(xy 287.62967 -163.103858) (xy 287.659131 -163.058014) (xy 287.694816 -163.01683) (xy 287.735998 -162.981143)
			(xy 287.78184 -162.95168) (xy 287.831409 -162.92904) (xy 287.883694 -162.913685) (xy 287.937633 -162.905928)
			(xy 287.96488 -162.90544) (xy 287.994276 -162.905996) (xy 288.052374 -162.915007) (xy 288.108404 -162.932819)
			(xy 288.16104 -162.95901) (xy 288.185352 -162.975544) (xy 288.196816 -162.983099) (xy 288.222639 -162.992391)
			(xy 288.250004 -162.994473) (xy 288.276935 -162.989194) (xy 288.30149 -162.976936) (xy 288.321894 -162.958583)
			(xy 288.336676 -162.93546) (xy 288.344769 -162.909237) (xy 288.345626 -162.895534) (xy 288.346752 -162.868777)
			(xy 288.35567 -162.815968) (xy 288.371889 -162.764927) (xy 288.395089 -162.716657) (xy 288.424815 -162.672107)
			(xy 288.460482 -162.632155) (xy 288.501387 -162.597586) (xy 288.546726 -162.56908) (xy 288.595608 -162.547197)
			(xy 288.647071 -162.532369) (xy 288.700102 -162.524887) (xy 288.72688 -162.52444) (xy 288.754137 -162.524806)
			(xy 288.808097 -162.532561) (xy 288.860404 -162.547917) (xy 288.909993 -162.570562) (xy 288.955854 -162.600033)
			(xy 288.997055 -162.635731) (xy 289.032755 -162.67693) (xy 289.062229 -162.722789) (xy 289.084876 -162.772377)
			(xy 289.100235 -162.824683) (xy 289.107993 -162.878643) (xy 289.107993 -162.933157) (xy 289.100235 -162.987117)
			(xy 289.084876 -163.039423) (xy 289.062229 -163.089011) (xy 289.032755 -163.13487) (xy 289.008503 -163.162858)
			(xy 293.944419 -163.162858) (xy 293.944419 -163.108342) (xy 293.952178 -163.054382) (xy 293.967538 -163.002075)
			(xy 293.990186 -162.952487) (xy 294.019661 -162.906628) (xy 294.055364 -162.86543) (xy 294.096566 -162.829733)
			(xy 294.14243 -162.800263) (xy 294.19202 -162.777621) (xy 294.244329 -162.762268) (xy 294.29829 -162.754516)
			(xy 294.325548 -162.754056) (xy 294.354285 -162.754593) (xy 294.411109 -162.763202) (xy 294.466001 -162.780232)
			(xy 294.51772 -162.805298) (xy 294.565096 -162.837835) (xy 294.607059 -162.877107) (xy 294.625268 -162.899344)
			(xy 294.634231 -162.909916) (xy 294.656567 -162.926296) (xy 294.682489 -162.936057) (xy 294.710083 -162.938475)
			(xy 294.737308 -162.933373) (xy 294.762153 -162.921127) (xy 294.782782 -162.902643) (xy 294.790622 -162.891216)
			(xy 294.805768 -162.868431) (xy 294.841474 -162.826982) (xy 294.882737 -162.79106) (xy 294.92871 -162.761403)
			(xy 294.978449 -162.738619) (xy 295.030933 -162.723177) (xy 295.085085 -162.715394) (xy 295.11244 -162.71494)
			(xy 295.97604 -162.71494) (xy 296.002737 -162.715361) (xy 296.055609 -162.722806) (xy 296.106927 -162.737545)
			(xy 296.155692 -162.759291) (xy 296.200951 -162.787619) (xy 296.241822 -162.821977) (xy 296.277507 -162.861694)
			(xy 296.292778 -162.883596) (xy 296.300972 -162.895128) (xy 296.322556 -162.913407) (xy 296.348322 -162.925073)
			(xy 296.376298 -162.929232) (xy 296.404343 -162.925567) (xy 296.430311 -162.914358) (xy 296.452214 -162.896463)
			(xy 296.460672 -162.88512) (xy 296.476021 -162.863773) (xy 296.511627 -162.825088) (xy 296.55221 -162.791661)
			(xy 296.597 -162.764126) (xy 296.645148 -162.743004) (xy 296.695741 -162.728697) (xy 296.74782 -162.721476)
			(xy 296.774108 -162.721036) (xy 296.801362 -162.721434) (xy 296.855315 -162.729193) (xy 296.907615 -162.74455)
			(xy 296.957197 -162.767195) (xy 297.003052 -162.796664) (xy 297.044246 -162.83236) (xy 297.07994 -162.873555)
			(xy 297.109409 -162.91941) (xy 297.132052 -162.968993) (xy 297.147409 -163.021293) (xy 297.155166 -163.075246)
			(xy 297.155166 -163.129754) (xy 297.152232 -163.150158) (xy 299.405419 -163.150158) (xy 299.405419 -163.095642)
			(xy 299.413178 -163.041682) (xy 299.428538 -162.989375) (xy 299.451186 -162.939787) (xy 299.480661 -162.893928)
			(xy 299.516364 -162.85273) (xy 299.557566 -162.817033) (xy 299.60343 -162.787563) (xy 299.65302 -162.764921)
			(xy 299.705329 -162.749568) (xy 299.75929 -162.741816) (xy 299.786548 -162.741356) (xy 299.815285 -162.741893)
			(xy 299.872109 -162.750502) (xy 299.927001 -162.767532) (xy 299.97872 -162.792598) (xy 300.026096 -162.825135)
			(xy 300.068059 -162.864407) (xy 300.086268 -162.886644) (xy 300.095231 -162.897216) (xy 300.117567 -162.913596)
			(xy 300.143489 -162.923357) (xy 300.171083 -162.925775) (xy 300.198308 -162.920673) (xy 300.223153 -162.908427)
			(xy 300.243782 -162.889943) (xy 300.251622 -162.878516) (xy 300.266768 -162.855731) (xy 300.302474 -162.814282)
			(xy 300.343737 -162.77836) (xy 300.38971 -162.748703) (xy 300.439449 -162.725919) (xy 300.491933 -162.710477)
			(xy 300.546085 -162.702694) (xy 300.57344 -162.70224) (xy 301.43704 -162.70224) (xy 301.463737 -162.702661)
			(xy 301.516609 -162.710106) (xy 301.567927 -162.724845) (xy 301.616692 -162.746591) (xy 301.661951 -162.774919)
			(xy 301.702822 -162.809277) (xy 301.738507 -162.848994) (xy 301.753778 -162.870896) (xy 301.761972 -162.882428)
			(xy 301.783556 -162.900707) (xy 301.809322 -162.912373) (xy 301.837298 -162.916532) (xy 301.865343 -162.912867)
			(xy 301.891311 -162.901658) (xy 301.913214 -162.883763) (xy 301.921672 -162.87242) (xy 301.937021 -162.851073)
			(xy 301.972627 -162.812388) (xy 302.01321 -162.778961) (xy 302.058 -162.751426) (xy 302.106148 -162.730304)
			(xy 302.156741 -162.715997) (xy 302.20882 -162.708776) (xy 302.235108 -162.708336) (xy 302.262362 -162.708734)
			(xy 302.316315 -162.716493) (xy 302.368615 -162.73185) (xy 302.418197 -162.754495) (xy 302.464052 -162.783964)
			(xy 302.505246 -162.81966) (xy 302.54094 -162.860855) (xy 302.570409 -162.90671) (xy 302.593052 -162.956293)
			(xy 302.608409 -163.008593) (xy 302.616166 -163.062546) (xy 302.616166 -163.117054) (xy 302.608409 -163.171007)
			(xy 302.593052 -163.223307) (xy 302.570409 -163.27289) (xy 302.54094 -163.318745) (xy 302.505246 -163.35994)
			(xy 302.464052 -163.395636) (xy 302.418197 -163.425105) (xy 302.368615 -163.44775) (xy 302.316315 -163.463107)
			(xy 302.262362 -163.470866) (xy 302.235108 -163.471352) (xy 302.208403 -163.470875) (xy 302.155515 -163.463415)
			(xy 302.104185 -163.448654) (xy 302.055414 -163.426879) (xy 302.010156 -163.398517) (xy 301.969294 -163.364121)
			(xy 301.933628 -163.324364) (xy 301.91837 -163.302442) (xy 301.910124 -163.290942) (xy 301.88853 -163.272668)
			(xy 301.862752 -163.26102) (xy 301.834767 -163.256891) (xy 301.806723 -163.260599) (xy 301.780772 -163.271859)
			(xy 301.758907 -163.289806) (xy 301.750476 -163.301172) (xy 301.735157 -163.322542) (xy 301.699546 -163.361226)
			(xy 301.658958 -163.394652) (xy 301.614163 -163.422185) (xy 301.56601 -163.443302) (xy 301.515413 -163.457604)
			(xy 301.46333 -163.464819) (xy 301.43704 -163.465256) (xy 300.57344 -163.465256) (xy 300.544703 -163.464723)
			(xy 300.487879 -163.456113) (xy 300.432987 -163.439082) (xy 300.381268 -163.414014) (xy 300.333892 -163.381477)
			(xy 300.291929 -163.342205) (xy 300.27372 -163.319968) (xy 300.264768 -163.309368) (xy 300.242384 -163.292994)
			(xy 300.216422 -163.283242) (xy 300.188793 -163.28083) (xy 300.161534 -163.285935) (xy 300.136651 -163.298181)
			(xy 300.115977 -163.316666) (xy 300.108112 -163.328096) (xy 300.093025 -163.350899) (xy 300.057337 -163.392324)
			(xy 300.0161 -163.428227) (xy 299.970158 -163.457874) (xy 299.920453 -163.480655) (xy 299.868004 -163.496105)
			(xy 299.813887 -163.503906) (xy 299.786548 -163.504372) (xy 299.75929 -163.503984) (xy 299.705329 -163.496232)
			(xy 299.65302 -163.480879) (xy 299.60343 -163.458237) (xy 299.557566 -163.428767) (xy 299.516364 -163.39307)
			(xy 299.480661 -163.351872) (xy 299.451186 -163.306013) (xy 299.428538 -163.256425) (xy 299.413178 -163.204118)
			(xy 299.405419 -163.150158) (xy 297.152232 -163.150158) (xy 297.147409 -163.183707) (xy 297.132052 -163.236007)
			(xy 297.109409 -163.28559) (xy 297.07994 -163.331445) (xy 297.044246 -163.37264) (xy 297.003052 -163.408336)
			(xy 296.957197 -163.437805) (xy 296.907615 -163.46045) (xy 296.855315 -163.475807) (xy 296.801362 -163.483566)
			(xy 296.774108 -163.484052) (xy 296.747403 -163.483575) (xy 296.694515 -163.476115) (xy 296.643185 -163.461354)
			(xy 296.594414 -163.439579) (xy 296.549156 -163.411217) (xy 296.508294 -163.376821) (xy 296.472628 -163.337064)
			(xy 296.45737 -163.315142) (xy 296.449124 -163.303642) (xy 296.42753 -163.285368) (xy 296.401752 -163.27372)
			(xy 296.373767 -163.269591) (xy 296.345723 -163.273299) (xy 296.319772 -163.284559) (xy 296.297907 -163.302506)
			(xy 296.289476 -163.313872) (xy 296.274157 -163.335242) (xy 296.238546 -163.373926) (xy 296.197958 -163.407352)
			(xy 296.153163 -163.434885) (xy 296.10501 -163.456002) (xy 296.054413 -163.470304) (xy 296.00233 -163.477519)
			(xy 295.97604 -163.477956) (xy 295.11244 -163.477956) (xy 295.083703 -163.477423) (xy 295.026879 -163.468813)
			(xy 294.971987 -163.451782) (xy 294.920268 -163.426714) (xy 294.872892 -163.394177) (xy 294.830929 -163.354905)
			(xy 294.81272 -163.332668) (xy 294.803768 -163.322068) (xy 294.781384 -163.305694) (xy 294.755422 -163.295942)
			(xy 294.727793 -163.29353) (xy 294.700534 -163.298635) (xy 294.675651 -163.310881) (xy 294.654977 -163.329366)
			(xy 294.647112 -163.340796) (xy 294.632025 -163.363599) (xy 294.596337 -163.405024) (xy 294.5551 -163.440927)
			(xy 294.509158 -163.470574) (xy 294.459453 -163.493355) (xy 294.407004 -163.508805) (xy 294.352887 -163.516606)
			(xy 294.325548 -163.517072) (xy 294.29829 -163.516684) (xy 294.244329 -163.508932) (xy 294.19202 -163.493579)
			(xy 294.14243 -163.470937) (xy 294.096566 -163.441467) (xy 294.055364 -163.40577) (xy 294.019661 -163.364572)
			(xy 293.990186 -163.318713) (xy 293.967538 -163.269125) (xy 293.952178 -163.216818) (xy 293.944419 -163.162858)
			(xy 289.008503 -163.162858) (xy 288.997055 -163.176069) (xy 288.955854 -163.211767) (xy 288.909993 -163.241238)
			(xy 288.860404 -163.263883) (xy 288.808097 -163.279239) (xy 288.754137 -163.286994) (xy 288.72688 -163.287456)
			(xy 288.697483 -163.286921) (xy 288.639384 -163.277904) (xy 288.583355 -163.260086) (xy 288.530719 -163.233888)
			(xy 288.506408 -163.217352) (xy 288.494974 -163.209751) (xy 288.469142 -163.200464) (xy 288.441771 -163.198389)
			(xy 288.414834 -163.203674) (xy 288.390276 -163.215939) (xy 288.369869 -163.234298) (xy 288.355086 -163.257427)
			(xy 288.346992 -163.283656) (xy 288.346134 -163.297362) (xy 288.345044 -163.324122) (xy 288.336125 -163.376934)
			(xy 288.319905 -163.427978) (xy 288.296702 -163.476251) (xy 288.266973 -163.520802) (xy 288.231302 -163.560755)
			(xy 288.190393 -163.595324) (xy 288.145049 -163.623829) (xy 288.096162 -163.645709) (xy 288.044695 -163.660534)
			(xy 287.99166 -163.668011) (xy 287.96488 -163.668456) (xy 287.937633 -163.667872) (xy 287.883694 -163.660115)
			(xy 287.831409 -163.64476) (xy 287.78184 -163.62212) (xy 287.735998 -163.592657) (xy 287.694816 -163.55697)
			(xy 287.659131 -163.515786) (xy 287.62967 -163.469942) (xy 287.607033 -163.420373) (xy 287.591681 -163.368086)
			(xy 287.583926 -163.314147) (xy 287.134723 -163.314147) (xy 287.137829 -163.316732) (xy 287.175046 -163.358269)
			(xy 287.205819 -163.404782) (xy 287.229491 -163.455279) (xy 287.245559 -163.508686) (xy 287.253679 -163.563862)
			(xy 287.254188 -163.591748) (xy 287.253679 -163.619634) (xy 287.245559 -163.67481) (xy 287.229491 -163.728217)
			(xy 287.205819 -163.778714) (xy 287.175046 -163.825227) (xy 287.137829 -163.866764) (xy 287.094961 -163.902439)
			(xy 287.047355 -163.931493) (xy 286.996026 -163.953305) (xy 286.942069 -163.967411) (xy 286.886632 -163.973511)
			(xy 286.830898 -163.971474) (xy 286.776055 -163.961344) (xy 286.723271 -163.943337) (xy 286.673671 -163.917836)
			(xy 286.628313 -163.885385) (xy 286.588164 -163.846676) (xy 286.554078 -163.802533) (xy 286.526782 -163.753898)
			(xy 286.506859 -163.701807) (xy 286.494733 -163.64737) (xy 286.490662 -163.591748) (xy 285.900369 -163.591748)
			(xy 285.899359 -163.59861) (xy 285.883291 -163.652017) (xy 285.859619 -163.702514) (xy 285.828846 -163.749027)
			(xy 285.791629 -163.790564) (xy 285.748761 -163.826239) (xy 285.701155 -163.855293) (xy 285.649826 -163.877105)
			(xy 285.595869 -163.891211) (xy 285.540432 -163.897311) (xy 285.484698 -163.895274) (xy 285.429855 -163.885144)
			(xy 285.377071 -163.867137) (xy 285.327471 -163.841636) (xy 285.282113 -163.809185) (xy 285.241964 -163.770476)
			(xy 285.207878 -163.726333) (xy 285.180582 -163.677698) (xy 285.160659 -163.625607) (xy 285.148533 -163.57117)
			(xy 285.144462 -163.515548) (xy 244.357659 -163.515548) (xy 244.376046 -163.536069) (xy 244.406819 -163.582582)
			(xy 244.430491 -163.633079) (xy 244.446559 -163.686486) (xy 244.454679 -163.741662) (xy 244.455188 -163.769548)
			(xy 244.454679 -163.797434) (xy 244.446559 -163.85261) (xy 244.430491 -163.906017) (xy 244.406819 -163.956514)
			(xy 244.376046 -164.003027) (xy 244.338829 -164.044564) (xy 244.295961 -164.080239) (xy 244.248355 -164.109293)
			(xy 244.197026 -164.131105) (xy 244.143069 -164.145211) (xy 244.087632 -164.151311) (xy 244.031898 -164.149274)
			(xy 243.977055 -164.139144) (xy 243.924271 -164.121137) (xy 243.874671 -164.095636) (xy 243.829313 -164.063185)
			(xy 243.789164 -164.024476) (xy 243.755078 -163.980333) (xy 243.727782 -163.931698) (xy 243.707859 -163.879607)
			(xy 243.695733 -163.82517) (xy 243.691662 -163.769548) (xy 206.946808 -163.769548) (xy 206.311802 -164.404548)
			(xy 244.402862 -164.404548) (xy 244.406933 -164.348926) (xy 244.419059 -164.294489) (xy 244.438982 -164.242398)
			(xy 244.466278 -164.193763) (xy 244.500364 -164.14962) (xy 244.540513 -164.110911) (xy 244.585871 -164.07846)
			(xy 244.635471 -164.052959) (xy 244.688255 -164.034952) (xy 244.743098 -164.024822) (xy 244.798832 -164.022785)
			(xy 244.854269 -164.028885) (xy 244.908226 -164.042991) (xy 244.959555 -164.064803) (xy 245.007161 -164.093857)
			(xy 245.050029 -164.129532) (xy 245.087246 -164.171069) (xy 245.118019 -164.217582) (xy 245.141691 -164.268079)
			(xy 245.157759 -164.321486) (xy 245.165879 -164.376662) (xy 245.166388 -164.404548) (xy 245.165879 -164.432434)
			(xy 245.157759 -164.48761) (xy 245.141691 -164.541017) (xy 245.118019 -164.591514) (xy 245.087246 -164.638027)
			(xy 245.050029 -164.679564) (xy 245.007161 -164.715239) (xy 244.959555 -164.744293) (xy 244.908226 -164.766105)
			(xy 244.854269 -164.780211) (xy 244.798832 -164.786311) (xy 244.743098 -164.784274) (xy 244.688255 -164.774144)
			(xy 244.635471 -164.756137) (xy 244.585871 -164.730636) (xy 244.540513 -164.698185) (xy 244.500364 -164.659476)
			(xy 244.466278 -164.615333) (xy 244.438982 -164.566698) (xy 244.419059 -164.514607) (xy 244.406933 -164.46017)
			(xy 244.402862 -164.404548) (xy 206.311802 -164.404548) (xy 205.676796 -165.039548) (xy 243.691662 -165.039548)
			(xy 243.695733 -164.983926) (xy 243.707859 -164.929489) (xy 243.727782 -164.877398) (xy 243.755078 -164.828763)
			(xy 243.789164 -164.78462) (xy 243.829313 -164.745911) (xy 243.874671 -164.71346) (xy 243.924271 -164.687959)
			(xy 243.977055 -164.669952) (xy 244.031898 -164.659822) (xy 244.087632 -164.657785) (xy 244.143069 -164.663885)
			(xy 244.197026 -164.677991) (xy 244.248355 -164.699803) (xy 244.295961 -164.728857) (xy 244.338829 -164.764532)
			(xy 244.376046 -164.806069) (xy 244.406819 -164.852582) (xy 244.430491 -164.903079) (xy 244.446559 -164.956486)
			(xy 244.454679 -165.011662) (xy 244.455188 -165.039548) (xy 244.454679 -165.067434) (xy 244.446559 -165.12261)
			(xy 244.430491 -165.176017) (xy 244.406819 -165.226514) (xy 244.376046 -165.273027) (xy 244.338829 -165.314564)
			(xy 244.295961 -165.350239) (xy 244.248355 -165.379293) (xy 244.197026 -165.401105) (xy 244.143069 -165.415211)
			(xy 244.087632 -165.421311) (xy 244.031898 -165.419274) (xy 243.977055 -165.409144) (xy 243.924271 -165.391137)
			(xy 243.874671 -165.365636) (xy 243.829313 -165.333185) (xy 243.789164 -165.294476) (xy 243.755078 -165.250333)
			(xy 243.727782 -165.201698) (xy 243.707859 -165.149607) (xy 243.695733 -165.09517) (xy 243.691662 -165.039548)
			(xy 205.676796 -165.039548) (xy 205.125611 -165.590728) (xy 210.826602 -165.590728) (xy 210.830673 -165.535106)
			(xy 210.842799 -165.480669) (xy 210.862722 -165.428578) (xy 210.890018 -165.379943) (xy 210.924104 -165.3358)
			(xy 210.964253 -165.297091) (xy 211.009611 -165.26464) (xy 211.059211 -165.239139) (xy 211.111995 -165.221132)
			(xy 211.166838 -165.211002) (xy 211.222572 -165.208965) (xy 211.278009 -165.215065) (xy 211.331966 -165.229171)
			(xy 211.383295 -165.250983) (xy 211.430901 -165.280037) (xy 211.473769 -165.315712) (xy 211.510986 -165.357249)
			(xy 211.541759 -165.403762) (xy 211.565431 -165.454259) (xy 211.581499 -165.507666) (xy 211.589619 -165.562842)
			(xy 211.590128 -165.590728) (xy 211.589619 -165.618614) (xy 211.581499 -165.67379) (xy 211.581271 -165.674548)
			(xy 244.402862 -165.674548) (xy 244.406933 -165.618926) (xy 244.419059 -165.564489) (xy 244.438982 -165.512398)
			(xy 244.466278 -165.463763) (xy 244.500364 -165.41962) (xy 244.540513 -165.380911) (xy 244.585871 -165.34846)
			(xy 244.635471 -165.322959) (xy 244.688255 -165.304952) (xy 244.743098 -165.294822) (xy 244.798832 -165.292785)
			(xy 244.854269 -165.298885) (xy 244.908226 -165.312991) (xy 244.959555 -165.334803) (xy 245.007161 -165.363857)
			(xy 245.050029 -165.399532) (xy 245.087246 -165.441069) (xy 245.118019 -165.487582) (xy 245.141691 -165.538079)
			(xy 245.157759 -165.591486) (xy 245.165879 -165.646662) (xy 245.166388 -165.674548) (xy 245.165879 -165.702434)
			(xy 245.157759 -165.75761) (xy 245.141691 -165.811017) (xy 245.118019 -165.861514) (xy 245.087246 -165.908027)
			(xy 245.050029 -165.949564) (xy 245.007161 -165.985239) (xy 244.959555 -166.014293) (xy 244.908226 -166.036105)
			(xy 244.854269 -166.050211) (xy 244.798832 -166.056311) (xy 244.743098 -166.054274) (xy 244.688255 -166.044144)
			(xy 244.635471 -166.026137) (xy 244.585871 -166.000636) (xy 244.540513 -165.968185) (xy 244.500364 -165.929476)
			(xy 244.466278 -165.885333) (xy 244.438982 -165.836698) (xy 244.419059 -165.784607) (xy 244.406933 -165.73017)
			(xy 244.402862 -165.674548) (xy 211.581271 -165.674548) (xy 211.565431 -165.727197) (xy 211.541759 -165.777694)
			(xy 211.510986 -165.824207) (xy 211.473769 -165.865744) (xy 211.430901 -165.901419) (xy 211.383295 -165.930473)
			(xy 211.331966 -165.952285) (xy 211.278009 -165.966391) (xy 211.222572 -165.972491) (xy 211.166838 -165.970454)
			(xy 211.111995 -165.960324) (xy 211.059211 -165.942317) (xy 211.009611 -165.916816) (xy 210.964253 -165.884365)
			(xy 210.924104 -165.845656) (xy 210.890018 -165.801513) (xy 210.862722 -165.752878) (xy 210.842799 -165.700787)
			(xy 210.830673 -165.64635) (xy 210.826602 -165.590728) (xy 205.125611 -165.590728) (xy 203.845761 -166.870566)
			(xy 243.142789 -166.870566) (xy 243.150543 -166.816621) (xy 243.165894 -166.764329) (xy 243.188532 -166.714753)
			(xy 243.217994 -166.668904) (xy 243.253681 -166.627714) (xy 243.294867 -166.592021) (xy 243.340713 -166.562554)
			(xy 243.390285 -166.539911) (xy 243.442576 -166.524552) (xy 243.49652 -166.516792) (xy 243.52377 -166.516304)
			(xy 243.539658 -166.516487) (xy 243.571322 -166.519156) (xy 243.587016 -166.521638) (xy 243.60121 -166.523477)
			(xy 243.629622 -166.520112) (xy 243.65599 -166.509011) (xy 243.678253 -166.491042) (xy 243.69467 -166.467611)
			(xy 243.703956 -166.44055) (xy 243.705386 -166.411976) (xy 243.702586 -166.39794) (xy 243.697733 -166.376164)
			(xy 243.692516 -166.331855) (xy 243.692172 -166.309548) (xy 243.692604 -166.282291) (xy 243.700355 -166.22833)
			(xy 243.715708 -166.176022) (xy 243.738349 -166.126431) (xy 243.767817 -166.080567) (xy 243.803512 -166.039364)
			(xy 243.844708 -166.003661) (xy 243.890566 -165.974184) (xy 243.940153 -165.951534) (xy 243.992458 -165.936171)
			(xy 244.046417 -165.928409) (xy 244.100932 -165.928405) (xy 244.154892 -165.93616) (xy 244.2072 -165.951516)
			(xy 244.256789 -165.97416) (xy 244.302651 -166.00363) (xy 244.343852 -166.039328) (xy 244.379553 -166.080527)
			(xy 244.409027 -166.126386) (xy 244.431674 -166.175974) (xy 244.447034 -166.22828) (xy 244.454793 -166.28224)
			(xy 244.454793 -166.336755) (xy 244.447035 -166.390714) (xy 244.431676 -166.443021) (xy 244.40903 -166.492609)
			(xy 244.379556 -166.538469) (xy 244.343856 -166.579668) (xy 244.302655 -166.615366) (xy 244.256794 -166.644838)
			(xy 244.207205 -166.667482) (xy 244.154898 -166.682839) (xy 244.100937 -166.690594) (xy 244.07368 -166.691056)
			(xy 244.057792 -166.69088) (xy 244.026128 -166.688206) (xy 244.010434 -166.685722) (xy 243.996239 -166.683859)
			(xy 243.967818 -166.687214) (xy 243.94144 -166.698313) (xy 243.919169 -166.716286) (xy 243.902751 -166.739726)
			(xy 243.893471 -166.766798) (xy 243.892054 -166.795381) (xy 243.894864 -166.80942) (xy 243.899709 -166.831197)
			(xy 243.904932 -166.875505) (xy 243.905278 -166.897812) (xy 243.904809 -166.925062) (xy 243.902007 -166.944548)
			(xy 244.402862 -166.944548) (xy 244.406933 -166.888926) (xy 244.419059 -166.834489) (xy 244.438982 -166.782398)
			(xy 244.466278 -166.733763) (xy 244.500364 -166.68962) (xy 244.540513 -166.650911) (xy 244.585871 -166.61846)
			(xy 244.635471 -166.592959) (xy 244.688255 -166.574952) (xy 244.743098 -166.564822) (xy 244.798832 -166.562785)
			(xy 244.854269 -166.568885) (xy 244.908226 -166.582991) (xy 244.959555 -166.604803) (xy 245.007161 -166.633857)
			(xy 245.050029 -166.669532) (xy 245.087246 -166.711069) (xy 245.118019 -166.757582) (xy 245.141691 -166.808079)
			(xy 245.157759 -166.861486) (xy 245.165879 -166.916662) (xy 245.166388 -166.944548) (xy 245.165879 -166.972434)
			(xy 245.157759 -167.02761) (xy 245.141691 -167.081017) (xy 245.118019 -167.131514) (xy 245.087246 -167.178027)
			(xy 245.050029 -167.219564) (xy 245.007161 -167.255239) (xy 244.959555 -167.284293) (xy 244.908226 -167.306105)
			(xy 244.854269 -167.320211) (xy 244.798832 -167.326311) (xy 244.743098 -167.324274) (xy 244.688255 -167.314144)
			(xy 244.635471 -167.296137) (xy 244.585871 -167.270636) (xy 244.540513 -167.238185) (xy 244.500364 -167.199476)
			(xy 244.466278 -167.155333) (xy 244.438982 -167.106698) (xy 244.419059 -167.054607) (xy 244.406933 -167.00017)
			(xy 244.402862 -166.944548) (xy 243.902007 -166.944548) (xy 243.897051 -166.979006) (xy 243.881696 -167.031298)
			(xy 243.859055 -167.080872) (xy 243.829589 -167.126719) (xy 243.793899 -167.167906) (xy 243.752711 -167.203595)
			(xy 243.706863 -167.23306) (xy 243.657288 -167.255699) (xy 243.604996 -167.271053) (xy 243.551052 -167.27881)
			(xy 243.496552 -167.27881) (xy 243.442607 -167.271054) (xy 243.390315 -167.255701) (xy 243.340741 -167.233062)
			(xy 243.294892 -167.203598) (xy 243.253704 -167.167909) (xy 243.218013 -167.126722) (xy 243.188547 -167.080875)
			(xy 243.165906 -167.031301) (xy 243.15055 -166.97901) (xy 243.142791 -166.925066) (xy 243.142789 -166.870566)
			(xy 203.845761 -166.870566) (xy 202.445065 -168.271249) (xy 243.17099 -168.271249) (xy 243.17099 -168.216751)
			(xy 243.178745 -168.162808) (xy 243.194098 -168.110518) (xy 243.216736 -168.060945) (xy 243.246198 -168.015098)
			(xy 243.281884 -167.97391) (xy 243.323069 -167.93822) (xy 243.368913 -167.908753) (xy 243.418485 -167.886111)
			(xy 243.470773 -167.870753) (xy 243.524715 -167.862993) (xy 243.551964 -167.862504) (xy 243.567143 -167.862653)
			(xy 243.597405 -167.865072) (xy 243.612416 -167.86733) (xy 243.625849 -167.869027) (xy 243.652759 -167.866136)
			(xy 243.677964 -167.856274) (xy 243.699689 -167.840133) (xy 243.716409 -167.81885) (xy 243.726946 -167.793921)
			(xy 243.730561 -167.767098) (xy 243.726998 -167.740269) (xy 243.722144 -167.72763) (xy 243.712679 -167.704102)
			(xy 243.699353 -167.655169) (xy 243.692607 -167.604905) (xy 243.692172 -167.579548) (xy 243.692604 -167.552291)
			(xy 243.700355 -167.49833) (xy 243.715708 -167.446022) (xy 243.738349 -167.396431) (xy 243.767817 -167.350567)
			(xy 243.803512 -167.309364) (xy 243.844708 -167.273661) (xy 243.890566 -167.244184) (xy 243.940153 -167.221534)
			(xy 243.992458 -167.206171) (xy 244.046417 -167.198409) (xy 244.100932 -167.198405) (xy 244.154892 -167.20616)
			(xy 244.2072 -167.221516) (xy 244.256789 -167.24416) (xy 244.302651 -167.27363) (xy 244.343852 -167.309328)
			(xy 244.379553 -167.350527) (xy 244.409027 -167.396386) (xy 244.431674 -167.445974) (xy 244.447034 -167.49828)
			(xy 244.454793 -167.55224) (xy 244.454793 -167.606755) (xy 244.447035 -167.660714) (xy 244.431676 -167.713021)
			(xy 244.40903 -167.762609) (xy 244.379556 -167.808469) (xy 244.343856 -167.849668) (xy 244.302655 -167.885366)
			(xy 244.256794 -167.914838) (xy 244.207205 -167.937482) (xy 244.154898 -167.952839) (xy 244.100937 -167.960594)
			(xy 244.07368 -167.961056) (xy 244.058501 -167.960903) (xy 244.028239 -167.958486) (xy 244.013228 -167.95623)
			(xy 243.999797 -167.954536) (xy 243.972894 -167.957438) (xy 243.947698 -167.967306) (xy 243.925979 -167.983447)
			(xy 243.909263 -168.004726) (xy 243.898724 -168.029649) (xy 243.895103 -168.056465) (xy 243.898654 -168.083291)
			(xy 243.9035 -168.09593) (xy 243.91295 -168.119464) (xy 243.926283 -168.168393) (xy 243.933034 -168.218656)
			(xy 243.933472 -168.244012) (xy 243.932994 -168.271457) (xy 243.925093 -168.325777) (xy 243.909483 -168.378402)
			(xy 243.89842 -168.403524) (xy 243.893133 -168.415967) (xy 243.888615 -168.442613) (xy 243.891249 -168.46951)
			(xy 243.900852 -168.494772) (xy 243.91675 -168.516628) (xy 243.937828 -168.533544) (xy 243.962606 -168.544334)
			(xy 243.989348 -168.548241) (xy 244.002814 -168.547034) (xy 244.014136 -168.545738) (xy 244.036884 -168.544339)
			(xy 244.04828 -168.54424) (xy 244.078403 -168.544826) (xy 244.137898 -168.554304) (xy 244.195166 -168.573011)
			(xy 244.248783 -168.600484) (xy 244.297419 -168.636039) (xy 244.319044 -168.657016) (xy 244.328766 -168.666234)
			(xy 244.351928 -168.679679) (xy 244.377789 -168.686641) (xy 244.404571 -168.686641) (xy 244.430432 -168.679679)
			(xy 244.453594 -168.666234) (xy 244.463316 -168.657016) (xy 244.47142 -168.648955) (xy 244.488448 -168.633703)
			(xy 244.497352 -168.626536) (xy 244.508062 -168.617384) (xy 244.524524 -168.594541) (xy 244.534126 -168.568073)
			(xy 244.536138 -168.539988) (xy 244.530407 -168.512421) (xy 244.517369 -168.487465) (xy 244.50802 -168.47693)
			(xy 244.488513 -168.45553) (xy 244.455469 -168.407983) (xy 244.429995 -168.355985) (xy 244.412677 -168.300734)
			(xy 244.403914 -168.243499) (xy 244.403372 -168.214548) (xy 244.403858 -168.187297) (xy 244.411614 -168.133349)
			(xy 244.426969 -168.081054) (xy 244.449611 -168.031477) (xy 244.479077 -167.985627) (xy 244.514768 -167.944436)
			(xy 244.555959 -167.908745) (xy 244.601809 -167.879279) (xy 244.651386 -167.856637) (xy 244.703681 -167.841282)
			(xy 244.757629 -167.833526) (xy 244.812131 -167.833526) (xy 244.866079 -167.841282) (xy 244.918374 -167.856637)
			(xy 244.967951 -167.879279) (xy 245.013801 -167.908745) (xy 245.054992 -167.944436) (xy 245.090683 -167.985627)
			(xy 245.120149 -168.031477) (xy 245.142791 -168.081054) (xy 245.158146 -168.133349) (xy 245.165902 -168.187297)
			(xy 245.166388 -168.214548) (xy 245.165905 -168.243226) (xy 245.157325 -168.299935) (xy 245.140351 -168.354721)
			(xy 245.115365 -168.406347) (xy 245.082931 -168.453651) (xy 245.04378 -168.495565) (xy 245.021608 -168.51376)
			(xy 245.010808 -168.522813) (xy 244.994354 -168.545684) (xy 244.984766 -168.572177) (xy 244.982771 -168.600281)
			(xy 244.988521 -168.627862) (xy 245.00158 -168.652828) (xy 245.01094 -168.663366) (xy 245.030503 -168.684717)
			(xy 245.063537 -168.732279) (xy 245.088999 -168.784289) (xy 245.106304 -168.839551) (xy 245.115053 -168.896794)
			(xy 245.115588 -168.925748) (xy 245.115167 -168.953001) (xy 245.107403 -169.006952) (xy 245.092041 -169.05925)
			(xy 245.069393 -169.108828) (xy 245.03992 -169.154679) (xy 245.004221 -169.19587) (xy 244.963025 -169.23156)
			(xy 244.917169 -169.261025) (xy 244.867586 -169.283665) (xy 244.815286 -169.299018) (xy 244.761333 -169.306772)
			(xy 244.73408 -169.307256) (xy 244.703956 -169.306696) (xy 244.644459 -169.297212) (xy 244.587191 -169.278499)
			(xy 244.533575 -169.25102) (xy 244.484941 -169.21546) (xy 244.463316 -169.19448) (xy 244.453594 -169.185262)
			(xy 244.430432 -169.171817) (xy 244.404571 -169.164855) (xy 244.377789 -169.164855) (xy 244.351928 -169.171817)
			(xy 244.328766 -169.185262) (xy 244.319044 -169.19448) (xy 244.29742 -169.215461) (xy 244.248791 -169.25103)
			(xy 244.195175 -169.27851) (xy 244.137904 -169.297218) (xy 244.078404 -169.306688) (xy 244.04828 -169.307256)
			(xy 244.02103 -169.306741) (xy 243.967086 -169.298983) (xy 243.914795 -169.283628) (xy 243.865221 -169.260988)
			(xy 243.819373 -169.231524) (xy 243.778184 -169.195836) (xy 243.742493 -169.15465) (xy 243.713026 -169.108804)
			(xy 243.690382 -169.059231) (xy 243.675023 -169.006941) (xy 243.667261 -168.952998) (xy 243.666772 -168.925748)
			(xy 243.667275 -168.898304) (xy 243.675167 -168.843985) (xy 243.690766 -168.791359) (xy 243.701824 -168.766236)
			(xy 243.707115 -168.753797) (xy 243.711621 -168.727153) (xy 243.708979 -168.70026) (xy 243.699373 -168.675003)
			(xy 243.683477 -168.653151) (xy 243.662404 -168.636235) (xy 243.637631 -168.625441) (xy 243.610894 -168.621525)
			(xy 243.59743 -168.622726) (xy 243.586108 -168.624027) (xy 243.56336 -168.625423) (xy 243.551964 -168.62552)
			(xy 243.524715 -168.625007) (xy 243.470773 -168.617247) (xy 243.418485 -168.601889) (xy 243.368913 -168.579247)
			(xy 243.323069 -168.54978) (xy 243.281884 -168.51409) (xy 243.246198 -168.472902) (xy 243.216736 -168.427055)
			(xy 243.194098 -168.377482) (xy 243.178745 -168.325192) (xy 243.17099 -168.271249) (xy 202.445065 -168.271249)
			(xy 201.196448 -169.519854) (xy 158.808928 -169.519854) (xy 156.14904 -172.179742) (xy 156.14904 -185.643266)
			(xy 323.614286 -185.643266) (xy 323.618357 -185.587644) (xy 323.630483 -185.533207) (xy 323.650406 -185.481116)
			(xy 323.677702 -185.432481) (xy 323.711788 -185.388338) (xy 323.751937 -185.349629) (xy 323.797295 -185.317178)
			(xy 323.846895 -185.291677) (xy 323.899679 -185.27367) (xy 323.954522 -185.26354) (xy 324.010256 -185.261503)
			(xy 324.065693 -185.267603) (xy 324.11965 -185.281709) (xy 324.170979 -185.303521) (xy 324.218585 -185.332575)
			(xy 324.261453 -185.36825) (xy 324.29867 -185.409787) (xy 324.329443 -185.4563) (xy 324.353115 -185.506797)
			(xy 324.369183 -185.560204) (xy 324.377303 -185.61538) (xy 324.377812 -185.643266) (xy 324.377303 -185.671152)
			(xy 324.369183 -185.726328) (xy 324.353115 -185.779735) (xy 324.329443 -185.830232) (xy 324.29867 -185.876745)
			(xy 324.261453 -185.918282) (xy 324.218585 -185.953957) (xy 324.170979 -185.983011) (xy 324.11965 -186.004823)
			(xy 324.065693 -186.018929) (xy 324.010256 -186.025029) (xy 323.954522 -186.022992) (xy 323.899679 -186.012862)
			(xy 323.846895 -185.994855) (xy 323.797295 -185.969354) (xy 323.751937 -185.936903) (xy 323.711788 -185.898194)
			(xy 323.677702 -185.854051) (xy 323.650406 -185.805416) (xy 323.630483 -185.753325) (xy 323.618357 -185.698888)
			(xy 323.614286 -185.643266) (xy 156.14904 -185.643266) (xy 156.14904 -187.402246) (xy 219.056016 -187.402246)
			(xy 219.056016 -187.347754) (xy 219.06377 -187.293816) (xy 219.079122 -187.24153) (xy 219.101757 -187.191961)
			(xy 219.131215 -187.146118) (xy 219.166898 -187.104933) (xy 219.208078 -187.069245) (xy 219.253918 -187.039781)
			(xy 219.303483 -187.017139) (xy 219.355767 -187.001781) (xy 219.409704 -186.99402) (xy 219.43695 -186.99353)
			(xy 219.464767 -186.994015) (xy 219.519812 -187.002097) (xy 219.573101 -187.018083) (xy 219.623505 -187.041633)
			(xy 219.647008 -187.056522) (xy 219.658852 -187.063811) (xy 219.685337 -187.072263) (xy 219.71312 -187.07327)
			(xy 219.740149 -187.066758) (xy 219.764425 -187.053209) (xy 219.784155 -187.033622) (xy 219.797883 -187.009446)
			(xy 219.801694 -186.99607) (xy 219.808889 -186.968777) (xy 219.83024 -186.91653) (xy 219.859055 -186.867998)
			(xy 219.894705 -186.824241) (xy 219.936411 -186.786212) (xy 219.983265 -186.754742) (xy 220.034243 -186.730518)
			(xy 220.088234 -186.714067) (xy 220.144059 -186.70575) (xy 220.17228 -186.70524) (xy 220.199537 -186.705606)
			(xy 220.253497 -186.713361) (xy 220.305804 -186.728717) (xy 220.355393 -186.751362) (xy 220.401254 -186.780833)
			(xy 220.442455 -186.816531) (xy 220.478155 -186.85773) (xy 220.507629 -186.903589) (xy 220.530276 -186.953177)
			(xy 220.545635 -187.005483) (xy 220.552937 -187.056268) (xy 224.487232 -187.056268) (xy 224.487718 -187.029017)
			(xy 224.495474 -186.975069) (xy 224.510829 -186.922774) (xy 224.533471 -186.873197) (xy 224.562937 -186.827347)
			(xy 224.598628 -186.786156) (xy 224.639819 -186.750465) (xy 224.685669 -186.720999) (xy 224.735246 -186.698357)
			(xy 224.787541 -186.683002) (xy 224.841489 -186.675246) (xy 224.895991 -186.675246) (xy 224.949939 -186.683002)
			(xy 225.002234 -186.698357) (xy 225.051811 -186.720999) (xy 225.078348 -186.738053) (xy 261.406583 -186.738053)
			(xy 261.406583 -186.683547) (xy 261.414341 -186.629597) (xy 261.429698 -186.5773) (xy 261.452342 -186.52772)
			(xy 261.481811 -186.481869) (xy 261.517506 -186.440678) (xy 261.558701 -186.404987) (xy 261.604556 -186.375522)
			(xy 261.654137 -186.352884) (xy 261.706436 -186.337532) (xy 261.760387 -186.329781) (xy 261.78764 -186.32932)
			(xy 261.815467 -186.329822) (xy 261.870531 -186.3379) (xy 261.923837 -186.353894) (xy 261.974254 -186.377464)
			(xy 262.02071 -186.408109) (xy 262.06222 -186.44518) (xy 262.097903 -186.487889) (xy 262.127002 -186.53533)
			(xy 262.138414 -186.560714) (xy 262.144596 -186.573893) (xy 262.1631 -186.596347) (xy 262.187182 -186.612676)
			(xy 262.214891 -186.621555) (xy 262.243978 -186.622264) (xy 262.272087 -186.614746) (xy 262.296936 -186.599611)
			(xy 262.30707 -186.589162) (xy 262.325226 -186.569825) (xy 262.365943 -186.535833) (xy 262.41098 -186.507817)
			(xy 262.459468 -186.486317) (xy 262.510469 -186.47175) (xy 262.562998 -186.464396) (xy 262.589518 -186.46394)
			(xy 262.617975 -186.464429) (xy 262.674264 -186.472841) (xy 262.728675 -186.489537) (xy 262.779995 -186.514142)
			(xy 262.827082 -186.546111) (xy 262.848344 -186.565032) (xy 262.859846 -186.574799) (xy 262.887017 -186.587877)
			(xy 262.91682 -186.592463) (xy 262.946666 -186.588157) (xy 262.973958 -186.575334) (xy 262.996324 -186.555109)
			(xy 263.011819 -186.52924) (xy 263.015984 -186.51474) (xy 263.023198 -186.487489) (xy 263.044578 -186.435329)
			(xy 263.0734 -186.386883) (xy 263.109039 -186.343207) (xy 263.150716 -186.30525) (xy 263.197526 -186.27384)
			(xy 263.248448 -186.249661) (xy 263.302375 -186.233238) (xy 263.35813 -186.22493) (xy 263.386316 -186.224418)
			(xy 263.413568 -186.224853) (xy 263.467518 -186.232612) (xy 263.519814 -186.247969) (xy 263.569393 -186.270613)
			(xy 263.615245 -186.300082) (xy 263.656436 -186.335776) (xy 263.692128 -186.376968) (xy 263.721595 -186.422821)
			(xy 263.744236 -186.472401) (xy 263.759592 -186.524698) (xy 263.767348 -186.578648) (xy 263.767348 -186.633152)
			(xy 263.759592 -186.687102) (xy 263.744236 -186.739399) (xy 263.721595 -186.788979) (xy 263.692128 -186.834832)
			(xy 263.656436 -186.876024) (xy 263.615245 -186.911718) (xy 263.569393 -186.941187) (xy 263.519814 -186.963831)
			(xy 263.467518 -186.979188) (xy 263.413568 -186.986947) (xy 263.386316 -186.987434) (xy 263.35786 -186.986905)
			(xy 263.301574 -186.978499) (xy 263.247165 -186.961812) (xy 263.195844 -186.937216) (xy 263.148754 -186.905258)
			(xy 263.12749 -186.886342) (xy 263.116043 -186.876509) (xy 263.088856 -186.863441) (xy 263.059041 -186.858867)
			(xy 263.029187 -186.863184) (xy 263.001889 -186.876017) (xy 262.979518 -186.896252) (xy 262.964018 -186.922129)
			(xy 262.95985 -186.936634) (xy 262.952679 -186.963898) (xy 262.931298 -187.016062) (xy 262.902472 -187.064511)
			(xy 262.866829 -187.10819) (xy 262.825145 -187.146147) (xy 262.778329 -187.177555) (xy 262.7274 -187.201731)
			(xy 262.673467 -187.218148) (xy 262.617706 -187.226448) (xy 262.589518 -187.226956) (xy 262.561692 -187.22642)
			(xy 262.506628 -187.218349) (xy 262.453322 -187.202362) (xy 262.402906 -187.178798) (xy 262.356449 -187.148157)
			(xy 262.314938 -187.11109) (xy 262.279254 -187.068384) (xy 262.250156 -187.020945) (xy 262.238744 -186.995562)
			(xy 262.232625 -186.982351) (xy 262.214108 -186.959896) (xy 262.190012 -186.943569) (xy 262.162293 -186.934694)
			(xy 262.133195 -186.933991) (xy 262.105079 -186.941517) (xy 262.080224 -186.956661) (xy 262.070088 -186.967114)
			(xy 262.051947 -186.986466) (xy 262.011228 -187.020457) (xy 261.966187 -187.048473) (xy 261.917696 -187.06997)
			(xy 261.866692 -187.084533) (xy 261.814161 -187.091882) (xy 261.78764 -187.092336) (xy 261.760387 -187.091819)
			(xy 261.706436 -187.084068) (xy 261.654137 -187.068716) (xy 261.604556 -187.046078) (xy 261.558701 -187.016613)
			(xy 261.517506 -186.980922) (xy 261.481811 -186.939731) (xy 261.452342 -186.89388) (xy 261.429698 -186.8443)
			(xy 261.414341 -186.792003) (xy 261.406583 -186.738053) (xy 225.078348 -186.738053) (xy 225.097661 -186.750465)
			(xy 225.138852 -186.786156) (xy 225.174543 -186.827347) (xy 225.204009 -186.873197) (xy 225.226651 -186.922774)
			(xy 225.242006 -186.975069) (xy 225.249762 -187.029017) (xy 225.250248 -187.056268) (xy 225.249676 -187.087019)
			(xy 225.239812 -187.147724) (xy 225.220334 -187.20606) (xy 225.20656 -187.23356) (xy 225.200032 -187.247284)
			(xy 225.194442 -187.277137) (xy 225.197878 -187.307313) (xy 225.210037 -187.335145) (xy 225.229843 -187.35817)
			(xy 225.255544 -187.374352) (xy 225.27006 -187.378848) (xy 225.293174 -187.385706) (xy 225.30773 -187.389945)
			(xy 225.338017 -187.390732) (xy 225.367205 -187.382606) (xy 225.392727 -187.366279) (xy 225.412341 -187.343188)
			(xy 225.424323 -187.31536) (xy 225.426524 -187.300362) (xy 225.429971 -187.272615) (xy 225.443969 -187.218482)
			(xy 225.465714 -187.16697) (xy 225.494739 -187.11918) (xy 225.530425 -187.076136) (xy 225.572008 -187.038757)
			(xy 225.618599 -187.007844) (xy 225.6692 -186.984057) (xy 225.72273 -186.967906) (xy 225.778043 -186.959736)
			(xy 225.806 -186.95924) (xy 225.833255 -186.95963) (xy 225.887209 -186.967387) (xy 225.939511 -186.982744)
			(xy 225.989094 -187.005388) (xy 226.03495 -187.034858) (xy 226.076146 -187.070554) (xy 226.111842 -187.11175)
			(xy 226.141312 -187.157606) (xy 226.163956 -187.207189) (xy 226.179313 -187.259491) (xy 226.18707 -187.313445)
			(xy 226.18707 -187.367955) (xy 226.179313 -187.421909) (xy 226.163956 -187.474211) (xy 226.141312 -187.523794)
			(xy 226.111842 -187.56965) (xy 226.076146 -187.610846) (xy 226.03495 -187.646542) (xy 225.989094 -187.676012)
			(xy 225.939511 -187.698656) (xy 225.887209 -187.714013) (xy 225.833255 -187.72177) (xy 225.806 -187.722256)
			(xy 225.77489 -187.721659) (xy 225.713494 -187.711572) (xy 225.683826 -187.70219) (xy 225.669269 -187.697954)
			(xy 225.638983 -187.697167) (xy 225.609796 -187.705294) (xy 225.584274 -187.721619) (xy 225.56466 -187.74471)
			(xy 225.552677 -187.772536) (xy 225.550476 -187.787534) (xy 225.546791 -187.816968) (xy 225.531438 -187.874265)
			(xy 225.507412 -187.9285) (xy 225.475291 -187.978369) (xy 225.455988 -188.000894) (xy 225.447183 -188.011384)
			(xy 225.435089 -188.03595) (xy 225.429952 -188.062845) (xy 225.432139 -188.090138) (xy 225.441495 -188.115871)
			(xy 225.457347 -188.138197) (xy 225.467672 -188.147198) (xy 225.489256 -188.165411) (xy 225.527327 -188.207123)
			(xy 225.558834 -188.253992) (xy 225.583086 -188.304994) (xy 225.599554 -188.359014) (xy 225.607879 -188.414871)
			(xy 225.608388 -188.443108) (xy 225.607902 -188.470359) (xy 225.600146 -188.524307) (xy 225.584791 -188.576602)
			(xy 225.562149 -188.626179) (xy 225.532683 -188.672029) (xy 225.496992 -188.71322) (xy 225.455801 -188.748911)
			(xy 225.409951 -188.778377) (xy 225.360374 -188.801019) (xy 225.308079 -188.816374) (xy 225.254131 -188.82413)
			(xy 225.199629 -188.82413) (xy 225.145681 -188.816374) (xy 225.093386 -188.801019) (xy 225.043809 -188.778377)
			(xy 224.997959 -188.748911) (xy 224.956768 -188.71322) (xy 224.921077 -188.672029) (xy 224.891611 -188.626179)
			(xy 224.868969 -188.576602) (xy 224.853614 -188.524307) (xy 224.845858 -188.470359) (xy 224.845372 -188.443108)
			(xy 224.845857 -188.415339) (xy 224.853904 -188.360388) (xy 224.869829 -188.307182) (xy 224.893295 -188.256845)
			(xy 224.923808 -188.210441) (xy 224.941892 -188.189362) (xy 224.950641 -188.178828) (xy 224.962743 -188.154276)
			(xy 224.96789 -188.127393) (xy 224.965713 -188.100108) (xy 224.956369 -188.07438) (xy 224.940528 -188.052058)
			(xy 224.930208 -188.043058) (xy 224.908599 -188.024873) (xy 224.87053 -187.983155) (xy 224.839028 -187.93628)
			(xy 224.81478 -187.885273) (xy 224.798317 -187.831248) (xy 224.789998 -187.775387) (xy 224.789492 -187.747148)
			(xy 224.790077 -187.716398) (xy 224.799937 -187.655693) (xy 224.819409 -187.597356) (xy 224.83318 -187.569856)
			(xy 224.839663 -187.556113) (xy 224.845253 -187.52627) (xy 224.841821 -187.496103) (xy 224.829672 -187.468277)
			(xy 224.809878 -187.445254) (xy 224.784189 -187.429069) (xy 224.76968 -187.424568) (xy 224.743021 -187.41691)
			(xy 224.692106 -187.394906) (xy 224.644915 -187.36576) (xy 224.602443 -187.330087) (xy 224.565584 -187.288639)
			(xy 224.535117 -187.24229) (xy 224.511683 -187.192017) (xy 224.495778 -187.138881) (xy 224.487735 -187.084001)
			(xy 224.487232 -187.056268) (xy 220.552937 -187.056268) (xy 220.553393 -187.059443) (xy 220.553393 -187.113957)
			(xy 220.545635 -187.167917) (xy 220.530276 -187.220223) (xy 220.507629 -187.269811) (xy 220.478155 -187.31567)
			(xy 220.442455 -187.356869) (xy 220.401254 -187.392567) (xy 220.355393 -187.422038) (xy 220.305804 -187.444683)
			(xy 220.253497 -187.460039) (xy 220.199537 -187.467794) (xy 220.17228 -187.468256) (xy 220.144463 -187.467759)
			(xy 220.089419 -187.459681) (xy 220.03613 -187.443699) (xy 219.985725 -187.420151) (xy 219.962222 -187.405264)
			(xy 219.950353 -187.39802) (xy 219.923876 -187.389566) (xy 219.896101 -187.388554) (xy 219.869079 -187.395059)
			(xy 219.844807 -187.4086) (xy 219.825077 -187.428177) (xy 219.811349 -187.452344) (xy 219.807536 -187.465716)
			(xy 219.800304 -187.492998) (xy 219.778957 -187.545243) (xy 219.750147 -187.593774) (xy 219.714502 -187.637532)
			(xy 219.6728 -187.675561) (xy 219.625951 -187.707032) (xy 219.574977 -187.731259) (xy 219.520991 -187.747713)
			(xy 219.465169 -187.756034) (xy 219.43695 -187.756546) (xy 219.409704 -187.75598) (xy 219.355767 -187.748219)
			(xy 219.303483 -187.732861) (xy 219.253918 -187.710219) (xy 219.208078 -187.680755) (xy 219.166898 -187.645067)
			(xy 219.131215 -187.603882) (xy 219.101757 -187.558039) (xy 219.079122 -187.50847) (xy 219.06377 -187.456184)
			(xy 219.056016 -187.402246) (xy 156.14904 -187.402246) (xy 156.14904 -187.46343) (xy 156.19095 -187.47105)
			(xy 156.222075 -187.477217) (xy 156.281843 -187.498512) (xy 156.337249 -187.529428) (xy 156.3624 -187.548774)
			(xy 156.374684 -187.557945) (xy 156.403205 -187.569152) (xy 156.433765 -187.571401) (xy 156.463619 -187.564489)
			(xy 156.490081 -187.549038) (xy 156.50083 -187.538106) (xy 156.51897 -187.518979) (xy 156.559605 -187.485398)
			(xy 156.604474 -187.457729) (xy 156.652725 -187.4365) (xy 156.703439 -187.422114) (xy 156.755651 -187.414846)
			(xy 156.782008 -187.414408) (xy 156.809258 -187.414895) (xy 156.863202 -187.422652) (xy 156.915494 -187.438007)
			(xy 156.965068 -187.460648) (xy 157.010915 -187.490113) (xy 157.052103 -187.525803) (xy 157.087792 -187.566991)
			(xy 157.117256 -187.612839) (xy 157.139896 -187.662414) (xy 157.15525 -187.714706) (xy 157.163006 -187.76865)
			(xy 157.163006 -187.82315) (xy 157.15525 -187.877094) (xy 157.139896 -187.929386) (xy 157.117256 -187.978961)
			(xy 157.087792 -188.024809) (xy 157.052103 -188.065997) (xy 157.010915 -188.101687) (xy 156.965068 -188.131152)
			(xy 156.915494 -188.153793) (xy 156.863202 -188.169148) (xy 156.809258 -188.176905) (xy 156.782008 -188.177424)
			(xy 156.756203 -188.177016) (xy 156.705062 -188.170091) (xy 156.655323 -188.156327) (xy 156.607897 -188.135975)
			(xy 156.563652 -188.109407) (xy 156.543248 -188.093604) (xy 156.530962 -188.084427) (xy 156.502436 -188.073208)
			(xy 156.471867 -188.070949) (xy 156.442002 -188.077851) (xy 156.415525 -188.093295) (xy 156.404818 -188.104272)
			(xy 156.387731 -188.122327) (xy 156.349666 -188.154299) (xy 156.307764 -188.181044) (xy 156.262737 -188.202108)
			(xy 156.215352 -188.217133) (xy 156.19095 -188.221874) (xy 156.14904 -188.229494) (xy 156.14904 -190.078955)
			(xy 157.987145 -190.078955) (xy 157.987145 -190.024445) (xy 157.994903 -189.970489) (xy 158.010262 -189.918187)
			(xy 158.032907 -189.868603) (xy 158.06238 -189.822746) (xy 158.098079 -189.781552) (xy 158.139277 -189.745857)
			(xy 158.185136 -189.716389) (xy 158.234722 -189.693748) (xy 158.287026 -189.678395) (xy 158.340983 -189.670642)
			(xy 158.368238 -189.670182) (xy 158.396243 -189.670668) (xy 158.451655 -189.67884) (xy 158.505278 -189.695017)
			(xy 158.555964 -189.718854) (xy 158.579566 -189.733936) (xy 158.591444 -189.741245) (xy 158.617964 -189.749832)
			(xy 158.645817 -189.750936) (xy 158.672933 -189.744474) (xy 158.697295 -189.730926) (xy 158.717092 -189.711301)
			(xy 158.724346 -189.699392) (xy 158.730535 -189.688534) (xy 158.744133 -189.667561) (xy 158.751524 -189.657482)
			(xy 158.759955 -189.645436) (xy 158.770238 -189.617906) (xy 158.772258 -189.588588) (xy 158.765847 -189.559907)
			(xy 158.751536 -189.534239) (xy 158.741364 -189.523624) (xy 158.720066 -189.501957) (xy 158.683951 -189.453105)
			(xy 158.656034 -189.399145) (xy 158.637023 -189.341444) (xy 158.627397 -189.281458) (xy 158.62681 -189.251082)
			(xy 158.627261 -189.223829) (xy 158.635021 -189.16988) (xy 158.650379 -189.117583) (xy 158.673023 -189.068005)
			(xy 158.702493 -189.022153) (xy 158.738188 -188.980963) (xy 158.779382 -188.945272) (xy 158.825236 -188.915806)
			(xy 158.874817 -188.893166) (xy 158.927115 -188.877813) (xy 158.981065 -188.870059) (xy 159.008318 -188.869574)
			(xy 159.034777 -188.87003) (xy 159.087186 -188.87734) (xy 159.138085 -188.891817) (xy 159.186496 -188.913184)
			(xy 159.209232 -188.926724) (xy 159.220859 -188.933517) (xy 159.246649 -188.941242) (xy 159.273562 -188.941958)
			(xy 159.299727 -188.935617) (xy 159.323326 -188.922659) (xy 159.342718 -188.903985) (xy 159.356557 -188.880891)
			(xy 159.360616 -188.86805) (xy 159.372607 -188.827444) (xy 159.403049 -188.748434) (xy 159.440662 -188.672575)
			(xy 159.485122 -188.600515) (xy 159.536051 -188.532872) (xy 159.593012 -188.470224) (xy 159.655519 -188.413107)
			(xy 159.723035 -188.36201) (xy 159.794984 -188.31737) (xy 159.870749 -188.279568) (xy 159.949683 -188.24893)
			(xy 160.031111 -188.225715) (xy 160.114335 -188.210124) (xy 160.198644 -188.20229) (xy 160.24098 -188.201808)
			(xy 161.48558 -188.201808) (xy 161.527858 -188.202248) (xy 161.612054 -188.210049) (xy 161.695171 -188.225584)
			(xy 161.7765 -188.248723) (xy 161.855347 -188.279267) (xy 161.931039 -188.316955) (xy 162.002931 -188.361468)
			(xy 162.070409 -188.412423) (xy 162.132898 -188.469388) (xy 162.189864 -188.531875) (xy 162.240821 -188.599352)
			(xy 162.285335 -188.671243) (xy 162.323025 -188.746935) (xy 162.353571 -188.825781) (xy 162.376711 -188.90711)
			(xy 162.392249 -188.990226) (xy 162.400051 -189.074422) (xy 162.400051 -189.158975) (xy 166.870396 -189.158975)
			(xy 166.870396 -189.074425) (xy 166.878197 -188.990236) (xy 166.893733 -188.907126) (xy 166.916871 -188.825804)
			(xy 166.947413 -188.746963) (xy 166.9851 -188.671277) (xy 167.029609 -188.599391) (xy 167.080561 -188.531919)
			(xy 167.137521 -188.469435) (xy 167.200003 -188.412474) (xy 167.267475 -188.36152) (xy 167.33936 -188.31701)
			(xy 167.415045 -188.279321) (xy 167.493885 -188.248777) (xy 167.575207 -188.225638) (xy 167.658316 -188.2101)
			(xy 167.742505 -188.202297) (xy 167.78478 -188.201808) (xy 169.02938 -188.201808) (xy 169.071657 -188.202284)
			(xy 169.15585 -188.210084) (xy 169.238965 -188.22562) (xy 169.320292 -188.248758) (xy 169.399136 -188.279301)
			(xy 169.474826 -188.316989) (xy 169.546716 -188.361501) (xy 169.614192 -188.412456) (xy 169.676678 -188.469419)
			(xy 169.733642 -188.531905) (xy 169.784597 -188.599381) (xy 169.829109 -188.67127) (xy 169.847068 -188.707338)
			(xy 170.207199 -188.707338) (xy 170.207201 -188.65284) (xy 170.214958 -188.598896) (xy 170.230314 -188.546606)
			(xy 170.252954 -188.497033) (xy 170.282419 -188.451187) (xy 170.318109 -188.41) (xy 170.359296 -188.374312)
			(xy 170.405143 -188.344848) (xy 170.454717 -188.322209) (xy 170.507008 -188.306856) (xy 170.560952 -188.2991)
			(xy 170.61545 -188.2991) (xy 170.669393 -188.306856) (xy 170.721684 -188.32221) (xy 170.771258 -188.344849)
			(xy 170.817105 -188.374313) (xy 170.858292 -188.410001) (xy 170.893982 -188.451188) (xy 170.923447 -188.497034)
			(xy 170.924223 -188.498734) (xy 171.80128 -188.498734) (xy 171.805351 -188.443112) (xy 171.817477 -188.388675)
			(xy 171.8374 -188.336584) (xy 171.864696 -188.287949) (xy 171.898782 -188.243806) (xy 171.938931 -188.205097)
			(xy 171.984289 -188.172646) (xy 172.033889 -188.147145) (xy 172.086673 -188.129138) (xy 172.141516 -188.119008)
			(xy 172.19725 -188.116971) (xy 172.252687 -188.123071) (xy 172.306644 -188.137177) (xy 172.357973 -188.158989)
			(xy 172.405579 -188.188043) (xy 172.448447 -188.223718) (xy 172.485664 -188.265255) (xy 172.516437 -188.311768)
			(xy 172.540109 -188.362265) (xy 172.556177 -188.415672) (xy 172.564297 -188.470848) (xy 172.564806 -188.498734)
			(xy 172.564297 -188.52662) (xy 172.556177 -188.581796) (xy 172.540109 -188.635203) (xy 172.516437 -188.6857)
			(xy 172.485664 -188.732213) (xy 172.448447 -188.77375) (xy 172.405579 -188.809425) (xy 172.357973 -188.838479)
			(xy 172.306644 -188.860291) (xy 172.252687 -188.874397) (xy 172.19725 -188.880497) (xy 172.141516 -188.87846)
			(xy 172.086673 -188.86833) (xy 172.033889 -188.850323) (xy 171.984289 -188.824822) (xy 171.938931 -188.792371)
			(xy 171.898782 -188.753662) (xy 171.864696 -188.709519) (xy 171.8374 -188.660884) (xy 171.817477 -188.608793)
			(xy 171.805351 -188.554356) (xy 171.80128 -188.498734) (xy 170.924223 -188.498734) (xy 170.946087 -188.546607)
			(xy 170.961442 -188.598897) (xy 170.969199 -188.652841) (xy 170.969686 -188.68009) (xy 170.969686 -188.680344)
			(xy 170.970121 -188.694147) (xy 170.977553 -188.720734) (xy 170.991833 -188.74436) (xy 171.011919 -188.763299)
			(xy 171.036343 -188.776167) (xy 171.063321 -188.782023) (xy 171.077128 -188.78169) (xy 171.098718 -188.781182)
			(xy 171.125968 -188.781698) (xy 171.179912 -188.789456) (xy 171.232204 -188.804813) (xy 171.281777 -188.827455)
			(xy 171.327624 -188.856922) (xy 171.36881 -188.892613) (xy 171.404498 -188.933803) (xy 171.433961 -188.979652)
			(xy 171.456599 -189.029228) (xy 171.471951 -189.08152) (xy 171.479705 -189.135466) (xy 171.479703 -189.189965)
			(xy 171.471944 -189.24391) (xy 171.462975 -189.27445) (xy 173.21657 -189.27445) (xy 173.217136 -189.245733)
			(xy 173.225738 -189.188948) (xy 173.242756 -189.134094) (xy 173.267804 -189.082411) (xy 173.300317 -189.035066)
			(xy 173.33956 -188.993131) (xy 173.384646 -188.957552) (xy 173.434555 -188.929134) (xy 173.461172 -188.918342)
			(xy 173.475168 -188.912403) (xy 173.499063 -188.893623) (xy 173.516374 -188.868643) (xy 173.525569 -188.839677)
			(xy 173.525834 -188.809286) (xy 173.517146 -188.780163) (xy 173.509178 -188.767212) (xy 173.494064 -188.743581)
			(xy 173.470132 -188.692851) (xy 173.453883 -188.639163) (xy 173.445668 -188.583676) (xy 173.44517 -188.55563)
			(xy 173.445656 -188.528379) (xy 173.453412 -188.474431) (xy 173.468767 -188.422136) (xy 173.491409 -188.372559)
			(xy 173.520875 -188.326709) (xy 173.556566 -188.285518) (xy 173.597757 -188.249827) (xy 173.643607 -188.220361)
			(xy 173.693184 -188.197719) (xy 173.745479 -188.182364) (xy 173.799427 -188.174608) (xy 173.853929 -188.174608)
			(xy 173.907877 -188.182364) (xy 173.960172 -188.197719) (xy 174.009749 -188.220361) (xy 174.055599 -188.249827)
			(xy 174.09679 -188.285518) (xy 174.132481 -188.326709) (xy 174.161947 -188.372559) (xy 174.184589 -188.422136)
			(xy 174.199944 -188.474431) (xy 174.2077 -188.528379) (xy 174.208186 -188.55563) (xy 174.207631 -188.584347)
			(xy 174.19903 -188.641135) (xy 174.182013 -188.695991) (xy 174.156964 -188.747675) (xy 174.12445 -188.79502)
			(xy 174.085204 -188.836955) (xy 174.040115 -188.872533) (xy 173.990202 -188.900948) (xy 173.963584 -188.911738)
			(xy 173.949607 -188.917721) (xy 173.925708 -188.936487) (xy 173.908391 -188.961456) (xy 173.899191 -188.990416)
			(xy 173.898923 -189.020802) (xy 173.90761 -189.04992) (xy 173.915578 -189.062868) (xy 173.930732 -189.086475)
			(xy 173.954653 -189.137214) (xy 173.961234 -189.158975) (xy 174.414196 -189.158975) (xy 174.414196 -189.074425)
			(xy 174.421997 -188.990236) (xy 174.437533 -188.907126) (xy 174.460671 -188.825804) (xy 174.491213 -188.746963)
			(xy 174.5289 -188.671277) (xy 174.573409 -188.599391) (xy 174.624361 -188.531919) (xy 174.681321 -188.469435)
			(xy 174.743803 -188.412474) (xy 174.811275 -188.36152) (xy 174.88316 -188.31701) (xy 174.958845 -188.279321)
			(xy 175.037685 -188.248777) (xy 175.119007 -188.225638) (xy 175.202116 -188.2101) (xy 175.286305 -188.202297)
			(xy 175.32858 -188.201808) (xy 176.57318 -188.201808) (xy 176.615104 -188.202259) (xy 176.698602 -188.209923)
			(xy 176.781047 -188.225197) (xy 176.861748 -188.247954) (xy 176.940028 -188.278002) (xy 177.015228 -188.315088)
			(xy 177.086719 -188.358902) (xy 177.153898 -188.409076) (xy 177.216204 -188.465189) (xy 177.273111 -188.526769)
			(xy 177.324144 -188.593299) (xy 177.368872 -188.664221) (xy 177.406921 -188.738939) (xy 177.437972 -188.816826)
			(xy 177.461762 -188.897229) (xy 177.478094 -188.979471) (xy 177.486829 -189.062863) (xy 177.487834 -189.104778)
			(xy 177.488483 -189.119614) (xy 177.497427 -189.147924) (xy 177.514128 -189.17247) (xy 177.537177 -189.191182)
			(xy 177.564632 -189.202481) (xy 177.594175 -189.205416) (xy 177.623316 -189.199737) (xy 177.649596 -189.185925)
			(xy 177.660554 -189.175898) (xy 177.680056 -189.157495) (xy 177.72332 -189.125816) (xy 177.770588 -189.100499)
			(xy 177.820933 -189.082041) (xy 177.873364 -189.070804) (xy 177.900076 -189.068456) (xy 177.913465 -189.067077)
			(xy 177.938867 -189.058206) (xy 177.961069 -189.043007) (xy 177.978529 -189.022535) (xy 177.990034 -188.998212)
			(xy 177.994785 -188.971729) (xy 177.992453 -188.944924) (xy 177.983198 -188.919659) (xy 177.975768 -188.908436)
			(xy 177.959195 -188.884099) (xy 177.932897 -188.831421) (xy 177.91501 -188.775326) (xy 177.905958 -188.717149)
			(xy 177.90541 -188.68771) (xy 177.905865 -188.660457) (xy 177.913621 -188.606504) (xy 177.928976 -188.554205)
			(xy 177.951619 -188.504624) (xy 177.981088 -188.45877) (xy 178.016782 -188.417577) (xy 178.057976 -188.381883)
			(xy 178.103831 -188.352415) (xy 178.153413 -188.329774) (xy 178.205712 -188.314419) (xy 178.259665 -188.306664)
			(xy 178.286918 -188.306202) (xy 178.323748 -188.30798) (xy 178.338382 -188.308888) (xy 178.367165 -188.303391)
			(xy 178.393205 -188.289951) (xy 178.41436 -188.269674) (xy 178.428891 -188.244226) (xy 178.435603 -188.215702)
			(xy 178.435254 -188.201046) (xy 178.434492 -188.178948) (xy 178.434904 -188.151691) (xy 178.442655 -188.097731)
			(xy 178.458007 -188.045423) (xy 178.480648 -187.995833) (xy 178.510115 -187.949969) (xy 178.54581 -187.908767)
			(xy 178.587005 -187.873063) (xy 178.632862 -187.843586) (xy 178.682448 -187.820935) (xy 178.734752 -187.805572)
			(xy 178.788711 -187.797809) (xy 178.843225 -187.797805) (xy 178.897185 -187.805559) (xy 178.949492 -187.820913)
			(xy 178.999081 -187.843555) (xy 179.044944 -187.873025) (xy 179.086145 -187.908721) (xy 179.121846 -187.949918)
			(xy 179.151322 -187.995776) (xy 179.17397 -188.045363) (xy 179.189331 -188.097668) (xy 179.197092 -188.151627)
			(xy 179.197094 -188.206141) (xy 179.189338 -188.260101) (xy 179.173981 -188.312407) (xy 179.151337 -188.361995)
			(xy 179.121866 -188.407856) (xy 179.086167 -188.449056) (xy 179.044969 -188.484756) (xy 178.999109 -188.514229)
			(xy 178.949522 -188.536876) (xy 178.897216 -188.552235) (xy 178.843257 -188.559993) (xy 178.816 -188.560456)
			(xy 178.77917 -188.558678) (xy 178.764536 -188.557726) (xy 178.735743 -188.563222) (xy 178.709695 -188.576667)
			(xy 178.688536 -188.596955) (xy 178.674009 -188.622415) (xy 178.667307 -188.650952) (xy 178.667664 -188.665612)
			(xy 178.668426 -188.68771) (xy 178.667932 -188.714961) (xy 178.660174 -188.768907) (xy 178.644819 -188.821201)
			(xy 178.622178 -188.870777) (xy 178.592712 -188.916626) (xy 178.557022 -188.957816) (xy 178.515833 -188.993507)
			(xy 178.469984 -189.022974) (xy 178.420408 -189.045616) (xy 178.368115 -189.060972) (xy 178.314169 -189.068731)
			(xy 178.286918 -189.069218) (xy 178.266629 -189.06895) (xy 178.226284 -189.064624) (xy 178.2064 -189.060582)
			(xy 178.196772 -189.058941) (xy 178.177544 -189.062286) (xy 178.160951 -189.072562) (xy 178.149389 -189.088285)
			(xy 178.144527 -189.107187) (xy 178.147066 -189.126538) (xy 178.156641 -189.143545) (xy 178.163982 -189.14999)
			(xy 178.184127 -189.166511) (xy 178.220191 -189.204109) (xy 178.235864 -189.22492) (xy 178.244126 -189.235597)
			(xy 178.265144 -189.252527) (xy 178.289868 -189.263347) (xy 178.316565 -189.267297) (xy 178.343363 -189.2641)
			(xy 178.368383 -189.253981) (xy 178.389868 -189.237649) (xy 178.398424 -189.227206) (xy 178.416621 -189.204554)
			(xy 178.458702 -189.164491) (xy 178.506369 -189.131268) (xy 178.558519 -189.105652) (xy 178.61395 -189.088235)
			(xy 178.671379 -189.079419) (xy 178.70043 -189.07887) (xy 178.727678 -189.079402) (xy 178.78162 -189.087162)
			(xy 178.833908 -189.102519) (xy 178.883478 -189.12516) (xy 178.929322 -189.154625) (xy 178.934342 -189.158975)
			(xy 181.957996 -189.158975) (xy 181.957996 -189.074425) (xy 181.965797 -188.990236) (xy 181.981333 -188.907126)
			(xy 182.004471 -188.825804) (xy 182.035013 -188.746963) (xy 182.0727 -188.671277) (xy 182.117209 -188.599391)
			(xy 182.168161 -188.531919) (xy 182.225121 -188.469435) (xy 182.287603 -188.412474) (xy 182.355075 -188.36152)
			(xy 182.42696 -188.31701) (xy 182.502645 -188.279321) (xy 182.581485 -188.248777) (xy 182.662807 -188.225638)
			(xy 182.745916 -188.2101) (xy 182.830105 -188.202297) (xy 182.87238 -188.201808) (xy 184.11698 -188.201808)
			(xy 184.159258 -188.202248) (xy 184.243454 -188.210049) (xy 184.326571 -188.225584) (xy 184.4079 -188.248723)
			(xy 184.486747 -188.279267) (xy 184.562439 -188.316955) (xy 184.634331 -188.361468) (xy 184.695353 -188.407548)
			(xy 187.786262 -188.407548) (xy 187.790333 -188.351926) (xy 187.802459 -188.297489) (xy 187.822382 -188.245398)
			(xy 187.849678 -188.196763) (xy 187.883764 -188.15262) (xy 187.923913 -188.113911) (xy 187.969271 -188.08146)
			(xy 188.018871 -188.055959) (xy 188.071655 -188.037952) (xy 188.126498 -188.027822) (xy 188.182232 -188.025785)
			(xy 188.237669 -188.031885) (xy 188.291626 -188.045991) (xy 188.342955 -188.067803) (xy 188.390561 -188.096857)
			(xy 188.433429 -188.132532) (xy 188.470646 -188.174069) (xy 188.501419 -188.220582) (xy 188.525091 -188.271079)
			(xy 188.541159 -188.324486) (xy 188.549279 -188.379662) (xy 188.549788 -188.407548) (xy 188.549279 -188.435434)
			(xy 188.541159 -188.49061) (xy 188.525091 -188.544017) (xy 188.501419 -188.594514) (xy 188.470646 -188.641027)
			(xy 188.433429 -188.682564) (xy 188.390561 -188.718239) (xy 188.342955 -188.747293) (xy 188.291626 -188.769105)
			(xy 188.237669 -188.783211) (xy 188.182232 -188.789311) (xy 188.126498 -188.787274) (xy 188.071655 -188.777144)
			(xy 188.018871 -188.759137) (xy 187.969271 -188.733636) (xy 187.923913 -188.701185) (xy 187.883764 -188.662476)
			(xy 187.849678 -188.618333) (xy 187.822382 -188.569698) (xy 187.802459 -188.517607) (xy 187.790333 -188.46317)
			(xy 187.786262 -188.407548) (xy 184.695353 -188.407548) (xy 184.701809 -188.412423) (xy 184.764298 -188.469388)
			(xy 184.821264 -188.531875) (xy 184.872221 -188.599352) (xy 184.916735 -188.671243) (xy 184.954425 -188.746935)
			(xy 184.984971 -188.825781) (xy 185.008111 -188.90711) (xy 185.023649 -188.990226) (xy 185.028968 -189.047628)
			(xy 186.970668 -189.047628) (xy 186.974739 -188.992006) (xy 186.986865 -188.937569) (xy 187.006788 -188.885478)
			(xy 187.034084 -188.836843) (xy 187.06817 -188.7927) (xy 187.108319 -188.753991) (xy 187.153677 -188.72154)
			(xy 187.203277 -188.696039) (xy 187.256061 -188.678032) (xy 187.310904 -188.667902) (xy 187.366638 -188.665865)
			(xy 187.422075 -188.671965) (xy 187.476032 -188.686071) (xy 187.527361 -188.707883) (xy 187.574967 -188.736937)
			(xy 187.617835 -188.772612) (xy 187.655052 -188.814149) (xy 187.685825 -188.860662) (xy 187.709497 -188.911159)
			(xy 187.725565 -188.964566) (xy 187.733685 -189.019742) (xy 187.734194 -189.047628) (xy 187.733685 -189.075514)
			(xy 187.725565 -189.13069) (xy 187.709497 -189.184097) (xy 187.685825 -189.234594) (xy 187.655052 -189.281107)
			(xy 187.617835 -189.322644) (xy 187.574967 -189.358319) (xy 187.527361 -189.387373) (xy 187.476032 -189.409185)
			(xy 187.422075 -189.423291) (xy 187.366638 -189.429391) (xy 187.310904 -189.427354) (xy 187.256061 -189.417224)
			(xy 187.203277 -189.399217) (xy 187.153677 -189.373716) (xy 187.108319 -189.341265) (xy 187.06817 -189.302556)
			(xy 187.034084 -189.258413) (xy 187.006788 -189.209778) (xy 186.986865 -189.157687) (xy 186.974739 -189.10325)
			(xy 186.970668 -189.047628) (xy 185.028968 -189.047628) (xy 185.031451 -189.074422) (xy 185.031451 -189.158978)
			(xy 185.023649 -189.243174) (xy 185.008111 -189.32629) (xy 184.984971 -189.407619) (xy 184.954425 -189.486465)
			(xy 184.916735 -189.562157) (xy 184.872221 -189.634048) (xy 184.82556 -189.695836) (xy 185.263788 -189.695836)
			(xy 185.267859 -189.640214) (xy 185.279985 -189.585777) (xy 185.299908 -189.533686) (xy 185.327204 -189.485051)
			(xy 185.36129 -189.440908) (xy 185.401439 -189.402199) (xy 185.446797 -189.369748) (xy 185.496397 -189.344247)
			(xy 185.549181 -189.32624) (xy 185.604024 -189.31611) (xy 185.659758 -189.314073) (xy 185.715195 -189.320173)
			(xy 185.769152 -189.334279) (xy 185.820481 -189.356091) (xy 185.868087 -189.385145) (xy 185.910955 -189.42082)
			(xy 185.948172 -189.462357) (xy 185.978945 -189.50887) (xy 186.002617 -189.559367) (xy 186.018685 -189.612774)
			(xy 186.023332 -189.644349) (xy 188.731674 -189.644349) (xy 188.731674 -189.589851) (xy 188.739429 -189.535907)
			(xy 188.754782 -189.483615) (xy 188.77742 -189.434041) (xy 188.806882 -189.388192) (xy 188.842569 -189.347003)
			(xy 188.883753 -189.311311) (xy 188.929598 -189.281843) (xy 188.97917 -189.259199) (xy 189.03146 -189.243839)
			(xy 189.085403 -189.236077) (xy 189.112652 -189.235588) (xy 189.13762 -189.23596) (xy 189.187129 -189.242472)
			(xy 189.235364 -189.25539) (xy 189.281501 -189.274493) (xy 189.324749 -189.299455) (xy 189.344808 -189.314328)
			(xy 189.356941 -189.322946) (xy 189.38479 -189.333399) (xy 189.41447 -189.33539) (xy 189.443467 -189.328751)
			(xy 189.469324 -189.314044) (xy 189.489851 -189.292515) (xy 189.503309 -189.265986) (xy 189.508559 -189.236707)
			(xy 189.507368 -189.221872) (xy 189.504514 -189.195677) (xy 189.501465 -189.143066) (xy 189.501272 -189.116716)
			(xy 189.501795 -189.074441) (xy 189.509595 -188.990251) (xy 189.52513 -188.907139) (xy 189.548267 -188.825816)
			(xy 189.578809 -188.746974) (xy 189.616495 -188.671287) (xy 189.661003 -188.5994) (xy 189.711955 -188.531926)
			(xy 189.768916 -188.469441) (xy 189.831398 -188.412478) (xy 189.89887 -188.361524) (xy 189.970755 -188.317012)
			(xy 190.046441 -188.279323) (xy 190.125282 -188.248778) (xy 190.206604 -188.225638) (xy 190.289715 -188.2101)
			(xy 190.373905 -188.202297) (xy 190.41618 -188.201808) (xy 191.66078 -188.201808) (xy 191.703058 -188.202248)
			(xy 191.787254 -188.210049) (xy 191.870371 -188.225584) (xy 191.9517 -188.248723) (xy 192.030547 -188.279267)
			(xy 192.106239 -188.316955) (xy 192.178131 -188.361468) (xy 192.245609 -188.412423) (xy 192.308098 -188.469388)
			(xy 192.353647 -188.519352) (xy 193.908885 -188.519352) (xy 193.908885 -188.464848) (xy 193.916643 -188.410898)
			(xy 193.931999 -188.358602) (xy 193.954642 -188.309023) (xy 193.984111 -188.263172) (xy 194.019806 -188.221982)
			(xy 194.060999 -188.186291) (xy 194.106853 -188.156826) (xy 194.156434 -188.134187) (xy 194.208731 -188.118835)
			(xy 194.262682 -188.111083) (xy 194.289934 -188.110622) (xy 194.317305 -188.111063) (xy 194.371486 -188.118886)
			(xy 194.423989 -188.134381) (xy 194.473736 -188.157228) (xy 194.519701 -188.186958) (xy 194.540632 -188.204602)
			(xy 194.55196 -188.213838) (xy 194.578517 -188.226014) (xy 194.607434 -188.230187) (xy 194.636351 -188.226014)
			(xy 194.662908 -188.213838) (xy 194.674236 -188.204602) (xy 194.695169 -188.186961) (xy 194.741137 -188.157237)
			(xy 194.790883 -188.134391) (xy 194.843385 -188.118895) (xy 194.897563 -188.111066) (xy 194.952305 -188.111066)
			(xy 195.006483 -188.118895) (xy 195.058985 -188.134391) (xy 195.108731 -188.157237) (xy 195.154699 -188.186961)
			(xy 195.175632 -188.204602) (xy 195.18696 -188.213838) (xy 195.213517 -188.226014) (xy 195.242434 -188.230187)
			(xy 195.271351 -188.226014) (xy 195.297908 -188.213838) (xy 195.309236 -188.204602) (xy 195.330182 -188.18698)
			(xy 195.376151 -188.157265) (xy 195.425895 -188.134426) (xy 195.478392 -188.118931) (xy 195.532566 -188.111098)
			(xy 195.559934 -188.110622) (xy 195.587186 -188.11105) (xy 195.641134 -188.118811) (xy 195.693429 -188.134171)
			(xy 195.743006 -188.156815) (xy 195.788855 -188.186285) (xy 195.830045 -188.221979) (xy 195.865736 -188.263172)
			(xy 195.895201 -188.309024) (xy 195.917841 -188.358603) (xy 195.933196 -188.410899) (xy 195.940952 -188.464848)
			(xy 195.940952 -188.519352) (xy 195.933196 -188.573301) (xy 195.917841 -188.625597) (xy 195.895201 -188.675176)
			(xy 195.865736 -188.721028) (xy 195.830045 -188.762221) (xy 195.788855 -188.797915) (xy 195.743006 -188.827385)
			(xy 195.693429 -188.850029) (xy 195.641134 -188.865389) (xy 195.587186 -188.87315) (xy 195.559934 -188.873638)
			(xy 195.532564 -188.873167) (xy 195.478384 -188.865353) (xy 195.425881 -188.849866) (xy 195.376134 -188.827025)
			(xy 195.330167 -188.7973) (xy 195.309236 -188.779658) (xy 195.297908 -188.770422) (xy 195.271351 -188.758246)
			(xy 195.242434 -188.754073) (xy 195.213517 -188.758246) (xy 195.18696 -188.770422) (xy 195.175632 -188.779658)
			(xy 195.154699 -188.797299) (xy 195.108731 -188.827023) (xy 195.058985 -188.849869) (xy 195.006483 -188.865365)
			(xy 194.952305 -188.873194) (xy 194.897563 -188.873194) (xy 194.843385 -188.865365) (xy 194.790883 -188.849869)
			(xy 194.741137 -188.827023) (xy 194.695169 -188.797299) (xy 194.674236 -188.779658) (xy 194.662908 -188.770422)
			(xy 194.636351 -188.758246) (xy 194.607434 -188.754073) (xy 194.578517 -188.758246) (xy 194.55196 -188.770422)
			(xy 194.540632 -188.779658) (xy 194.519693 -188.797289) (xy 194.473723 -188.827004) (xy 194.423977 -188.849842)
			(xy 194.371478 -188.865334) (xy 194.317303 -188.873164) (xy 194.289934 -188.873638) (xy 194.262682 -188.873117)
			(xy 194.208731 -188.865365) (xy 194.156434 -188.850013) (xy 194.106853 -188.827374) (xy 194.060999 -188.797909)
			(xy 194.019806 -188.762218) (xy 193.984111 -188.721028) (xy 193.954642 -188.675177) (xy 193.931999 -188.625598)
			(xy 193.916643 -188.573302) (xy 193.908885 -188.519352) (xy 192.353647 -188.519352) (xy 192.365064 -188.531875)
			(xy 192.416021 -188.599352) (xy 192.460535 -188.671243) (xy 192.498225 -188.746935) (xy 192.528771 -188.825781)
			(xy 192.551911 -188.90711) (xy 192.567449 -188.990226) (xy 192.570732 -189.025658) (xy 196.312407 -189.025658)
			(xy 196.312407 -188.971142) (xy 196.320166 -188.917181) (xy 196.335526 -188.864874) (xy 196.358174 -188.815285)
			(xy 196.387649 -188.769424) (xy 196.423351 -188.728225) (xy 196.464553 -188.692527) (xy 196.510417 -188.663056)
			(xy 196.560008 -188.640413) (xy 196.612316 -188.625058) (xy 196.666278 -188.617305) (xy 196.693536 -188.616844)
			(xy 196.719669 -188.61728) (xy 196.771446 -188.624425) (xy 196.821764 -188.638563) (xy 196.869685 -188.659431)
			(xy 196.914313 -188.686638) (xy 196.954814 -188.719675) (xy 196.972936 -188.73851) (xy 196.982892 -188.748474)
			(xy 197.006953 -188.763091) (xy 197.034091 -188.770577) (xy 197.062243 -188.770363) (xy 197.089265 -188.762466)
			(xy 197.1131 -188.747486) (xy 197.131936 -188.726563) (xy 197.138544 -188.714126) (xy 197.157698 -188.676167)
			(xy 197.202027 -188.603608) (xy 197.252898 -188.535476) (xy 197.309873 -188.472359) (xy 197.37246 -188.414803)
			(xy 197.440119 -188.363303) (xy 197.512265 -188.318305) (xy 197.588276 -188.280197) (xy 197.667496 -188.249307)
			(xy 197.74924 -188.225903) (xy 197.832804 -188.210187) (xy 197.917466 -188.202294) (xy 197.95998 -188.201808)
			(xy 199.20458 -188.201808) (xy 199.246858 -188.202248) (xy 199.331054 -188.210049) (xy 199.414171 -188.225584)
			(xy 199.4955 -188.248723) (xy 199.574347 -188.279267) (xy 199.650039 -188.316955) (xy 199.721931 -188.361468)
			(xy 199.789409 -188.412423) (xy 199.851898 -188.469388) (xy 199.908864 -188.531875) (xy 199.959821 -188.599352)
			(xy 200.004335 -188.671243) (xy 200.042025 -188.746935) (xy 200.072571 -188.825781) (xy 200.095711 -188.90711)
			(xy 200.111249 -188.990226) (xy 200.119051 -189.074422) (xy 200.119051 -189.158975) (xy 204.589396 -189.158975)
			(xy 204.589396 -189.074425) (xy 204.597197 -188.990236) (xy 204.612733 -188.907126) (xy 204.635871 -188.825804)
			(xy 204.666413 -188.746963) (xy 204.7041 -188.671277) (xy 204.748609 -188.599391) (xy 204.799561 -188.531919)
			(xy 204.856521 -188.469435) (xy 204.919003 -188.412474) (xy 204.986475 -188.36152) (xy 205.05836 -188.31701)
			(xy 205.134045 -188.279321) (xy 205.212885 -188.248777) (xy 205.294207 -188.225638) (xy 205.377316 -188.2101)
			(xy 205.461505 -188.202297) (xy 205.50378 -188.201808) (xy 206.74838 -188.201808) (xy 206.790658 -188.202248)
			(xy 206.874854 -188.210049) (xy 206.957971 -188.225584) (xy 207.004626 -188.238858) (xy 210.588079 -188.238858)
			(xy 210.595834 -188.184911) (xy 210.611187 -188.132617) (xy 210.633827 -188.083041) (xy 210.663291 -188.03719)
			(xy 210.69898 -187.996) (xy 210.740168 -187.960307) (xy 210.786016 -187.93084) (xy 210.835591 -187.908197)
			(xy 210.887884 -187.89284) (xy 210.94183 -187.885081) (xy 210.996331 -187.885078) (xy 211.050278 -187.892832)
			(xy 211.102573 -187.908184) (xy 211.15215 -187.930821) (xy 211.198001 -187.960284) (xy 211.239193 -187.995972)
			(xy 211.274886 -188.037159) (xy 211.304355 -188.083007) (xy 211.326999 -188.132581) (xy 211.342358 -188.184874)
			(xy 211.350118 -188.238819) (xy 211.350606 -188.26607) (xy 211.35032 -188.286746) (xy 211.345871 -188.327856)
			(xy 211.341716 -188.348112) (xy 211.339187 -188.361567) (xy 211.340628 -188.388897) (xy 211.349274 -188.414864)
			(xy 211.364504 -188.437603) (xy 211.385224 -188.455483) (xy 211.409948 -188.46722) (xy 211.436901 -188.471971)
			(xy 211.464148 -188.469396) (xy 211.477098 -188.464952) (xy 211.498792 -188.457082) (xy 211.543596 -188.446018)
			(xy 211.589405 -188.440426) (xy 211.61248 -188.44006) (xy 211.639735 -188.440534) (xy 211.693691 -188.448289)
			(xy 211.745994 -188.463644) (xy 211.795579 -188.486286) (xy 211.841437 -188.515755) (xy 211.882634 -188.55145)
			(xy 211.918332 -188.592645) (xy 211.947803 -188.638501) (xy 211.970449 -188.688085) (xy 211.985807 -188.740387)
			(xy 211.993565 -188.794342) (xy 211.993565 -188.848852) (xy 211.985808 -188.902808) (xy 211.97045 -188.95511)
			(xy 211.947806 -189.004694) (xy 211.918335 -189.050551) (xy 211.882638 -189.091746) (xy 211.841441 -189.127442)
			(xy 211.795584 -189.156912) (xy 211.791066 -189.158975) (xy 212.133196 -189.158975) (xy 212.133196 -189.074425)
			(xy 212.140997 -188.990236) (xy 212.156533 -188.907126) (xy 212.179671 -188.825804) (xy 212.210213 -188.746963)
			(xy 212.2479 -188.671277) (xy 212.292409 -188.599391) (xy 212.343361 -188.531919) (xy 212.400321 -188.469435)
			(xy 212.462803 -188.412474) (xy 212.530275 -188.36152) (xy 212.60216 -188.31701) (xy 212.677845 -188.279321)
			(xy 212.756685 -188.248777) (xy 212.838007 -188.225638) (xy 212.921116 -188.2101) (xy 213.005305 -188.202297)
			(xy 213.04758 -188.201808) (xy 214.29218 -188.201808) (xy 214.334458 -188.202248) (xy 214.418654 -188.210049)
			(xy 214.501771 -188.225584) (xy 214.5831 -188.248723) (xy 214.661947 -188.279267) (xy 214.737639 -188.316955)
			(xy 214.809531 -188.361468) (xy 214.877009 -188.412423) (xy 214.939498 -188.469388) (xy 214.996464 -188.531875)
			(xy 215.047421 -188.599352) (xy 215.091935 -188.671243) (xy 215.129625 -188.746935) (xy 215.160171 -188.825781)
			(xy 215.183311 -188.90711) (xy 215.198849 -188.990226) (xy 215.206651 -189.074422) (xy 215.206651 -189.158978)
			(xy 215.198849 -189.243174) (xy 215.183311 -189.32629) (xy 215.160171 -189.407619) (xy 215.129625 -189.486465)
			(xy 215.091935 -189.562157) (xy 215.047421 -189.634048) (xy 214.996464 -189.701525) (xy 214.939498 -189.764012)
			(xy 214.877009 -189.820977) (xy 214.809531 -189.871932) (xy 214.737639 -189.916445) (xy 214.661947 -189.954133)
			(xy 214.5831 -189.984677) (xy 214.501771 -190.007816) (xy 214.418654 -190.023351) (xy 214.334458 -190.031152)
			(xy 214.29218 -190.031624) (xy 213.04758 -190.031624) (xy 213.005305 -190.031103) (xy 212.921116 -190.0233)
			(xy 212.838007 -190.007762) (xy 212.756685 -189.984623) (xy 212.677845 -189.954079) (xy 212.60216 -189.91639)
			(xy 212.530275 -189.87188) (xy 212.462803 -189.820926) (xy 212.400321 -189.763965) (xy 212.343361 -189.701481)
			(xy 212.292409 -189.634009) (xy 212.2479 -189.562123) (xy 212.210213 -189.486437) (xy 212.179671 -189.407596)
			(xy 212.156533 -189.326274) (xy 212.140997 -189.243164) (xy 212.133196 -189.158975) (xy 211.791066 -189.158975)
			(xy 211.745999 -189.179555) (xy 211.693696 -189.19491) (xy 211.63974 -189.202666) (xy 211.58523 -189.202664)
			(xy 211.531275 -189.194904) (xy 211.478974 -189.179544) (xy 211.429391 -189.156897) (xy 211.383535 -189.127425)
			(xy 211.342341 -189.091725) (xy 211.306647 -189.050527) (xy 211.27718 -189.004668) (xy 211.254539 -188.955082)
			(xy 211.239186 -188.902779) (xy 211.231433 -188.848823) (xy 211.230972 -188.821568) (xy 211.231246 -188.800892)
			(xy 211.235703 -188.759781) (xy 211.239862 -188.739526) (xy 211.242349 -188.726069) (xy 211.240893 -188.698753)
			(xy 211.232243 -188.672802) (xy 211.217017 -188.650075) (xy 211.196309 -188.632202) (xy 211.1716 -188.620464)
			(xy 211.144663 -188.615701) (xy 211.117427 -188.618255) (xy 211.10448 -188.622686) (xy 211.082789 -188.630564)
			(xy 211.037983 -188.641624) (xy 210.992173 -188.647213) (xy 210.969098 -188.647578) (xy 210.941847 -188.64712)
			(xy 210.887901 -188.639364) (xy 210.835607 -188.624009) (xy 210.786031 -188.601368) (xy 210.740182 -188.571903)
			(xy 210.698992 -188.536213) (xy 210.663301 -188.495024) (xy 210.633835 -188.449175) (xy 210.611193 -188.399599)
			(xy 210.595838 -188.347306) (xy 210.58808 -188.293359) (xy 210.588079 -188.238858) (xy 207.004626 -188.238858)
			(xy 207.0393 -188.248723) (xy 207.118147 -188.279267) (xy 207.193839 -188.316955) (xy 207.265731 -188.361468)
			(xy 207.333209 -188.412423) (xy 207.395698 -188.469388) (xy 207.452664 -188.531875) (xy 207.503621 -188.599352)
			(xy 207.548135 -188.671243) (xy 207.585825 -188.746935) (xy 207.616371 -188.825781) (xy 207.639511 -188.90711)
			(xy 207.655049 -188.990226) (xy 207.662851 -189.074422) (xy 207.662851 -189.138814) (xy 208.053684 -189.138814)
			(xy 208.057755 -189.083192) (xy 208.069881 -189.028755) (xy 208.089804 -188.976664) (xy 208.1171 -188.928029)
			(xy 208.151186 -188.883886) (xy 208.191335 -188.845177) (xy 208.236693 -188.812726) (xy 208.286293 -188.787225)
			(xy 208.339077 -188.769218) (xy 208.39392 -188.759088) (xy 208.449654 -188.757051) (xy 208.505091 -188.763151)
			(xy 208.559048 -188.777257) (xy 208.610377 -188.799069) (xy 208.657983 -188.828123) (xy 208.700851 -188.863798)
			(xy 208.738068 -188.905335) (xy 208.768841 -188.951848) (xy 208.792513 -189.002345) (xy 208.808581 -189.055752)
			(xy 208.816701 -189.110928) (xy 208.81721 -189.138814) (xy 208.816701 -189.1667) (xy 208.808581 -189.221876)
			(xy 208.792513 -189.275283) (xy 208.768841 -189.32578) (xy 208.738068 -189.372293) (xy 208.700851 -189.41383)
			(xy 208.657983 -189.449505) (xy 208.610377 -189.478559) (xy 208.559048 -189.500371) (xy 208.505091 -189.514477)
			(xy 208.449654 -189.520577) (xy 208.39392 -189.51854) (xy 208.339077 -189.50841) (xy 208.286293 -189.490403)
			(xy 208.236693 -189.464902) (xy 208.191335 -189.432451) (xy 208.151186 -189.393742) (xy 208.1171 -189.349599)
			(xy 208.089804 -189.300964) (xy 208.069881 -189.248873) (xy 208.057755 -189.194436) (xy 208.053684 -189.138814)
			(xy 207.662851 -189.138814) (xy 207.662851 -189.158978) (xy 207.655049 -189.243174) (xy 207.639511 -189.32629)
			(xy 207.616371 -189.407619) (xy 207.585825 -189.486465) (xy 207.548135 -189.562157) (xy 207.503621 -189.634048)
			(xy 207.452664 -189.701525) (xy 207.43701 -189.718696) (xy 208.809588 -189.718696) (xy 208.813659 -189.663074)
			(xy 208.825785 -189.608637) (xy 208.845708 -189.556546) (xy 208.873004 -189.507911) (xy 208.90709 -189.463768)
			(xy 208.947239 -189.425059) (xy 208.992597 -189.392608) (xy 209.042197 -189.367107) (xy 209.094981 -189.3491)
			(xy 209.149824 -189.33897) (xy 209.205558 -189.336933) (xy 209.260995 -189.343033) (xy 209.314952 -189.357139)
			(xy 209.366281 -189.378951) (xy 209.413887 -189.408005) (xy 209.456755 -189.44368) (xy 209.493972 -189.485217)
			(xy 209.524745 -189.53173) (xy 209.548417 -189.582227) (xy 209.564485 -189.635634) (xy 209.572605 -189.69081)
			(xy 209.573114 -189.718696) (xy 209.572605 -189.746582) (xy 209.564485 -189.801758) (xy 209.548417 -189.855165)
			(xy 209.524745 -189.905662) (xy 209.493972 -189.952175) (xy 209.456755 -189.993712) (xy 209.413887 -190.029387)
			(xy 209.366281 -190.058441) (xy 209.314952 -190.080253) (xy 209.260995 -190.094359) (xy 209.205558 -190.100459)
			(xy 209.149824 -190.098422) (xy 209.094981 -190.088292) (xy 209.042197 -190.070285) (xy 208.992597 -190.044784)
			(xy 208.947239 -190.012333) (xy 208.90709 -189.973624) (xy 208.873004 -189.929481) (xy 208.845708 -189.880846)
			(xy 208.825785 -189.828755) (xy 208.813659 -189.774318) (xy 208.809588 -189.718696) (xy 207.43701 -189.718696)
			(xy 207.395698 -189.764012) (xy 207.333209 -189.820977) (xy 207.265731 -189.871932) (xy 207.193839 -189.916445)
			(xy 207.118147 -189.954133) (xy 207.0393 -189.984677) (xy 206.957971 -190.007816) (xy 206.874854 -190.023351)
			(xy 206.790658 -190.031152) (xy 206.74838 -190.031624) (xy 205.50378 -190.031624) (xy 205.461505 -190.031103)
			(xy 205.377316 -190.0233) (xy 205.294207 -190.007762) (xy 205.212885 -189.984623) (xy 205.134045 -189.954079)
			(xy 205.05836 -189.91639) (xy 204.986475 -189.87188) (xy 204.919003 -189.820926) (xy 204.856521 -189.763965)
			(xy 204.799561 -189.701481) (xy 204.748609 -189.634009) (xy 204.7041 -189.562123) (xy 204.666413 -189.486437)
			(xy 204.635871 -189.407596) (xy 204.612733 -189.326274) (xy 204.597197 -189.243164) (xy 204.589396 -189.158975)
			(xy 200.119051 -189.158975) (xy 200.119051 -189.158978) (xy 200.111249 -189.243174) (xy 200.095711 -189.32629)
			(xy 200.072571 -189.407619) (xy 200.042025 -189.486465) (xy 200.004335 -189.562157) (xy 199.959821 -189.634048)
			(xy 199.908864 -189.701525) (xy 199.851898 -189.764012) (xy 199.789409 -189.820977) (xy 199.721931 -189.871932)
			(xy 199.650039 -189.916445) (xy 199.574347 -189.954133) (xy 199.4955 -189.984677) (xy 199.414171 -190.007816)
			(xy 199.331054 -190.023351) (xy 199.246858 -190.031152) (xy 199.20458 -190.031624) (xy 197.95998 -190.031624)
			(xy 197.917446 -190.031098) (xy 197.832746 -190.023191) (xy 197.749146 -190.007456) (xy 197.667368 -189.98403)
			(xy 197.588116 -189.953114) (xy 197.512077 -189.914975) (xy 197.439906 -189.869942) (xy 197.372226 -189.818406)
			(xy 197.309623 -189.760809) (xy 197.252635 -189.697651) (xy 197.201756 -189.629475) (xy 197.157425 -189.556872)
			(xy 197.120024 -189.480467) (xy 197.089876 -189.40092) (xy 197.078092 -189.360048) (xy 197.073988 -189.346561)
			(xy 197.059352 -189.322474) (xy 197.038684 -189.303309) (xy 197.013562 -189.29053) (xy 196.985902 -189.285111)
			(xy 196.957815 -189.287465) (xy 196.931444 -189.297413) (xy 196.91985 -189.305438) (xy 196.895107 -189.322944)
			(xy 196.841254 -189.350747) (xy 196.783682 -189.369682) (xy 196.723839 -189.379274) (xy 196.693536 -189.37986)
			(xy 196.666278 -189.379495) (xy 196.612316 -189.371742) (xy 196.560008 -189.356387) (xy 196.510417 -189.333744)
			(xy 196.464553 -189.304273) (xy 196.423351 -189.268575) (xy 196.387649 -189.227376) (xy 196.358174 -189.181515)
			(xy 196.335526 -189.131926) (xy 196.320166 -189.079619) (xy 196.312407 -189.025658) (xy 192.570732 -189.025658)
			(xy 192.575251 -189.074422) (xy 192.575251 -189.158978) (xy 192.567449 -189.243174) (xy 192.551911 -189.32629)
			(xy 192.528771 -189.407619) (xy 192.498225 -189.486465) (xy 192.460535 -189.562157) (xy 192.439099 -189.596776)
			(xy 193.30873 -189.596776) (xy 193.312801 -189.541154) (xy 193.324927 -189.486717) (xy 193.34485 -189.434626)
			(xy 193.372146 -189.385991) (xy 193.406232 -189.341848) (xy 193.446381 -189.303139) (xy 193.491739 -189.270688)
			(xy 193.541339 -189.245187) (xy 193.594123 -189.22718) (xy 193.648966 -189.21705) (xy 193.7047 -189.215013)
			(xy 193.760137 -189.221113) (xy 193.814094 -189.235219) (xy 193.865423 -189.257031) (xy 193.913029 -189.286085)
			(xy 193.955897 -189.32176) (xy 193.993114 -189.363297) (xy 194.023887 -189.40981) (xy 194.047559 -189.460307)
			(xy 194.063627 -189.513714) (xy 194.071747 -189.56889) (xy 194.072256 -189.596776) (xy 194.071747 -189.624662)
			(xy 194.07144 -189.626748) (xy 195.711062 -189.626748) (xy 195.715133 -189.571126) (xy 195.727259 -189.516689)
			(xy 195.747182 -189.464598) (xy 195.774478 -189.415963) (xy 195.808564 -189.37182) (xy 195.848713 -189.333111)
			(xy 195.894071 -189.30066) (xy 195.943671 -189.275159) (xy 195.996455 -189.257152) (xy 196.051298 -189.247022)
			(xy 196.107032 -189.244985) (xy 196.162469 -189.251085) (xy 196.216426 -189.265191) (xy 196.267755 -189.287003)
			(xy 196.315361 -189.316057) (xy 196.358229 -189.351732) (xy 196.395446 -189.393269) (xy 196.426219 -189.439782)
			(xy 196.449891 -189.490279) (xy 196.465959 -189.543686) (xy 196.474079 -189.598862) (xy 196.474588 -189.626748)
			(xy 196.474079 -189.654634) (xy 196.465959 -189.70981) (xy 196.449891 -189.763217) (xy 196.426219 -189.813714)
			(xy 196.395446 -189.860227) (xy 196.358229 -189.901764) (xy 196.315361 -189.937439) (xy 196.267755 -189.966493)
			(xy 196.216426 -189.988305) (xy 196.162469 -190.002411) (xy 196.107032 -190.008511) (xy 196.051298 -190.006474)
			(xy 195.996455 -189.996344) (xy 195.943671 -189.978337) (xy 195.894071 -189.952836) (xy 195.848713 -189.920385)
			(xy 195.808564 -189.881676) (xy 195.774478 -189.837533) (xy 195.747182 -189.788898) (xy 195.727259 -189.736807)
			(xy 195.715133 -189.68237) (xy 195.711062 -189.626748) (xy 194.07144 -189.626748) (xy 194.063627 -189.679838)
			(xy 194.047559 -189.733245) (xy 194.023887 -189.783742) (xy 193.993114 -189.830255) (xy 193.955897 -189.871792)
			(xy 193.913029 -189.907467) (xy 193.865423 -189.936521) (xy 193.814094 -189.958333) (xy 193.760137 -189.972439)
			(xy 193.7047 -189.978539) (xy 193.648966 -189.976502) (xy 193.594123 -189.966372) (xy 193.541339 -189.948365)
			(xy 193.491739 -189.922864) (xy 193.446381 -189.890413) (xy 193.406232 -189.851704) (xy 193.372146 -189.807561)
			(xy 193.34485 -189.758926) (xy 193.324927 -189.706835) (xy 193.312801 -189.652398) (xy 193.30873 -189.596776)
			(xy 192.439099 -189.596776) (xy 192.416021 -189.634048) (xy 192.365064 -189.701525) (xy 192.308098 -189.764012)
			(xy 192.245609 -189.820977) (xy 192.178131 -189.871932) (xy 192.106239 -189.916445) (xy 192.030547 -189.954133)
			(xy 191.9517 -189.984677) (xy 191.870371 -190.007816) (xy 191.787254 -190.023351) (xy 191.703058 -190.031152)
			(xy 191.66078 -190.031624) (xy 190.41618 -190.031624) (xy 190.372574 -190.031151) (xy 190.285757 -190.022848)
			(xy 190.200125 -190.006318) (xy 190.116455 -189.981713) (xy 190.035507 -189.949255) (xy 189.958016 -189.909239)
			(xy 189.884686 -189.862029) (xy 189.816182 -189.808053) (xy 189.753128 -189.747802) (xy 189.696095 -189.681822)
			(xy 189.670436 -189.64656) (xy 189.661438 -189.634708) (xy 189.637932 -189.616475) (xy 189.610172 -189.605781)
			(xy 189.580509 -189.603534) (xy 189.551454 -189.609923) (xy 189.52547 -189.624406) (xy 189.504756 -189.645758)
			(xy 189.491067 -189.67217) (xy 189.48781 -189.686692) (xy 189.482507 -189.712635) (xy 189.465733 -189.762859)
			(xy 189.442175 -189.810281) (xy 189.412288 -189.853991) (xy 189.376644 -189.893149) (xy 189.335929 -189.927003)
			(xy 189.290924 -189.954903) (xy 189.242494 -189.976312) (xy 189.191569 -189.99082) (xy 189.139127 -189.998148)
			(xy 189.112652 -189.998604) (xy 189.085403 -189.998123) (xy 189.03146 -189.990361) (xy 188.97917 -189.975001)
			(xy 188.929598 -189.952357) (xy 188.883753 -189.922889) (xy 188.842569 -189.887197) (xy 188.806882 -189.846008)
			(xy 188.77742 -189.800159) (xy 188.754782 -189.750585) (xy 188.739429 -189.698293) (xy 188.731674 -189.644349)
			(xy 186.023332 -189.644349) (xy 186.026805 -189.66795) (xy 186.027314 -189.695836) (xy 186.026805 -189.723722)
			(xy 186.018685 -189.778898) (xy 186.002617 -189.832305) (xy 185.978945 -189.882802) (xy 185.948172 -189.929315)
			(xy 185.910955 -189.970852) (xy 185.868087 -190.006527) (xy 185.820481 -190.035581) (xy 185.769152 -190.057393)
			(xy 185.715195 -190.071499) (xy 185.659758 -190.077599) (xy 185.604024 -190.075562) (xy 185.549181 -190.065432)
			(xy 185.496397 -190.047425) (xy 185.446797 -190.021924) (xy 185.401439 -189.989473) (xy 185.36129 -189.950764)
			(xy 185.327204 -189.906621) (xy 185.299908 -189.857986) (xy 185.279985 -189.805895) (xy 185.267859 -189.751458)
			(xy 185.263788 -189.695836) (xy 184.82556 -189.695836) (xy 184.821264 -189.701525) (xy 184.764298 -189.764012)
			(xy 184.701809 -189.820977) (xy 184.634331 -189.871932) (xy 184.562439 -189.916445) (xy 184.486747 -189.954133)
			(xy 184.4079 -189.984677) (xy 184.326571 -190.007816) (xy 184.243454 -190.023351) (xy 184.159258 -190.031152)
			(xy 184.11698 -190.031624) (xy 182.87238 -190.031624) (xy 182.830105 -190.031103) (xy 182.745916 -190.0233)
			(xy 182.662807 -190.007762) (xy 182.581485 -189.984623) (xy 182.502645 -189.954079) (xy 182.42696 -189.91639)
			(xy 182.355075 -189.87188) (xy 182.287603 -189.820926) (xy 182.225121 -189.763965) (xy 182.168161 -189.701481)
			(xy 182.117209 -189.634009) (xy 182.0727 -189.562123) (xy 182.035013 -189.486437) (xy 182.004471 -189.407596)
			(xy 181.981333 -189.326274) (xy 181.965797 -189.243164) (xy 181.957996 -189.158975) (xy 178.934342 -189.158975)
			(xy 178.970506 -189.190315) (xy 179.006193 -189.231502) (xy 179.035654 -189.277348) (xy 179.058292 -189.326921)
			(xy 179.073645 -189.37921) (xy 179.0814 -189.433152) (xy 179.0814 -189.487648) (xy 179.073645 -189.54159)
			(xy 179.058292 -189.593879) (xy 179.035654 -189.643452) (xy 179.006193 -189.689298) (xy 178.970506 -189.730485)
			(xy 178.929322 -189.766175) (xy 178.883478 -189.79564) (xy 178.833908 -189.818281) (xy 178.78162 -189.833638)
			(xy 178.727678 -189.841398) (xy 178.70043 -189.841886) (xy 178.674711 -189.841508) (xy 178.623736 -189.83461)
			(xy 178.574152 -189.820923) (xy 178.526858 -189.800694) (xy 178.482713 -189.77429) (xy 178.442518 -189.742192)
			(xy 178.407003 -189.704982) (xy 178.391566 -189.684406) (xy 178.383269 -189.673756) (xy 178.362261 -189.656822)
			(xy 178.337544 -189.645998) (xy 178.310852 -189.642044) (xy 178.284059 -189.645236) (xy 178.259043 -189.655351)
			(xy 178.237561 -189.671679) (xy 178.229006 -189.68212) (xy 178.21083 -189.70479) (xy 178.168746 -189.744856)
			(xy 178.121076 -189.778079) (xy 178.068921 -189.803692) (xy 178.013486 -189.821104) (xy 177.956053 -189.829912)
			(xy 177.927 -189.830456) (xy 177.900393 -189.830039) (xy 177.847698 -189.822624) (xy 177.796543 -189.807965)
			(xy 177.747918 -189.786346) (xy 177.702766 -189.758186) (xy 177.66196 -189.724031) (xy 177.626291 -189.684541)
			(xy 177.596449 -189.640481) (xy 177.573014 -189.592706) (xy 177.564288 -189.567566) (xy 177.559156 -189.553643)
			(xy 177.542261 -189.529271) (xy 177.519073 -189.510783) (xy 177.491551 -189.49974) (xy 177.462016 -189.497073)
			(xy 177.43296 -189.503007) (xy 177.406836 -189.517043) (xy 177.385848 -189.537994) (xy 177.37836 -189.550802)
			(xy 177.358482 -189.586705) (xy 177.313243 -189.655183) (xy 177.26205 -189.719331) (xy 177.205315 -189.778635)
			(xy 177.143494 -189.832615) (xy 177.077085 -189.880839) (xy 177.006621 -189.922919) (xy 176.932671 -189.958514)
			(xy 176.855828 -189.987341) (xy 176.776711 -190.009165) (xy 176.695957 -190.023813) (xy 176.614216 -190.031165)
			(xy 176.57318 -190.031624) (xy 175.32858 -190.031624) (xy 175.286305 -190.031103) (xy 175.202116 -190.0233)
			(xy 175.119007 -190.007762) (xy 175.037685 -189.984623) (xy 174.958845 -189.954079) (xy 174.88316 -189.91639)
			(xy 174.811275 -189.87188) (xy 174.743803 -189.820926) (xy 174.681321 -189.763965) (xy 174.624361 -189.701481)
			(xy 174.573409 -189.634009) (xy 174.5289 -189.562123) (xy 174.491213 -189.486437) (xy 174.460671 -189.407596)
			(xy 174.437533 -189.326274) (xy 174.421997 -189.243164) (xy 174.414196 -189.158975) (xy 173.961234 -189.158975)
			(xy 173.970891 -189.190909) (xy 173.979094 -189.246402) (xy 173.979586 -189.27445) (xy 173.9791 -189.301701)
			(xy 173.971344 -189.355649) (xy 173.955989 -189.407944) (xy 173.933347 -189.457521) (xy 173.903881 -189.503371)
			(xy 173.86819 -189.544562) (xy 173.826999 -189.580253) (xy 173.781149 -189.609719) (xy 173.731572 -189.632361)
			(xy 173.679277 -189.647716) (xy 173.625329 -189.655472) (xy 173.570827 -189.655472) (xy 173.516879 -189.647716)
			(xy 173.464584 -189.632361) (xy 173.415007 -189.609719) (xy 173.369157 -189.580253) (xy 173.327966 -189.544562)
			(xy 173.292275 -189.503371) (xy 173.262809 -189.457521) (xy 173.240167 -189.407944) (xy 173.224812 -189.355649)
			(xy 173.217056 -189.301701) (xy 173.21657 -189.27445) (xy 171.462975 -189.27445) (xy 171.456588 -189.296201)
			(xy 171.433946 -189.345775) (xy 171.40448 -189.391622) (xy 171.368789 -189.432808) (xy 171.327599 -189.468497)
			(xy 171.28175 -189.49796) (xy 171.232175 -189.520598) (xy 171.179882 -189.53595) (xy 171.125937 -189.543705)
			(xy 171.071438 -189.543703) (xy 171.017493 -189.535945) (xy 170.965201 -189.520589) (xy 170.915628 -189.497948)
			(xy 170.86978 -189.468481) (xy 170.828593 -189.432791) (xy 170.792905 -189.391601) (xy 170.763442 -189.345753)
			(xy 170.740803 -189.296177) (xy 170.72545 -189.243885) (xy 170.717696 -189.18994) (xy 170.71721 -189.16269)
			(xy 170.71721 -189.162436) (xy 170.716796 -189.148632) (xy 170.70936 -189.122043) (xy 170.695075 -189.098417)
			(xy 170.674985 -189.079479) (xy 170.650557 -189.066612) (xy 170.623576 -189.060756) (xy 170.609768 -189.06109)
			(xy 170.588178 -189.061598) (xy 170.560929 -189.061098) (xy 170.506986 -189.053339) (xy 170.454696 -189.037983)
			(xy 170.405123 -189.015341) (xy 170.359278 -188.985875) (xy 170.318093 -188.950184) (xy 170.282405 -188.908995)
			(xy 170.252943 -188.863147) (xy 170.230306 -188.813573) (xy 170.214954 -188.761282) (xy 170.207199 -188.707338)
			(xy 169.847068 -188.707338) (xy 169.866797 -188.74696) (xy 169.897341 -188.825805) (xy 169.920479 -188.907131)
			(xy 169.936015 -188.990246) (xy 169.943815 -189.074439) (xy 169.944288 -189.116716) (xy 169.943272 -189.15888)
			(xy 169.943041 -189.173638) (xy 169.950137 -189.202277) (xy 169.965136 -189.227684) (xy 169.986783 -189.247732)
			(xy 170.013265 -189.260741) (xy 170.042363 -189.265622) (xy 170.057064 -189.26429) (xy 170.068701 -189.262955)
			(xy 170.092086 -189.261558) (xy 170.1038 -189.261496) (xy 170.131052 -189.261974) (xy 170.185 -189.26973)
			(xy 170.237295 -189.285086) (xy 170.286873 -189.307727) (xy 170.332724 -189.337194) (xy 170.373914 -189.372886)
			(xy 170.409606 -189.414076) (xy 170.439073 -189.459927) (xy 170.461714 -189.509505) (xy 170.47707 -189.5618)
			(xy 170.484826 -189.615748) (xy 170.484826 -189.670252) (xy 170.47707 -189.7242) (xy 170.461714 -189.776495)
			(xy 170.439073 -189.826073) (xy 170.409606 -189.871924) (xy 170.373914 -189.913114) (xy 170.332724 -189.948806)
			(xy 170.286873 -189.978273) (xy 170.237295 -190.000914) (xy 170.185 -190.01627) (xy 170.131052 -190.024026)
			(xy 170.1038 -190.024512) (xy 170.075633 -190.023989) (xy 170.019913 -190.015693) (xy 169.966019 -189.999294)
			(xy 169.915121 -189.975151) (xy 169.868325 -189.943786) (xy 169.826649 -189.905883) (xy 169.790999 -189.862265)
			(xy 169.77614 -189.83833) (xy 169.768218 -189.825827) (xy 169.746469 -189.805764) (xy 169.719883 -189.792775)
			(xy 169.690689 -189.78795) (xy 169.661337 -189.791693) (xy 169.634289 -189.80369) (xy 169.622724 -189.81293)
			(xy 169.59171 -189.838764) (xy 169.525909 -189.885522) (xy 169.456245 -189.926301) (xy 169.383258 -189.960784)
			(xy 169.307518 -189.988703) (xy 169.229612 -190.009841) (xy 169.150147 -190.024033) (xy 169.069741 -190.031169)
			(xy 169.02938 -190.031624) (xy 167.78478 -190.031624) (xy 167.742505 -190.031103) (xy 167.658316 -190.0233)
			(xy 167.575207 -190.007762) (xy 167.493885 -189.984623) (xy 167.415045 -189.954079) (xy 167.33936 -189.91639)
			(xy 167.267475 -189.87188) (xy 167.200003 -189.820926) (xy 167.137521 -189.763965) (xy 167.080561 -189.701481)
			(xy 167.029609 -189.634009) (xy 166.9851 -189.562123) (xy 166.947413 -189.486437) (xy 166.916871 -189.407596)
			(xy 166.893733 -189.326274) (xy 166.878197 -189.243164) (xy 166.870396 -189.158975) (xy 162.400051 -189.158975)
			(xy 162.400051 -189.158978) (xy 162.392249 -189.243174) (xy 162.376711 -189.32629) (xy 162.353571 -189.407619)
			(xy 162.323025 -189.486465) (xy 162.285335 -189.562157) (xy 162.240821 -189.634048) (xy 162.189864 -189.701525)
			(xy 162.132898 -189.764012) (xy 162.070409 -189.820977) (xy 162.002931 -189.871932) (xy 161.931039 -189.916445)
			(xy 161.855347 -189.954133) (xy 161.7765 -189.984677) (xy 161.695171 -190.007816) (xy 161.612054 -190.023351)
			(xy 161.527858 -190.031152) (xy 161.48558 -190.031624) (xy 160.24098 -190.031624) (xy 160.19691 -190.031082)
			(xy 160.109176 -190.022619) (xy 160.022664 -190.005754) (xy 159.938176 -189.980644) (xy 159.856496 -189.947522)
			(xy 159.778382 -189.906694) (xy 159.704558 -189.858541) (xy 159.635709 -189.803507) (xy 159.572475 -189.742105)
			(xy 159.515442 -189.674904) (xy 159.465139 -189.602528) (xy 159.422033 -189.525647) (xy 159.403796 -189.485524)
			(xy 159.398988 -189.475995) (xy 159.383153 -189.461718) (xy 159.362886 -189.455094) (xy 159.341675 -189.457265)
			(xy 159.323171 -189.467857) (xy 159.31642 -189.476126) (xy 159.313372 -189.48019) (xy 159.304868 -189.492189)
			(xy 159.294596 -189.519738) (xy 159.292591 -189.54907) (xy 159.29902 -189.57776) (xy 159.31335 -189.603433)
			(xy 159.323532 -189.614048) (xy 159.344816 -189.635728) (xy 159.380933 -189.684577) (xy 159.408852 -189.738533)
			(xy 159.427867 -189.796232) (xy 159.437496 -189.856214) (xy 159.438086 -189.88659) (xy 159.437635 -189.913844)
			(xy 159.429879 -189.967796) (xy 159.414523 -190.020096) (xy 159.39188 -190.069677) (xy 159.362411 -190.115531)
			(xy 159.326716 -190.156725) (xy 159.285522 -190.192419) (xy 159.239667 -190.221886) (xy 159.190084 -190.244527)
			(xy 159.137784 -190.259882) (xy 159.083832 -190.267636) (xy 159.056578 -190.268098) (xy 159.028573 -190.267607)
			(xy 158.973161 -190.259437) (xy 158.919538 -190.243261) (xy 158.868852 -190.219426) (xy 158.84525 -190.204344)
			(xy 158.833376 -190.197025) (xy 158.806854 -190.188426) (xy 158.778996 -190.187317) (xy 158.751875 -190.193781)
			(xy 158.727511 -190.207336) (xy 158.70772 -190.226973) (xy 158.70047 -190.238888) (xy 158.685886 -190.263767)
			(xy 158.650369 -190.309201) (xy 158.608412 -190.348764) (xy 158.560974 -190.381555) (xy 158.509136 -190.406823)
			(xy 158.454084 -190.423993) (xy 158.397072 -190.432673) (xy 158.368238 -190.433198) (xy 158.340983 -190.432758)
			(xy 158.287026 -190.425005) (xy 158.234722 -190.409652) (xy 158.185136 -190.387011) (xy 158.139277 -190.357543)
			(xy 158.098079 -190.321848) (xy 158.06238 -190.280654) (xy 158.032907 -190.234797) (xy 158.010262 -190.185213)
			(xy 157.994903 -190.132911) (xy 157.987145 -190.078955) (xy 156.14904 -190.078955) (xy 156.14904 -190.796948)
			(xy 216.331826 -190.796948) (xy 216.331826 -190.742452) (xy 216.339582 -190.688511) (xy 216.354935 -190.636223)
			(xy 216.377573 -190.586652) (xy 216.407036 -190.540808) (xy 216.442723 -190.499623) (xy 216.483908 -190.463936)
			(xy 216.529752 -190.434473) (xy 216.579323 -190.411835) (xy 216.631611 -190.396482) (xy 216.685552 -190.388726)
			(xy 216.7128 -190.38824) (xy 216.739617 -190.388707) (xy 216.792721 -190.396226) (xy 216.84425 -190.411102)
			(xy 216.893191 -190.433042) (xy 216.93858 -190.461615) (xy 216.979524 -190.496258) (xy 217.015218 -190.536289)
			(xy 217.044959 -190.580921) (xy 217.05697 -190.604902) (xy 217.063231 -190.616904) (xy 217.080925 -190.637376)
			(xy 217.103378 -190.652477) (xy 217.12901 -190.661146) (xy 217.156019 -190.662774) (xy 217.182507 -190.657246)
			(xy 217.206611 -190.644951) (xy 217.226636 -190.626753) (xy 217.234262 -190.61557) (xy 217.24936 -190.592743)
			(xy 217.285066 -190.551266) (xy 217.326331 -190.515315) (xy 217.372307 -190.485626) (xy 217.422053 -190.462809)
			(xy 217.474548 -190.447332) (xy 217.528716 -190.439512) (xy 217.55608 -190.43904) (xy 217.581209 -190.439416)
			(xy 217.631032 -190.446024) (xy 217.679556 -190.459116) (xy 217.725942 -190.478465) (xy 217.769386 -190.503735)
			(xy 217.789506 -190.518796) (xy 217.800359 -190.526716) (xy 217.825187 -190.536972) (xy 217.851829 -190.540413)
			(xy 217.878448 -190.536801) (xy 217.90321 -190.526385) (xy 217.924406 -190.509883) (xy 217.940577 -190.488432)
			(xy 217.94597 -190.476124) (xy 217.956961 -190.449905) (xy 217.985592 -190.400793) (xy 218.021198 -190.356476)
			(xy 218.06299 -190.317937) (xy 218.110041 -190.286031) (xy 218.161308 -190.261465) (xy 218.215655 -190.244784)
			(xy 218.271875 -190.236358) (xy 218.3003 -190.23584) (xy 218.327555 -190.23623) (xy 218.381509 -190.243987)
			(xy 218.433811 -190.259344) (xy 218.483394 -190.281988) (xy 218.52925 -190.311458) (xy 218.570446 -190.347154)
			(xy 218.606142 -190.38835) (xy 218.635612 -190.434206) (xy 218.658256 -190.483789) (xy 218.673613 -190.536091)
			(xy 218.68137 -190.590045) (xy 218.68137 -190.644555) (xy 218.673613 -190.698509) (xy 218.658256 -190.750811)
			(xy 218.635612 -190.800394) (xy 218.606142 -190.84625) (xy 218.570446 -190.887446) (xy 218.553848 -190.901828)
			(xy 219.246702 -190.901828) (xy 219.250773 -190.846206) (xy 219.262899 -190.791769) (xy 219.282822 -190.739678)
			(xy 219.310118 -190.691043) (xy 219.344204 -190.6469) (xy 219.384353 -190.608191) (xy 219.429711 -190.57574)
			(xy 219.479311 -190.550239) (xy 219.532095 -190.532232) (xy 219.586938 -190.522102) (xy 219.642672 -190.520065)
			(xy 219.698109 -190.526165) (xy 219.752066 -190.540271) (xy 219.803395 -190.562083) (xy 219.851001 -190.591137)
			(xy 219.893869 -190.626812) (xy 219.931086 -190.668349) (xy 219.961859 -190.714862) (xy 219.985531 -190.765359)
			(xy 220.001599 -190.818766) (xy 220.009719 -190.873942) (xy 220.010228 -190.901828) (xy 220.009719 -190.929714)
			(xy 220.001599 -190.98489) (xy 219.985531 -191.038297) (xy 219.961859 -191.088794) (xy 219.931086 -191.135307)
			(xy 219.893869 -191.176844) (xy 219.851001 -191.212519) (xy 219.803395 -191.241573) (xy 219.752066 -191.263385)
			(xy 219.698109 -191.277491) (xy 219.642672 -191.283591) (xy 219.586938 -191.281554) (xy 219.532095 -191.271424)
			(xy 219.479311 -191.253417) (xy 219.429711 -191.227916) (xy 219.384353 -191.195465) (xy 219.344204 -191.156756)
			(xy 219.310118 -191.112613) (xy 219.282822 -191.063978) (xy 219.262899 -191.011887) (xy 219.250773 -190.95745)
			(xy 219.246702 -190.901828) (xy 218.553848 -190.901828) (xy 218.52925 -190.923142) (xy 218.483394 -190.952612)
			(xy 218.433811 -190.975256) (xy 218.381509 -190.990613) (xy 218.327555 -190.99837) (xy 218.3003 -190.998856)
			(xy 218.275172 -190.998437) (xy 218.225351 -190.991839) (xy 218.176827 -190.978757) (xy 218.130441 -190.959418)
			(xy 218.086996 -190.934157) (xy 218.066874 -190.9191) (xy 218.055956 -190.911277) (xy 218.031148 -190.901012)
			(xy 218.004523 -190.897559) (xy 217.977917 -190.901157) (xy 217.953165 -190.911556) (xy 217.931973 -190.92804)
			(xy 217.915804 -190.949473) (xy 217.91041 -190.961772) (xy 217.899351 -190.98796) (xy 217.870729 -191.03707)
			(xy 217.835132 -191.081386) (xy 217.79335 -191.119926) (xy 217.746309 -191.151836) (xy 217.695051 -191.176407)
			(xy 217.640714 -191.193096) (xy 217.584501 -191.201533) (xy 217.55608 -191.202056) (xy 217.529263 -191.201607)
			(xy 217.476158 -191.194086) (xy 217.424628 -191.179207) (xy 217.375687 -191.157264) (xy 217.330298 -191.128689)
			(xy 217.289354 -191.094044) (xy 217.253661 -191.05401) (xy 217.22392 -191.009376) (xy 217.21191 -190.985394)
			(xy 217.205678 -190.973375) (xy 217.187979 -190.952903) (xy 217.165521 -190.937801) (xy 217.139884 -190.929133)
			(xy 217.11287 -190.927507) (xy 217.086378 -190.933039) (xy 217.062271 -190.945338) (xy 217.042245 -190.96354)
			(xy 217.034618 -190.974726) (xy 217.019532 -190.997562) (xy 216.983824 -191.039039) (xy 216.942558 -191.074989)
			(xy 216.896579 -191.104677) (xy 216.846831 -191.127492) (xy 216.794334 -191.142968) (xy 216.740165 -191.150785)
			(xy 216.7128 -191.151256) (xy 216.685552 -191.150674) (xy 216.631611 -191.142918) (xy 216.579323 -191.127565)
			(xy 216.529752 -191.104927) (xy 216.483908 -191.075464) (xy 216.442723 -191.039777) (xy 216.407036 -190.998592)
			(xy 216.377573 -190.952748) (xy 216.354935 -190.903177) (xy 216.339582 -190.850889) (xy 216.331826 -190.796948)
			(xy 156.14904 -190.796948) (xy 156.14904 -192.339554) (xy 159.744845 -192.339554) (xy 159.744845 -192.285046)
			(xy 159.752603 -192.231092) (xy 159.76796 -192.178791) (xy 159.790604 -192.129208) (xy 159.820075 -192.083353)
			(xy 159.855771 -192.042159) (xy 159.896967 -192.006464) (xy 159.942824 -191.976996) (xy 159.992408 -191.954354)
			(xy 160.044709 -191.938999) (xy 160.098664 -191.931244) (xy 160.125918 -191.930782) (xy 160.153435 -191.931306)
			(xy 160.207895 -191.939237) (xy 160.260652 -191.954903) (xy 160.310614 -191.97798) (xy 160.356746 -192.00799)
			(xy 160.398093 -192.044311) (xy 160.433798 -192.086191) (xy 160.463121 -192.132763) (xy 160.485456 -192.183061)
			(xy 160.500339 -192.236045) (xy 160.504378 -192.263268) (xy 160.5066 -192.276908) (xy 160.511275 -192.287906)
			(xy 208.500978 -192.287906) (xy 208.505049 -192.232284) (xy 208.517175 -192.177847) (xy 208.537098 -192.125756)
			(xy 208.564394 -192.077121) (xy 208.59848 -192.032978) (xy 208.638629 -191.994269) (xy 208.683987 -191.961818)
			(xy 208.733587 -191.936317) (xy 208.786371 -191.91831) (xy 208.841214 -191.90818) (xy 208.896948 -191.906143)
			(xy 208.952385 -191.912243) (xy 209.006342 -191.926349) (xy 209.057671 -191.948161) (xy 209.105277 -191.977215)
			(xy 209.148145 -192.01289) (xy 209.185362 -192.054427) (xy 209.216135 -192.10094) (xy 209.239807 -192.151437)
			(xy 209.255875 -192.204844) (xy 209.263995 -192.26002) (xy 209.264291 -192.276222) (xy 221.653352 -192.276222)
			(xy 221.657423 -192.2206) (xy 221.669549 -192.166163) (xy 221.689472 -192.114072) (xy 221.716768 -192.065437)
			(xy 221.750854 -192.021294) (xy 221.791003 -191.982585) (xy 221.836361 -191.950134) (xy 221.885961 -191.924633)
			(xy 221.938745 -191.906626) (xy 221.993588 -191.896496) (xy 222.049322 -191.894459) (xy 222.104759 -191.900559)
			(xy 222.158716 -191.914665) (xy 222.210045 -191.936477) (xy 222.257651 -191.965531) (xy 222.300519 -192.001206)
			(xy 222.337736 -192.042743) (xy 222.368509 -192.089256) (xy 222.392181 -192.139753) (xy 222.408249 -192.19316)
			(xy 222.416369 -192.248336) (xy 222.416878 -192.276222) (xy 222.416369 -192.304108) (xy 222.408249 -192.359284)
			(xy 222.392181 -192.412691) (xy 222.368509 -192.463188) (xy 222.344157 -192.499996) (xy 231.378004 -192.499996)
			(xy 231.382018 -192.294312) (xy 231.394054 -192.088942) (xy 231.414093 -191.884198) (xy 231.442106 -191.680391)
			(xy 231.478049 -191.477832) (xy 231.521868 -191.27683) (xy 231.573495 -191.077691) (xy 231.632853 -190.880718)
			(xy 231.699851 -190.68621) (xy 231.774387 -190.494465) (xy 231.856347 -190.305774) (xy 231.945607 -190.120424)
			(xy 232.04203 -189.938698) (xy 232.145471 -189.760872) (xy 232.25577 -189.587218) (xy 232.372761 -189.417999)
			(xy 232.496265 -189.253473) (xy 232.626094 -189.093892) (xy 232.762051 -188.939497) (xy 232.903928 -188.790525)
			(xy 233.051509 -188.647201) (xy 233.20457 -188.509745) (xy 233.362877 -188.378365) (xy 233.52619 -188.253262)
			(xy 233.694259 -188.134625) (xy 233.866829 -188.022637) (xy 234.043637 -187.917466) (xy 234.224414 -187.819275)
			(xy 234.408884 -187.728211) (xy 234.596766 -187.644414) (xy 234.787776 -187.568011) (xy 234.98162 -187.499118)
			(xy 235.178005 -187.437841) (xy 235.376631 -187.384273) (xy 235.577196 -187.338496) (xy 235.779394 -187.300578)
			(xy 235.982918 -187.270579) (xy 236.187457 -187.248542) (xy 236.3927 -187.234503) (xy 236.598335 -187.228483)
			(xy 236.804048 -187.23049) (xy 237.009526 -187.240522) (xy 237.214456 -187.258563) (xy 237.418526 -187.284586)
			(xy 237.621426 -187.318551) (xy 237.822846 -187.360406) (xy 238.022479 -187.410088) (xy 238.220022 -187.467522)
			(xy 238.415174 -187.532619) (xy 238.607638 -187.60528) (xy 238.79712 -187.685396) (xy 238.959797 -187.761791)
			(xy 300.103542 -187.761791) (xy 300.103542 -187.702025) (xy 300.11168 -187.642815) (xy 300.127805 -187.585265)
			(xy 300.151616 -187.530446) (xy 300.18267 -187.47938) (xy 300.220388 -187.433019) (xy 300.264067 -187.392225)
			(xy 300.312895 -187.357759) (xy 300.365961 -187.330262) (xy 300.422276 -187.310247) (xy 300.480793 -187.298088)
			(xy 300.54042 -187.294009) (xy 300.600047 -187.298088) (xy 300.658564 -187.310247) (xy 300.714879 -187.330262)
			(xy 300.767945 -187.357759) (xy 300.816773 -187.392225) (xy 300.860452 -187.433019) (xy 300.89817 -187.47938)
			(xy 300.929224 -187.530446) (xy 300.953035 -187.585265) (xy 300.96916 -187.642815) (xy 300.977298 -187.702025)
			(xy 300.977808 -187.731908) (xy 300.977298 -187.761791) (xy 300.96916 -187.821001) (xy 300.953035 -187.878551)
			(xy 300.929224 -187.93337) (xy 300.920907 -187.947046) (xy 320.543426 -187.947046) (xy 320.547497 -187.891424)
			(xy 320.559623 -187.836987) (xy 320.579546 -187.784896) (xy 320.606842 -187.736261) (xy 320.640928 -187.692118)
			(xy 320.681077 -187.653409) (xy 320.726435 -187.620958) (xy 320.776035 -187.595457) (xy 320.828819 -187.57745)
			(xy 320.883662 -187.56732) (xy 320.939396 -187.565283) (xy 320.994833 -187.571383) (xy 321.04879 -187.585489)
			(xy 321.100119 -187.607301) (xy 321.147725 -187.636355) (xy 321.190593 -187.67203) (xy 321.22781 -187.713567)
			(xy 321.258583 -187.76008) (xy 321.282255 -187.810577) (xy 321.298323 -187.863984) (xy 321.306443 -187.91916)
			(xy 321.306952 -187.947046) (xy 321.306443 -187.974932) (xy 321.298323 -188.030108) (xy 321.282255 -188.083515)
			(xy 321.258583 -188.134012) (xy 321.22781 -188.180525) (xy 321.190593 -188.222062) (xy 321.147725 -188.257737)
			(xy 321.100119 -188.286791) (xy 321.04879 -188.308603) (xy 320.994833 -188.322709) (xy 320.939396 -188.328809)
			(xy 320.883662 -188.326772) (xy 320.828819 -188.316642) (xy 320.776035 -188.298635) (xy 320.726435 -188.273134)
			(xy 320.681077 -188.240683) (xy 320.640928 -188.201974) (xy 320.606842 -188.157831) (xy 320.579546 -188.109196)
			(xy 320.559623 -188.057105) (xy 320.547497 -188.002668) (xy 320.543426 -187.947046) (xy 300.920907 -187.947046)
			(xy 300.89817 -187.984436) (xy 300.860452 -188.030797) (xy 300.816773 -188.071591) (xy 300.767945 -188.106057)
			(xy 300.714879 -188.133554) (xy 300.658564 -188.153569) (xy 300.600047 -188.165728) (xy 300.54042 -188.169807)
			(xy 300.480793 -188.165728) (xy 300.422276 -188.153569) (xy 300.365961 -188.133554) (xy 300.312895 -188.106057)
			(xy 300.264067 -188.071591) (xy 300.220388 -188.030797) (xy 300.18267 -187.984436) (xy 300.151616 -187.93337)
			(xy 300.127805 -187.878551) (xy 300.11168 -187.821001) (xy 300.103542 -187.761791) (xy 238.959797 -187.761791)
			(xy 238.983331 -187.772843) (xy 239.16599 -187.867489) (xy 239.344816 -187.969189) (xy 239.519538 -188.077789)
			(xy 239.689891 -188.193124) (xy 239.855613 -188.315017) (xy 240.016454 -188.443283) (xy 240.172167 -188.577726)
			(xy 240.322517 -188.718143) (xy 240.467274 -188.864319) (xy 240.606217 -189.016031) (xy 240.739135 -189.173049)
			(xy 240.865826 -189.335134) (xy 240.986096 -189.502037) (xy 241.099763 -189.673507) (xy 241.206653 -189.84928)
			(xy 241.306604 -190.02909) (xy 241.399463 -190.212663) (xy 241.48509 -190.399719) (xy 241.563352 -190.589974)
			(xy 241.634133 -190.783137) (xy 241.697323 -190.978915) (xy 241.752826 -191.177009) (xy 241.800558 -191.377118)
			(xy 241.840447 -191.578936) (xy 241.872431 -191.782158) (xy 241.896461 -191.986472) (xy 241.912502 -192.191568)
			(xy 241.920528 -192.397135) (xy 241.92103 -192.499996) (xy 241.920528 -192.602857) (xy 241.912502 -192.808424)
			(xy 241.896461 -193.01352) (xy 241.872431 -193.217834) (xy 241.840447 -193.421056) (xy 241.800558 -193.622874)
			(xy 241.752826 -193.822983) (xy 241.697323 -194.021077) (xy 241.634133 -194.216855) (xy 241.563352 -194.410018)
			(xy 241.48509 -194.600273) (xy 241.399463 -194.787329) (xy 241.306604 -194.970902) (xy 241.206653 -195.150712)
			(xy 241.099763 -195.326485) (xy 240.986096 -195.497955) (xy 240.865826 -195.664858) (xy 240.739135 -195.826943)
			(xy 240.606217 -195.983961) (xy 240.467274 -196.135673) (xy 240.322517 -196.281849) (xy 240.172167 -196.422266)
			(xy 240.016454 -196.556709) (xy 239.855613 -196.684975) (xy 239.689891 -196.806868) (xy 239.519538 -196.922203)
			(xy 239.344816 -197.030803) (xy 239.16599 -197.132503) (xy 238.983331 -197.227149) (xy 238.79712 -197.314596)
			(xy 238.607638 -197.394712) (xy 238.415174 -197.467373) (xy 238.220022 -197.53247) (xy 238.022479 -197.589904)
			(xy 237.822846 -197.639586) (xy 237.621426 -197.681441) (xy 237.418526 -197.715406) (xy 237.214456 -197.741429)
			(xy 237.009526 -197.75947) (xy 236.804048 -197.769502) (xy 236.598335 -197.771509) (xy 236.3927 -197.765489)
			(xy 236.187457 -197.75145) (xy 235.982918 -197.729413) (xy 235.779394 -197.699414) (xy 235.577196 -197.661496)
			(xy 235.376631 -197.615719) (xy 235.178005 -197.562151) (xy 234.98162 -197.500874) (xy 234.787776 -197.431981)
			(xy 234.596766 -197.355578) (xy 234.408884 -197.271781) (xy 234.224414 -197.180717) (xy 234.043637 -197.082526)
			(xy 233.866829 -196.977355) (xy 233.694259 -196.865367) (xy 233.52619 -196.74673) (xy 233.362877 -196.621627)
			(xy 233.20457 -196.490247) (xy 233.051509 -196.352791) (xy 232.903928 -196.209467) (xy 232.762051 -196.060495)
			(xy 232.626094 -195.9061) (xy 232.496265 -195.746519) (xy 232.372761 -195.581993) (xy 232.25577 -195.412774)
			(xy 232.145471 -195.23912) (xy 232.04203 -195.061294) (xy 231.945607 -194.879568) (xy 231.856347 -194.694218)
			(xy 231.774387 -194.505527) (xy 231.699851 -194.313782) (xy 231.632853 -194.119274) (xy 231.573495 -193.922301)
			(xy 231.521868 -193.723162) (xy 231.478049 -193.52216) (xy 231.442106 -193.319601) (xy 231.414093 -193.115794)
			(xy 231.394054 -192.91105) (xy 231.382018 -192.70568) (xy 231.378004 -192.499996) (xy 222.344157 -192.499996)
			(xy 222.337736 -192.509701) (xy 222.300519 -192.551238) (xy 222.257651 -192.586913) (xy 222.210045 -192.615967)
			(xy 222.158716 -192.637779) (xy 222.104759 -192.651885) (xy 222.049322 -192.657985) (xy 221.993588 -192.655948)
			(xy 221.938745 -192.645818) (xy 221.885961 -192.627811) (xy 221.836361 -192.60231) (xy 221.791003 -192.569859)
			(xy 221.750854 -192.53115) (xy 221.716768 -192.487007) (xy 221.689472 -192.438372) (xy 221.669549 -192.386281)
			(xy 221.657423 -192.331844) (xy 221.653352 -192.276222) (xy 209.264291 -192.276222) (xy 209.264504 -192.287906)
			(xy 209.263995 -192.315792) (xy 209.255875 -192.370968) (xy 209.239807 -192.424375) (xy 209.216135 -192.474872)
			(xy 209.185362 -192.521385) (xy 209.148145 -192.562922) (xy 209.105277 -192.598597) (xy 209.057671 -192.627651)
			(xy 209.006342 -192.649463) (xy 208.952385 -192.663569) (xy 208.896948 -192.669669) (xy 208.841214 -192.667632)
			(xy 208.786371 -192.657502) (xy 208.733587 -192.639495) (xy 208.683987 -192.613994) (xy 208.638629 -192.581543)
			(xy 208.59848 -192.542834) (xy 208.564394 -192.498691) (xy 208.537098 -192.450056) (xy 208.517175 -192.397965)
			(xy 208.505049 -192.343528) (xy 208.500978 -192.287906) (xy 160.511275 -192.287906) (xy 160.517408 -192.302332)
			(xy 160.534631 -192.323932) (xy 160.557009 -192.340131) (xy 160.582908 -192.349745) (xy 160.610436 -192.352071)
			(xy 160.637581 -192.34694) (xy 160.650174 -192.341246) (xy 160.676617 -192.328786) (xy 160.732348 -192.311152)
			(xy 160.790112 -192.302203) (xy 160.819338 -192.301622) (xy 160.84659 -192.30205) (xy 160.900537 -192.309812)
			(xy 160.952832 -192.325172) (xy 161.002408 -192.347817) (xy 161.048257 -192.377286) (xy 161.089446 -192.412981)
			(xy 161.125136 -192.454173) (xy 161.154602 -192.500025) (xy 161.177242 -192.549604) (xy 161.192596 -192.6019)
			(xy 161.200352 -192.655848) (xy 161.200352 -192.710352) (xy 161.192596 -192.7643) (xy 161.177242 -192.816596)
			(xy 161.154602 -192.866175) (xy 161.125136 -192.912027) (xy 161.089446 -192.953219) (xy 161.048257 -192.988914)
			(xy 161.002408 -193.018383) (xy 160.994564 -193.021966) (xy 169.741594 -193.021966) (xy 169.745665 -192.966344)
			(xy 169.757791 -192.911907) (xy 169.777714 -192.859816) (xy 169.80501 -192.811181) (xy 169.839096 -192.767038)
			(xy 169.879245 -192.728329) (xy 169.924603 -192.695878) (xy 169.974203 -192.670377) (xy 170.026987 -192.65237)
			(xy 170.08183 -192.64224) (xy 170.137564 -192.640203) (xy 170.193001 -192.646303) (xy 170.246958 -192.660409)
			(xy 170.298287 -192.682221) (xy 170.345893 -192.711275) (xy 170.388761 -192.74695) (xy 170.397578 -192.75679)
			(xy 193.3227 -192.75679) (xy 193.326771 -192.701168) (xy 193.338897 -192.646731) (xy 193.35882 -192.59464)
			(xy 193.386116 -192.546005) (xy 193.420202 -192.501862) (xy 193.460351 -192.463153) (xy 193.505709 -192.430702)
			(xy 193.555309 -192.405201) (xy 193.608093 -192.387194) (xy 193.662936 -192.377064) (xy 193.71867 -192.375027)
			(xy 193.774107 -192.381127) (xy 193.828064 -192.395233) (xy 193.879393 -192.417045) (xy 193.926999 -192.446099)
			(xy 193.969867 -192.481774) (xy 194.007084 -192.523311) (xy 194.037857 -192.569824) (xy 194.061529 -192.620321)
			(xy 194.077597 -192.673728) (xy 194.085717 -192.728904) (xy 194.086226 -192.75679) (xy 194.085804 -192.779904)
			(xy 212.24824 -192.779904) (xy 212.252311 -192.724282) (xy 212.264437 -192.669845) (xy 212.28436 -192.617754)
			(xy 212.311656 -192.569119) (xy 212.345742 -192.524976) (xy 212.385891 -192.486267) (xy 212.431249 -192.453816)
			(xy 212.480849 -192.428315) (xy 212.533633 -192.410308) (xy 212.588476 -192.400178) (xy 212.64421 -192.398141)
			(xy 212.699647 -192.404241) (xy 212.753604 -192.418347) (xy 212.804933 -192.440159) (xy 212.852539 -192.469213)
			(xy 212.895407 -192.504888) (xy 212.932624 -192.546425) (xy 212.963397 -192.592938) (xy 212.987069 -192.643435)
			(xy 213.003137 -192.696842) (xy 213.011257 -192.752018) (xy 213.011766 -192.779904) (xy 213.011257 -192.80779)
			(xy 213.003137 -192.862966) (xy 212.987069 -192.916373) (xy 212.963397 -192.96687) (xy 212.932624 -193.013383)
			(xy 212.895407 -193.05492) (xy 212.852539 -193.090595) (xy 212.804933 -193.119649) (xy 212.753604 -193.141461)
			(xy 212.699647 -193.155567) (xy 212.64421 -193.161667) (xy 212.588476 -193.15963) (xy 212.533633 -193.1495)
			(xy 212.480849 -193.131493) (xy 212.431249 -193.105992) (xy 212.385891 -193.073541) (xy 212.345742 -193.034832)
			(xy 212.311656 -192.990689) (xy 212.28436 -192.942054) (xy 212.264437 -192.889963) (xy 212.252311 -192.835526)
			(xy 212.24824 -192.779904) (xy 194.085804 -192.779904) (xy 194.085717 -192.784676) (xy 194.077597 -192.839852)
			(xy 194.061529 -192.893259) (xy 194.037857 -192.943756) (xy 194.007084 -192.990269) (xy 193.969867 -193.031806)
			(xy 193.926999 -193.067481) (xy 193.879393 -193.096535) (xy 193.828064 -193.118347) (xy 193.774107 -193.132453)
			(xy 193.71867 -193.138553) (xy 193.662936 -193.136516) (xy 193.608093 -193.126386) (xy 193.555309 -193.108379)
			(xy 193.505709 -193.082878) (xy 193.460351 -193.050427) (xy 193.420202 -193.011718) (xy 193.386116 -192.967575)
			(xy 193.35882 -192.91894) (xy 193.338897 -192.866849) (xy 193.326771 -192.812412) (xy 193.3227 -192.75679)
			(xy 170.397578 -192.75679) (xy 170.425978 -192.788487) (xy 170.456751 -192.835) (xy 170.480423 -192.885497)
			(xy 170.496491 -192.938904) (xy 170.504611 -192.99408) (xy 170.50512 -193.021966) (xy 170.504611 -193.049852)
			(xy 170.496491 -193.105028) (xy 170.480423 -193.158435) (xy 170.456751 -193.208932) (xy 170.425978 -193.255445)
			(xy 170.388761 -193.296982) (xy 170.345893 -193.332657) (xy 170.298287 -193.361711) (xy 170.246958 -193.383523)
			(xy 170.193001 -193.397629) (xy 170.137564 -193.403729) (xy 170.08183 -193.401692) (xy 170.026987 -193.391562)
			(xy 169.974203 -193.373555) (xy 169.924603 -193.348054) (xy 169.879245 -193.315603) (xy 169.839096 -193.276894)
			(xy 169.80501 -193.232751) (xy 169.777714 -193.184116) (xy 169.757791 -193.132025) (xy 169.745665 -193.077588)
			(xy 169.741594 -193.021966) (xy 160.994564 -193.021966) (xy 160.952832 -193.041028) (xy 160.900537 -193.056388)
			(xy 160.84659 -193.06415) (xy 160.819338 -193.064638) (xy 160.791819 -193.064132) (xy 160.737355 -193.056207)
			(xy 160.684594 -193.040544) (xy 160.634627 -193.017468) (xy 160.588492 -192.987457) (xy 160.547144 -192.951132)
			(xy 160.511439 -192.909248) (xy 160.482118 -192.862671) (xy 160.459788 -192.812367) (xy 160.444912 -192.759378)
			(xy 160.440878 -192.732152) (xy 160.438566 -192.718531) (xy 160.427771 -192.693116) (xy 160.410563 -192.671521)
			(xy 160.388201 -192.655323) (xy 160.362318 -192.645705) (xy 160.334805 -192.643369) (xy 160.307671 -192.648487)
			(xy 160.295082 -192.654174) (xy 160.268631 -192.666616) (xy 160.212904 -192.684256) (xy 160.155143 -192.693213)
			(xy 160.125918 -192.693798) (xy 160.098664 -192.693356) (xy 160.044709 -192.685601) (xy 159.992408 -192.670246)
			(xy 159.942824 -192.647604) (xy 159.896967 -192.618136) (xy 159.855771 -192.582441) (xy 159.820075 -192.541247)
			(xy 159.790604 -192.495392) (xy 159.76796 -192.445809) (xy 159.752603 -192.393508) (xy 159.744845 -192.339554)
			(xy 156.14904 -192.339554) (xy 156.14904 -192.85839) (xy 156.862272 -193.571622) (xy 156.888434 -193.566796)
			(xy 156.90537 -193.563934) (xy 156.939585 -193.560879) (xy 156.95676 -193.5607) (xy 156.983339 -193.561158)
			(xy 157.035983 -193.568536) (xy 157.087091 -193.583156) (xy 157.135673 -193.604733) (xy 157.180787 -193.632848)
			(xy 157.221558 -193.666958) (xy 157.257196 -193.706401) (xy 157.28701 -193.750411) (xy 157.299152 -193.77406)
			(xy 157.313122 -193.802508) (xy 157.3784 -193.802508) (xy 157.3784 -193.929) (xy 157.4038 -193.9544)
			(xy 193.658998 -193.9544) (xy 193.672596 -193.931115) (xy 193.705339 -193.888272) (xy 193.743788 -193.850467)
			(xy 193.787176 -193.818451) (xy 193.834641 -193.792863) (xy 193.885235 -193.774214) (xy 193.937951 -193.762873)
			(xy 193.991738 -193.759067) (xy 194.045525 -193.762873) (xy 194.098241 -193.774214) (xy 194.148835 -193.792863)
			(xy 194.1963 -193.818451) (xy 194.239688 -193.850467) (xy 194.278137 -193.888272) (xy 194.31088 -193.931115)
			(xy 194.324478 -193.9544) (xy 195.3768 -193.9544) (xy 195.4149 -193.9163) (xy 196.576696 -193.9163)
			(xy 196.59092 -193.888614) (xy 196.604077 -193.863967) (xy 196.636506 -193.818472) (xy 196.675225 -193.778194)
			(xy 196.719404 -193.743994) (xy 196.7681 -193.716605) (xy 196.82027 -193.696611) (xy 196.874798 -193.684442)
			(xy 196.930518 -193.680356) (xy 196.986238 -193.684442) (xy 197.040766 -193.696611) (xy 197.092936 -193.716605)
			(xy 197.141632 -193.743994) (xy 197.185811 -193.778194) (xy 197.22453 -193.818472) (xy 197.256959 -193.863967)
			(xy 197.270116 -193.888614) (xy 197.28434 -193.9163) (xy 198.630794 -193.9163) (xy 198.645028 -193.915828)
			(xy 198.672391 -193.907979) (xy 198.69653 -193.892889) (xy 198.71557 -193.871727) (xy 198.728037 -193.846135)
			(xy 198.732963 -193.818097) (xy 198.729966 -193.789789) (xy 198.719279 -193.763404) (xy 198.710804 -193.751962)
			(xy 198.695428 -193.731717) (xy 198.669601 -193.687928) (xy 198.649818 -193.641098) (xy 198.636429 -193.592055)
			(xy 198.629672 -193.541669) (xy 198.62927 -193.51625) (xy 198.629756 -193.488999) (xy 198.637512 -193.435051)
			(xy 198.652867 -193.382756) (xy 198.675509 -193.333179) (xy 198.704975 -193.287329) (xy 198.740666 -193.246138)
			(xy 198.781857 -193.210447) (xy 198.827707 -193.180981) (xy 198.877284 -193.158339) (xy 198.929579 -193.142984)
			(xy 198.983527 -193.135228) (xy 199.038029 -193.135228) (xy 199.091977 -193.142984) (xy 199.144272 -193.158339)
			(xy 199.193849 -193.180981) (xy 199.239699 -193.210447) (xy 199.28089 -193.246138) (xy 199.316581 -193.287329)
			(xy 199.346047 -193.333179) (xy 199.368689 -193.382756) (xy 199.384044 -193.435051) (xy 199.3918 -193.488999)
			(xy 199.392286 -193.51625) (xy 199.391869 -193.541669) (xy 199.385124 -193.592058) (xy 199.371745 -193.641105)
			(xy 199.35197 -193.68794) (xy 199.32615 -193.731734) (xy 199.310752 -193.751962) (xy 199.302338 -193.763452)
			(xy 199.291626 -193.789827) (xy 199.28861 -193.818134) (xy 199.293522 -193.846175) (xy 199.305982 -193.87177)
			(xy 199.325021 -193.892934) (xy 199.349162 -193.908021) (xy 199.376528 -193.91586) (xy 199.390762 -193.9163)
			(xy 202.726798 -193.9163) (xy 202.735688 -193.876676) (xy 202.741561 -193.852459) (xy 202.758752 -193.805686)
			(xy 202.781885 -193.761549) (xy 202.810566 -193.720797) (xy 202.827128 -193.702178) (xy 202.837287 -193.690309)
			(xy 202.850522 -193.662028) (xy 202.854612 -193.631072) (xy 202.849178 -193.600323) (xy 202.834724 -193.572645)
			(xy 202.82408 -193.561208) (xy 202.822302 -193.55943) (xy 202.811667 -193.549455) (xy 202.786082 -193.535493)
			(xy 202.757597 -193.529318) (xy 202.728527 -193.531431) (xy 202.701235 -193.541661) (xy 202.677939 -193.559177)
			(xy 202.668886 -193.570606) (xy 202.650764 -193.59413) (xy 202.608462 -193.635801) (xy 202.560215 -193.670413)
			(xy 202.507187 -193.697132) (xy 202.450659 -193.715312) (xy 202.391998 -193.724514) (xy 202.362308 -193.725038)
			(xy 202.335806 -193.724583) (xy 202.283314 -193.717242) (xy 202.232345 -193.7027) (xy 202.183882 -193.681238)
			(xy 202.138858 -193.65327) (xy 202.118214 -193.636646) (xy 202.106401 -193.627499) (xy 202.078904 -193.61585)
			(xy 202.049214 -193.612643) (xy 202.019864 -193.618153) (xy 201.993358 -193.631909) (xy 201.982324 -193.64198)
			(xy 201.960815 -193.662194) (xy 201.912723 -193.696414) (xy 201.859935 -193.722819) (xy 201.80371 -193.740779)
			(xy 201.74539 -193.749866) (xy 201.715878 -193.750438) (xy 201.688626 -193.749951) (xy 201.634676 -193.742191)
			(xy 201.58238 -193.726833) (xy 201.532801 -193.704189) (xy 201.48695 -193.674719) (xy 201.445759 -193.639025)
			(xy 201.410067 -193.597832) (xy 201.380601 -193.551979) (xy 201.35796 -193.5024) (xy 201.342604 -193.450102)
			(xy 201.334848 -193.396152) (xy 201.334848 -193.341648) (xy 201.342604 -193.287698) (xy 201.35796 -193.2354)
			(xy 201.380601 -193.185821) (xy 201.410067 -193.139968) (xy 201.445759 -193.098775) (xy 201.48695 -193.063081)
			(xy 201.532801 -193.033611) (xy 201.58238 -193.010967) (xy 201.634676 -192.995609) (xy 201.688626 -192.987849)
			(xy 201.715878 -192.987422) (xy 201.74238 -192.987876) (xy 201.794872 -192.995217) (xy 201.845841 -193.009759)
			(xy 201.894304 -193.031222) (xy 201.939326 -193.059193) (xy 201.959972 -193.075814) (xy 201.971784 -193.084967)
			(xy 201.999282 -193.096624) (xy 202.028976 -193.099835) (xy 202.05833 -193.094326) (xy 202.084839 -193.080566)
			(xy 202.095862 -193.07048) (xy 202.117369 -193.050262) (xy 202.165459 -193.016035) (xy 202.218247 -192.989624)
			(xy 202.274473 -192.971659) (xy 202.332795 -192.962568) (xy 202.362308 -192.962022) (xy 202.39236 -192.962586)
			(xy 202.45172 -192.972015) (xy 202.508866 -192.990638) (xy 202.562383 -193.017993) (xy 202.610948 -193.053405)
			(xy 202.632564 -193.07429) (xy 202.643199 -193.084254) (xy 202.668778 -193.098195) (xy 202.69725 -193.104353)
			(xy 202.726304 -193.102229) (xy 202.753578 -193.091994) (xy 202.776857 -193.074481) (xy 202.78598 -193.063114)
			(xy 202.804106 -193.039597) (xy 202.846413 -192.997943) (xy 202.894663 -192.963346) (xy 202.947691 -192.936642)
			(xy 203.004215 -192.918476) (xy 203.062872 -192.909286) (xy 203.092558 -192.908682) (xy 203.119813 -192.909142)
			(xy 203.173769 -192.916894) (xy 203.226073 -192.932246) (xy 203.275659 -192.954886) (xy 203.321518 -192.984353)
			(xy 203.362717 -193.020047) (xy 203.398416 -193.06124) (xy 203.427889 -193.107095) (xy 203.450535 -193.156679)
			(xy 203.465895 -193.20898) (xy 203.473654 -193.262935) (xy 203.474066 -193.29019) (xy 203.473564 -193.31861)
			(xy 203.465167 -193.374826) (xy 203.448513 -193.429171) (xy 203.423971 -193.48044) (xy 203.392087 -193.527494)
			(xy 203.373228 -193.548762) (xy 203.363064 -193.560633) (xy 203.349817 -193.588921) (xy 203.345713 -193.619886)
			(xy 203.351135 -193.650647) (xy 203.365576 -193.678344) (xy 203.376276 -193.689732) (xy 203.397298 -193.711365)
			(xy 203.432933 -193.76003) (xy 203.460468 -193.813696) (xy 203.479218 -193.871026) (xy 203.488715 -193.930591)
			(xy 203.489306 -193.96075) (xy 203.488829 -193.988247) (xy 203.483649 -194.023996) (xy 206.570072 -194.023996)
			(xy 206.570572 -193.995412) (xy 206.579108 -193.938886) (xy 206.595988 -193.884268) (xy 206.620835 -193.832782)
			(xy 206.65309 -193.785584) (xy 206.692031 -193.743731) (xy 206.71409 -193.725546) (xy 206.725587 -193.71577)
			(xy 206.742667 -193.690904) (xy 206.751744 -193.662135) (xy 206.752028 -193.631969) (xy 206.743494 -193.603034)
			(xy 206.726885 -193.577851) (xy 206.715614 -193.567812) (xy 206.694419 -193.549605) (xy 206.657081 -193.508039)
			(xy 206.626204 -193.461472) (xy 206.60245 -193.410899) (xy 206.586327 -193.357402) (xy 206.578179 -193.302125)
			(xy 206.577692 -193.274188) (xy 206.578178 -193.246937) (xy 206.585934 -193.192989) (xy 206.601289 -193.140694)
			(xy 206.623931 -193.091117) (xy 206.653397 -193.045267) (xy 206.689088 -193.004076) (xy 206.730279 -192.968385)
			(xy 206.776129 -192.938919) (xy 206.825706 -192.916277) (xy 206.878001 -192.900922) (xy 206.931949 -192.893166)
			(xy 206.986451 -192.893166) (xy 207.040399 -192.900922) (xy 207.092694 -192.916277) (xy 207.142271 -192.938919)
			(xy 207.188121 -192.968385) (xy 207.229312 -193.004076) (xy 207.265003 -193.045267) (xy 207.294469 -193.091117)
			(xy 207.317111 -193.140694) (xy 207.332466 -193.192989) (xy 207.340222 -193.246937) (xy 207.340708 -193.274188)
			(xy 207.340167 -193.30277) (xy 207.331635 -193.359293) (xy 207.314761 -193.413909) (xy 207.289922 -193.465394)
			(xy 207.257676 -193.512594) (xy 207.218744 -193.554451) (xy 207.19669 -193.572638) (xy 207.185211 -193.582432)
			(xy 207.168134 -193.607294) (xy 207.159056 -193.636058) (xy 207.159002 -193.641726) (xy 208.51825 -193.641726)
			(xy 208.522321 -193.586104) (xy 208.534447 -193.531667) (xy 208.55437 -193.479576) (xy 208.581666 -193.430941)
			(xy 208.615752 -193.386798) (xy 208.655901 -193.348089) (xy 208.701259 -193.315638) (xy 208.750859 -193.290137)
			(xy 208.803643 -193.27213) (xy 208.858486 -193.262) (xy 208.91422 -193.259963) (xy 208.969657 -193.266063)
			(xy 209.023614 -193.280169) (xy 209.074943 -193.301981) (xy 209.122549 -193.331035) (xy 209.165417 -193.36671)
			(xy 209.202634 -193.408247) (xy 209.233407 -193.45476) (xy 209.257079 -193.505257) (xy 209.273147 -193.558664)
			(xy 209.281267 -193.61384) (xy 209.281776 -193.641726) (xy 209.281267 -193.669612) (xy 209.280661 -193.67373)
			(xy 212.17712 -193.67373) (xy 212.181191 -193.618108) (xy 212.193317 -193.563671) (xy 212.21324 -193.51158)
			(xy 212.240536 -193.462945) (xy 212.274622 -193.418802) (xy 212.314771 -193.380093) (xy 212.360129 -193.347642)
			(xy 212.409729 -193.322141) (xy 212.462513 -193.304134) (xy 212.517356 -193.294004) (xy 212.57309 -193.291967)
			(xy 212.628527 -193.298067) (xy 212.682484 -193.312173) (xy 212.733813 -193.333985) (xy 212.781419 -193.363039)
			(xy 212.824287 -193.398714) (xy 212.861504 -193.440251) (xy 212.892277 -193.486764) (xy 212.915949 -193.537261)
			(xy 212.932017 -193.590668) (xy 212.940137 -193.645844) (xy 212.940646 -193.67373) (xy 212.940137 -193.701616)
			(xy 212.932017 -193.756792) (xy 212.915949 -193.810199) (xy 212.912053 -193.81851) (xy 214.23706 -193.81851)
			(xy 214.241131 -193.762888) (xy 214.253257 -193.708451) (xy 214.27318 -193.65636) (xy 214.300476 -193.607725)
			(xy 214.334562 -193.563582) (xy 214.374711 -193.524873) (xy 214.420069 -193.492422) (xy 214.469669 -193.466921)
			(xy 214.522453 -193.448914) (xy 214.577296 -193.438784) (xy 214.63303 -193.436747) (xy 214.688467 -193.442847)
			(xy 214.742424 -193.456953) (xy 214.768397 -193.46799) (xy 216.70848 -193.46799) (xy 216.712551 -193.412368)
			(xy 216.724677 -193.357931) (xy 216.7446 -193.30584) (xy 216.771896 -193.257205) (xy 216.805982 -193.213062)
			(xy 216.846131 -193.174353) (xy 216.891489 -193.141902) (xy 216.941089 -193.116401) (xy 216.993873 -193.098394)
			(xy 217.048716 -193.088264) (xy 217.10445 -193.086227) (xy 217.159887 -193.092327) (xy 217.213844 -193.106433)
			(xy 217.265173 -193.128245) (xy 217.312779 -193.157299) (xy 217.355647 -193.192974) (xy 217.392864 -193.234511)
			(xy 217.423637 -193.281024) (xy 217.447309 -193.331521) (xy 217.463377 -193.384928) (xy 217.471497 -193.440104)
			(xy 217.472006 -193.46799) (xy 217.471497 -193.495876) (xy 217.463377 -193.551052) (xy 217.447309 -193.604459)
			(xy 217.423637 -193.654956) (xy 217.392864 -193.701469) (xy 217.355647 -193.743006) (xy 217.312779 -193.778681)
			(xy 217.265173 -193.807735) (xy 217.213844 -193.829547) (xy 217.159887 -193.843653) (xy 217.10445 -193.849753)
			(xy 217.048716 -193.847716) (xy 216.993873 -193.837586) (xy 216.941089 -193.819579) (xy 216.891489 -193.794078)
			(xy 216.846131 -193.761627) (xy 216.805982 -193.722918) (xy 216.771896 -193.678775) (xy 216.7446 -193.63014)
			(xy 216.724677 -193.578049) (xy 216.712551 -193.523612) (xy 216.70848 -193.46799) (xy 214.768397 -193.46799)
			(xy 214.793753 -193.478765) (xy 214.841359 -193.507819) (xy 214.884227 -193.543494) (xy 214.921444 -193.585031)
			(xy 214.952217 -193.631544) (xy 214.975889 -193.682041) (xy 214.991957 -193.735448) (xy 215.000077 -193.790624)
			(xy 215.000586 -193.81851) (xy 215.000077 -193.846396) (xy 214.991957 -193.901572) (xy 214.975889 -193.954979)
			(xy 214.952217 -194.005476) (xy 214.921444 -194.051989) (xy 214.884227 -194.093526) (xy 214.841359 -194.129201)
			(xy 214.793753 -194.158255) (xy 214.742424 -194.180067) (xy 214.688467 -194.194173) (xy 214.63303 -194.200273)
			(xy 214.577296 -194.198236) (xy 214.522453 -194.188106) (xy 214.469669 -194.170099) (xy 214.420069 -194.144598)
			(xy 214.374711 -194.112147) (xy 214.334562 -194.073438) (xy 214.300476 -194.029295) (xy 214.27318 -193.98066)
			(xy 214.253257 -193.928569) (xy 214.241131 -193.874132) (xy 214.23706 -193.81851) (xy 212.912053 -193.81851)
			(xy 212.892277 -193.860696) (xy 212.861504 -193.907209) (xy 212.824287 -193.948746) (xy 212.781419 -193.984421)
			(xy 212.733813 -194.013475) (xy 212.682484 -194.035287) (xy 212.628527 -194.049393) (xy 212.57309 -194.055493)
			(xy 212.517356 -194.053456) (xy 212.462513 -194.043326) (xy 212.409729 -194.025319) (xy 212.360129 -193.999818)
			(xy 212.314771 -193.967367) (xy 212.274622 -193.928658) (xy 212.240536 -193.884515) (xy 212.21324 -193.83588)
			(xy 212.193317 -193.783789) (xy 212.181191 -193.729352) (xy 212.17712 -193.67373) (xy 209.280661 -193.67373)
			(xy 209.273147 -193.724788) (xy 209.257079 -193.778195) (xy 209.233407 -193.828692) (xy 209.202634 -193.875205)
			(xy 209.165417 -193.916742) (xy 209.122549 -193.952417) (xy 209.074943 -193.981471) (xy 209.023614 -194.003283)
			(xy 208.969657 -194.017389) (xy 208.91422 -194.023489) (xy 208.858486 -194.021452) (xy 208.803643 -194.011322)
			(xy 208.750859 -193.993315) (xy 208.701259 -193.967814) (xy 208.655901 -193.935363) (xy 208.615752 -193.896654)
			(xy 208.581666 -193.852511) (xy 208.55437 -193.803876) (xy 208.534447 -193.751785) (xy 208.522321 -193.697348)
			(xy 208.51825 -193.641726) (xy 207.159002 -193.641726) (xy 207.158769 -193.666219) (xy 207.167298 -193.69515)
			(xy 207.183899 -193.720332) (xy 207.195166 -193.730372) (xy 207.216349 -193.748592) (xy 207.253689 -193.790155)
			(xy 207.284568 -193.836719) (xy 207.308324 -193.88729) (xy 207.32445 -193.940785) (xy 207.3326 -193.99606)
			(xy 207.333088 -194.023996) (xy 207.332508 -194.054047) (xy 207.323073 -194.113404) (xy 207.304452 -194.170548)
			(xy 207.277106 -194.224069) (xy 207.241709 -194.272641) (xy 207.22082 -194.294252) (xy 207.211568 -194.304034)
			(xy 207.198172 -194.327383) (xy 207.19134 -194.35342) (xy 207.191547 -194.380338) (xy 207.198779 -194.406267)
			(xy 207.212532 -194.429407) (xy 207.231853 -194.44815) (xy 207.243426 -194.455034) (xy 207.266918 -194.468608)
			(xy 207.309881 -194.501739) (xy 207.34732 -194.541005) (xy 207.378368 -194.585497) (xy 207.402305 -194.634184)
			(xy 207.418579 -194.68594) (xy 207.426812 -194.739565) (xy 207.427322 -194.766692) (xy 207.426824 -194.793341)
			(xy 208.925404 -194.793341) (xy 208.925404 -194.740043) (xy 208.933347 -194.687339) (xy 208.949057 -194.636409)
			(xy 208.972183 -194.588388) (xy 209.002207 -194.544351) (xy 209.038459 -194.50528) (xy 209.08013 -194.472049)
			(xy 209.126288 -194.4454) (xy 209.175902 -194.425928) (xy 209.227864 -194.414068) (xy 209.281014 -194.410085)
			(xy 209.334164 -194.414068) (xy 209.386126 -194.425928) (xy 209.43574 -194.4454) (xy 209.481898 -194.472049)
			(xy 209.523569 -194.50528) (xy 209.559821 -194.544351) (xy 209.589845 -194.588388) (xy 209.612971 -194.636409)
			(xy 209.628681 -194.687339) (xy 209.636624 -194.740043) (xy 209.637122 -194.766692) (xy 209.636624 -194.793341)
			(xy 210.133936 -194.793341) (xy 210.133936 -194.740043) (xy 210.141879 -194.687339) (xy 210.157589 -194.636409)
			(xy 210.180715 -194.588388) (xy 210.210739 -194.544351) (xy 210.246991 -194.50528) (xy 210.288662 -194.472049)
			(xy 210.33482 -194.4454) (xy 210.384434 -194.425928) (xy 210.436396 -194.414068) (xy 210.489546 -194.410085)
			(xy 210.542696 -194.414068) (xy 210.594658 -194.425928) (xy 210.644272 -194.4454) (xy 210.69043 -194.472049)
			(xy 210.732101 -194.50528) (xy 210.768353 -194.544351) (xy 210.798377 -194.588388) (xy 210.821503 -194.636409)
			(xy 210.837213 -194.687339) (xy 210.845156 -194.740043) (xy 210.845654 -194.766692) (xy 210.845156 -194.793341)
			(xy 210.84404 -194.800748) (xy 212.620128 -194.800748) (xy 212.620128 -194.746252) (xy 212.627884 -194.692312)
			(xy 212.643237 -194.640024) (xy 212.665875 -194.590454) (xy 212.695337 -194.54461) (xy 212.731023 -194.503425)
			(xy 212.772208 -194.467738) (xy 212.818052 -194.438276) (xy 212.867622 -194.415637) (xy 212.91991 -194.400284)
			(xy 212.97385 -194.392528) (xy 213.001098 -194.392042) (xy 213.028633 -194.392549) (xy 213.083133 -194.400454)
			(xy 213.135929 -194.416115) (xy 213.185924 -194.439205) (xy 213.232079 -194.469245) (xy 213.273434 -194.505611)
			(xy 213.309129 -194.547545) (xy 213.324186 -194.570604) (xy 213.332511 -194.582854) (xy 213.354822 -194.602313)
			(xy 213.381772 -194.614569) (xy 213.411102 -194.618595) (xy 213.440357 -194.614053) (xy 213.467086 -194.601324)
			(xy 213.48905 -194.581474) (xy 213.49716 -194.56908) (xy 213.512062 -194.545308) (xy 213.547739 -194.502011)
			(xy 213.589372 -194.464404) (xy 213.636064 -194.433299) (xy 213.686806 -194.409365) (xy 213.740506 -194.39312)
			(xy 213.796006 -194.384914) (xy 213.824058 -194.384422) (xy 213.851778 -194.384895) (xy 213.906633 -194.39292)
			(xy 213.959748 -194.408806) (xy 214.010001 -194.432219) (xy 214.056332 -194.462664) (xy 214.097765 -194.4995)
			(xy 214.133425 -194.541948) (xy 214.148416 -194.56527) (xy 214.15649 -194.577384) (xy 214.178106 -194.596862)
			(xy 214.20434 -194.609446) (xy 214.233061 -194.614114) (xy 214.26193 -194.610485) (xy 214.288602 -194.598854)
			(xy 214.310906 -194.580169) (xy 214.319358 -194.568318) (xy 214.333626 -194.547868) (xy 214.3669 -194.510733)
			(xy 214.40503 -194.478604) (xy 214.44727 -194.452109) (xy 214.492794 -194.431768) (xy 214.540711 -194.417978)
			(xy 214.590083 -194.411008) (xy 214.615014 -194.410584) (xy 214.641662 -194.411099) (xy 214.694363 -194.419044)
			(xy 214.74529 -194.434755) (xy 214.793308 -194.45788) (xy 214.837342 -194.487904) (xy 214.87641 -194.524156)
			(xy 214.909639 -194.565825) (xy 214.936287 -194.611981) (xy 214.955758 -194.661593) (xy 214.967617 -194.713553)
			(xy 214.9716 -194.7667) (xy 214.969603 -194.793341) (xy 216.469204 -194.793341) (xy 216.469204 -194.740043)
			(xy 216.477147 -194.687339) (xy 216.492857 -194.636409) (xy 216.515983 -194.588388) (xy 216.546007 -194.544351)
			(xy 216.582259 -194.50528) (xy 216.62393 -194.472049) (xy 216.670088 -194.4454) (xy 216.719702 -194.425928)
			(xy 216.771664 -194.414068) (xy 216.824814 -194.410085) (xy 216.877964 -194.414068) (xy 216.929926 -194.425928)
			(xy 216.97954 -194.4454) (xy 217.025698 -194.472049) (xy 217.067369 -194.50528) (xy 217.103621 -194.544351)
			(xy 217.133645 -194.588388) (xy 217.156771 -194.636409) (xy 217.172481 -194.687339) (xy 217.180424 -194.740043)
			(xy 217.180922 -194.766692) (xy 217.180424 -194.793341) (xy 217.172481 -194.846045) (xy 217.156771 -194.896975)
			(xy 217.133645 -194.944996) (xy 217.103621 -194.989033) (xy 217.067369 -195.028104) (xy 217.025698 -195.061335)
			(xy 216.97954 -195.087984) (xy 216.929926 -195.107456) (xy 216.877964 -195.119316) (xy 216.824814 -195.1233)
			(xy 216.771664 -195.119316) (xy 216.719702 -195.107456) (xy 216.670088 -195.087984) (xy 216.62393 -195.061335)
			(xy 216.582259 -195.028104) (xy 216.546007 -194.989033) (xy 216.515983 -194.944996) (xy 216.492857 -194.896975)
			(xy 216.477147 -194.846045) (xy 216.469204 -194.793341) (xy 214.969603 -194.793341) (xy 214.967617 -194.819847)
			(xy 214.955758 -194.871807) (xy 214.936287 -194.921419) (xy 214.909639 -194.967575) (xy 214.87641 -195.009244)
			(xy 214.837342 -195.045496) (xy 214.793308 -195.07552) (xy 214.74529 -195.098645) (xy 214.694363 -195.114356)
			(xy 214.641662 -195.122301) (xy 214.615014 -195.1228) (xy 214.59003 -195.122343) (xy 214.540553 -195.115353)
			(xy 214.492537 -195.101522) (xy 214.446923 -195.08112) (xy 214.404605 -195.054548) (xy 214.366413 -195.022327)
			(xy 214.333095 -194.985088) (xy 214.31885 -194.964558) (xy 214.310416 -194.952723) (xy 214.288165 -194.934047)
			(xy 214.26155 -194.922403) (xy 214.232732 -194.918736) (xy 214.204049 -194.923344) (xy 214.17783 -194.935852)
			(xy 214.156201 -194.955245) (xy 214.148162 -194.967352) (xy 214.13314 -194.990592) (xy 214.097436 -195.032867)
			(xy 214.056 -195.069543) (xy 214.009702 -195.09985) (xy 213.959512 -195.123153) (xy 213.906482 -195.138963)
			(xy 213.851726 -195.146949) (xy 213.824058 -195.147438) (xy 213.796521 -195.146974) (xy 213.742019 -195.139062)
			(xy 213.689222 -195.123395) (xy 213.639226 -195.100298) (xy 213.593072 -195.070251) (xy 213.551718 -195.033879)
			(xy 213.516025 -194.991938) (xy 213.50097 -194.968876) (xy 213.492709 -194.956575) (xy 213.470388 -194.937098)
			(xy 213.443423 -194.924833) (xy 213.414074 -194.92081) (xy 213.384803 -194.925364) (xy 213.358065 -194.938114)
			(xy 213.3361 -194.957992) (xy 213.327996 -194.9704) (xy 213.313085 -194.994165) (xy 213.277405 -195.037458)
			(xy 213.235772 -195.075063) (xy 213.189083 -195.106167) (xy 213.138343 -195.130101) (xy 213.084646 -195.14635)
			(xy 213.029149 -195.154562) (xy 213.001098 -195.155058) (xy 212.97385 -195.154472) (xy 212.91991 -195.146716)
			(xy 212.867622 -195.131363) (xy 212.818052 -195.108724) (xy 212.772208 -195.079262) (xy 212.731023 -195.043575)
			(xy 212.695337 -195.00239) (xy 212.665875 -194.956546) (xy 212.643237 -194.906976) (xy 212.627884 -194.854688)
			(xy 212.620128 -194.800748) (xy 210.84404 -194.800748) (xy 210.837213 -194.846045) (xy 210.821503 -194.896975)
			(xy 210.798377 -194.944996) (xy 210.768353 -194.989033) (xy 210.732101 -195.028104) (xy 210.69043 -195.061335)
			(xy 210.644272 -195.087984) (xy 210.594658 -195.107456) (xy 210.542696 -195.119316) (xy 210.489546 -195.1233)
			(xy 210.436396 -195.119316) (xy 210.384434 -195.107456) (xy 210.33482 -195.087984) (xy 210.288662 -195.061335)
			(xy 210.246991 -195.028104) (xy 210.210739 -194.989033) (xy 210.180715 -194.944996) (xy 210.157589 -194.896975)
			(xy 210.141879 -194.846045) (xy 210.133936 -194.793341) (xy 209.636624 -194.793341) (xy 209.628681 -194.846045)
			(xy 209.612971 -194.896975) (xy 209.589845 -194.944996) (xy 209.559821 -194.989033) (xy 209.523569 -195.028104)
			(xy 209.481898 -195.061335) (xy 209.43574 -195.087984) (xy 209.386126 -195.107456) (xy 209.334164 -195.119316)
			(xy 209.281014 -195.1233) (xy 209.227864 -195.119316) (xy 209.175902 -195.107456) (xy 209.126288 -195.087984)
			(xy 209.08013 -195.061335) (xy 209.038459 -195.028104) (xy 209.002207 -194.989033) (xy 208.972183 -194.944996)
			(xy 208.949057 -194.896975) (xy 208.933347 -194.846045) (xy 208.925404 -194.793341) (xy 207.426824 -194.793341)
			(xy 207.418881 -194.846045) (xy 207.403171 -194.896975) (xy 207.380045 -194.944996) (xy 207.350021 -194.989033)
			(xy 207.313769 -195.028104) (xy 207.272098 -195.061335) (xy 207.22594 -195.087984) (xy 207.176326 -195.107456)
			(xy 207.124364 -195.119316) (xy 207.071214 -195.1233) (xy 207.018064 -195.119316) (xy 206.966102 -195.107456)
			(xy 206.916488 -195.087984) (xy 206.87033 -195.061335) (xy 206.828659 -195.028104) (xy 206.792407 -194.989033)
			(xy 206.762383 -194.944996) (xy 206.739257 -194.896975) (xy 206.723547 -194.846045) (xy 206.715604 -194.793341)
			(xy 206.715106 -194.766692) (xy 206.715589 -194.740094) (xy 206.723498 -194.68749) (xy 206.739152 -194.63665)
			(xy 206.762203 -194.588708) (xy 206.792137 -194.544734) (xy 206.809848 -194.524884) (xy 206.818732 -194.514748)
			(xy 206.831201 -194.49086) (xy 206.836983 -194.46454) (xy 206.835673 -194.437625) (xy 206.827363 -194.411991)
			(xy 206.812632 -194.389427) (xy 206.792509 -194.371505) (xy 206.780638 -194.365118) (xy 206.757238 -194.352908)
			(xy 206.713767 -194.322971) (xy 206.674837 -194.28733) (xy 206.64119 -194.246664) (xy 206.613467 -194.201749)
			(xy 206.592199 -194.153442) (xy 206.577791 -194.102665) (xy 206.570518 -194.050387) (xy 206.570072 -194.023996)
			(xy 203.483649 -194.023996) (xy 203.480943 -194.042672) (xy 203.465325 -194.095401) (xy 203.4423 -194.145343)
			(xy 203.412344 -194.191462) (xy 203.376079 -194.232803) (xy 203.334254 -194.268511) (xy 203.311252 -194.283584)
			(xy 203.298698 -194.292181) (xy 203.278899 -194.315262) (xy 203.266758 -194.343144) (xy 203.263348 -194.373362)
			(xy 203.268969 -194.403249) (xy 203.283126 -194.430162) (xy 203.293472 -194.441318) (xy 204.468874 -195.6166)
			(xy 204.824244 -195.6166) (xy 204.828228 -195.563439) (xy 204.840092 -195.511465) (xy 204.85957 -195.461841)
			(xy 204.886227 -195.415674) (xy 204.919468 -195.373996) (xy 204.958549 -195.337739) (xy 205.002599 -195.307711)
			(xy 205.050632 -195.284585) (xy 205.101575 -195.268877) (xy 205.154291 -195.260938) (xy 205.180946 -195.260468)
			(xy 205.206193 -195.260932) (xy 205.25618 -195.268065) (xy 205.30466 -195.282181) (xy 205.350662 -195.302999)
			(xy 205.393266 -195.330101) (xy 205.431618 -195.362944) (xy 205.464951 -195.400872) (xy 205.479142 -195.421758)
			(xy 205.487172 -195.433346) (xy 205.508422 -195.451863) (xy 205.533926 -195.463861) (xy 205.561739 -195.468425)
			(xy 205.58974 -195.465207) (xy 205.615793 -195.454453) (xy 205.637911 -195.436982) (xy 205.646528 -195.425822)
			(xy 205.661967 -195.405171) (xy 205.697498 -195.367806) (xy 205.737738 -195.335567) (xy 205.781952 -195.309041)
			(xy 205.829337 -195.288712) (xy 205.879028 -195.27495) (xy 205.930119 -195.268006) (xy 205.9559 -195.26758)
			(xy 205.98315 -195.26809) (xy 206.037096 -195.275847) (xy 206.089389 -195.291201) (xy 206.138965 -195.313842)
			(xy 206.184814 -195.343307) (xy 206.226003 -195.378997) (xy 206.261693 -195.420186) (xy 206.291158 -195.466035)
			(xy 206.313799 -195.515611) (xy 206.329153 -195.567904) (xy 206.33691 -195.62185) (xy 206.33691 -195.643225)
			(xy 206.715604 -195.643225) (xy 206.715604 -195.589927) (xy 206.723547 -195.537223) (xy 206.739257 -195.486293)
			(xy 206.762383 -195.438272) (xy 206.792407 -195.394235) (xy 206.828659 -195.355164) (xy 206.87033 -195.321933)
			(xy 206.916488 -195.295284) (xy 206.966102 -195.275812) (xy 207.018064 -195.263952) (xy 207.071214 -195.259969)
			(xy 207.124364 -195.263952) (xy 207.176326 -195.275812) (xy 207.22594 -195.295284) (xy 207.272098 -195.321933)
			(xy 207.313769 -195.355164) (xy 207.350021 -195.394235) (xy 207.380045 -195.438272) (xy 207.403171 -195.486293)
			(xy 207.418881 -195.537223) (xy 207.426824 -195.589927) (xy 207.427322 -195.616576) (xy 207.426824 -195.643225)
			(xy 210.159336 -195.643225) (xy 210.159336 -195.589927) (xy 210.167279 -195.537223) (xy 210.182989 -195.486293)
			(xy 210.206115 -195.438272) (xy 210.236139 -195.394235) (xy 210.272391 -195.355164) (xy 210.314062 -195.321933)
			(xy 210.36022 -195.295284) (xy 210.409834 -195.275812) (xy 210.461796 -195.263952) (xy 210.514946 -195.259969)
			(xy 210.568096 -195.263952) (xy 210.620058 -195.275812) (xy 210.669672 -195.295284) (xy 210.71583 -195.321933)
			(xy 210.757501 -195.355164) (xy 210.793753 -195.394235) (xy 210.823777 -195.438272) (xy 210.846903 -195.486293)
			(xy 210.862613 -195.537223) (xy 210.870556 -195.589927) (xy 210.871054 -195.616576) (xy 210.870556 -195.643225)
			(xy 212.369136 -195.643225) (xy 212.369136 -195.589927) (xy 212.377079 -195.537223) (xy 212.392789 -195.486293)
			(xy 212.415915 -195.438272) (xy 212.445939 -195.394235) (xy 212.482191 -195.355164) (xy 212.523862 -195.321933)
			(xy 212.57002 -195.295284) (xy 212.619634 -195.275812) (xy 212.671596 -195.263952) (xy 212.724746 -195.259969)
			(xy 212.777896 -195.263952) (xy 212.829858 -195.275812) (xy 212.879472 -195.295284) (xy 212.92563 -195.321933)
			(xy 212.967301 -195.355164) (xy 213.003553 -195.394235) (xy 213.033577 -195.438272) (xy 213.056703 -195.486293)
			(xy 213.072413 -195.537223) (xy 213.080356 -195.589927) (xy 213.080854 -195.616576) (xy 213.080356 -195.643225)
			(xy 213.072413 -195.695929) (xy 213.056703 -195.746859) (xy 213.033577 -195.79488) (xy 213.003553 -195.838917)
			(xy 212.967301 -195.877988) (xy 212.92563 -195.911219) (xy 212.879472 -195.937868) (xy 212.829858 -195.95734)
			(xy 212.777896 -195.9692) (xy 212.724746 -195.973184) (xy 212.671596 -195.9692) (xy 212.619634 -195.95734)
			(xy 212.57002 -195.937868) (xy 212.523862 -195.911219) (xy 212.482191 -195.877988) (xy 212.445939 -195.838917)
			(xy 212.415915 -195.79488) (xy 212.392789 -195.746859) (xy 212.377079 -195.695929) (xy 212.369136 -195.643225)
			(xy 210.870556 -195.643225) (xy 210.862613 -195.695929) (xy 210.846903 -195.746859) (xy 210.823777 -195.79488)
			(xy 210.793753 -195.838917) (xy 210.757501 -195.877988) (xy 210.71583 -195.911219) (xy 210.669672 -195.937868)
			(xy 210.620058 -195.95734) (xy 210.568096 -195.9692) (xy 210.514946 -195.973184) (xy 210.461796 -195.9692)
			(xy 210.409834 -195.95734) (xy 210.36022 -195.937868) (xy 210.314062 -195.911219) (xy 210.272391 -195.877988)
			(xy 210.236139 -195.838917) (xy 210.206115 -195.79488) (xy 210.182989 -195.746859) (xy 210.167279 -195.695929)
			(xy 210.159336 -195.643225) (xy 207.426824 -195.643225) (xy 207.418881 -195.695929) (xy 207.403171 -195.746859)
			(xy 207.380045 -195.79488) (xy 207.350021 -195.838917) (xy 207.313769 -195.877988) (xy 207.272098 -195.911219)
			(xy 207.22594 -195.937868) (xy 207.176326 -195.95734) (xy 207.124364 -195.9692) (xy 207.071214 -195.973184)
			(xy 207.018064 -195.9692) (xy 206.966102 -195.95734) (xy 206.916488 -195.937868) (xy 206.87033 -195.911219)
			(xy 206.828659 -195.877988) (xy 206.792407 -195.838917) (xy 206.762383 -195.79488) (xy 206.739257 -195.746859)
			(xy 206.723547 -195.695929) (xy 206.715604 -195.643225) (xy 206.33691 -195.643225) (xy 206.33691 -195.67635)
			(xy 206.329153 -195.730296) (xy 206.313799 -195.782589) (xy 206.291158 -195.832165) (xy 206.261693 -195.878014)
			(xy 206.226003 -195.919203) (xy 206.184814 -195.954893) (xy 206.138965 -195.984358) (xy 206.089389 -196.006999)
			(xy 206.037096 -196.022353) (xy 205.98315 -196.03011) (xy 205.9559 -196.030596) (xy 205.927838 -196.030088)
			(xy 205.872323 -196.021852) (xy 205.818612 -196.005574) (xy 205.767864 -195.981605) (xy 205.721175 -195.95046)
			(xy 205.679552 -195.912813) (xy 205.643892 -195.869475) (xy 205.629002 -195.845684) (xy 205.621298 -195.83389)
			(xy 205.600745 -195.814648) (xy 205.575717 -195.80175) (xy 205.548119 -195.796177) (xy 205.520048 -195.798353)
			(xy 205.493638 -195.808112) (xy 205.470898 -195.824713) (xy 205.46187 -195.835524) (xy 205.444892 -195.856503)
			(xy 205.405664 -195.893568) (xy 205.361294 -195.92429) (xy 205.312796 -195.947967) (xy 205.261282 -195.964056)
			(xy 205.20793 -195.97219) (xy 205.180946 -195.972684) (xy 205.154291 -195.972262) (xy 205.101575 -195.964323)
			(xy 205.050632 -195.948615) (xy 205.002599 -195.925489) (xy 204.958549 -195.895461) (xy 204.919468 -195.859204)
			(xy 204.886227 -195.817526) (xy 204.85957 -195.771359) (xy 204.840092 -195.721735) (xy 204.828228 -195.669761)
			(xy 204.824244 -195.6166) (xy 204.468874 -195.6166) (xy 205.345727 -196.493363) (xy 206.715604 -196.493363)
			(xy 206.715604 -196.440065) (xy 206.723547 -196.387361) (xy 206.739257 -196.336431) (xy 206.762383 -196.28841)
			(xy 206.792407 -196.244373) (xy 206.828659 -196.205302) (xy 206.87033 -196.172071) (xy 206.916488 -196.145422)
			(xy 206.966102 -196.12595) (xy 207.018064 -196.11409) (xy 207.071214 -196.110107) (xy 207.124364 -196.11409)
			(xy 207.176326 -196.12595) (xy 207.22594 -196.145422) (xy 207.272098 -196.172071) (xy 207.313769 -196.205302)
			(xy 207.350021 -196.244373) (xy 207.380045 -196.28841) (xy 207.403171 -196.336431) (xy 207.418881 -196.387361)
			(xy 207.426824 -196.440065) (xy 207.427322 -196.466714) (xy 207.426824 -196.493363) (xy 208.925404 -196.493363)
			(xy 208.925404 -196.440065) (xy 208.933347 -196.387361) (xy 208.949057 -196.336431) (xy 208.972183 -196.28841)
			(xy 209.002207 -196.244373) (xy 209.038459 -196.205302) (xy 209.08013 -196.172071) (xy 209.126288 -196.145422)
			(xy 209.175902 -196.12595) (xy 209.227864 -196.11409) (xy 209.281014 -196.110107) (xy 209.334164 -196.11409)
			(xy 209.386126 -196.12595) (xy 209.43574 -196.145422) (xy 209.481898 -196.172071) (xy 209.523569 -196.205302)
			(xy 209.559821 -196.244373) (xy 209.589845 -196.28841) (xy 209.612971 -196.336431) (xy 209.628681 -196.387361)
			(xy 209.636624 -196.440065) (xy 209.637122 -196.466714) (xy 209.636624 -196.493363) (xy 214.259404 -196.493363)
			(xy 214.259404 -196.440065) (xy 214.267347 -196.387361) (xy 214.283057 -196.336431) (xy 214.306183 -196.28841)
			(xy 214.336207 -196.244373) (xy 214.372459 -196.205302) (xy 214.41413 -196.172071) (xy 214.460288 -196.145422)
			(xy 214.509902 -196.12595) (xy 214.561864 -196.11409) (xy 214.615014 -196.110107) (xy 214.668164 -196.11409)
			(xy 214.720126 -196.12595) (xy 214.76974 -196.145422) (xy 214.815898 -196.172071) (xy 214.857569 -196.205302)
			(xy 214.893821 -196.244373) (xy 214.923845 -196.28841) (xy 214.946971 -196.336431) (xy 214.962681 -196.387361)
			(xy 214.970624 -196.440065) (xy 214.971122 -196.466714) (xy 214.970624 -196.493363) (xy 216.469204 -196.493363)
			(xy 216.469204 -196.440065) (xy 216.477147 -196.387361) (xy 216.492857 -196.336431) (xy 216.515983 -196.28841)
			(xy 216.546007 -196.244373) (xy 216.582259 -196.205302) (xy 216.62393 -196.172071) (xy 216.670088 -196.145422)
			(xy 216.719702 -196.12595) (xy 216.771664 -196.11409) (xy 216.824814 -196.110107) (xy 216.877964 -196.11409)
			(xy 216.929926 -196.12595) (xy 216.97954 -196.145422) (xy 217.025698 -196.172071) (xy 217.067369 -196.205302)
			(xy 217.103621 -196.244373) (xy 217.133645 -196.28841) (xy 217.156771 -196.336431) (xy 217.172481 -196.387361)
			(xy 217.180424 -196.440065) (xy 217.180922 -196.466714) (xy 217.180424 -196.493363) (xy 217.172481 -196.546067)
			(xy 217.156771 -196.596997) (xy 217.133645 -196.645018) (xy 217.103621 -196.689055) (xy 217.067369 -196.728126)
			(xy 217.025698 -196.761357) (xy 216.97954 -196.788006) (xy 216.929926 -196.807478) (xy 216.877964 -196.819338)
			(xy 216.824814 -196.823322) (xy 216.771664 -196.819338) (xy 216.719702 -196.807478) (xy 216.670088 -196.788006)
			(xy 216.62393 -196.761357) (xy 216.582259 -196.728126) (xy 216.546007 -196.689055) (xy 216.515983 -196.645018)
			(xy 216.492857 -196.596997) (xy 216.477147 -196.546067) (xy 216.469204 -196.493363) (xy 214.970624 -196.493363)
			(xy 214.962681 -196.546067) (xy 214.946971 -196.596997) (xy 214.923845 -196.645018) (xy 214.893821 -196.689055)
			(xy 214.857569 -196.728126) (xy 214.815898 -196.761357) (xy 214.76974 -196.788006) (xy 214.720126 -196.807478)
			(xy 214.668164 -196.819338) (xy 214.615014 -196.823322) (xy 214.561864 -196.819338) (xy 214.509902 -196.807478)
			(xy 214.460288 -196.788006) (xy 214.41413 -196.761357) (xy 214.372459 -196.728126) (xy 214.336207 -196.689055)
			(xy 214.306183 -196.645018) (xy 214.283057 -196.596997) (xy 214.267347 -196.546067) (xy 214.259404 -196.493363)
			(xy 209.636624 -196.493363) (xy 209.628681 -196.546067) (xy 209.612971 -196.596997) (xy 209.589845 -196.645018)
			(xy 209.559821 -196.689055) (xy 209.523569 -196.728126) (xy 209.481898 -196.761357) (xy 209.43574 -196.788006)
			(xy 209.386126 -196.807478) (xy 209.334164 -196.819338) (xy 209.281014 -196.823322) (xy 209.227864 -196.819338)
			(xy 209.175902 -196.807478) (xy 209.126288 -196.788006) (xy 209.08013 -196.761357) (xy 209.038459 -196.728126)
			(xy 209.002207 -196.689055) (xy 208.972183 -196.645018) (xy 208.949057 -196.596997) (xy 208.933347 -196.546067)
			(xy 208.925404 -196.493363) (xy 207.426824 -196.493363) (xy 207.418881 -196.546067) (xy 207.403171 -196.596997)
			(xy 207.380045 -196.645018) (xy 207.350021 -196.689055) (xy 207.313769 -196.728126) (xy 207.272098 -196.761357)
			(xy 207.22594 -196.788006) (xy 207.176326 -196.807478) (xy 207.124364 -196.819338) (xy 207.071214 -196.823322)
			(xy 207.018064 -196.819338) (xy 206.966102 -196.807478) (xy 206.916488 -196.788006) (xy 206.87033 -196.761357)
			(xy 206.828659 -196.728126) (xy 206.792407 -196.689055) (xy 206.762383 -196.645018) (xy 206.739257 -196.596997)
			(xy 206.723547 -196.546067) (xy 206.715604 -196.493363) (xy 205.345727 -196.493363) (xy 205.781148 -196.92874)
			(xy 213.83879 -196.92874) (xy 213.864444 -196.954648) (xy 213.872826 -196.954648) (xy 214.606378 -197.6882)
			(xy 219.251782 -197.6882) (xy 219.255853 -197.632578) (xy 219.267979 -197.578141) (xy 219.287902 -197.52605)
			(xy 219.315198 -197.477415) (xy 219.349284 -197.433272) (xy 219.389433 -197.394563) (xy 219.434791 -197.362112)
			(xy 219.484391 -197.336611) (xy 219.537175 -197.318604) (xy 219.592018 -197.308474) (xy 219.647752 -197.306437)
			(xy 219.703189 -197.312537) (xy 219.757146 -197.326643) (xy 219.808475 -197.348455) (xy 219.856081 -197.377509)
			(xy 219.898949 -197.413184) (xy 219.936166 -197.454721) (xy 219.966939 -197.501234) (xy 219.990611 -197.551731)
			(xy 220.006679 -197.605138) (xy 220.014799 -197.660314) (xy 220.015308 -197.6882) (xy 220.014799 -197.716086)
			(xy 220.006679 -197.771262) (xy 219.990611 -197.824669) (xy 219.966939 -197.875166) (xy 219.936166 -197.921679)
			(xy 219.898949 -197.963216) (xy 219.856081 -197.998891) (xy 219.808475 -198.027945) (xy 219.757146 -198.049757)
			(xy 219.703189 -198.063863) (xy 219.647752 -198.069963) (xy 219.592018 -198.067926) (xy 219.537175 -198.057796)
			(xy 219.484391 -198.039789) (xy 219.434791 -198.014288) (xy 219.389433 -197.981837) (xy 219.349284 -197.943128)
			(xy 219.315198 -197.898985) (xy 219.287902 -197.85035) (xy 219.267979 -197.798259) (xy 219.255853 -197.743822)
			(xy 219.251782 -197.6882) (xy 214.606378 -197.6882) (xy 214.759286 -197.841108) (xy 214.76716 -197.844664)
			(xy 214.789157 -197.85551) (xy 214.830206 -197.882347) (xy 214.867184 -197.914563) (xy 214.899393 -197.951548)
			(xy 214.926223 -197.992601) (xy 214.937086 -198.01459) (xy 214.940642 -198.022464) (xy 215.111563 -198.193385)
			(xy 216.469204 -198.193385) (xy 216.469204 -198.140087) (xy 216.477147 -198.087383) (xy 216.492857 -198.036453)
			(xy 216.515983 -197.988432) (xy 216.546007 -197.944395) (xy 216.582259 -197.905324) (xy 216.62393 -197.872093)
			(xy 216.670088 -197.845444) (xy 216.719702 -197.825972) (xy 216.771664 -197.814112) (xy 216.824814 -197.810129)
			(xy 216.877964 -197.814112) (xy 216.929926 -197.825972) (xy 216.97954 -197.845444) (xy 217.025698 -197.872093)
			(xy 217.067369 -197.905324) (xy 217.103621 -197.944395) (xy 217.133645 -197.988432) (xy 217.156771 -198.036453)
			(xy 217.172481 -198.087383) (xy 217.180424 -198.140087) (xy 217.180922 -198.166736) (xy 217.180424 -198.193385)
			(xy 217.172481 -198.246089) (xy 217.156771 -198.297019) (xy 217.133645 -198.34504) (xy 217.103621 -198.389077)
			(xy 217.067369 -198.428148) (xy 217.025698 -198.461379) (xy 216.97954 -198.488028) (xy 216.929926 -198.5075)
			(xy 216.877964 -198.51936) (xy 216.824814 -198.523344) (xy 216.771664 -198.51936) (xy 216.719702 -198.5075)
			(xy 216.670088 -198.488028) (xy 216.62393 -198.461379) (xy 216.582259 -198.428148) (xy 216.546007 -198.389077)
			(xy 216.515983 -198.34504) (xy 216.492857 -198.297019) (xy 216.477147 -198.246089) (xy 216.469204 -198.193385)
			(xy 215.111563 -198.193385) (xy 216.964631 -200.046453) (xy 241.831836 -200.046453) (xy 241.831836 -199.991947)
			(xy 241.839593 -199.937995) (xy 241.854948 -199.885697) (xy 241.87759 -199.836116) (xy 241.907057 -199.790261)
			(xy 241.94275 -199.749067) (xy 241.983942 -199.713372) (xy 242.029795 -199.683902) (xy 242.079374 -199.661257)
			(xy 242.131672 -199.645898) (xy 242.185623 -199.638138) (xy 242.212876 -199.63765) (xy 242.242963 -199.638234)
			(xy 242.302389 -199.647689) (xy 242.359596 -199.666352) (xy 242.413165 -199.693762) (xy 242.461768 -199.729238)
			(xy 242.483386 -199.750172) (xy 242.493838 -199.759954) (xy 242.518841 -199.77386) (xy 242.546724 -199.780272)
			(xy 242.575291 -199.778682) (xy 242.60229 -199.769217) (xy 242.625597 -199.752622) (xy 242.643373 -199.730205)
			(xy 242.649248 -199.717152) (xy 242.660432 -199.691348) (xy 242.689325 -199.6431) (xy 242.724988 -199.599615)
			(xy 242.766648 -199.561836) (xy 242.813401 -199.530581) (xy 242.864236 -199.506527) (xy 242.918051 -199.490196)
			(xy 242.973681 -199.481941) (xy 243.0018 -199.48144) (xy 243.029055 -199.48183) (xy 243.083009 -199.489587)
			(xy 243.135311 -199.504944) (xy 243.184894 -199.527588) (xy 243.23075 -199.557058) (xy 243.271946 -199.592754)
			(xy 243.307642 -199.63395) (xy 243.337112 -199.679806) (xy 243.359756 -199.729389) (xy 243.375113 -199.781691)
			(xy 243.38287 -199.835645) (xy 243.38287 -199.890155) (xy 243.375113 -199.944109) (xy 243.359756 -199.996411)
			(xy 243.337112 -200.045994) (xy 243.307642 -200.09185) (xy 243.271946 -200.133046) (xy 243.23075 -200.168742)
			(xy 243.184894 -200.198212) (xy 243.135311 -200.220856) (xy 243.083009 -200.236213) (xy 243.029055 -200.24397)
			(xy 243.0018 -200.244456) (xy 242.971713 -200.243885) (xy 242.912286 -200.234427) (xy 242.855079 -200.21576)
			(xy 242.801511 -200.188348) (xy 242.752907 -200.152869) (xy 242.73129 -200.131934) (xy 242.720864 -200.122123)
			(xy 242.695854 -200.108216) (xy 242.667964 -200.101807) (xy 242.639392 -200.103401) (xy 242.612388 -200.112872)
			(xy 242.589079 -200.129473) (xy 242.571302 -200.151898) (xy 242.565428 -200.164954) (xy 242.554216 -200.190746)
			(xy 242.525332 -200.238998) (xy 242.489675 -200.282487) (xy 242.448021 -200.32027) (xy 242.40127 -200.351527)
			(xy 242.350437 -200.375582) (xy 242.296623 -200.391913) (xy 242.240995 -200.400166) (xy 242.212876 -200.400666)
			(xy 242.185623 -200.400262) (xy 242.131672 -200.392502) (xy 242.079374 -200.377143) (xy 242.029795 -200.354498)
			(xy 241.983942 -200.325028) (xy 241.94275 -200.289333) (xy 241.907057 -200.248139) (xy 241.87759 -200.202284)
			(xy 241.854948 -200.152703) (xy 241.839593 -200.100405) (xy 241.831836 -200.046453) (xy 216.964631 -200.046453)
			(xy 217.543126 -200.624948) (xy 243.229382 -200.624948) (xy 243.233453 -200.569326) (xy 243.245579 -200.514889)
			(xy 243.265502 -200.462798) (xy 243.292798 -200.414163) (xy 243.326884 -200.37002) (xy 243.367033 -200.331311)
			(xy 243.412391 -200.29886) (xy 243.461991 -200.273359) (xy 243.514775 -200.255352) (xy 243.569618 -200.245222)
			(xy 243.625352 -200.243185) (xy 243.680789 -200.249285) (xy 243.734746 -200.263391) (xy 243.786075 -200.285203)
			(xy 243.833681 -200.314257) (xy 243.876549 -200.349932) (xy 243.913766 -200.391469) (xy 243.944539 -200.437982)
			(xy 243.968211 -200.488479) (xy 243.984279 -200.541886) (xy 243.992399 -200.597062) (xy 243.992908 -200.624948)
			(xy 243.992399 -200.652834) (xy 243.984279 -200.70801) (xy 243.968211 -200.761417) (xy 243.944539 -200.811914)
			(xy 243.913766 -200.858427) (xy 243.876549 -200.899964) (xy 243.833681 -200.935639) (xy 243.786075 -200.964693)
			(xy 243.734746 -200.986505) (xy 243.680789 -201.000611) (xy 243.625352 -201.006711) (xy 243.569618 -201.004674)
			(xy 243.514775 -200.994544) (xy 243.461991 -200.976537) (xy 243.412391 -200.951036) (xy 243.367033 -200.918585)
			(xy 243.326884 -200.879876) (xy 243.292798 -200.835733) (xy 243.265502 -200.787098) (xy 243.245579 -200.735007)
			(xy 243.233453 -200.68057) (xy 243.229382 -200.624948) (xy 217.543126 -200.624948) (xy 217.77198 -200.853802)
			(xy 217.77198 -201.011028) (xy 240.966242 -201.011028) (xy 240.970313 -200.955406) (xy 240.982439 -200.900969)
			(xy 241.002362 -200.848878) (xy 241.029658 -200.800243) (xy 241.063744 -200.7561) (xy 241.103893 -200.717391)
			(xy 241.149251 -200.68494) (xy 241.198851 -200.659439) (xy 241.251635 -200.641432) (xy 241.306478 -200.631302)
			(xy 241.362212 -200.629265) (xy 241.417649 -200.635365) (xy 241.471606 -200.649471) (xy 241.522935 -200.671283)
			(xy 241.570541 -200.700337) (xy 241.613409 -200.736012) (xy 241.650626 -200.777549) (xy 241.681399 -200.824062)
			(xy 241.705071 -200.874559) (xy 241.721139 -200.927966) (xy 241.729259 -200.983142) (xy 241.729768 -201.011028)
			(xy 241.729259 -201.038914) (xy 241.721139 -201.09409) (xy 241.719153 -201.10069) (xy 242.04752 -201.10069)
			(xy 242.051591 -201.045068) (xy 242.063717 -200.990631) (xy 242.08364 -200.93854) (xy 242.110936 -200.889905)
			(xy 242.145022 -200.845762) (xy 242.185171 -200.807053) (xy 242.230529 -200.774602) (xy 242.280129 -200.749101)
			(xy 242.332913 -200.731094) (xy 242.387756 -200.720964) (xy 242.44349 -200.718927) (xy 242.498927 -200.725027)
			(xy 242.552884 -200.739133) (xy 242.604213 -200.760945) (xy 242.651819 -200.789999) (xy 242.694687 -200.825674)
			(xy 242.731904 -200.867211) (xy 242.762677 -200.913724) (xy 242.786349 -200.964221) (xy 242.802417 -201.017628)
			(xy 242.810537 -201.072804) (xy 242.811046 -201.10069) (xy 242.810537 -201.128576) (xy 242.802417 -201.183752)
			(xy 242.786349 -201.237159) (xy 242.762677 -201.287656) (xy 242.731904 -201.334169) (xy 242.694687 -201.375706)
			(xy 242.651819 -201.411381) (xy 242.604213 -201.440435) (xy 242.552884 -201.462247) (xy 242.498927 -201.476353)
			(xy 242.44349 -201.482453) (xy 242.387756 -201.480416) (xy 242.332913 -201.470286) (xy 242.280129 -201.452279)
			(xy 242.230529 -201.426778) (xy 242.185171 -201.394327) (xy 242.145022 -201.355618) (xy 242.110936 -201.311475)
			(xy 242.08364 -201.26284) (xy 242.063717 -201.210749) (xy 242.051591 -201.156312) (xy 242.04752 -201.10069)
			(xy 241.719153 -201.10069) (xy 241.705071 -201.147497) (xy 241.681399 -201.197994) (xy 241.650626 -201.244507)
			(xy 241.613409 -201.286044) (xy 241.570541 -201.321719) (xy 241.522935 -201.350773) (xy 241.471606 -201.372585)
			(xy 241.417649 -201.386691) (xy 241.362212 -201.392791) (xy 241.306478 -201.390754) (xy 241.251635 -201.380624)
			(xy 241.198851 -201.362617) (xy 241.149251 -201.337116) (xy 241.103893 -201.304665) (xy 241.063744 -201.265956)
			(xy 241.029658 -201.221813) (xy 241.002362 -201.173178) (xy 240.982439 -201.121087) (xy 240.970313 -201.06665)
			(xy 240.966242 -201.011028) (xy 217.77198 -201.011028) (xy 217.77198 -201.894948) (xy 230.686862 -201.894948)
			(xy 230.690933 -201.839326) (xy 230.703059 -201.784889) (xy 230.722982 -201.732798) (xy 230.750278 -201.684163)
			(xy 230.784364 -201.64002) (xy 230.824513 -201.601311) (xy 230.869871 -201.56886) (xy 230.919471 -201.543359)
			(xy 230.972255 -201.525352) (xy 231.027098 -201.515222) (xy 231.082832 -201.513185) (xy 231.138269 -201.519285)
			(xy 231.192226 -201.533391) (xy 231.243555 -201.555203) (xy 231.291161 -201.584257) (xy 231.334029 -201.619932)
			(xy 231.371246 -201.661469) (xy 231.402019 -201.707982) (xy 231.425691 -201.758479) (xy 231.441759 -201.811886)
			(xy 231.449879 -201.867062) (xy 231.450388 -201.894948) (xy 231.449879 -201.922834) (xy 231.441759 -201.97801)
			(xy 231.434271 -202.002898) (xy 240.101626 -202.002898) (xy 240.105697 -201.947276) (xy 240.117823 -201.892839)
			(xy 240.137746 -201.840748) (xy 240.165042 -201.792113) (xy 240.199128 -201.74797) (xy 240.239277 -201.709261)
			(xy 240.284635 -201.67681) (xy 240.334235 -201.651309) (xy 240.387019 -201.633302) (xy 240.441862 -201.623172)
			(xy 240.497596 -201.621135) (xy 240.553033 -201.627235) (xy 240.60699 -201.641341) (xy 240.658319 -201.663153)
			(xy 240.705925 -201.692207) (xy 240.748793 -201.727882) (xy 240.78601 -201.769419) (xy 240.816783 -201.815932)
			(xy 240.840455 -201.866429) (xy 240.856523 -201.919836) (xy 240.864643 -201.975012) (xy 240.865152 -202.002898)
			(xy 240.864643 -202.030784) (xy 240.856523 -202.08596) (xy 240.840455 -202.139367) (xy 240.816783 -202.189864)
			(xy 240.797136 -202.21956) (xy 241.182904 -202.21956) (xy 241.186975 -202.163938) (xy 241.199101 -202.109501)
			(xy 241.219024 -202.05741) (xy 241.24632 -202.008775) (xy 241.280406 -201.964632) (xy 241.320555 -201.925923)
			(xy 241.365913 -201.893472) (xy 241.415513 -201.867971) (xy 241.468297 -201.849964) (xy 241.52314 -201.839834)
			(xy 241.578874 -201.837797) (xy 241.634311 -201.843897) (xy 241.688268 -201.858003) (xy 241.739597 -201.879815)
			(xy 241.787203 -201.908869) (xy 241.830071 -201.944544) (xy 241.867288 -201.986081) (xy 241.898061 -202.032594)
			(xy 241.921733 -202.083091) (xy 241.937801 -202.136498) (xy 241.945921 -202.191674) (xy 241.94643 -202.21956)
			(xy 241.945921 -202.247446) (xy 241.937801 -202.302622) (xy 241.921733 -202.356029) (xy 241.898061 -202.406526)
			(xy 241.867288 -202.453039) (xy 241.830071 -202.494576) (xy 241.787203 -202.530251) (xy 241.739597 -202.559305)
			(xy 241.688268 -202.581117) (xy 241.634311 -202.595223) (xy 241.578874 -202.601323) (xy 241.52314 -202.599286)
			(xy 241.468297 -202.589156) (xy 241.415513 -202.571149) (xy 241.365913 -202.545648) (xy 241.320555 -202.513197)
			(xy 241.280406 -202.474488) (xy 241.24632 -202.430345) (xy 241.219024 -202.38171) (xy 241.199101 -202.329619)
			(xy 241.186975 -202.275182) (xy 241.182904 -202.21956) (xy 240.797136 -202.21956) (xy 240.78601 -202.236377)
			(xy 240.748793 -202.277914) (xy 240.705925 -202.313589) (xy 240.658319 -202.342643) (xy 240.60699 -202.364455)
			(xy 240.553033 -202.378561) (xy 240.497596 -202.384661) (xy 240.441862 -202.382624) (xy 240.387019 -202.372494)
			(xy 240.334235 -202.354487) (xy 240.284635 -202.328986) (xy 240.239277 -202.296535) (xy 240.199128 -202.257826)
			(xy 240.165042 -202.213683) (xy 240.137746 -202.165048) (xy 240.117823 -202.112957) (xy 240.105697 -202.05852)
			(xy 240.101626 -202.002898) (xy 231.434271 -202.002898) (xy 231.425691 -202.031417) (xy 231.402019 -202.081914)
			(xy 231.371246 -202.128427) (xy 231.334029 -202.169964) (xy 231.291161 -202.205639) (xy 231.243555 -202.234693)
			(xy 231.192226 -202.256505) (xy 231.138269 -202.270611) (xy 231.082832 -202.276711) (xy 231.027098 -202.274674)
			(xy 230.972255 -202.264544) (xy 230.919471 -202.246537) (xy 230.869871 -202.221036) (xy 230.824513 -202.188585)
			(xy 230.784364 -202.149876) (xy 230.750278 -202.105733) (xy 230.722982 -202.057098) (xy 230.703059 -202.005007)
			(xy 230.690933 -201.95057) (xy 230.686862 -201.894948) (xy 217.77198 -201.894948) (xy 217.77198 -202.910694)
			(xy 230.686862 -202.910694) (xy 230.690933 -202.855072) (xy 230.703059 -202.800635) (xy 230.722982 -202.748544)
			(xy 230.750278 -202.699909) (xy 230.784364 -202.655766) (xy 230.824513 -202.617057) (xy 230.869871 -202.584606)
			(xy 230.919471 -202.559105) (xy 230.972255 -202.541098) (xy 231.027098 -202.530968) (xy 231.082832 -202.528931)
			(xy 231.138269 -202.535031) (xy 231.192226 -202.549137) (xy 231.243555 -202.570949) (xy 231.291161 -202.600003)
			(xy 231.334029 -202.635678) (xy 231.371246 -202.677215) (xy 231.402019 -202.723728) (xy 231.425691 -202.774225)
			(xy 231.441759 -202.827632) (xy 231.449879 -202.882808) (xy 231.450388 -202.910694) (xy 231.449879 -202.93858)
			(xy 231.441759 -202.993756) (xy 231.428463 -203.037948) (xy 231.702862 -203.037948) (xy 231.706933 -202.982326)
			(xy 231.719059 -202.927889) (xy 231.738982 -202.875798) (xy 231.766278 -202.827163) (xy 231.800364 -202.78302)
			(xy 231.840513 -202.744311) (xy 231.885871 -202.71186) (xy 231.935471 -202.686359) (xy 231.988255 -202.668352)
			(xy 232.043098 -202.658222) (xy 232.098832 -202.656185) (xy 232.154269 -202.662285) (xy 232.208226 -202.676391)
			(xy 232.259555 -202.698203) (xy 232.307161 -202.727257) (xy 232.350029 -202.762932) (xy 232.387246 -202.804469)
			(xy 232.418019 -202.850982) (xy 232.427674 -202.871578) (xy 239.232946 -202.871578) (xy 239.237017 -202.815956)
			(xy 239.249143 -202.761519) (xy 239.269066 -202.709428) (xy 239.296362 -202.660793) (xy 239.330448 -202.61665)
			(xy 239.370597 -202.577941) (xy 239.415955 -202.54549) (xy 239.465555 -202.519989) (xy 239.518339 -202.501982)
			(xy 239.573182 -202.491852) (xy 239.628916 -202.489815) (xy 239.684353 -202.495915) (xy 239.73831 -202.510021)
			(xy 239.789639 -202.531833) (xy 239.837245 -202.560887) (xy 239.880113 -202.596562) (xy 239.91733 -202.638099)
			(xy 239.948103 -202.684612) (xy 239.971775 -202.735109) (xy 239.987843 -202.788516) (xy 239.995963 -202.843692)
			(xy 239.996472 -202.871578) (xy 239.995963 -202.899464) (xy 239.987843 -202.95464) (xy 239.971775 -203.008047)
			(xy 239.948103 -203.058544) (xy 239.91733 -203.105057) (xy 239.886654 -203.139294) (xy 240.389916 -203.139294)
			(xy 240.393987 -203.083672) (xy 240.406113 -203.029235) (xy 240.426036 -202.977144) (xy 240.453332 -202.928509)
			(xy 240.487418 -202.884366) (xy 240.527567 -202.845657) (xy 240.572925 -202.813206) (xy 240.622525 -202.787705)
			(xy 240.675309 -202.769698) (xy 240.730152 -202.759568) (xy 240.785886 -202.757531) (xy 240.841323 -202.763631)
			(xy 240.89528 -202.777737) (xy 240.946609 -202.799549) (xy 240.994215 -202.828603) (xy 241.037083 -202.864278)
			(xy 241.0743 -202.905815) (xy 241.105073 -202.952328) (xy 241.128745 -203.002825) (xy 241.144813 -203.056232)
			(xy 241.152933 -203.111408) (xy 241.153442 -203.139294) (xy 241.152933 -203.16718) (xy 241.144813 -203.222356)
			(xy 241.128745 -203.275763) (xy 241.105073 -203.32626) (xy 241.0743 -203.372773) (xy 241.037083 -203.41431)
			(xy 240.994215 -203.449985) (xy 240.946609 -203.479039) (xy 240.89528 -203.500851) (xy 240.841323 -203.514957)
			(xy 240.785886 -203.521057) (xy 240.730152 -203.51902) (xy 240.675309 -203.50889) (xy 240.622525 -203.490883)
			(xy 240.572925 -203.465382) (xy 240.527567 -203.432931) (xy 240.487418 -203.394222) (xy 240.453332 -203.350079)
			(xy 240.426036 -203.301444) (xy 240.406113 -203.249353) (xy 240.393987 -203.194916) (xy 240.389916 -203.139294)
			(xy 239.886654 -203.139294) (xy 239.880113 -203.146594) (xy 239.837245 -203.182269) (xy 239.789639 -203.211323)
			(xy 239.73831 -203.233135) (xy 239.684353 -203.247241) (xy 239.628916 -203.253341) (xy 239.573182 -203.251304)
			(xy 239.518339 -203.241174) (xy 239.465555 -203.223167) (xy 239.415955 -203.197666) (xy 239.370597 -203.165215)
			(xy 239.330448 -203.126506) (xy 239.296362 -203.082363) (xy 239.269066 -203.033728) (xy 239.249143 -202.981637)
			(xy 239.237017 -202.9272) (xy 239.232946 -202.871578) (xy 232.427674 -202.871578) (xy 232.441691 -202.901479)
			(xy 232.457759 -202.954886) (xy 232.465879 -203.010062) (xy 232.466388 -203.037948) (xy 232.465879 -203.065834)
			(xy 232.457759 -203.12101) (xy 232.441691 -203.174417) (xy 232.418019 -203.224914) (xy 232.387246 -203.271427)
			(xy 232.350029 -203.312964) (xy 232.307161 -203.348639) (xy 232.259555 -203.377693) (xy 232.208226 -203.399505)
			(xy 232.154269 -203.413611) (xy 232.098832 -203.419711) (xy 232.043098 -203.417674) (xy 231.988255 -203.407544)
			(xy 231.935471 -203.389537) (xy 231.885871 -203.364036) (xy 231.840513 -203.331585) (xy 231.800364 -203.292876)
			(xy 231.766278 -203.248733) (xy 231.738982 -203.200098) (xy 231.719059 -203.148007) (xy 231.706933 -203.09357)
			(xy 231.702862 -203.037948) (xy 231.428463 -203.037948) (xy 231.425691 -203.047163) (xy 231.402019 -203.09766)
			(xy 231.371246 -203.144173) (xy 231.334029 -203.18571) (xy 231.291161 -203.221385) (xy 231.243555 -203.250439)
			(xy 231.192226 -203.272251) (xy 231.138269 -203.286357) (xy 231.082832 -203.292457) (xy 231.027098 -203.29042)
			(xy 230.972255 -203.28029) (xy 230.919471 -203.262283) (xy 230.869871 -203.236782) (xy 230.824513 -203.204331)
			(xy 230.784364 -203.165622) (xy 230.750278 -203.121479) (xy 230.722982 -203.072844) (xy 230.703059 -203.020753)
			(xy 230.690933 -202.966316) (xy 230.686862 -202.910694) (xy 217.77198 -202.910694) (xy 217.77198 -204.036676)
			(xy 231.81259 -204.036676) (xy 231.816661 -203.981054) (xy 231.828787 -203.926617) (xy 231.84871 -203.874526)
			(xy 231.876006 -203.825891) (xy 231.910092 -203.781748) (xy 231.950241 -203.743039) (xy 231.995599 -203.710588)
			(xy 232.045199 -203.685087) (xy 232.097983 -203.66708) (xy 232.152826 -203.65695) (xy 232.20856 -203.654913)
			(xy 232.263997 -203.661013) (xy 232.317954 -203.675119) (xy 232.369283 -203.696931) (xy 232.416889 -203.725985)
			(xy 232.459757 -203.76166) (xy 232.496974 -203.803197) (xy 232.527747 -203.84971) (xy 232.551419 -203.900207)
			(xy 232.567487 -203.953614) (xy 232.575607 -204.00879) (xy 232.576116 -204.036676) (xy 232.575607 -204.064562)
			(xy 232.567487 -204.119738) (xy 232.551419 -204.173145) (xy 232.527747 -204.223642) (xy 232.522384 -204.231748)
			(xy 232.896662 -204.231748) (xy 232.900733 -204.176126) (xy 232.912859 -204.121689) (xy 232.932782 -204.069598)
			(xy 232.960078 -204.020963) (xy 232.994164 -203.97682) (xy 233.034313 -203.938111) (xy 233.079671 -203.90566)
			(xy 233.129271 -203.880159) (xy 233.182055 -203.862152) (xy 233.236898 -203.852022) (xy 233.292632 -203.849985)
			(xy 233.348069 -203.856085) (xy 233.402026 -203.870191) (xy 233.453355 -203.892003) (xy 233.500961 -203.921057)
			(xy 233.543829 -203.956732) (xy 233.581046 -203.998269) (xy 233.611819 -204.044782) (xy 233.635491 -204.095279)
			(xy 233.651559 -204.148686) (xy 233.655148 -204.173074) (xy 237.677454 -204.173074) (xy 237.681498 -204.09462)
			(xy 237.693587 -204.016998) (xy 237.713594 -203.94103) (xy 237.741305 -203.867522) (xy 237.776428 -203.797253)
			(xy 237.81859 -203.730968) (xy 237.867344 -203.669369) (xy 237.922173 -203.613109) (xy 237.982496 -203.562785)
			(xy 238.047674 -203.518931) (xy 238.117015 -203.48201) (xy 238.189786 -203.452415) (xy 238.265213 -203.43046)
			(xy 238.342498 -203.416376) (xy 238.420822 -203.410313) (xy 238.499354 -203.412336) (xy 238.577262 -203.422422)
			(xy 238.653719 -203.440466) (xy 238.727917 -203.466276) (xy 238.799067 -203.499578) (xy 238.866416 -203.540019)
			(xy 238.92925 -203.58717) (xy 238.986902 -203.640533) (xy 239.038762 -203.69954) (xy 239.084281 -203.763567)
			(xy 239.122974 -203.831935) (xy 239.154433 -203.903919) (xy 239.178324 -203.978756) (xy 239.194393 -204.055653)
			(xy 239.195477 -204.06614) (xy 239.46307 -204.06614) (xy 239.467141 -204.010518) (xy 239.479267 -203.956081)
			(xy 239.49919 -203.90399) (xy 239.526486 -203.855355) (xy 239.560572 -203.811212) (xy 239.600721 -203.772503)
			(xy 239.646079 -203.740052) (xy 239.695679 -203.714551) (xy 239.748463 -203.696544) (xy 239.803306 -203.686414)
			(xy 239.85904 -203.684377) (xy 239.914477 -203.690477) (xy 239.968434 -203.704583) (xy 240.019763 -203.726395)
			(xy 240.067369 -203.755449) (xy 240.110237 -203.791124) (xy 240.147454 -203.832661) (xy 240.178227 -203.879174)
			(xy 240.201899 -203.929671) (xy 240.217967 -203.983078) (xy 240.226087 -204.038254) (xy 240.226596 -204.06614)
			(xy 240.226087 -204.094026) (xy 240.217967 -204.149202) (xy 240.201899 -204.202609) (xy 240.178227 -204.253106)
			(xy 240.147454 -204.299619) (xy 240.110237 -204.341156) (xy 240.067369 -204.376831) (xy 240.019763 -204.405885)
			(xy 239.968434 -204.427697) (xy 239.914477 -204.441803) (xy 239.85904 -204.447903) (xy 239.803306 -204.445866)
			(xy 239.748463 -204.435736) (xy 239.695679 -204.417729) (xy 239.646079 -204.392228) (xy 239.600721 -204.359777)
			(xy 239.560572 -204.321068) (xy 239.526486 -204.276925) (xy 239.49919 -204.22829) (xy 239.479267 -204.176199)
			(xy 239.467141 -204.121762) (xy 239.46307 -204.06614) (xy 239.195477 -204.06614) (xy 239.20247 -204.133795)
			(xy 239.202976 -204.173074) (xy 239.20247 -204.212353) (xy 239.194393 -204.290495) (xy 239.178324 -204.367392)
			(xy 239.154433 -204.442229) (xy 239.122974 -204.514213) (xy 239.084281 -204.582581) (xy 239.038762 -204.646608)
			(xy 238.986902 -204.705615) (xy 238.92925 -204.758978) (xy 238.866416 -204.806129) (xy 238.799067 -204.84657)
			(xy 238.727917 -204.879872) (xy 238.653719 -204.905682) (xy 238.577262 -204.923726) (xy 238.499354 -204.933812)
			(xy 238.420822 -204.935835) (xy 238.342498 -204.929772) (xy 238.265213 -204.915688) (xy 238.189786 -204.893733)
			(xy 238.117015 -204.864138) (xy 238.047674 -204.827217) (xy 237.982496 -204.783363) (xy 237.922173 -204.733039)
			(xy 237.867344 -204.676779) (xy 237.81859 -204.61518) (xy 237.776428 -204.548895) (xy 237.741305 -204.478626)
			(xy 237.713594 -204.405118) (xy 237.693587 -204.32915) (xy 237.681498 -204.251528) (xy 237.677454 -204.173074)
			(xy 233.655148 -204.173074) (xy 233.659679 -204.203862) (xy 233.660188 -204.231748) (xy 233.659679 -204.259634)
			(xy 233.651559 -204.31481) (xy 233.635491 -204.368217) (xy 233.611819 -204.418714) (xy 233.581046 -204.465227)
			(xy 233.543829 -204.506764) (xy 233.500961 -204.542439) (xy 233.453355 -204.571493) (xy 233.402026 -204.593305)
			(xy 233.348069 -204.607411) (xy 233.292632 -204.613511) (xy 233.236898 -204.611474) (xy 233.182055 -204.601344)
			(xy 233.129271 -204.583337) (xy 233.079671 -204.557836) (xy 233.034313 -204.525385) (xy 232.994164 -204.486676)
			(xy 232.960078 -204.442533) (xy 232.932782 -204.393898) (xy 232.912859 -204.341807) (xy 232.900733 -204.28737)
			(xy 232.896662 -204.231748) (xy 232.522384 -204.231748) (xy 232.496974 -204.270155) (xy 232.459757 -204.311692)
			(xy 232.416889 -204.347367) (xy 232.369283 -204.376421) (xy 232.317954 -204.398233) (xy 232.263997 -204.412339)
			(xy 232.20856 -204.418439) (xy 232.152826 -204.416402) (xy 232.097983 -204.406272) (xy 232.045199 -204.388265)
			(xy 231.995599 -204.362764) (xy 231.950241 -204.330313) (xy 231.910092 -204.291604) (xy 231.876006 -204.247461)
			(xy 231.84871 -204.198826) (xy 231.828787 -204.146735) (xy 231.816661 -204.092298) (xy 231.81259 -204.036676)
			(xy 217.77198 -204.036676) (xy 217.77198 -205.311248) (xy 236.920022 -205.311248) (xy 236.924093 -205.255626)
			(xy 236.936219 -205.201189) (xy 236.956142 -205.149098) (xy 236.983438 -205.100463) (xy 237.017524 -205.05632)
			(xy 237.057673 -205.017611) (xy 237.103031 -204.98516) (xy 237.152631 -204.959659) (xy 237.205415 -204.941652)
			(xy 237.260258 -204.931522) (xy 237.315992 -204.929485) (xy 237.371429 -204.935585) (xy 237.425386 -204.949691)
			(xy 237.476715 -204.971503) (xy 237.524321 -205.000557) (xy 237.567189 -205.036232) (xy 237.604406 -205.077769)
			(xy 237.635179 -205.124282) (xy 237.658851 -205.174779) (xy 237.674919 -205.228186) (xy 237.683039 -205.283362)
			(xy 237.683548 -205.311248) (xy 237.683039 -205.339134) (xy 237.674919 -205.39431) (xy 237.658851 -205.447717)
			(xy 237.635179 -205.498214) (xy 237.604406 -205.544727) (xy 237.567189 -205.586264) (xy 237.55999 -205.592255)
			(xy 237.965149 -205.592255) (xy 237.965149 -205.537745) (xy 237.972907 -205.48379) (xy 237.988265 -205.431489)
			(xy 238.010911 -205.381906) (xy 238.040382 -205.33605) (xy 238.07608 -205.294856) (xy 238.117278 -205.259162)
			(xy 238.163136 -205.229694) (xy 238.212721 -205.207054) (xy 238.265024 -205.1917) (xy 238.318979 -205.183947)
			(xy 238.346234 -205.183486) (xy 238.37499 -205.184026) (xy 238.431854 -205.192636) (xy 238.486781 -205.209688)
			(xy 238.538524 -205.234793) (xy 238.585912 -205.267382) (xy 238.627869 -205.306718) (xy 238.663444 -205.351907)
			(xy 238.69183 -205.401926) (xy 238.702596 -205.428596) (xy 238.707963 -205.441517) (xy 238.72472 -205.463916)
			(xy 238.746917 -205.480939) (xy 238.772895 -205.491315) (xy 238.800712 -205.494267) (xy 238.828289 -205.489575)
			(xy 238.853564 -205.47759) (xy 238.864394 -205.468728) (xy 238.885361 -205.451021) (xy 238.931391 -205.421141)
			(xy 238.981231 -205.398172) (xy 239.033851 -205.382591) (xy 239.088161 -205.374718) (xy 239.1156 -205.37424)
			(xy 239.142855 -205.37463) (xy 239.196809 -205.382387) (xy 239.249111 -205.397744) (xy 239.298694 -205.420388)
			(xy 239.34455 -205.449858) (xy 239.385746 -205.485554) (xy 239.421442 -205.52675) (xy 239.450912 -205.572606)
			(xy 239.473556 -205.622189) (xy 239.488913 -205.674491) (xy 239.49667 -205.728445) (xy 239.49667 -205.782955)
			(xy 239.488913 -205.836909) (xy 239.473556 -205.889211) (xy 239.450912 -205.938794) (xy 239.421442 -205.98465)
			(xy 239.385746 -206.025846) (xy 239.34455 -206.061542) (xy 239.298694 -206.091012) (xy 239.249111 -206.113656)
			(xy 239.196809 -206.129013) (xy 239.142855 -206.13677) (xy 239.1156 -206.137256) (xy 239.086843 -206.136724)
			(xy 239.029977 -206.128117) (xy 238.975048 -206.111067) (xy 238.923303 -206.085962) (xy 238.875914 -206.053371)
			(xy 238.833958 -206.014033) (xy 238.798384 -205.96884) (xy 238.770001 -205.918818) (xy 238.759238 -205.892146)
			(xy 238.753813 -205.879251) (xy 238.73707 -205.856851) (xy 238.714885 -205.839824) (xy 238.688916 -205.829444)
			(xy 238.661107 -205.826487) (xy 238.633537 -205.831174) (xy 238.608267 -205.843155) (xy 238.59744 -205.852014)
			(xy 238.576503 -205.869758) (xy 238.530464 -205.899632) (xy 238.480616 -205.922592) (xy 238.42799 -205.938165)
			(xy 238.373675 -205.946028) (xy 238.346234 -205.946502) (xy 238.318979 -205.946053) (xy 238.265024 -205.9383)
			(xy 238.212721 -205.922946) (xy 238.163136 -205.900306) (xy 238.117278 -205.870838) (xy 238.07608 -205.835144)
			(xy 238.040382 -205.79395) (xy 238.010911 -205.748094) (xy 237.988265 -205.698511) (xy 237.972907 -205.64621)
			(xy 237.965149 -205.592255) (xy 237.55999 -205.592255) (xy 237.524321 -205.621939) (xy 237.476715 -205.650993)
			(xy 237.425386 -205.672805) (xy 237.371429 -205.686911) (xy 237.315992 -205.693011) (xy 237.260258 -205.690974)
			(xy 237.205415 -205.680844) (xy 237.152631 -205.662837) (xy 237.103031 -205.637336) (xy 237.057673 -205.604885)
			(xy 237.017524 -205.566176) (xy 236.983438 -205.522033) (xy 236.956142 -205.473398) (xy 236.936219 -205.421307)
			(xy 236.924093 -205.36687) (xy 236.920022 -205.311248) (xy 217.77198 -205.311248) (xy 217.77198 -206.111348)
			(xy 235.126782 -206.111348) (xy 235.130853 -206.055726) (xy 235.142979 -206.001289) (xy 235.162902 -205.949198)
			(xy 235.190198 -205.900563) (xy 235.224284 -205.85642) (xy 235.264433 -205.817711) (xy 235.309791 -205.78526)
			(xy 235.359391 -205.759759) (xy 235.412175 -205.741752) (xy 235.467018 -205.731622) (xy 235.522752 -205.729585)
			(xy 235.578189 -205.735685) (xy 235.632146 -205.749791) (xy 235.683475 -205.771603) (xy 235.731081 -205.800657)
			(xy 235.773949 -205.836332) (xy 235.811166 -205.877869) (xy 235.841939 -205.924382) (xy 235.865611 -205.974879)
			(xy 235.881679 -206.028286) (xy 235.889799 -206.083462) (xy 235.890308 -206.111348) (xy 235.889799 -206.139234)
			(xy 235.881829 -206.19339) (xy 236.037626 -206.19339) (xy 236.041697 -206.137768) (xy 236.053823 -206.083331)
			(xy 236.073746 -206.03124) (xy 236.101042 -205.982605) (xy 236.135128 -205.938462) (xy 236.175277 -205.899753)
			(xy 236.220635 -205.867302) (xy 236.270235 -205.841801) (xy 236.323019 -205.823794) (xy 236.377862 -205.813664)
			(xy 236.433596 -205.811627) (xy 236.489033 -205.817727) (xy 236.54299 -205.831833) (xy 236.594319 -205.853645)
			(xy 236.641925 -205.882699) (xy 236.684793 -205.918374) (xy 236.72201 -205.959911) (xy 236.752783 -206.006424)
			(xy 236.776455 -206.056921) (xy 236.792523 -206.110328) (xy 236.800643 -206.165504) (xy 236.801152 -206.19339)
			(xy 236.800643 -206.221276) (xy 236.792523 -206.276452) (xy 236.776455 -206.329859) (xy 236.752783 -206.380356)
			(xy 236.73448 -206.40802) (xy 237.12119 -206.40802) (xy 237.125261 -206.352398) (xy 237.137387 -206.297961)
			(xy 237.15731 -206.24587) (xy 237.184606 -206.197235) (xy 237.218692 -206.153092) (xy 237.258841 -206.114383)
			(xy 237.304199 -206.081932) (xy 237.353799 -206.056431) (xy 237.406583 -206.038424) (xy 237.461426 -206.028294)
			(xy 237.51716 -206.026257) (xy 237.572597 -206.032357) (xy 237.626554 -206.046463) (xy 237.677883 -206.068275)
			(xy 237.725489 -206.097329) (xy 237.768357 -206.133004) (xy 237.805574 -206.174541) (xy 237.836347 -206.221054)
			(xy 237.860019 -206.271551) (xy 237.876087 -206.324958) (xy 237.884207 -206.380134) (xy 237.884716 -206.40802)
			(xy 237.884207 -206.435906) (xy 237.876087 -206.491082) (xy 237.860019 -206.544489) (xy 237.836347 -206.594986)
			(xy 237.805574 -206.641499) (xy 237.768357 -206.683036) (xy 237.725489 -206.718711) (xy 237.677883 -206.747765)
			(xy 237.626554 -206.769577) (xy 237.572597 -206.783683) (xy 237.51716 -206.789783) (xy 237.461426 -206.787746)
			(xy 237.406583 -206.777616) (xy 237.353799 -206.759609) (xy 237.304199 -206.734108) (xy 237.258841 -206.701657)
			(xy 237.218692 -206.662948) (xy 237.184606 -206.618805) (xy 237.15731 -206.57017) (xy 237.137387 -206.518079)
			(xy 237.125261 -206.463642) (xy 237.12119 -206.40802) (xy 236.73448 -206.40802) (xy 236.72201 -206.426869)
			(xy 236.684793 -206.468406) (xy 236.641925 -206.504081) (xy 236.594319 -206.533135) (xy 236.54299 -206.554947)
			(xy 236.489033 -206.569053) (xy 236.433596 -206.575153) (xy 236.377862 -206.573116) (xy 236.323019 -206.562986)
			(xy 236.270235 -206.544979) (xy 236.220635 -206.519478) (xy 236.175277 -206.487027) (xy 236.135128 -206.448318)
			(xy 236.101042 -206.404175) (xy 236.073746 -206.35554) (xy 236.053823 -206.303449) (xy 236.041697 -206.249012)
			(xy 236.037626 -206.19339) (xy 235.881829 -206.19339) (xy 235.881679 -206.19441) (xy 235.865611 -206.247817)
			(xy 235.841939 -206.298314) (xy 235.811166 -206.344827) (xy 235.773949 -206.386364) (xy 235.731081 -206.422039)
			(xy 235.683475 -206.451093) (xy 235.632146 -206.472905) (xy 235.578189 -206.487011) (xy 235.522752 -206.493111)
			(xy 235.467018 -206.491074) (xy 235.412175 -206.480944) (xy 235.359391 -206.462937) (xy 235.309791 -206.437436)
			(xy 235.264433 -206.404985) (xy 235.224284 -206.366276) (xy 235.190198 -206.322133) (xy 235.162902 -206.273498)
			(xy 235.142979 -206.221407) (xy 235.130853 -206.16697) (xy 235.126782 -206.111348) (xy 217.77198 -206.111348)
			(xy 217.77198 -207.038448) (xy 235.195362 -207.038448) (xy 235.199433 -206.982826) (xy 235.211559 -206.928389)
			(xy 235.231482 -206.876298) (xy 235.258778 -206.827663) (xy 235.292864 -206.78352) (xy 235.333013 -206.744811)
			(xy 235.378371 -206.71236) (xy 235.427971 -206.686859) (xy 235.480755 -206.668852) (xy 235.535598 -206.658722)
			(xy 235.591332 -206.656685) (xy 235.646769 -206.662785) (xy 235.700726 -206.676891) (xy 235.752055 -206.698703)
			(xy 235.799661 -206.727757) (xy 235.842529 -206.763432) (xy 235.879746 -206.804969) (xy 235.910519 -206.851482)
			(xy 235.934191 -206.901979) (xy 235.950259 -206.955386) (xy 235.958379 -207.010562) (xy 235.958888 -207.038448)
			(xy 235.958379 -207.066334) (xy 235.950259 -207.12151) (xy 235.934191 -207.174917) (xy 235.910519 -207.225414)
			(xy 235.879746 -207.271927) (xy 235.862042 -207.291686) (xy 236.237524 -207.291686) (xy 236.241595 -207.236064)
			(xy 236.253721 -207.181627) (xy 236.273644 -207.129536) (xy 236.30094 -207.080901) (xy 236.335026 -207.036758)
			(xy 236.375175 -206.998049) (xy 236.420533 -206.965598) (xy 236.470133 -206.940097) (xy 236.522917 -206.92209)
			(xy 236.57776 -206.91196) (xy 236.633494 -206.909923) (xy 236.688931 -206.916023) (xy 236.742888 -206.930129)
			(xy 236.794217 -206.951941) (xy 236.841823 -206.980995) (xy 236.884691 -207.01667) (xy 236.921908 -207.058207)
			(xy 236.952681 -207.10472) (xy 236.976353 -207.155217) (xy 236.992421 -207.208624) (xy 237.000541 -207.2638)
			(xy 237.00105 -207.291686) (xy 237.000541 -207.319572) (xy 236.992421 -207.374748) (xy 236.976353 -207.428155)
			(xy 236.952681 -207.478652) (xy 236.921908 -207.525165) (xy 236.884691 -207.566702) (xy 236.841823 -207.602377)
			(xy 236.794217 -207.631431) (xy 236.742888 -207.653243) (xy 236.688931 -207.667349) (xy 236.633494 -207.673449)
			(xy 236.57776 -207.671412) (xy 236.522917 -207.661282) (xy 236.470133 -207.643275) (xy 236.420533 -207.617774)
			(xy 236.375175 -207.585323) (xy 236.335026 -207.546614) (xy 236.30094 -207.502471) (xy 236.273644 -207.453836)
			(xy 236.253721 -207.401745) (xy 236.241595 -207.347308) (xy 236.237524 -207.291686) (xy 235.862042 -207.291686)
			(xy 235.842529 -207.313464) (xy 235.799661 -207.349139) (xy 235.752055 -207.378193) (xy 235.700726 -207.400005)
			(xy 235.646769 -207.414111) (xy 235.591332 -207.420211) (xy 235.535598 -207.418174) (xy 235.480755 -207.408044)
			(xy 235.427971 -207.390037) (xy 235.378371 -207.364536) (xy 235.333013 -207.332085) (xy 235.292864 -207.293376)
			(xy 235.258778 -207.249233) (xy 235.231482 -207.200598) (xy 235.211559 -207.148507) (xy 235.199433 -207.09407)
			(xy 235.195362 -207.038448) (xy 217.77198 -207.038448) (xy 217.77198 -207.736948) (xy 234.623862 -207.736948)
			(xy 234.627933 -207.681326) (xy 234.640059 -207.626889) (xy 234.659982 -207.574798) (xy 234.687278 -207.526163)
			(xy 234.721364 -207.48202) (xy 234.761513 -207.443311) (xy 234.806871 -207.41086) (xy 234.856471 -207.385359)
			(xy 234.909255 -207.367352) (xy 234.964098 -207.357222) (xy 235.019832 -207.355185) (xy 235.075269 -207.361285)
			(xy 235.129226 -207.375391) (xy 235.180555 -207.397203) (xy 235.228161 -207.426257) (xy 235.271029 -207.461932)
			(xy 235.308246 -207.503469) (xy 235.339019 -207.549982) (xy 235.362691 -207.600479) (xy 235.378759 -207.653886)
			(xy 235.386879 -207.709062) (xy 235.387388 -207.736948) (xy 235.386879 -207.764834) (xy 235.378759 -207.82001)
			(xy 235.362691 -207.873417) (xy 235.339019 -207.923914) (xy 235.308246 -207.970427) (xy 235.271029 -208.011964)
			(xy 235.228161 -208.047639) (xy 235.180555 -208.076693) (xy 235.129226 -208.098505) (xy 235.075269 -208.112611)
			(xy 235.019832 -208.118711) (xy 234.964098 -208.116674) (xy 234.909255 -208.106544) (xy 234.856471 -208.088537)
			(xy 234.806871 -208.063036) (xy 234.761513 -208.030585) (xy 234.721364 -207.991876) (xy 234.687278 -207.947733)
			(xy 234.659982 -207.899098) (xy 234.640059 -207.847007) (xy 234.627933 -207.79257) (xy 234.623862 -207.736948)
			(xy 217.77198 -207.736948) (xy 217.77198 -209.389738) (xy 234.467354 -209.389738) (xy 234.467357 -209.33523)
			(xy 234.475116 -209.281278) (xy 234.490475 -209.22898) (xy 234.513121 -209.1794) (xy 234.542592 -209.133547)
			(xy 234.578289 -209.092355) (xy 234.619486 -209.056664) (xy 234.665342 -209.027198) (xy 234.714925 -209.004558)
			(xy 234.767225 -208.989206) (xy 234.821178 -208.981453) (xy 234.875686 -208.981458) (xy 234.929637 -208.98922)
			(xy 234.981935 -209.004581) (xy 235.031514 -209.027229) (xy 235.077366 -209.056702) (xy 235.118556 -209.092401)
			(xy 235.154246 -209.133598) (xy 235.18371 -209.179456) (xy 235.206347 -209.22904) (xy 235.221697 -209.281341)
			(xy 235.229448 -209.335294) (xy 235.229908 -209.362548) (xy 235.229612 -209.385246) (xy 235.22426 -209.430326)
			(xy 235.21924 -209.452464) (xy 235.216193 -209.467598) (xy 235.218234 -209.498383) (xy 235.229363 -209.527158)
			(xy 235.248566 -209.551306) (xy 235.274097 -209.568628) (xy 235.303631 -209.577549) (xy 235.319062 -209.57794)
			(xy 235.323126 -209.57794) (xy 235.338112 -209.578194) (xy 235.348659 -209.578136) (xy 235.368281 -209.570449)
			(xy 235.383176 -209.555541) (xy 235.390844 -209.535911) (xy 235.390944 -209.525362) (xy 235.39069 -209.510376)
			(xy 235.391176 -209.483125) (xy 235.398932 -209.429177) (xy 235.414287 -209.376882) (xy 235.436929 -209.327305)
			(xy 235.466395 -209.281455) (xy 235.502086 -209.240264) (xy 235.543277 -209.204573) (xy 235.589127 -209.175107)
			(xy 235.638704 -209.152465) (xy 235.690999 -209.13711) (xy 235.744947 -209.129354) (xy 235.799449 -209.129354)
			(xy 235.853397 -209.13711) (xy 235.905692 -209.152465) (xy 235.955269 -209.175107) (xy 236.001119 -209.204573)
			(xy 236.04231 -209.240264) (xy 236.078001 -209.281455) (xy 236.107467 -209.327305) (xy 236.130109 -209.376882)
			(xy 236.145464 -209.429177) (xy 236.15322 -209.483125) (xy 236.153706 -209.510376) (xy 236.153101 -209.539055)
			(xy 236.144496 -209.595763) (xy 236.127505 -209.650547) (xy 236.102511 -209.702172) (xy 236.070076 -209.749479)
			(xy 236.03093 -209.791402) (xy 235.985955 -209.826998) (xy 235.93616 -209.855466) (xy 235.882668 -209.876166)
			(xy 235.826681 -209.888632) (xy 235.798106 -209.891122) (xy 235.783614 -209.892654) (xy 235.756313 -209.902805)
			(xy 235.732986 -209.920248) (xy 235.71553 -209.943565) (xy 235.705365 -209.970861) (xy 235.703872 -209.985356)
			(xy 235.701405 -210.013942) (xy 235.688975 -210.069954) (xy 235.668299 -210.123474) (xy 235.639843 -210.173295)
			(xy 235.604248 -210.218293) (xy 235.562317 -210.257455) (xy 235.514995 -210.289897) (xy 235.463349 -210.314888)
			(xy 235.408543 -210.331865) (xy 235.351814 -210.340445) (xy 235.323126 -210.340956) (xy 235.295878 -210.340398)
			(xy 235.241935 -210.332646) (xy 235.189645 -210.317297) (xy 235.140071 -210.294662) (xy 235.094223 -210.265203)
			(xy 235.053033 -210.229519) (xy 235.017341 -210.188337) (xy 234.987874 -210.142494) (xy 234.965229 -210.092925)
			(xy 234.94987 -210.040637) (xy 234.942108 -209.986696) (xy 234.941618 -209.959448) (xy 234.941915 -209.93675)
			(xy 234.947267 -209.89167) (xy 234.952286 -209.869532) (xy 234.955411 -209.854409) (xy 234.953369 -209.823608)
			(xy 234.94223 -209.79482) (xy 234.923009 -209.770665) (xy 234.897458 -209.753345) (xy 234.867903 -209.744436)
			(xy 234.852464 -209.744056) (xy 234.8484 -209.744056) (xy 234.821146 -209.743545) (xy 234.767194 -209.735787)
			(xy 234.714895 -209.72043) (xy 234.665314 -209.697787) (xy 234.61946 -209.668317) (xy 234.578267 -209.632622)
			(xy 234.542573 -209.591427) (xy 234.513106 -209.545572) (xy 234.490464 -209.49599) (xy 234.475109 -209.44369)
			(xy 234.467354 -209.389738) (xy 217.77198 -209.389738) (xy 217.77198 -221.42323) (xy 224.34372 -221.42323)
			(xy 224.347791 -221.367608) (xy 224.359917 -221.313171) (xy 224.37984 -221.26108) (xy 224.407136 -221.212445)
			(xy 224.441222 -221.168302) (xy 224.481371 -221.129593) (xy 224.526729 -221.097142) (xy 224.576329 -221.071641)
			(xy 224.629113 -221.053634) (xy 224.683956 -221.043504) (xy 224.73969 -221.041467) (xy 224.795127 -221.047567)
			(xy 224.849084 -221.061673) (xy 224.900413 -221.083485) (xy 224.948019 -221.112539) (xy 224.990887 -221.148214)
			(xy 225.028104 -221.189751) (xy 225.058877 -221.236264) (xy 225.082549 -221.286761) (xy 225.098617 -221.340168)
			(xy 225.106737 -221.395344) (xy 225.107246 -221.42323) (xy 226.92182 -221.42323) (xy 226.925891 -221.367608)
			(xy 226.938017 -221.313171) (xy 226.95794 -221.26108) (xy 226.985236 -221.212445) (xy 227.019322 -221.168302)
			(xy 227.059471 -221.129593) (xy 227.104829 -221.097142) (xy 227.154429 -221.071641) (xy 227.207213 -221.053634)
			(xy 227.262056 -221.043504) (xy 227.31779 -221.041467) (xy 227.373227 -221.047567) (xy 227.427184 -221.061673)
			(xy 227.478513 -221.083485) (xy 227.526119 -221.112539) (xy 227.568987 -221.148214) (xy 227.606204 -221.189751)
			(xy 227.636977 -221.236264) (xy 227.660649 -221.286761) (xy 227.676717 -221.340168) (xy 227.684837 -221.395344)
			(xy 227.685346 -221.42323) (xy 227.684837 -221.451116) (xy 227.676717 -221.506292) (xy 227.660649 -221.559699)
			(xy 227.636977 -221.610196) (xy 227.606204 -221.656709) (xy 227.568987 -221.698246) (xy 227.526119 -221.733921)
			(xy 227.478513 -221.762975) (xy 227.427184 -221.784787) (xy 227.373227 -221.798893) (xy 227.31779 -221.804993)
			(xy 227.262056 -221.802956) (xy 227.207213 -221.792826) (xy 227.154429 -221.774819) (xy 227.104829 -221.749318)
			(xy 227.059471 -221.716867) (xy 227.019322 -221.678158) (xy 226.985236 -221.634015) (xy 226.95794 -221.58538)
			(xy 226.938017 -221.533289) (xy 226.925891 -221.478852) (xy 226.92182 -221.42323) (xy 225.107246 -221.42323)
			(xy 225.106737 -221.451116) (xy 225.098617 -221.506292) (xy 225.082549 -221.559699) (xy 225.058877 -221.610196)
			(xy 225.028104 -221.656709) (xy 224.990887 -221.698246) (xy 224.948019 -221.733921) (xy 224.900413 -221.762975)
			(xy 224.849084 -221.784787) (xy 224.795127 -221.798893) (xy 224.73969 -221.804993) (xy 224.683956 -221.802956)
			(xy 224.629113 -221.792826) (xy 224.576329 -221.774819) (xy 224.526729 -221.749318) (xy 224.481371 -221.716867)
			(xy 224.441222 -221.678158) (xy 224.407136 -221.634015) (xy 224.37984 -221.58538) (xy 224.359917 -221.533289)
			(xy 224.347791 -221.478852) (xy 224.34372 -221.42323) (xy 217.77198 -221.42323) (xy 217.77198 -222.69704)
			(xy 222.6691 -222.69704) (xy 222.669586 -222.669789) (xy 222.677342 -222.615841) (xy 222.692697 -222.563546)
			(xy 222.715339 -222.513969) (xy 222.744805 -222.468119) (xy 222.780496 -222.426928) (xy 222.821687 -222.391237)
			(xy 222.867537 -222.361771) (xy 222.917114 -222.339129) (xy 222.969409 -222.323774) (xy 223.023357 -222.316018)
			(xy 223.077859 -222.316018) (xy 223.131807 -222.323774) (xy 223.184102 -222.339129) (xy 223.233679 -222.361771)
			(xy 223.279529 -222.391237) (xy 223.32072 -222.426928) (xy 223.356411 -222.468119) (xy 223.385877 -222.513969)
			(xy 223.408519 -222.563546) (xy 223.423874 -222.615841) (xy 223.43163 -222.669789) (xy 223.432116 -222.69704)
			(xy 223.431635 -222.72329) (xy 223.424456 -222.775296) (xy 223.41021 -222.825826) (xy 223.389168 -222.873925)
			(xy 223.361727 -222.918682) (xy 223.328407 -222.959252) (xy 223.289836 -222.994868) (xy 223.26854 -223.010222)
			(xy 223.257104 -223.018661) (xy 223.239127 -223.040666) (xy 223.227903 -223.066769) (xy 223.224299 -223.094953)
			(xy 223.228593 -223.123041) (xy 223.240454 -223.148861) (xy 223.258965 -223.170418) (xy 223.270572 -223.178624)
			(xy 223.292795 -223.193862) (xy 223.333191 -223.229516) (xy 223.368166 -223.270502) (xy 223.397022 -223.316004)
			(xy 223.419185 -223.365115) (xy 223.434213 -223.416857) (xy 223.441807 -223.4702) (xy 223.442276 -223.49714)
			(xy 223.44179 -223.524391) (xy 223.434034 -223.578339) (xy 223.418679 -223.630634) (xy 223.396037 -223.680211)
			(xy 223.366571 -223.726061) (xy 223.33088 -223.767252) (xy 223.289689 -223.802943) (xy 223.243839 -223.832409)
			(xy 223.194262 -223.855051) (xy 223.141967 -223.870406) (xy 223.088019 -223.878162) (xy 223.033517 -223.878162)
			(xy 222.979569 -223.870406) (xy 222.927274 -223.855051) (xy 222.877697 -223.832409) (xy 222.831847 -223.802943)
			(xy 222.790656 -223.767252) (xy 222.754965 -223.726061) (xy 222.725499 -223.680211) (xy 222.702857 -223.630634)
			(xy 222.687502 -223.578339) (xy 222.679746 -223.524391) (xy 222.67926 -223.49714) (xy 222.679693 -223.470888)
			(xy 222.686877 -223.418878) (xy 222.701128 -223.368346) (xy 222.722178 -223.320246) (xy 222.749626 -223.275489)
			(xy 222.782956 -223.234921) (xy 222.821536 -223.199309) (xy 222.842836 -223.183958) (xy 222.854185 -223.175415)
			(xy 222.872146 -223.15343) (xy 222.883365 -223.127351) (xy 222.886976 -223.099192) (xy 222.882701 -223.071127)
			(xy 222.870868 -223.045321) (xy 222.852393 -223.023766) (xy 222.840804 -223.015556) (xy 222.818567 -223.000339)
			(xy 222.778171 -222.964681) (xy 222.743198 -222.92369) (xy 222.714344 -222.878185) (xy 222.692184 -222.829071)
			(xy 222.677159 -222.777326) (xy 222.669568 -222.723981) (xy 222.6691 -222.69704) (xy 217.77198 -222.69704)
			(xy 217.77198 -226.54133) (xy 227.455982 -226.54133) (xy 227.460053 -226.485708) (xy 227.472179 -226.431271)
			(xy 227.492102 -226.37918) (xy 227.519398 -226.330545) (xy 227.553484 -226.286402) (xy 227.593633 -226.247693)
			(xy 227.638991 -226.215242) (xy 227.688591 -226.189741) (xy 227.741375 -226.171734) (xy 227.796218 -226.161604)
			(xy 227.851952 -226.159567) (xy 227.907389 -226.165667) (xy 227.961346 -226.179773) (xy 228.012675 -226.201585)
			(xy 228.060281 -226.230639) (xy 228.103149 -226.266314) (xy 228.140366 -226.307851) (xy 228.171139 -226.354364)
			(xy 228.194811 -226.404861) (xy 228.210879 -226.458268) (xy 228.218999 -226.513444) (xy 228.219508 -226.54133)
			(xy 228.218999 -226.569216) (xy 228.210879 -226.624392) (xy 228.194811 -226.677799) (xy 228.171139 -226.728296)
			(xy 228.140366 -226.774809) (xy 228.103149 -226.816346) (xy 228.060281 -226.852021) (xy 228.012675 -226.881075)
			(xy 227.961346 -226.902887) (xy 227.907389 -226.916993) (xy 227.851952 -226.923093) (xy 227.796218 -226.921056)
			(xy 227.741375 -226.910926) (xy 227.688591 -226.892919) (xy 227.638991 -226.867418) (xy 227.593633 -226.834967)
			(xy 227.553484 -226.796258) (xy 227.519398 -226.752115) (xy 227.492102 -226.70348) (xy 227.472179 -226.651389)
			(xy 227.460053 -226.596952) (xy 227.455982 -226.54133) (xy 217.77198 -226.54133) (xy 217.77198 -232.785158)
			(xy 224.311208 -232.785158) (xy 224.315279 -232.729536) (xy 224.327405 -232.675099) (xy 224.347328 -232.623008)
			(xy 224.374624 -232.574373) (xy 224.40871 -232.53023) (xy 224.448859 -232.491521) (xy 224.494217 -232.45907)
			(xy 224.543817 -232.433569) (xy 224.596601 -232.415562) (xy 224.651444 -232.405432) (xy 224.707178 -232.403395)
			(xy 224.762615 -232.409495) (xy 224.816572 -232.423601) (xy 224.867901 -232.445413) (xy 224.915507 -232.474467)
			(xy 224.958375 -232.510142) (xy 224.995592 -232.551679) (xy 225.026365 -232.598192) (xy 225.050037 -232.648689)
			(xy 225.053063 -232.658746) (xy 226.267442 -232.658746) (xy 226.267443 -232.604238) (xy 226.275202 -232.550284)
			(xy 226.29056 -232.497984) (xy 226.313205 -232.448402) (xy 226.342676 -232.402548) (xy 226.378373 -232.361354)
			(xy 226.419569 -232.32566) (xy 226.465425 -232.296193) (xy 226.515009 -232.273551) (xy 226.56731 -232.258197)
			(xy 226.621264 -232.250442) (xy 226.648518 -232.24998) (xy 226.684078 -232.251758) (xy 226.699488 -232.252723)
			(xy 226.729686 -232.246341) (xy 226.756601 -232.231233) (xy 226.777778 -232.208779) (xy 226.791284 -232.181025)
			(xy 226.795887 -232.150505) (xy 226.79406 -232.135172) (xy 226.792026 -232.120908) (xy 226.789864 -232.092175)
			(xy 226.789742 -232.077768) (xy 226.79029 -232.050517) (xy 226.798051 -231.996571) (xy 226.81341 -231.944278)
			(xy 226.836055 -231.894704) (xy 226.865525 -231.848857) (xy 226.90122 -231.80767) (xy 226.942413 -231.771983)
			(xy 226.988265 -231.742522) (xy 227.037844 -231.719886) (xy 227.090139 -231.704536) (xy 227.144087 -231.696785)
			(xy 227.198589 -231.69679) (xy 227.252535 -231.704552) (xy 227.304827 -231.719912) (xy 227.354401 -231.742558)
			(xy 227.400248 -231.772029) (xy 227.441434 -231.807724) (xy 227.47712 -231.848918) (xy 227.506581 -231.894771)
			(xy 227.529217 -231.94435) (xy 227.544566 -231.996645) (xy 227.552316 -232.050593) (xy 227.55231 -232.105095)
			(xy 227.544547 -232.159041) (xy 227.529186 -232.211333) (xy 227.506539 -232.260907) (xy 227.477068 -232.306753)
			(xy 227.441372 -232.347938) (xy 227.400178 -232.383624) (xy 227.354324 -232.413084) (xy 227.304745 -232.435719)
			(xy 227.252449 -232.451067) (xy 227.198501 -232.458816) (xy 227.17125 -232.459276) (xy 227.13569 -232.457498)
			(xy 227.120281 -232.456554) (xy 227.090091 -232.462941) (xy 227.063183 -232.478048) (xy 227.042009 -232.500496)
			(xy 227.028501 -232.528241) (xy 227.023888 -232.558753) (xy 227.025708 -232.574084) (xy 227.027748 -232.588347)
			(xy 227.029906 -232.617081) (xy 227.030026 -232.631488) (xy 227.029558 -232.658742) (xy 227.021802 -232.712696)
			(xy 227.006447 -232.764997) (xy 226.983804 -232.81458) (xy 226.954336 -232.860436) (xy 226.918641 -232.901631)
			(xy 226.877447 -232.937328) (xy 226.831592 -232.966798) (xy 226.78201 -232.989442) (xy 226.72971 -233.004799)
			(xy 226.675756 -233.012557) (xy 226.621248 -233.012557) (xy 226.567294 -233.0048) (xy 226.514994 -232.989443)
			(xy 226.465411 -232.9668) (xy 226.419556 -232.93733) (xy 226.378362 -232.901634) (xy 226.342666 -232.860439)
			(xy 226.313198 -232.814583) (xy 226.290555 -232.765001) (xy 226.275199 -232.7127) (xy 226.267442 -232.658746)
			(xy 225.053063 -232.658746) (xy 225.066105 -232.702096) (xy 225.074225 -232.757272) (xy 225.074734 -232.785158)
			(xy 225.074225 -232.813044) (xy 225.066105 -232.86822) (xy 225.050037 -232.921627) (xy 225.026365 -232.972124)
			(xy 224.995592 -233.018637) (xy 224.958375 -233.060174) (xy 224.915507 -233.095849) (xy 224.867901 -233.124903)
			(xy 224.816572 -233.146715) (xy 224.762615 -233.160821) (xy 224.707178 -233.166921) (xy 224.651444 -233.164884)
			(xy 224.596601 -233.154754) (xy 224.543817 -233.136747) (xy 224.494217 -233.111246) (xy 224.448859 -233.078795)
			(xy 224.40871 -233.040086) (xy 224.374624 -232.995943) (xy 224.347328 -232.947308) (xy 224.327405 -232.895217)
			(xy 224.315279 -232.84078) (xy 224.311208 -232.785158) (xy 217.77198 -232.785158) (xy 217.77198 -233.84637)
			(xy 223.48647 -233.84637) (xy 223.490541 -233.790748) (xy 223.502667 -233.736311) (xy 223.52259 -233.68422)
			(xy 223.549886 -233.635585) (xy 223.583972 -233.591442) (xy 223.624121 -233.552733) (xy 223.669479 -233.520282)
			(xy 223.719079 -233.494781) (xy 223.771863 -233.476774) (xy 223.826706 -233.466644) (xy 223.88244 -233.464607)
			(xy 223.937877 -233.470707) (xy 223.991834 -233.484813) (xy 224.043163 -233.506625) (xy 224.090769 -233.535679)
			(xy 224.133637 -233.571354) (xy 224.170854 -233.612891) (xy 224.201627 -233.659404) (xy 224.225299 -233.709901)
			(xy 224.241367 -233.763308) (xy 224.249487 -233.818484) (xy 224.249996 -233.84637) (xy 224.249487 -233.874256)
			(xy 224.241367 -233.929432) (xy 224.225299 -233.982839) (xy 224.201627 -234.033336) (xy 224.170854 -234.079849)
			(xy 224.133637 -234.121386) (xy 224.090769 -234.157061) (xy 224.043163 -234.186115) (xy 223.991834 -234.207927)
			(xy 223.937877 -234.222033) (xy 223.88244 -234.228133) (xy 223.826706 -234.226096) (xy 223.771863 -234.215966)
			(xy 223.719079 -234.197959) (xy 223.669479 -234.172458) (xy 223.624121 -234.140007) (xy 223.583972 -234.101298)
			(xy 223.549886 -234.057155) (xy 223.52259 -234.00852) (xy 223.502667 -233.956429) (xy 223.490541 -233.901992)
			(xy 223.48647 -233.84637) (xy 217.77198 -233.84637) (xy 217.77198 -244.375432) (xy 232.529378 -244.375432)
			(xy 232.533449 -244.31981) (xy 232.545575 -244.265373) (xy 232.565498 -244.213282) (xy 232.592794 -244.164647)
			(xy 232.62688 -244.120504) (xy 232.667029 -244.081795) (xy 232.712387 -244.049344) (xy 232.761987 -244.023843)
			(xy 232.814771 -244.005836) (xy 232.869614 -243.995706) (xy 232.925348 -243.993669) (xy 232.980785 -243.999769)
			(xy 233.034742 -244.013875) (xy 233.086071 -244.035687) (xy 233.133677 -244.064741) (xy 233.176545 -244.100416)
			(xy 233.213762 -244.141953) (xy 233.244535 -244.188466) (xy 233.268207 -244.238963) (xy 233.284275 -244.29237)
			(xy 233.292395 -244.347546) (xy 233.292783 -244.368828) (xy 236.217966 -244.368828) (xy 236.222037 -244.313206)
			(xy 236.234163 -244.258769) (xy 236.254086 -244.206678) (xy 236.281382 -244.158043) (xy 236.315468 -244.1139)
			(xy 236.355617 -244.075191) (xy 236.400975 -244.04274) (xy 236.450575 -244.017239) (xy 236.503359 -243.999232)
			(xy 236.558202 -243.989102) (xy 236.613936 -243.987065) (xy 236.669373 -243.993165) (xy 236.72333 -244.007271)
			(xy 236.774659 -244.029083) (xy 236.822265 -244.058137) (xy 236.865133 -244.093812) (xy 236.90235 -244.135349)
			(xy 236.933123 -244.181862) (xy 236.956795 -244.232359) (xy 236.972863 -244.285766) (xy 236.980983 -244.340942)
			(xy 236.981492 -244.368828) (xy 236.980983 -244.396714) (xy 236.972863 -244.45189) (xy 236.956795 -244.505297)
			(xy 236.933123 -244.555794) (xy 236.90235 -244.602307) (xy 236.865133 -244.643844) (xy 236.822265 -244.679519)
			(xy 236.774659 -244.708573) (xy 236.72333 -244.730385) (xy 236.669373 -244.744491) (xy 236.613936 -244.750591)
			(xy 236.558202 -244.748554) (xy 236.503359 -244.738424) (xy 236.450575 -244.720417) (xy 236.400975 -244.694916)
			(xy 236.355617 -244.662465) (xy 236.315468 -244.623756) (xy 236.281382 -244.579613) (xy 236.254086 -244.530978)
			(xy 236.234163 -244.478887) (xy 236.222037 -244.42445) (xy 236.217966 -244.368828) (xy 233.292783 -244.368828)
			(xy 233.292904 -244.375432) (xy 233.292395 -244.403318) (xy 233.284275 -244.458494) (xy 233.268207 -244.511901)
			(xy 233.244535 -244.562398) (xy 233.213762 -244.608911) (xy 233.176545 -244.650448) (xy 233.133677 -244.686123)
			(xy 233.086071 -244.715177) (xy 233.034742 -244.736989) (xy 232.980785 -244.751095) (xy 232.925348 -244.757195)
			(xy 232.869614 -244.755158) (xy 232.814771 -244.745028) (xy 232.761987 -244.727021) (xy 232.712387 -244.70152)
			(xy 232.667029 -244.669069) (xy 232.62688 -244.63036) (xy 232.592794 -244.586217) (xy 232.565498 -244.537582)
			(xy 232.545575 -244.485491) (xy 232.533449 -244.431054) (xy 232.529378 -244.375432) (xy 217.77198 -244.375432)
			(xy 217.77198 -246.335158) (xy 227.726619 -246.335158) (xy 227.726619 -246.280642) (xy 227.734378 -246.226682)
			(xy 227.749738 -246.174375) (xy 227.772386 -246.124787) (xy 227.801861 -246.078928) (xy 227.837564 -246.03773)
			(xy 227.878766 -246.002033) (xy 227.92463 -245.972563) (xy 227.97422 -245.949921) (xy 228.026529 -245.934568)
			(xy 228.08049 -245.926816) (xy 228.107748 -245.926356) (xy 228.136409 -245.926886) (xy 228.193081 -245.935496)
			(xy 228.247829 -245.952485) (xy 228.29942 -245.97747) (xy 228.346694 -246.00989) (xy 228.388588 -246.049015)
			(xy 228.424159 -246.093966) (xy 228.452608 -246.143731) (xy 228.473294 -246.197192) (xy 228.485752 -246.253144)
			(xy 228.48824 -246.281702) (xy 228.489681 -246.296254) (xy 228.499842 -246.323664) (xy 228.517347 -246.347075)
			(xy 228.540765 -246.364573) (xy 228.568177 -246.374726) (xy 228.582728 -246.37619) (xy 228.611319 -246.37862)
			(xy 228.667336 -246.391048) (xy 228.72086 -246.411725) (xy 228.770684 -246.440184) (xy 228.815685 -246.475783)
			(xy 228.854848 -246.517719) (xy 228.887289 -246.565047) (xy 228.912277 -246.616699) (xy 228.929249 -246.671511)
			(xy 228.937821 -246.728246) (xy 228.938328 -246.756936) (xy 228.938328 -247.620536) (xy 228.938041 -247.637808)
			(xy 232.784902 -247.637808) (xy 232.788973 -247.582186) (xy 232.801099 -247.527749) (xy 232.821022 -247.475658)
			(xy 232.848318 -247.427023) (xy 232.882404 -247.38288) (xy 232.922553 -247.344171) (xy 232.967911 -247.31172)
			(xy 233.017511 -247.286219) (xy 233.070295 -247.268212) (xy 233.125138 -247.258082) (xy 233.180872 -247.256045)
			(xy 233.236309 -247.262145) (xy 233.290266 -247.276251) (xy 233.341595 -247.298063) (xy 233.389201 -247.327117)
			(xy 233.432069 -247.362792) (xy 233.469286 -247.404329) (xy 233.500059 -247.450842) (xy 233.523731 -247.501339)
			(xy 233.539799 -247.554746) (xy 233.547919 -247.609922) (xy 233.548428 -247.637808) (xy 233.547919 -247.665694)
			(xy 233.539799 -247.72087) (xy 233.523731 -247.774277) (xy 233.500059 -247.824774) (xy 233.469286 -247.871287)
			(xy 233.432069 -247.912824) (xy 233.389201 -247.948499) (xy 233.341595 -247.977553) (xy 233.290266 -247.999365)
			(xy 233.236309 -248.013471) (xy 233.180872 -248.019571) (xy 233.125138 -248.017534) (xy 233.070295 -248.007404)
			(xy 233.017511 -247.989397) (xy 232.967911 -247.963896) (xy 232.922553 -247.931445) (xy 232.882404 -247.892736)
			(xy 232.848318 -247.848593) (xy 232.821022 -247.799958) (xy 232.801099 -247.747867) (xy 232.788973 -247.69343)
			(xy 232.784902 -247.637808) (xy 228.938041 -247.637808) (xy 228.937851 -247.64922) (xy 228.929235 -247.705937)
			(xy 228.912231 -247.760728) (xy 228.887224 -247.812358) (xy 228.854775 -247.859668) (xy 228.815614 -247.901591)
			(xy 228.770623 -247.937185) (xy 228.720815 -247.965648) (xy 228.667308 -247.986341) (xy 228.611309 -247.998798)
			(xy 228.582728 -248.001282) (xy 228.568173 -248.002709) (xy 228.540758 -248.012868) (xy 228.517344 -248.030376)
			(xy 228.499846 -248.053798) (xy 228.493995 -248.069608) (xy 234.296202 -248.069608) (xy 234.300273 -248.013986)
			(xy 234.312399 -247.959549) (xy 234.332322 -247.907458) (xy 234.359618 -247.858823) (xy 234.393704 -247.81468)
			(xy 234.433853 -247.775971) (xy 234.479211 -247.74352) (xy 234.528811 -247.718019) (xy 234.581595 -247.700012)
			(xy 234.636438 -247.689882) (xy 234.692172 -247.687845) (xy 234.747609 -247.693945) (xy 234.801566 -247.708051)
			(xy 234.852895 -247.729863) (xy 234.900501 -247.758917) (xy 234.943369 -247.794592) (xy 234.980586 -247.836129)
			(xy 235.011359 -247.882642) (xy 235.035031 -247.933139) (xy 235.051099 -247.986546) (xy 235.059219 -248.041722)
			(xy 235.059728 -248.069608) (xy 235.059219 -248.097494) (xy 235.051099 -248.15267) (xy 235.035031 -248.206077)
			(xy 235.011359 -248.256574) (xy 234.980586 -248.303087) (xy 234.943369 -248.344624) (xy 234.900501 -248.380299)
			(xy 234.852895 -248.409353) (xy 234.801566 -248.431165) (xy 234.747609 -248.445271) (xy 234.692172 -248.451371)
			(xy 234.636438 -248.449334) (xy 234.581595 -248.439204) (xy 234.528811 -248.421197) (xy 234.479211 -248.395696)
			(xy 234.433853 -248.363245) (xy 234.393704 -248.324536) (xy 234.359618 -248.280393) (xy 234.332322 -248.231758)
			(xy 234.312399 -248.179667) (xy 234.300273 -248.12523) (xy 234.296202 -248.069608) (xy 228.493995 -248.069608)
			(xy 228.489699 -248.081217) (xy 228.48824 -248.09577) (xy 228.485763 -248.124334) (xy 228.473339 -248.180306)
			(xy 228.452675 -248.233786) (xy 228.424237 -248.28357) (xy 228.388667 -248.328535) (xy 228.346765 -248.367668)
			(xy 228.299478 -248.400087) (xy 228.247869 -248.425061) (xy 228.193103 -248.442028) (xy 228.136415 -248.450603)
			(xy 228.107748 -248.451116) (xy 228.080493 -248.45064) (xy 228.026538 -248.442889) (xy 227.974236 -248.427537)
			(xy 227.924651 -248.404898) (xy 227.878793 -248.375432) (xy 227.837595 -248.339739) (xy 227.801897 -248.298546)
			(xy 227.772425 -248.252691) (xy 227.74978 -248.203109) (xy 227.734422 -248.150808) (xy 227.726663 -248.096854)
			(xy 227.726663 -248.042346) (xy 227.734422 -247.988392) (xy 227.74978 -247.936091) (xy 227.772425 -247.886509)
			(xy 227.801897 -247.840654) (xy 227.837595 -247.799461) (xy 227.878793 -247.763768) (xy 227.924651 -247.734302)
			(xy 227.974236 -247.711663) (xy 228.026538 -247.696311) (xy 228.080493 -247.68856) (xy 228.107748 -247.6881)
			(xy 228.122734 -247.688354) (xy 228.133282 -247.688271) (xy 228.152911 -247.680603) (xy 228.16781 -247.665701)
			(xy 228.175473 -247.646071) (xy 228.175566 -247.635522) (xy 228.175312 -247.620536) (xy 228.175312 -246.756936)
			(xy 228.175566 -246.74195) (xy 228.175484 -246.731402) (xy 228.167813 -246.711776) (xy 228.152911 -246.696878)
			(xy 228.133283 -246.689213) (xy 228.122734 -246.689118) (xy 228.107748 -246.689372) (xy 228.08049 -246.688984)
			(xy 228.026529 -246.681232) (xy 227.97422 -246.665879) (xy 227.92463 -246.643237) (xy 227.878766 -246.613767)
			(xy 227.837564 -246.57807) (xy 227.801861 -246.536872) (xy 227.772386 -246.491013) (xy 227.749738 -246.441425)
			(xy 227.734378 -246.389118) (xy 227.726619 -246.335158) (xy 217.77198 -246.335158) (xy 217.77198 -249.765058)
			(xy 234.162344 -249.765058) (xy 234.166415 -249.709436) (xy 234.178541 -249.654999) (xy 234.198464 -249.602908)
			(xy 234.22576 -249.554273) (xy 234.259846 -249.51013) (xy 234.299995 -249.471421) (xy 234.345353 -249.43897)
			(xy 234.394953 -249.413469) (xy 234.447737 -249.395462) (xy 234.50258 -249.385332) (xy 234.558314 -249.383295)
			(xy 234.613751 -249.389395) (xy 234.667708 -249.403501) (xy 234.719037 -249.425313) (xy 234.766643 -249.454367)
			(xy 234.809511 -249.490042) (xy 234.846728 -249.531579) (xy 234.877501 -249.578092) (xy 234.901173 -249.628589)
			(xy 234.917241 -249.681996) (xy 234.925361 -249.737172) (xy 234.925736 -249.757692) (xy 235.897164 -249.757692)
			(xy 235.901235 -249.70207) (xy 235.913361 -249.647633) (xy 235.933284 -249.595542) (xy 235.96058 -249.546907)
			(xy 235.994666 -249.502764) (xy 236.034815 -249.464055) (xy 236.080173 -249.431604) (xy 236.129773 -249.406103)
			(xy 236.182557 -249.388096) (xy 236.2374 -249.377966) (xy 236.293134 -249.375929) (xy 236.348571 -249.382029)
			(xy 236.402528 -249.396135) (xy 236.453857 -249.417947) (xy 236.501463 -249.447001) (xy 236.544331 -249.482676)
			(xy 236.581548 -249.524213) (xy 236.612321 -249.570726) (xy 236.635993 -249.621223) (xy 236.652061 -249.67463)
			(xy 236.660181 -249.729806) (xy 236.66069 -249.757692) (xy 236.660181 -249.785578) (xy 236.652061 -249.840754)
			(xy 236.635993 -249.894161) (xy 236.612321 -249.944658) (xy 236.581548 -249.991171) (xy 236.544331 -250.032708)
			(xy 236.501463 -250.068383) (xy 236.453857 -250.097437) (xy 236.402528 -250.119249) (xy 236.348571 -250.133355)
			(xy 236.293134 -250.139455) (xy 236.2374 -250.137418) (xy 236.182557 -250.127288) (xy 236.129773 -250.109281)
			(xy 236.080173 -250.08378) (xy 236.034815 -250.051329) (xy 235.994666 -250.01262) (xy 235.96058 -249.968477)
			(xy 235.933284 -249.919842) (xy 235.913361 -249.867751) (xy 235.901235 -249.813314) (xy 235.897164 -249.757692)
			(xy 234.925736 -249.757692) (xy 234.92587 -249.765058) (xy 234.925361 -249.792944) (xy 234.917241 -249.84812)
			(xy 234.901173 -249.901527) (xy 234.877501 -249.952024) (xy 234.846728 -249.998537) (xy 234.809511 -250.040074)
			(xy 234.766643 -250.075749) (xy 234.719037 -250.104803) (xy 234.667708 -250.126615) (xy 234.613751 -250.140721)
			(xy 234.558314 -250.146821) (xy 234.50258 -250.144784) (xy 234.447737 -250.134654) (xy 234.394953 -250.116647)
			(xy 234.345353 -250.091146) (xy 234.299995 -250.058695) (xy 234.259846 -250.019986) (xy 234.22576 -249.975843)
			(xy 234.198464 -249.927208) (xy 234.178541 -249.875117) (xy 234.166415 -249.82068) (xy 234.162344 -249.765058)
			(xy 217.77198 -249.765058) (xy 217.77198 -250.441206) (xy 231.986834 -250.441206) (xy 231.990905 -250.385584)
			(xy 232.003031 -250.331147) (xy 232.022954 -250.279056) (xy 232.05025 -250.230421) (xy 232.084336 -250.186278)
			(xy 232.124485 -250.147569) (xy 232.169843 -250.115118) (xy 232.219443 -250.089617) (xy 232.272227 -250.07161)
			(xy 232.32707 -250.06148) (xy 232.382804 -250.059443) (xy 232.438241 -250.065543) (xy 232.492198 -250.079649)
			(xy 232.543527 -250.101461) (xy 232.591133 -250.130515) (xy 232.634001 -250.16619) (xy 232.671218 -250.207727)
			(xy 232.701991 -250.25424) (xy 232.725663 -250.304737) (xy 232.741731 -250.358144) (xy 232.749031 -250.407745)
			(xy 237.616485 -250.407745) (xy 237.616486 -250.353244) (xy 237.624243 -250.299298) (xy 237.639599 -250.247005)
			(xy 237.66224 -250.197429) (xy 237.691706 -250.15158) (xy 237.727397 -250.110391) (xy 237.768586 -250.074701)
			(xy 237.814436 -250.045236) (xy 237.864012 -250.022596) (xy 237.916306 -250.007241) (xy 237.970252 -249.999486)
			(xy 238.024753 -249.999486) (xy 238.0787 -250.007243) (xy 238.130993 -250.022598) (xy 238.180569 -250.045238)
			(xy 238.226418 -250.074704) (xy 238.267607 -250.110395) (xy 238.303297 -250.151584) (xy 238.332763 -250.197434)
			(xy 238.355403 -250.24701) (xy 238.370758 -250.299303) (xy 238.378514 -250.353249) (xy 238.379 -250.3805)
			(xy 238.378846 -250.396579) (xy 238.377449 -250.413351) (xy 239.323866 -250.413351) (xy 239.323866 -250.358849)
			(xy 239.331622 -250.304901) (xy 239.346977 -250.252606) (xy 239.369617 -250.203029) (xy 239.399082 -250.157178)
			(xy 239.434773 -250.115987) (xy 239.475962 -250.080294) (xy 239.521811 -250.050827) (xy 239.571388 -250.028184)
			(xy 239.623682 -250.012826) (xy 239.677629 -250.005067) (xy 239.70488 -250.00458) (xy 239.738622 -250.005328)
			(xy 239.805053 -250.017201) (xy 239.83696 -250.028202) (xy 239.850221 -250.032661) (xy 239.878104 -250.034857)
			(xy 239.905535 -250.0294) (xy 239.930455 -250.0167) (xy 239.950989 -249.99771) (xy 239.965596 -249.973859)
			(xy 239.973178 -249.946937) (xy 239.973612 -249.932952) (xy 239.973612 -247.019318) (xy 240.43259 -246.56034)
			(xy 244.72773 -246.56034) (xy 245.301008 -247.133618) (xy 245.301008 -251.875798) (xy 244.74297 -252.433836)
			(xy 240.34623 -252.433836) (xy 239.973612 -252.061218) (xy 239.973612 -250.839224) (xy 239.973194 -250.825249)
			(xy 239.965572 -250.798355) (xy 239.950948 -250.774534) (xy 239.930415 -250.755566) (xy 239.905511 -250.742873)
			(xy 239.878099 -250.737404) (xy 239.850231 -250.739568) (xy 239.83696 -250.743974) (xy 239.805061 -250.755004)
			(xy 239.738625 -250.76688) (xy 239.70488 -250.767596) (xy 239.677629 -250.767133) (xy 239.623682 -250.759374)
			(xy 239.571388 -250.744016) (xy 239.521811 -250.721373) (xy 239.475962 -250.691906) (xy 239.434773 -250.656213)
			(xy 239.399082 -250.615022) (xy 239.369617 -250.569171) (xy 239.346977 -250.519594) (xy 239.331622 -250.467299)
			(xy 239.323866 -250.413351) (xy 238.377449 -250.413351) (xy 238.376177 -250.428626) (xy 238.373666 -250.444508)
			(xy 238.371718 -250.458448) (xy 238.374735 -250.486424) (xy 238.385279 -250.512513) (xy 238.402549 -250.534728)
			(xy 238.425229 -250.551382) (xy 238.451597 -250.561208) (xy 238.479645 -250.563457) (xy 238.507241 -250.55796)
			(xy 238.51997 -250.55195) (xy 238.54704 -250.538714) (xy 238.604321 -250.520021) (xy 238.663832 -250.510585)
			(xy 238.69396 -250.51004) (xy 238.721214 -250.510435) (xy 238.775168 -250.518187) (xy 238.82747 -250.533538)
			(xy 238.877054 -250.556176) (xy 238.922912 -250.58564) (xy 238.964111 -250.621331) (xy 238.99981 -250.662521)
			(xy 239.029284 -250.708373) (xy 239.051933 -250.757953) (xy 239.067296 -250.810251) (xy 239.075059 -250.864203)
			(xy 239.075065 -250.918711) (xy 239.067314 -250.972665) (xy 239.051963 -251.024967) (xy 239.029325 -251.074552)
			(xy 238.999861 -251.12041) (xy 238.964171 -251.161609) (xy 238.922981 -251.197309) (xy 238.877129 -251.226783)
			(xy 238.82755 -251.249432) (xy 238.775251 -251.264795) (xy 238.721299 -251.272559) (xy 238.666791 -251.272565)
			(xy 238.612837 -251.264815) (xy 238.560535 -251.249464) (xy 238.51095 -251.226827) (xy 238.465092 -251.197363)
			(xy 238.423893 -251.161673) (xy 238.388193 -251.120483) (xy 238.358718 -251.074632) (xy 238.336069 -251.025052)
			(xy 238.320705 -250.972754) (xy 238.312941 -250.918802) (xy 238.312452 -250.891548) (xy 238.3126 -250.875469)
			(xy 238.315274 -250.843422) (xy 238.317786 -250.82754) (xy 238.319706 -250.8136) (xy 238.316678 -250.785635)
			(xy 238.30613 -250.759559) (xy 238.288865 -250.737353) (xy 238.266193 -250.720704) (xy 238.239837 -250.710876)
			(xy 238.2118 -250.708617) (xy 238.18421 -250.714098) (xy 238.171482 -250.720098) (xy 238.144418 -250.733347)
			(xy 238.087134 -250.752037) (xy 238.027621 -250.761467) (xy 237.997492 -250.762008) (xy 237.970241 -250.761514)
			(xy 237.916295 -250.753756) (xy 237.864002 -250.7384) (xy 237.814427 -250.715759) (xy 237.768578 -250.686293)
			(xy 237.727389 -250.650601) (xy 237.691699 -250.609411) (xy 237.662235 -250.563562) (xy 237.639595 -250.513985)
			(xy 237.624241 -250.461692) (xy 237.616485 -250.407745) (xy 232.749031 -250.407745) (xy 232.749851 -250.41332)
			(xy 232.75036 -250.441206) (xy 232.749851 -250.469092) (xy 232.741731 -250.524268) (xy 232.725663 -250.577675)
			(xy 232.701991 -250.628172) (xy 232.671218 -250.674685) (xy 232.634001 -250.716222) (xy 232.591133 -250.751897)
			(xy 232.543527 -250.780951) (xy 232.492198 -250.802763) (xy 232.438241 -250.816869) (xy 232.382804 -250.822969)
			(xy 232.32707 -250.820932) (xy 232.272227 -250.810802) (xy 232.219443 -250.792795) (xy 232.169843 -250.767294)
			(xy 232.124485 -250.734843) (xy 232.084336 -250.696134) (xy 232.05025 -250.651991) (xy 232.022954 -250.603356)
			(xy 232.003031 -250.551265) (xy 231.990905 -250.496828) (xy 231.986834 -250.441206) (xy 217.77198 -250.441206)
			(xy 217.77198 -251.517658) (xy 234.14177 -251.517658) (xy 234.145841 -251.462036) (xy 234.157967 -251.407599)
			(xy 234.17789 -251.355508) (xy 234.205186 -251.306873) (xy 234.239272 -251.26273) (xy 234.279421 -251.224021)
			(xy 234.324779 -251.19157) (xy 234.374379 -251.166069) (xy 234.427163 -251.148062) (xy 234.482006 -251.137932)
			(xy 234.53774 -251.135895) (xy 234.593177 -251.141995) (xy 234.647134 -251.156101) (xy 234.698463 -251.177913)
			(xy 234.746069 -251.206967) (xy 234.788937 -251.242642) (xy 234.826154 -251.284179) (xy 234.856927 -251.330692)
			(xy 234.880599 -251.381189) (xy 234.896667 -251.434596) (xy 234.904787 -251.489772) (xy 234.905296 -251.517658)
			(xy 234.90525 -251.520198) (xy 235.907578 -251.520198) (xy 235.911649 -251.464576) (xy 235.923775 -251.410139)
			(xy 235.943698 -251.358048) (xy 235.970994 -251.309413) (xy 236.00508 -251.26527) (xy 236.045229 -251.226561)
			(xy 236.090587 -251.19411) (xy 236.140187 -251.168609) (xy 236.192971 -251.150602) (xy 236.247814 -251.140472)
			(xy 236.303548 -251.138435) (xy 236.358985 -251.144535) (xy 236.412942 -251.158641) (xy 236.464271 -251.180453)
			(xy 236.511877 -251.209507) (xy 236.554745 -251.245182) (xy 236.591962 -251.286719) (xy 236.622735 -251.333232)
			(xy 236.646407 -251.383729) (xy 236.662475 -251.437136) (xy 236.670595 -251.492312) (xy 236.671104 -251.520198)
			(xy 236.670595 -251.548084) (xy 236.662475 -251.60326) (xy 236.646407 -251.656667) (xy 236.622735 -251.707164)
			(xy 236.591962 -251.753677) (xy 236.554745 -251.795214) (xy 236.511877 -251.830889) (xy 236.464271 -251.859943)
			(xy 236.412942 -251.881755) (xy 236.358985 -251.895861) (xy 236.303548 -251.901961) (xy 236.247814 -251.899924)
			(xy 236.192971 -251.889794) (xy 236.140187 -251.871787) (xy 236.090587 -251.846286) (xy 236.045229 -251.813835)
			(xy 236.00508 -251.775126) (xy 235.970994 -251.730983) (xy 235.943698 -251.682348) (xy 235.923775 -251.630257)
			(xy 235.911649 -251.57582) (xy 235.907578 -251.520198) (xy 234.90525 -251.520198) (xy 234.904787 -251.545544)
			(xy 234.896667 -251.60072) (xy 234.880599 -251.654127) (xy 234.856927 -251.704624) (xy 234.826154 -251.751137)
			(xy 234.788937 -251.792674) (xy 234.746069 -251.828349) (xy 234.698463 -251.857403) (xy 234.647134 -251.879215)
			(xy 234.593177 -251.893321) (xy 234.53774 -251.899421) (xy 234.482006 -251.897384) (xy 234.427163 -251.887254)
			(xy 234.374379 -251.869247) (xy 234.324779 -251.843746) (xy 234.279421 -251.811295) (xy 234.239272 -251.772586)
			(xy 234.205186 -251.728443) (xy 234.17789 -251.679808) (xy 234.157967 -251.627717) (xy 234.145841 -251.57328)
			(xy 234.14177 -251.517658) (xy 217.77198 -251.517658) (xy 217.77198 -253.200408) (xy 234.425742 -253.200408)
			(xy 234.429813 -253.144786) (xy 234.441939 -253.090349) (xy 234.461862 -253.038258) (xy 234.489158 -252.989623)
			(xy 234.523244 -252.94548) (xy 234.563393 -252.906771) (xy 234.608751 -252.87432) (xy 234.658351 -252.848819)
			(xy 234.711135 -252.830812) (xy 234.765978 -252.820682) (xy 234.821712 -252.818645) (xy 234.877149 -252.824745)
			(xy 234.931106 -252.838851) (xy 234.982435 -252.860663) (xy 235.030041 -252.889717) (xy 235.072909 -252.925392)
			(xy 235.110126 -252.966929) (xy 235.140899 -253.013442) (xy 235.164571 -253.063939) (xy 235.180639 -253.117346)
			(xy 235.188759 -253.172522) (xy 235.189083 -253.190248) (xy 236.424722 -253.190248) (xy 236.428793 -253.134626)
			(xy 236.440919 -253.080189) (xy 236.460842 -253.028098) (xy 236.488138 -252.979463) (xy 236.522224 -252.93532)
			(xy 236.562373 -252.896611) (xy 236.607731 -252.86416) (xy 236.657331 -252.838659) (xy 236.710115 -252.820652)
			(xy 236.764958 -252.810522) (xy 236.820692 -252.808485) (xy 236.876129 -252.814585) (xy 236.930086 -252.828691)
			(xy 236.981415 -252.850503) (xy 237.029021 -252.879557) (xy 237.071889 -252.915232) (xy 237.109106 -252.956769)
			(xy 237.139879 -253.003282) (xy 237.163551 -253.053779) (xy 237.179619 -253.107186) (xy 237.187739 -253.162362)
			(xy 237.188248 -253.190248) (xy 237.187739 -253.218134) (xy 237.179619 -253.27331) (xy 237.163551 -253.326717)
			(xy 237.146081 -253.363984) (xy 244.418102 -253.363984) (xy 244.422173 -253.308362) (xy 244.434299 -253.253925)
			(xy 244.454222 -253.201834) (xy 244.481518 -253.153199) (xy 244.515604 -253.109056) (xy 244.555753 -253.070347)
			(xy 244.601111 -253.037896) (xy 244.650711 -253.012395) (xy 244.703495 -252.994388) (xy 244.758338 -252.984258)
			(xy 244.814072 -252.982221) (xy 244.869509 -252.988321) (xy 244.923466 -253.002427) (xy 244.974795 -253.024239)
			(xy 245.022401 -253.053293) (xy 245.065269 -253.088968) (xy 245.102486 -253.130505) (xy 245.133259 -253.177018)
			(xy 245.156931 -253.227515) (xy 245.172999 -253.280922) (xy 245.181119 -253.336098) (xy 245.181628 -253.363984)
			(xy 245.181119 -253.39187) (xy 245.172999 -253.447046) (xy 245.156931 -253.500453) (xy 245.133259 -253.55095)
			(xy 245.102486 -253.597463) (xy 245.065269 -253.639) (xy 245.022401 -253.674675) (xy 244.974795 -253.703729)
			(xy 244.923466 -253.725541) (xy 244.869509 -253.739647) (xy 244.814072 -253.745747) (xy 244.758338 -253.74371)
			(xy 244.703495 -253.73358) (xy 244.650711 -253.715573) (xy 244.601111 -253.690072) (xy 244.555753 -253.657621)
			(xy 244.515604 -253.618912) (xy 244.481518 -253.574769) (xy 244.454222 -253.526134) (xy 244.434299 -253.474043)
			(xy 244.422173 -253.419606) (xy 244.418102 -253.363984) (xy 237.146081 -253.363984) (xy 237.139879 -253.377214)
			(xy 237.109106 -253.423727) (xy 237.071889 -253.465264) (xy 237.029021 -253.500939) (xy 236.981415 -253.529993)
			(xy 236.930086 -253.551805) (xy 236.876129 -253.565911) (xy 236.820692 -253.572011) (xy 236.764958 -253.569974)
			(xy 236.710115 -253.559844) (xy 236.657331 -253.541837) (xy 236.607731 -253.516336) (xy 236.562373 -253.483885)
			(xy 236.522224 -253.445176) (xy 236.488138 -253.401033) (xy 236.460842 -253.352398) (xy 236.440919 -253.300307)
			(xy 236.428793 -253.24587) (xy 236.424722 -253.190248) (xy 235.189083 -253.190248) (xy 235.189268 -253.200408)
			(xy 235.188759 -253.228294) (xy 235.180639 -253.28347) (xy 235.164571 -253.336877) (xy 235.140899 -253.387374)
			(xy 235.110126 -253.433887) (xy 235.072909 -253.475424) (xy 235.030041 -253.511099) (xy 234.982435 -253.540153)
			(xy 234.931106 -253.561965) (xy 234.877149 -253.576071) (xy 234.821712 -253.582171) (xy 234.765978 -253.580134)
			(xy 234.711135 -253.570004) (xy 234.658351 -253.551997) (xy 234.608751 -253.526496) (xy 234.563393 -253.494045)
			(xy 234.523244 -253.455336) (xy 234.489158 -253.411193) (xy 234.461862 -253.362558) (xy 234.441939 -253.310467)
			(xy 234.429813 -253.25603) (xy 234.425742 -253.200408) (xy 217.77198 -253.200408) (xy 217.77198 -256.523998)
			(xy 232.972862 -256.523998) (xy 232.976933 -256.468376) (xy 232.989059 -256.413939) (xy 233.008982 -256.361848)
			(xy 233.036278 -256.313213) (xy 233.070364 -256.26907) (xy 233.110513 -256.230361) (xy 233.155871 -256.19791)
			(xy 233.205471 -256.172409) (xy 233.258255 -256.154402) (xy 233.313098 -256.144272) (xy 233.368832 -256.142235)
			(xy 233.424269 -256.148335) (xy 233.478226 -256.162441) (xy 233.529555 -256.184253) (xy 233.577161 -256.213307)
			(xy 233.620029 -256.248982) (xy 233.657246 -256.290519) (xy 233.688019 -256.337032) (xy 233.711691 -256.387529)
			(xy 233.727759 -256.440936) (xy 233.735879 -256.496112) (xy 233.736388 -256.523998) (xy 233.735879 -256.551884)
			(xy 233.727759 -256.60706) (xy 233.711691 -256.660467) (xy 233.688019 -256.710964) (xy 233.657246 -256.757477)
			(xy 233.620029 -256.799014) (xy 233.577161 -256.834689) (xy 233.529555 -256.863743) (xy 233.478226 -256.885555)
			(xy 233.424269 -256.899661) (xy 233.368832 -256.905761) (xy 233.313098 -256.903724) (xy 233.258255 -256.893594)
			(xy 233.205471 -256.875587) (xy 233.155871 -256.850086) (xy 233.110513 -256.817635) (xy 233.070364 -256.778926)
			(xy 233.036278 -256.734783) (xy 233.008982 -256.686148) (xy 232.989059 -256.634057) (xy 232.976933 -256.57962)
			(xy 232.972862 -256.523998) (xy 217.77198 -256.523998) (xy 217.77198 -257.167123) (xy 235.132873 -257.167123)
			(xy 235.132877 -257.112619) (xy 235.140638 -257.058671) (xy 235.155998 -257.006376) (xy 235.178644 -256.956799)
			(xy 235.208115 -256.910951) (xy 235.243811 -256.869763) (xy 235.285005 -256.834074) (xy 235.330859 -256.804611)
			(xy 235.38044 -256.781974) (xy 235.432737 -256.766624) (xy 235.486687 -256.758873) (xy 235.54119 -256.758878)
			(xy 235.595139 -256.76664) (xy 235.647433 -256.782001) (xy 235.697009 -256.804648) (xy 235.742857 -256.83412)
			(xy 235.784044 -256.869817) (xy 235.819732 -256.911013) (xy 235.849193 -256.956867) (xy 235.871829 -257.006448)
			(xy 235.887178 -257.058746) (xy 235.894928 -257.112696) (xy 235.895388 -257.139948) (xy 235.895074 -257.160433)
			(xy 235.890623 -257.201161) (xy 235.886498 -257.221228) (xy 235.884006 -257.23453) (xy 235.885407 -257.261549)
			(xy 235.893853 -257.287252) (xy 235.908751 -257.309836) (xy 235.929057 -257.327715) (xy 235.953345 -257.339635)
			(xy 235.979911 -257.344759) (xy 235.993432 -257.344164) (xy 236.022134 -257.343148) (xy 236.050328 -257.344164)
			(xy 236.063829 -257.344717) (xy 236.09034 -257.339544) (xy 236.114566 -257.327599) (xy 236.134813 -257.30972)
			(xy 236.149663 -257.287157) (xy 236.158076 -257.26149) (xy 236.159465 -257.234515) (xy 236.157008 -257.221228)
			(xy 236.152943 -257.201155) (xy 236.148615 -257.160427) (xy 236.148372 -257.139948) (xy 236.148804 -257.112691)
			(xy 236.156555 -257.05873) (xy 236.171908 -257.006422) (xy 236.194549 -256.956831) (xy 236.224017 -256.910967)
			(xy 236.259712 -256.869764) (xy 236.300908 -256.834061) (xy 236.346766 -256.804584) (xy 236.396353 -256.781934)
			(xy 236.448658 -256.766571) (xy 236.502617 -256.758809) (xy 236.557132 -256.758805) (xy 236.611092 -256.76656)
			(xy 236.6634 -256.781916) (xy 236.712989 -256.80456) (xy 236.758851 -256.83403) (xy 236.800052 -256.869728)
			(xy 236.835753 -256.910927) (xy 236.865227 -256.956786) (xy 236.887874 -257.006374) (xy 236.903234 -257.05868)
			(xy 236.910993 -257.11264) (xy 236.910993 -257.167155) (xy 236.903235 -257.221114) (xy 236.887876 -257.273421)
			(xy 236.86523 -257.323009) (xy 236.835756 -257.368869) (xy 236.800056 -257.410068) (xy 236.758855 -257.445766)
			(xy 236.712994 -257.475238) (xy 236.663405 -257.497882) (xy 236.611098 -257.513239) (xy 236.557137 -257.520994)
			(xy 236.52988 -257.521456) (xy 236.501686 -257.52044) (xy 236.488185 -257.519895) (xy 236.461674 -257.525065)
			(xy 236.437446 -257.537008) (xy 236.417199 -257.554886) (xy 236.402349 -257.577448) (xy 236.393936 -257.603115)
			(xy 236.392548 -257.63009) (xy 236.395006 -257.643376) (xy 236.399072 -257.663449) (xy 236.403399 -257.704177)
			(xy 236.403642 -257.724656) (xy 236.403156 -257.751907) (xy 236.3954 -257.805855) (xy 236.380045 -257.85815)
			(xy 236.357403 -257.907727) (xy 236.327937 -257.953577) (xy 236.292246 -257.994768) (xy 236.251055 -258.030459)
			(xy 236.205205 -258.059925) (xy 236.155628 -258.082567) (xy 236.103333 -258.097922) (xy 236.049385 -258.105678)
			(xy 235.994883 -258.105678) (xy 235.940935 -258.097922) (xy 235.88864 -258.082567) (xy 235.839063 -258.059925)
			(xy 235.793213 -258.030459) (xy 235.752022 -257.994768) (xy 235.716331 -257.953577) (xy 235.686865 -257.907727)
			(xy 235.664223 -257.85815) (xy 235.648868 -257.805855) (xy 235.641112 -257.751907) (xy 235.640626 -257.724656)
			(xy 235.64094 -257.704171) (xy 235.645391 -257.663443) (xy 235.649516 -257.643376) (xy 235.651988 -257.630072)
			(xy 235.650589 -257.603056) (xy 235.642145 -257.577355) (xy 235.62725 -257.554773) (xy 235.606948 -257.536894)
			(xy 235.582664 -257.524973) (xy 235.556102 -257.519847) (xy 235.542582 -257.52044) (xy 235.51388 -257.521456)
			(xy 235.486628 -257.520923) (xy 235.43268 -257.513164) (xy 235.380385 -257.497805) (xy 235.330808 -257.475161)
			(xy 235.284958 -257.445691) (xy 235.243769 -257.409996) (xy 235.20808 -257.368802) (xy 235.178616 -257.322949)
			(xy 235.155978 -257.273369) (xy 235.140626 -257.221072) (xy 235.132873 -257.167123) (xy 217.77198 -257.167123)
			(xy 217.77198 -265.491468) (xy 230.191562 -265.491468) (xy 230.195633 -265.435846) (xy 230.207759 -265.381409)
			(xy 230.227682 -265.329318) (xy 230.254978 -265.280683) (xy 230.289064 -265.23654) (xy 230.329213 -265.197831)
			(xy 230.374571 -265.16538) (xy 230.424171 -265.139879) (xy 230.476955 -265.121872) (xy 230.531798 -265.111742)
			(xy 230.587532 -265.109705) (xy 230.642969 -265.115805) (xy 230.696926 -265.129911) (xy 230.748255 -265.151723)
			(xy 230.795861 -265.180777) (xy 230.838729 -265.216452) (xy 230.875946 -265.257989) (xy 230.906719 -265.304502)
			(xy 230.930391 -265.354999) (xy 230.946459 -265.408406) (xy 230.954579 -265.463582) (xy 230.955088 -265.491468)
			(xy 230.954579 -265.519354) (xy 230.946459 -265.57453) (xy 230.930391 -265.627937) (xy 230.906719 -265.678434)
			(xy 230.875946 -265.724947) (xy 230.838729 -265.766484) (xy 230.795861 -265.802159) (xy 230.748255 -265.831213)
			(xy 230.696926 -265.853025) (xy 230.642969 -265.867131) (xy 230.587532 -265.873231) (xy 230.531798 -265.871194)
			(xy 230.476955 -265.861064) (xy 230.424171 -265.843057) (xy 230.374571 -265.817556) (xy 230.329213 -265.785105)
			(xy 230.289064 -265.746396) (xy 230.254978 -265.702253) (xy 230.227682 -265.653618) (xy 230.207759 -265.601527)
			(xy 230.195633 -265.54709) (xy 230.191562 -265.491468) (xy 217.77198 -265.491468) (xy 217.77198 -272.499836)
			(xy 231.378004 -272.499836) (xy 231.382018 -272.294152) (xy 231.394054 -272.088782) (xy 231.414093 -271.884038)
			(xy 231.442106 -271.680231) (xy 231.478049 -271.477672) (xy 231.521868 -271.27667) (xy 231.573495 -271.077531)
			(xy 231.632853 -270.880558) (xy 231.699851 -270.68605) (xy 231.774387 -270.494305) (xy 231.856347 -270.305614)
			(xy 231.945607 -270.120264) (xy 232.04203 -269.938538) (xy 232.145471 -269.760712) (xy 232.25577 -269.587058)
			(xy 232.372761 -269.417839) (xy 232.496265 -269.253313) (xy 232.626094 -269.093732) (xy 232.762051 -268.939337)
			(xy 232.903928 -268.790365) (xy 233.051509 -268.647041) (xy 233.20457 -268.509585) (xy 233.362877 -268.378205)
			(xy 233.52619 -268.253102) (xy 233.694259 -268.134465) (xy 233.866829 -268.022477) (xy 234.043637 -267.917306)
			(xy 234.224414 -267.819115) (xy 234.408884 -267.728051) (xy 234.596766 -267.644254) (xy 234.787776 -267.567851)
			(xy 234.98162 -267.498958) (xy 235.178005 -267.437681) (xy 235.376631 -267.384113) (xy 235.577196 -267.338336)
			(xy 235.779394 -267.300418) (xy 235.982918 -267.270419) (xy 236.187457 -267.248382) (xy 236.3927 -267.234343)
			(xy 236.598335 -267.228323) (xy 236.804048 -267.23033) (xy 237.009526 -267.240362) (xy 237.214456 -267.258403)
			(xy 237.418526 -267.284426) (xy 237.621426 -267.318391) (xy 237.822846 -267.360246) (xy 238.022479 -267.409928)
			(xy 238.220022 -267.467362) (xy 238.415174 -267.532459) (xy 238.607638 -267.60512) (xy 238.79712 -267.685236)
			(xy 238.983331 -267.772683) (xy 239.16599 -267.867329) (xy 239.344816 -267.969029) (xy 239.519538 -268.077629)
			(xy 239.689891 -268.192964) (xy 239.855613 -268.314857) (xy 240.016454 -268.443123) (xy 240.172167 -268.577566)
			(xy 240.322517 -268.717983) (xy 240.467274 -268.864159) (xy 240.606217 -269.015871) (xy 240.739135 -269.172889)
			(xy 240.865826 -269.334974) (xy 240.986096 -269.501877) (xy 241.099763 -269.673347) (xy 241.206653 -269.84912)
			(xy 241.306604 -270.02893) (xy 241.399463 -270.212503) (xy 241.48509 -270.399559) (xy 241.563352 -270.589814)
			(xy 241.634133 -270.782977) (xy 241.697323 -270.978755) (xy 241.752826 -271.176849) (xy 241.800558 -271.376958)
			(xy 241.840447 -271.578776) (xy 241.872431 -271.781998) (xy 241.896461 -271.986312) (xy 241.912502 -272.191408)
			(xy 241.920528 -272.396975) (xy 241.92103 -272.499836) (xy 241.920528 -272.602697) (xy 241.912502 -272.808264)
			(xy 241.896461 -273.01336) (xy 241.872431 -273.217674) (xy 241.840447 -273.420896) (xy 241.800558 -273.622714)
			(xy 241.752826 -273.822823) (xy 241.697323 -274.020917) (xy 241.634133 -274.216695) (xy 241.563352 -274.409858)
			(xy 241.48509 -274.600113) (xy 241.399463 -274.787169) (xy 241.306604 -274.970742) (xy 241.206653 -275.150552)
			(xy 241.099763 -275.326325) (xy 240.986096 -275.497795) (xy 240.865826 -275.664698) (xy 240.739135 -275.826783)
			(xy 240.606217 -275.983801) (xy 240.467274 -276.135513) (xy 240.322517 -276.281689) (xy 240.172167 -276.422106)
			(xy 240.016454 -276.556549) (xy 239.855613 -276.684815) (xy 239.689891 -276.806708) (xy 239.519538 -276.922043)
			(xy 239.344816 -277.030643) (xy 239.16599 -277.132343) (xy 238.983331 -277.226989) (xy 238.79712 -277.314436)
			(xy 238.607638 -277.394552) (xy 238.415174 -277.467213) (xy 238.220022 -277.53231) (xy 238.022479 -277.589744)
			(xy 237.822846 -277.639426) (xy 237.621426 -277.681281) (xy 237.418526 -277.715246) (xy 237.214456 -277.741269)
			(xy 237.009526 -277.75931) (xy 236.804048 -277.769342) (xy 236.598335 -277.771349) (xy 236.3927 -277.765329)
			(xy 236.187457 -277.75129) (xy 235.982918 -277.729253) (xy 235.779394 -277.699254) (xy 235.577196 -277.661336)
			(xy 235.376631 -277.615559) (xy 235.178005 -277.561991) (xy 234.98162 -277.500714) (xy 234.787776 -277.431821)
			(xy 234.596766 -277.355418) (xy 234.408884 -277.271621) (xy 234.224414 -277.180557) (xy 234.043637 -277.082366)
			(xy 233.866829 -276.977195) (xy 233.694259 -276.865207) (xy 233.52619 -276.74657) (xy 233.362877 -276.621467)
			(xy 233.20457 -276.490087) (xy 233.051509 -276.352631) (xy 232.903928 -276.209307) (xy 232.762051 -276.060335)
			(xy 232.626094 -275.90594) (xy 232.496265 -275.746359) (xy 232.372761 -275.581833) (xy 232.25577 -275.412614)
			(xy 232.145471 -275.23896) (xy 232.04203 -275.061134) (xy 231.945607 -274.879408) (xy 231.856347 -274.694058)
			(xy 231.774387 -274.505367) (xy 231.699851 -274.313622) (xy 231.632853 -274.119114) (xy 231.573495 -273.922141)
			(xy 231.521868 -273.723002) (xy 231.478049 -273.522) (xy 231.442106 -273.319441) (xy 231.414093 -273.115634)
			(xy 231.394054 -272.91089) (xy 231.382018 -272.70552) (xy 231.378004 -272.499836) (xy 217.77198 -272.499836)
			(xy 217.77198 -312.882534) (xy 216.011273 -314.643241) (xy 216.469204 -314.643241) (xy 216.469204 -314.589943)
			(xy 216.477147 -314.537239) (xy 216.492857 -314.486309) (xy 216.515983 -314.438288) (xy 216.546007 -314.394251)
			(xy 216.582259 -314.35518) (xy 216.62393 -314.321949) (xy 216.670088 -314.2953) (xy 216.719702 -314.275828)
			(xy 216.771664 -314.263968) (xy 216.824814 -314.259985) (xy 216.877964 -314.263968) (xy 216.929926 -314.275828)
			(xy 216.97954 -314.2953) (xy 217.025698 -314.321949) (xy 217.067369 -314.35518) (xy 217.103621 -314.394251)
			(xy 217.133645 -314.438288) (xy 217.156771 -314.486309) (xy 217.172481 -314.537239) (xy 217.180424 -314.589943)
			(xy 217.180922 -314.616592) (xy 217.180424 -314.643241) (xy 217.172481 -314.695945) (xy 217.156771 -314.746875)
			(xy 217.133645 -314.794896) (xy 217.103621 -314.838933) (xy 217.067369 -314.878004) (xy 217.025698 -314.911235)
			(xy 216.97954 -314.937884) (xy 216.929926 -314.957356) (xy 216.877964 -314.969216) (xy 216.824814 -314.9732)
			(xy 216.771664 -314.969216) (xy 216.719702 -314.957356) (xy 216.670088 -314.937884) (xy 216.62393 -314.911235)
			(xy 216.582259 -314.878004) (xy 216.546007 -314.838933) (xy 216.515983 -314.794896) (xy 216.492857 -314.746875)
			(xy 216.477147 -314.695945) (xy 216.469204 -314.643241) (xy 216.011273 -314.643241) (xy 214.793068 -315.861446)
			(xy 214.782768 -315.872505) (xy 214.76857 -315.899166) (xy 214.762794 -315.928815) (xy 214.765946 -315.958856)
			(xy 214.777749 -315.98666) (xy 214.79717 -316.009795) (xy 214.809578 -316.018418) (xy 214.830493 -316.03259)
			(xy 214.86848 -316.065896) (xy 214.901381 -316.104234) (xy 214.928537 -316.146836) (xy 214.949402 -316.192847)
			(xy 214.963558 -316.241344) (xy 214.970721 -316.291354) (xy 214.971122 -316.316614) (xy 214.970669 -316.34263)
			(xy 214.970576 -316.343263) (xy 216.469204 -316.343263) (xy 216.469204 -316.289965) (xy 216.477147 -316.237261)
			(xy 216.492857 -316.186331) (xy 216.515983 -316.13831) (xy 216.546007 -316.094273) (xy 216.582259 -316.055202)
			(xy 216.62393 -316.021971) (xy 216.670088 -315.995322) (xy 216.719702 -315.97585) (xy 216.771664 -315.96399)
			(xy 216.824814 -315.960007) (xy 216.877964 -315.96399) (xy 216.929926 -315.97585) (xy 216.97954 -315.995322)
			(xy 217.025698 -316.021971) (xy 217.067369 -316.055202) (xy 217.103621 -316.094273) (xy 217.133645 -316.13831)
			(xy 217.156771 -316.186331) (xy 217.172481 -316.237261) (xy 217.180424 -316.289965) (xy 217.180922 -316.316614)
			(xy 217.180424 -316.343263) (xy 217.172481 -316.395967) (xy 217.156771 -316.446897) (xy 217.133645 -316.494918)
			(xy 217.103621 -316.538955) (xy 217.067369 -316.578026) (xy 217.025698 -316.611257) (xy 216.97954 -316.637906)
			(xy 216.929926 -316.657378) (xy 216.877964 -316.669238) (xy 216.824814 -316.673222) (xy 216.771664 -316.669238)
			(xy 216.719702 -316.657378) (xy 216.670088 -316.637906) (xy 216.62393 -316.611257) (xy 216.582259 -316.578026)
			(xy 216.546007 -316.538955) (xy 216.515983 -316.494918) (xy 216.492857 -316.446897) (xy 216.477147 -316.395967)
			(xy 216.469204 -316.343263) (xy 214.970576 -316.343263) (xy 214.963089 -316.394107) (xy 214.948093 -316.443931)
			(xy 214.926001 -316.491041) (xy 214.897284 -316.53443) (xy 214.862553 -316.573175) (xy 214.842852 -316.590172)
			(xy 214.831538 -316.600353) (xy 214.814958 -316.625858) (xy 214.806618 -316.655112) (xy 214.807255 -316.685525)
			(xy 214.816814 -316.714404) (xy 214.834448 -316.739191) (xy 214.846154 -316.748922) (xy 214.867409 -316.765893)
			(xy 214.905004 -316.805195) (xy 214.936185 -316.849757) (xy 214.960226 -316.898544) (xy 214.976567 -316.950419)
			(xy 214.984829 -317.004176) (xy 214.985346 -317.03137) (xy 214.984848 -317.058019) (xy 214.976905 -317.110723)
			(xy 214.961195 -317.161653) (xy 214.945906 -317.193401) (xy 254.620004 -317.193401) (xy 254.620004 -317.140103)
			(xy 254.627947 -317.087399) (xy 254.643657 -317.036469) (xy 254.666783 -316.988448) (xy 254.696807 -316.944411)
			(xy 254.733059 -316.90534) (xy 254.77473 -316.872109) (xy 254.820888 -316.84546) (xy 254.870502 -316.825988)
			(xy 254.922464 -316.814128) (xy 254.975614 -316.810145) (xy 255.028764 -316.814128) (xy 255.080726 -316.825988)
			(xy 255.13034 -316.84546) (xy 255.176498 -316.872109) (xy 255.218169 -316.90534) (xy 255.254421 -316.944411)
			(xy 255.284445 -316.988448) (xy 255.307571 -317.036469) (xy 255.323281 -317.087399) (xy 255.331224 -317.140103)
			(xy 255.331722 -317.166752) (xy 255.331224 -317.193401) (xy 255.323281 -317.246105) (xy 255.307571 -317.297035)
			(xy 255.284445 -317.345056) (xy 255.254421 -317.389093) (xy 255.218169 -317.428164) (xy 255.176498 -317.461395)
			(xy 255.13034 -317.488044) (xy 255.080726 -317.507516) (xy 255.028764 -317.519376) (xy 254.975614 -317.52336)
			(xy 254.922464 -317.519376) (xy 254.870502 -317.507516) (xy 254.820888 -317.488044) (xy 254.77473 -317.461395)
			(xy 254.733059 -317.428164) (xy 254.696807 -317.389093) (xy 254.666783 -317.345056) (xy 254.643657 -317.297035)
			(xy 254.627947 -317.246105) (xy 254.620004 -317.193401) (xy 214.945906 -317.193401) (xy 214.938069 -317.209674)
			(xy 214.908045 -317.253711) (xy 214.871793 -317.292782) (xy 214.830122 -317.326013) (xy 214.783964 -317.352662)
			(xy 214.73435 -317.372134) (xy 214.682388 -317.383994) (xy 214.629238 -317.387978) (xy 214.576088 -317.383994)
			(xy 214.524126 -317.372134) (xy 214.474512 -317.352662) (xy 214.428354 -317.326013) (xy 214.386683 -317.292782)
			(xy 214.350431 -317.253711) (xy 214.320407 -317.209674) (xy 214.297281 -317.161653) (xy 214.281571 -317.110723)
			(xy 214.273628 -317.058019) (xy 214.27313 -317.03137) (xy 214.273584 -317.005354) (xy 214.281165 -316.953877)
			(xy 214.296161 -316.904053) (xy 214.318253 -316.856944) (xy 214.346969 -316.813553) (xy 214.381697 -316.774807)
			(xy 214.4014 -316.757812) (xy 214.412707 -316.747628) (xy 214.429273 -316.722124) (xy 214.437605 -316.692875)
			(xy 214.436965 -316.662469) (xy 214.42741 -316.633596) (xy 214.409784 -316.608812) (xy 214.398098 -316.599062)
			(xy 214.374642 -316.58021) (xy 214.333791 -316.536028) (xy 214.316818 -316.511178) (xy 214.309307 -316.500399)
			(xy 214.289834 -316.482777) (xy 214.266511 -316.470703) (xy 214.24088 -316.464974) (xy 214.214636 -316.46597)
			(xy 214.189513 -316.473625) (xy 214.178134 -316.48019) (xy 209.597244 -316.48019) (xy 209.584907 -316.503049)
			(xy 209.554617 -316.545245) (xy 209.518514 -316.58259) (xy 209.477367 -316.61429) (xy 209.432049 -316.639673)
			(xy 209.383522 -316.658199) (xy 209.332818 -316.669474) (xy 209.281014 -316.673259) (xy 209.22921 -316.669474)
			(xy 209.178506 -316.658199) (xy 209.129979 -316.639673) (xy 209.084661 -316.61429) (xy 209.043514 -316.58259)
			(xy 209.007411 -316.545245) (xy 208.977121 -316.503049) (xy 208.964784 -316.48019) (xy 207.387444 -316.48019)
			(xy 207.375107 -316.503049) (xy 207.344817 -316.545245) (xy 207.308714 -316.58259) (xy 207.267567 -316.61429)
			(xy 207.222249 -316.639673) (xy 207.173722 -316.658199) (xy 207.123018 -316.669474) (xy 207.071214 -316.673259)
			(xy 207.01941 -316.669474) (xy 206.968706 -316.658199) (xy 206.920179 -316.639673) (xy 206.874861 -316.61429)
			(xy 206.833714 -316.58259) (xy 206.797611 -316.545245) (xy 206.767321 -316.503049) (xy 206.754984 -316.48019)
			(xy 203.287376 -316.48019) (xy 203.275039 -316.503049) (xy 203.244749 -316.545245) (xy 203.208646 -316.58259)
			(xy 203.167499 -316.61429) (xy 203.122181 -316.639673) (xy 203.073654 -316.658199) (xy 203.02295 -316.669474)
			(xy 202.971146 -316.673259) (xy 202.919342 -316.669474) (xy 202.868638 -316.658199) (xy 202.820111 -316.639673)
			(xy 202.774793 -316.61429) (xy 202.733646 -316.58259) (xy 202.697543 -316.545245) (xy 202.667253 -316.503049)
			(xy 202.654916 -316.48019) (xy 202.053444 -316.48019) (xy 202.041107 -316.503049) (xy 202.010817 -316.545245)
			(xy 201.974714 -316.58259) (xy 201.933567 -316.61429) (xy 201.888249 -316.639673) (xy 201.839722 -316.658199)
			(xy 201.789018 -316.669474) (xy 201.737214 -316.673259) (xy 201.68541 -316.669474) (xy 201.634706 -316.658199)
			(xy 201.586179 -316.639673) (xy 201.540861 -316.61429) (xy 201.499714 -316.58259) (xy 201.463611 -316.545245)
			(xy 201.433321 -316.503049) (xy 201.420984 -316.48019) (xy 199.843644 -316.48019) (xy 199.831307 -316.503049)
			(xy 199.801017 -316.545245) (xy 199.764914 -316.58259) (xy 199.723767 -316.61429) (xy 199.678449 -316.639673)
			(xy 199.629922 -316.658199) (xy 199.579218 -316.669474) (xy 199.527414 -316.673259) (xy 199.47561 -316.669474)
			(xy 199.424906 -316.658199) (xy 199.376379 -316.639673) (xy 199.331061 -316.61429) (xy 199.289914 -316.58259)
			(xy 199.253811 -316.545245) (xy 199.223521 -316.503049) (xy 199.211184 -316.48019) (xy 194.509644 -316.48019)
			(xy 194.497307 -316.503049) (xy 194.467017 -316.545245) (xy 194.430914 -316.58259) (xy 194.389767 -316.61429)
			(xy 194.344449 -316.639673) (xy 194.295922 -316.658199) (xy 194.245218 -316.669474) (xy 194.193414 -316.673259)
			(xy 194.14161 -316.669474) (xy 194.090906 -316.658199) (xy 194.042379 -316.639673) (xy 193.997061 -316.61429)
			(xy 193.955914 -316.58259) (xy 193.919811 -316.545245) (xy 193.889521 -316.503049) (xy 193.877184 -316.48019)
			(xy 192.299844 -316.48019) (xy 192.287507 -316.503049) (xy 192.257217 -316.545245) (xy 192.221114 -316.58259)
			(xy 192.179967 -316.61429) (xy 192.134649 -316.639673) (xy 192.086122 -316.658199) (xy 192.035418 -316.669474)
			(xy 191.983614 -316.673259) (xy 191.93181 -316.669474) (xy 191.881106 -316.658199) (xy 191.832579 -316.639673)
			(xy 191.787261 -316.61429) (xy 191.746114 -316.58259) (xy 191.710011 -316.545245) (xy 191.679721 -316.503049)
			(xy 191.667384 -316.48019) (xy 188.199776 -316.48019) (xy 188.187439 -316.503049) (xy 188.157149 -316.545245)
			(xy 188.121046 -316.58259) (xy 188.079899 -316.61429) (xy 188.034581 -316.639673) (xy 187.986054 -316.658199)
			(xy 187.93535 -316.669474) (xy 187.883546 -316.673259) (xy 187.831742 -316.669474) (xy 187.781038 -316.658199)
			(xy 187.732511 -316.639673) (xy 187.687193 -316.61429) (xy 187.646046 -316.58259) (xy 187.609943 -316.545245)
			(xy 187.579653 -316.503049) (xy 187.567316 -316.48019) (xy 186.965844 -316.48019) (xy 186.953507 -316.503049)
			(xy 186.923217 -316.545245) (xy 186.887114 -316.58259) (xy 186.845967 -316.61429) (xy 186.800649 -316.639673)
			(xy 186.752122 -316.658199) (xy 186.701418 -316.669474) (xy 186.649614 -316.673259) (xy 186.59781 -316.669474)
			(xy 186.547106 -316.658199) (xy 186.498579 -316.639673) (xy 186.453261 -316.61429) (xy 186.412114 -316.58259)
			(xy 186.376011 -316.545245) (xy 186.345721 -316.503049) (xy 186.333384 -316.48019) (xy 184.756044 -316.48019)
			(xy 184.742799 -316.504668) (xy 184.709875 -316.549537) (xy 184.670366 -316.588732) (xy 184.625233 -316.621294)
			(xy 184.575581 -316.64643) (xy 184.522619 -316.663526) (xy 184.467641 -316.672165) (xy 184.439814 -316.672722)
			(xy 184.415542 -316.672312) (xy 184.367448 -316.66572) (xy 184.320694 -316.652655) (xy 184.276149 -316.633361)
			(xy 184.234638 -316.608195) (xy 184.215532 -316.59322) (xy 184.204513 -316.58487) (xy 184.179171 -316.573847)
			(xy 184.151801 -316.570025) (xy 184.124409 -316.573685) (xy 184.099003 -316.584559) (xy 184.077444 -316.601849)
			(xy 184.068974 -316.612778) (xy 184.053554 -316.633558) (xy 184.018006 -316.671161) (xy 183.977699 -316.703611)
			(xy 183.933374 -316.730312) (xy 183.885846 -316.750773) (xy 183.835987 -316.764619) (xy 183.784713 -316.771595)
			(xy 183.75884 -316.772036) (xy 183.732544 -316.771599) (xy 183.680448 -316.764382) (xy 183.629837 -316.750081)
			(xy 183.581669 -316.728965) (xy 183.536857 -316.701436) (xy 183.49625 -316.668013) (xy 183.460616 -316.629332)
			(xy 183.430632 -316.586123) (xy 183.406865 -316.539207) (xy 183.397906 -316.51448) (xy 183.386222 -316.48019)
			(xy 179.422044 -316.48019) (xy 179.409707 -316.503049) (xy 179.379417 -316.545245) (xy 179.343314 -316.58259)
			(xy 179.302167 -316.61429) (xy 179.256849 -316.639673) (xy 179.208322 -316.658199) (xy 179.157618 -316.669474)
			(xy 179.105814 -316.673259) (xy 179.05401 -316.669474) (xy 179.003306 -316.658199) (xy 178.954779 -316.639673)
			(xy 178.909461 -316.61429) (xy 178.868314 -316.58259) (xy 178.832211 -316.545245) (xy 178.801921 -316.503049)
			(xy 178.789584 -316.48019) (xy 177.212244 -316.48019) (xy 177.199907 -316.503049) (xy 177.169617 -316.545245)
			(xy 177.133514 -316.58259) (xy 177.092367 -316.61429) (xy 177.047049 -316.639673) (xy 176.998522 -316.658199)
			(xy 176.947818 -316.669474) (xy 176.896014 -316.673259) (xy 176.84421 -316.669474) (xy 176.793506 -316.658199)
			(xy 176.744979 -316.639673) (xy 176.699661 -316.61429) (xy 176.658514 -316.58259) (xy 176.622411 -316.545245)
			(xy 176.592121 -316.503049) (xy 176.579784 -316.48019) (xy 173.112176 -316.48019) (xy 173.099839 -316.503049)
			(xy 173.069549 -316.545245) (xy 173.033446 -316.58259) (xy 172.992299 -316.61429) (xy 172.946981 -316.639673)
			(xy 172.898454 -316.658199) (xy 172.84775 -316.669474) (xy 172.795946 -316.673259) (xy 172.744142 -316.669474)
			(xy 172.693438 -316.658199) (xy 172.644911 -316.639673) (xy 172.599593 -316.61429) (xy 172.558446 -316.58259)
			(xy 172.522343 -316.545245) (xy 172.492053 -316.503049) (xy 172.479716 -316.48019) (xy 171.878244 -316.48019)
			(xy 171.865907 -316.503049) (xy 171.835617 -316.545245) (xy 171.799514 -316.58259) (xy 171.758367 -316.61429)
			(xy 171.713049 -316.639673) (xy 171.664522 -316.658199) (xy 171.613818 -316.669474) (xy 171.562014 -316.673259)
			(xy 171.51021 -316.669474) (xy 171.459506 -316.658199) (xy 171.410979 -316.639673) (xy 171.365661 -316.61429)
			(xy 171.324514 -316.58259) (xy 171.288411 -316.545245) (xy 171.258121 -316.503049) (xy 171.245784 -316.48019)
			(xy 169.668444 -316.48019) (xy 169.656107 -316.503049) (xy 169.625817 -316.545245) (xy 169.589714 -316.58259)
			(xy 169.548567 -316.61429) (xy 169.503249 -316.639673) (xy 169.454722 -316.658199) (xy 169.404018 -316.669474)
			(xy 169.352214 -316.673259) (xy 169.30041 -316.669474) (xy 169.249706 -316.658199) (xy 169.201179 -316.639673)
			(xy 169.155861 -316.61429) (xy 169.114714 -316.58259) (xy 169.078611 -316.545245) (xy 169.048321 -316.503049)
			(xy 169.035984 -316.48019) (xy 164.334444 -316.48019) (xy 164.322107 -316.503049) (xy 164.291817 -316.545245)
			(xy 164.255714 -316.58259) (xy 164.214567 -316.61429) (xy 164.169249 -316.639673) (xy 164.120722 -316.658199)
			(xy 164.070018 -316.669474) (xy 164.018214 -316.673259) (xy 163.96641 -316.669474) (xy 163.915706 -316.658199)
			(xy 163.867179 -316.639673) (xy 163.821861 -316.61429) (xy 163.780714 -316.58259) (xy 163.744611 -316.545245)
			(xy 163.714321 -316.503049) (xy 163.701984 -316.48019) (xy 162.124644 -316.48019) (xy 162.112307 -316.503049)
			(xy 162.082017 -316.545245) (xy 162.045914 -316.58259) (xy 162.004767 -316.61429) (xy 161.959449 -316.639673)
			(xy 161.910922 -316.658199) (xy 161.860218 -316.669474) (xy 161.808414 -316.673259) (xy 161.75661 -316.669474)
			(xy 161.705906 -316.658199) (xy 161.657379 -316.639673) (xy 161.612061 -316.61429) (xy 161.570914 -316.58259)
			(xy 161.534811 -316.545245) (xy 161.504521 -316.503049) (xy 161.492184 -316.48019) (xy 160.759648 -316.48019)
			(xy 160.236408 -317.00343) (xy 160.248854 -317.034672) (xy 160.258046 -317.058948) (xy 160.270101 -317.109436)
			(xy 160.2747 -317.161139) (xy 160.271745 -317.212962) (xy 160.270702 -317.218039) (xy 163.702228 -317.218039)
			(xy 163.702228 -317.164741) (xy 163.710171 -317.112037) (xy 163.725881 -317.061107) (xy 163.749007 -317.013086)
			(xy 163.779031 -316.969049) (xy 163.815283 -316.929978) (xy 163.856954 -316.896747) (xy 163.903112 -316.870098)
			(xy 163.952726 -316.850626) (xy 164.004688 -316.838766) (xy 164.057838 -316.834783) (xy 164.110988 -316.838766)
			(xy 164.16295 -316.850626) (xy 164.212564 -316.870098) (xy 164.258722 -316.896747) (xy 164.300393 -316.929978)
			(xy 164.336645 -316.969049) (xy 164.366669 -317.013086) (xy 164.389795 -317.061107) (xy 164.405505 -317.112037)
			(xy 164.413448 -317.164741) (xy 164.413946 -317.19139) (xy 164.413908 -317.193401) (xy 164.896536 -317.193401)
			(xy 164.896536 -317.140103) (xy 164.904479 -317.087399) (xy 164.920189 -317.036469) (xy 164.943315 -316.988448)
			(xy 164.973339 -316.944411) (xy 165.009591 -316.90534) (xy 165.051262 -316.872109) (xy 165.09742 -316.84546)
			(xy 165.147034 -316.825988) (xy 165.198996 -316.814128) (xy 165.252146 -316.810145) (xy 165.305296 -316.814128)
			(xy 165.357258 -316.825988) (xy 165.406872 -316.84546) (xy 165.45303 -316.872109) (xy 165.494701 -316.90534)
			(xy 165.530953 -316.944411) (xy 165.560977 -316.988448) (xy 165.584103 -317.036469) (xy 165.599813 -317.087399)
			(xy 165.607756 -317.140103) (xy 165.608254 -317.166752) (xy 165.607756 -317.193401) (xy 167.106336 -317.193401)
			(xy 167.106336 -317.140103) (xy 167.114279 -317.087399) (xy 167.129989 -317.036469) (xy 167.153115 -316.988448)
			(xy 167.183139 -316.944411) (xy 167.219391 -316.90534) (xy 167.261062 -316.872109) (xy 167.30722 -316.84546)
			(xy 167.356834 -316.825988) (xy 167.408796 -316.814128) (xy 167.461946 -316.810145) (xy 167.515096 -316.814128)
			(xy 167.567058 -316.825988) (xy 167.616672 -316.84546) (xy 167.66283 -316.872109) (xy 167.704501 -316.90534)
			(xy 167.740753 -316.944411) (xy 167.770777 -316.988448) (xy 167.793903 -317.036469) (xy 167.809613 -317.087399)
			(xy 167.817556 -317.140103) (xy 167.818054 -317.166752) (xy 167.817556 -317.193401) (xy 167.810015 -317.243439)
			(xy 171.230788 -317.243439) (xy 171.230788 -317.190141) (xy 171.238731 -317.137437) (xy 171.254441 -317.086507)
			(xy 171.277567 -317.038486) (xy 171.307591 -316.994449) (xy 171.343843 -316.955378) (xy 171.385514 -316.922147)
			(xy 171.431672 -316.895498) (xy 171.481286 -316.876026) (xy 171.533248 -316.864166) (xy 171.586398 -316.860183)
			(xy 171.639548 -316.864166) (xy 171.69151 -316.876026) (xy 171.741124 -316.895498) (xy 171.787282 -316.922147)
			(xy 171.828953 -316.955378) (xy 171.865205 -316.994449) (xy 171.895229 -317.038486) (xy 171.918355 -317.086507)
			(xy 171.934065 -317.137437) (xy 171.942008 -317.190141) (xy 171.942069 -317.193401) (xy 172.440336 -317.193401)
			(xy 172.440336 -317.140103) (xy 172.448279 -317.087399) (xy 172.463989 -317.036469) (xy 172.487115 -316.988448)
			(xy 172.517139 -316.944411) (xy 172.553391 -316.90534) (xy 172.595062 -316.872109) (xy 172.64122 -316.84546)
			(xy 172.690834 -316.825988) (xy 172.742796 -316.814128) (xy 172.795946 -316.810145) (xy 172.849096 -316.814128)
			(xy 172.901058 -316.825988) (xy 172.950672 -316.84546) (xy 172.99683 -316.872109) (xy 173.038501 -316.90534)
			(xy 173.074753 -316.944411) (xy 173.104777 -316.988448) (xy 173.127903 -317.036469) (xy 173.143613 -317.087399)
			(xy 173.151556 -317.140103) (xy 173.152054 -317.166752) (xy 173.151556 -317.193401) (xy 174.650136 -317.193401)
			(xy 174.650136 -317.140103) (xy 174.658079 -317.087399) (xy 174.673789 -317.036469) (xy 174.696915 -316.988448)
			(xy 174.726939 -316.944411) (xy 174.763191 -316.90534) (xy 174.804862 -316.872109) (xy 174.85102 -316.84546)
			(xy 174.900634 -316.825988) (xy 174.952596 -316.814128) (xy 175.005746 -316.810145) (xy 175.058896 -316.814128)
			(xy 175.110858 -316.825988) (xy 175.160472 -316.84546) (xy 175.20663 -316.872109) (xy 175.248301 -316.90534)
			(xy 175.284553 -316.944411) (xy 175.314577 -316.988448) (xy 175.337703 -317.036469) (xy 175.353413 -317.087399)
			(xy 175.361356 -317.140103) (xy 175.361854 -317.166752) (xy 175.361356 -317.193401) (xy 176.540404 -317.193401)
			(xy 176.540404 -317.140103) (xy 176.548347 -317.087399) (xy 176.564057 -317.036469) (xy 176.587183 -316.988448)
			(xy 176.617207 -316.944411) (xy 176.653459 -316.90534) (xy 176.69513 -316.872109) (xy 176.741288 -316.84546)
			(xy 176.790902 -316.825988) (xy 176.842864 -316.814128) (xy 176.896014 -316.810145) (xy 176.949164 -316.814128)
			(xy 177.001126 -316.825988) (xy 177.05074 -316.84546) (xy 177.096898 -316.872109) (xy 177.138569 -316.90534)
			(xy 177.174821 -316.944411) (xy 177.204845 -316.988448) (xy 177.227971 -317.036469) (xy 177.243681 -317.087399)
			(xy 177.251624 -317.140103) (xy 177.252122 -317.166752) (xy 177.251624 -317.193401) (xy 179.984136 -317.193401)
			(xy 179.984136 -317.140103) (xy 179.992079 -317.087399) (xy 180.007789 -317.036469) (xy 180.030915 -316.988448)
			(xy 180.060939 -316.944411) (xy 180.097191 -316.90534) (xy 180.138862 -316.872109) (xy 180.18502 -316.84546)
			(xy 180.234634 -316.825988) (xy 180.286596 -316.814128) (xy 180.339746 -316.810145) (xy 180.392896 -316.814128)
			(xy 180.444858 -316.825988) (xy 180.494472 -316.84546) (xy 180.54063 -316.872109) (xy 180.582301 -316.90534)
			(xy 180.618553 -316.944411) (xy 180.648577 -316.988448) (xy 180.671703 -317.036469) (xy 180.687413 -317.087399)
			(xy 180.695356 -317.140103) (xy 180.695854 -317.166752) (xy 180.695356 -317.193401) (xy 182.193936 -317.193401)
			(xy 182.193936 -317.140103) (xy 182.201879 -317.087399) (xy 182.217589 -317.036469) (xy 182.240715 -316.988448)
			(xy 182.270739 -316.944411) (xy 182.306991 -316.90534) (xy 182.348662 -316.872109) (xy 182.39482 -316.84546)
			(xy 182.444434 -316.825988) (xy 182.496396 -316.814128) (xy 182.549546 -316.810145) (xy 182.602696 -316.814128)
			(xy 182.654658 -316.825988) (xy 182.704272 -316.84546) (xy 182.75043 -316.872109) (xy 182.792101 -316.90534)
			(xy 182.828353 -316.944411) (xy 182.858377 -316.988448) (xy 182.881503 -317.036469) (xy 182.897213 -317.087399)
			(xy 182.905156 -317.140103) (xy 182.905654 -317.166752) (xy 182.905156 -317.193401) (xy 184.084204 -317.193401)
			(xy 184.084204 -317.140103) (xy 184.092147 -317.087399) (xy 184.107857 -317.036469) (xy 184.130983 -316.988448)
			(xy 184.161007 -316.944411) (xy 184.197259 -316.90534) (xy 184.23893 -316.872109) (xy 184.285088 -316.84546)
			(xy 184.334702 -316.825988) (xy 184.386664 -316.814128) (xy 184.439814 -316.810145) (xy 184.492964 -316.814128)
			(xy 184.544926 -316.825988) (xy 184.59454 -316.84546) (xy 184.640698 -316.872109) (xy 184.682369 -316.90534)
			(xy 184.718621 -316.944411) (xy 184.748645 -316.988448) (xy 184.771771 -317.036469) (xy 184.787481 -317.087399)
			(xy 184.795424 -317.140103) (xy 184.795922 -317.166752) (xy 184.795424 -317.193401) (xy 187.527936 -317.193401)
			(xy 187.527936 -317.140103) (xy 187.535879 -317.087399) (xy 187.551589 -317.036469) (xy 187.574715 -316.988448)
			(xy 187.604739 -316.944411) (xy 187.640991 -316.90534) (xy 187.682662 -316.872109) (xy 187.72882 -316.84546)
			(xy 187.778434 -316.825988) (xy 187.830396 -316.814128) (xy 187.883546 -316.810145) (xy 187.936696 -316.814128)
			(xy 187.988658 -316.825988) (xy 188.038272 -316.84546) (xy 188.08443 -316.872109) (xy 188.126101 -316.90534)
			(xy 188.162353 -316.944411) (xy 188.192377 -316.988448) (xy 188.215503 -317.036469) (xy 188.231213 -317.087399)
			(xy 188.239156 -317.140103) (xy 188.239654 -317.166752) (xy 188.239653 -317.1668) (xy 189.73662 -317.1668)
			(xy 189.740604 -317.113635) (xy 189.752469 -317.061658) (xy 189.771948 -317.01203) (xy 189.798607 -316.965861)
			(xy 189.83185 -316.92418) (xy 189.870934 -316.88792) (xy 189.914987 -316.857891) (xy 189.963023 -316.834763)
			(xy 190.01397 -316.819054) (xy 190.066689 -316.811114) (xy 190.093346 -316.810644) (xy 190.117943 -316.811097)
			(xy 190.166668 -316.817866) (xy 190.214 -316.831271) (xy 190.259039 -316.851056) (xy 190.300931 -316.876845)
			(xy 190.320168 -316.892178) (xy 190.332521 -316.901726) (xy 190.361466 -316.913397) (xy 190.392584 -316.915797)
			(xy 190.422977 -316.908703) (xy 190.449816 -316.892774) (xy 190.46063 -316.88151) (xy 190.477583 -316.863175)
			(xy 190.515762 -316.830988) (xy 190.558062 -316.804449) (xy 190.603654 -316.784078) (xy 190.651644 -316.770274)
			(xy 190.701092 -316.763308) (xy 190.72606 -316.762892) (xy 190.752713 -316.763362) (xy 190.805425 -316.771302)
			(xy 190.856364 -316.787009) (xy 190.904393 -316.810134) (xy 190.948439 -316.84016) (xy 190.987517 -316.876415)
			(xy 191.020755 -316.918089) (xy 191.047409 -316.964253) (xy 191.066886 -317.013874) (xy 191.078748 -317.065843)
			(xy 191.082732 -317.119) (xy 191.078748 -317.172157) (xy 191.073899 -317.193401) (xy 191.628004 -317.193401)
			(xy 191.628004 -317.140103) (xy 191.635947 -317.087399) (xy 191.651657 -317.036469) (xy 191.674783 -316.988448)
			(xy 191.704807 -316.944411) (xy 191.741059 -316.90534) (xy 191.78273 -316.872109) (xy 191.828888 -316.84546)
			(xy 191.878502 -316.825988) (xy 191.930464 -316.814128) (xy 191.983614 -316.810145) (xy 192.036764 -316.814128)
			(xy 192.088726 -316.825988) (xy 192.13834 -316.84546) (xy 192.184498 -316.872109) (xy 192.226169 -316.90534)
			(xy 192.262421 -316.944411) (xy 192.292445 -316.988448) (xy 192.315571 -317.036469) (xy 192.331281 -317.087399)
			(xy 192.339224 -317.140103) (xy 192.339722 -317.166752) (xy 192.339224 -317.193401) (xy 195.071736 -317.193401)
			(xy 195.071736 -317.140103) (xy 195.079679 -317.087399) (xy 195.095389 -317.036469) (xy 195.118515 -316.988448)
			(xy 195.148539 -316.944411) (xy 195.184791 -316.90534) (xy 195.226462 -316.872109) (xy 195.27262 -316.84546)
			(xy 195.322234 -316.825988) (xy 195.374196 -316.814128) (xy 195.427346 -316.810145) (xy 195.480496 -316.814128)
			(xy 195.532458 -316.825988) (xy 195.582072 -316.84546) (xy 195.62823 -316.872109) (xy 195.669901 -316.90534)
			(xy 195.706153 -316.944411) (xy 195.736177 -316.988448) (xy 195.759303 -317.036469) (xy 195.775013 -317.087399)
			(xy 195.782956 -317.140103) (xy 195.783454 -317.166752) (xy 195.782956 -317.193401) (xy 197.281536 -317.193401)
			(xy 197.281536 -317.140103) (xy 197.289479 -317.087399) (xy 197.305189 -317.036469) (xy 197.328315 -316.988448)
			(xy 197.358339 -316.944411) (xy 197.394591 -316.90534) (xy 197.436262 -316.872109) (xy 197.48242 -316.84546)
			(xy 197.532034 -316.825988) (xy 197.583996 -316.814128) (xy 197.637146 -316.810145) (xy 197.690296 -316.814128)
			(xy 197.742258 -316.825988) (xy 197.791872 -316.84546) (xy 197.83803 -316.872109) (xy 197.879701 -316.90534)
			(xy 197.915953 -316.944411) (xy 197.945977 -316.988448) (xy 197.969103 -317.036469) (xy 197.984813 -317.087399)
			(xy 197.992756 -317.140103) (xy 197.993254 -317.166752) (xy 197.992756 -317.193401) (xy 199.171804 -317.193401)
			(xy 199.171804 -317.140103) (xy 199.179747 -317.087399) (xy 199.195457 -317.036469) (xy 199.218583 -316.988448)
			(xy 199.248607 -316.944411) (xy 199.284859 -316.90534) (xy 199.32653 -316.872109) (xy 199.372688 -316.84546)
			(xy 199.422302 -316.825988) (xy 199.474264 -316.814128) (xy 199.527414 -316.810145) (xy 199.580564 -316.814128)
			(xy 199.632526 -316.825988) (xy 199.68214 -316.84546) (xy 199.728298 -316.872109) (xy 199.769969 -316.90534)
			(xy 199.806221 -316.944411) (xy 199.836245 -316.988448) (xy 199.859371 -317.036469) (xy 199.875081 -317.087399)
			(xy 199.883024 -317.140103) (xy 199.883522 -317.166752) (xy 199.883024 -317.193401) (xy 202.615536 -317.193401)
			(xy 202.615536 -317.140103) (xy 202.623479 -317.087399) (xy 202.639189 -317.036469) (xy 202.662315 -316.988448)
			(xy 202.692339 -316.944411) (xy 202.728591 -316.90534) (xy 202.770262 -316.872109) (xy 202.81642 -316.84546)
			(xy 202.866034 -316.825988) (xy 202.917996 -316.814128) (xy 202.971146 -316.810145) (xy 203.024296 -316.814128)
			(xy 203.076258 -316.825988) (xy 203.125872 -316.84546) (xy 203.17203 -316.872109) (xy 203.213701 -316.90534)
			(xy 203.249953 -316.944411) (xy 203.279977 -316.988448) (xy 203.303103 -317.036469) (xy 203.318813 -317.087399)
			(xy 203.326756 -317.140103) (xy 203.327254 -317.166752) (xy 203.326756 -317.193401) (xy 204.825336 -317.193401)
			(xy 204.825336 -317.140103) (xy 204.833279 -317.087399) (xy 204.848989 -317.036469) (xy 204.872115 -316.988448)
			(xy 204.902139 -316.944411) (xy 204.938391 -316.90534) (xy 204.980062 -316.872109) (xy 205.02622 -316.84546)
			(xy 205.075834 -316.825988) (xy 205.127796 -316.814128) (xy 205.180946 -316.810145) (xy 205.234096 -316.814128)
			(xy 205.286058 -316.825988) (xy 205.335672 -316.84546) (xy 205.38183 -316.872109) (xy 205.423501 -316.90534)
			(xy 205.459753 -316.944411) (xy 205.489777 -316.988448) (xy 205.512903 -317.036469) (xy 205.528613 -317.087399)
			(xy 205.536556 -317.140103) (xy 205.537054 -317.166752) (xy 205.536556 -317.193401) (xy 206.715604 -317.193401)
			(xy 206.715604 -317.140103) (xy 206.723547 -317.087399) (xy 206.739257 -317.036469) (xy 206.762383 -316.988448)
			(xy 206.792407 -316.944411) (xy 206.828659 -316.90534) (xy 206.87033 -316.872109) (xy 206.916488 -316.84546)
			(xy 206.966102 -316.825988) (xy 207.018064 -316.814128) (xy 207.071214 -316.810145) (xy 207.124364 -316.814128)
			(xy 207.176326 -316.825988) (xy 207.22594 -316.84546) (xy 207.272098 -316.872109) (xy 207.313769 -316.90534)
			(xy 207.350021 -316.944411) (xy 207.380045 -316.988448) (xy 207.403171 -317.036469) (xy 207.418881 -317.087399)
			(xy 207.426824 -317.140103) (xy 207.427322 -317.166752) (xy 207.426824 -317.193401) (xy 210.159336 -317.193401)
			(xy 210.159336 -317.140103) (xy 210.167279 -317.087399) (xy 210.182989 -317.036469) (xy 210.206115 -316.988448)
			(xy 210.236139 -316.944411) (xy 210.272391 -316.90534) (xy 210.314062 -316.872109) (xy 210.36022 -316.84546)
			(xy 210.409834 -316.825988) (xy 210.461796 -316.814128) (xy 210.514946 -316.810145) (xy 210.568096 -316.814128)
			(xy 210.620058 -316.825988) (xy 210.669672 -316.84546) (xy 210.71583 -316.872109) (xy 210.757501 -316.90534)
			(xy 210.793753 -316.944411) (xy 210.823777 -316.988448) (xy 210.846903 -317.036469) (xy 210.862613 -317.087399)
			(xy 210.870556 -317.140103) (xy 210.871054 -317.166752) (xy 210.870556 -317.193401) (xy 212.369136 -317.193401)
			(xy 212.369136 -317.140103) (xy 212.377079 -317.087399) (xy 212.392789 -317.036469) (xy 212.415915 -316.988448)
			(xy 212.445939 -316.944411) (xy 212.482191 -316.90534) (xy 212.523862 -316.872109) (xy 212.57002 -316.84546)
			(xy 212.619634 -316.825988) (xy 212.671596 -316.814128) (xy 212.724746 -316.810145) (xy 212.777896 -316.814128)
			(xy 212.829858 -316.825988) (xy 212.879472 -316.84546) (xy 212.92563 -316.872109) (xy 212.967301 -316.90534)
			(xy 213.003553 -316.944411) (xy 213.033577 -316.988448) (xy 213.056703 -317.036469) (xy 213.072413 -317.087399)
			(xy 213.080356 -317.140103) (xy 213.080854 -317.166752) (xy 213.080356 -317.193401) (xy 213.072413 -317.246105)
			(xy 213.056703 -317.297035) (xy 213.033577 -317.345056) (xy 213.003553 -317.389093) (xy 212.967301 -317.428164)
			(xy 212.92563 -317.461395) (xy 212.879472 -317.488044) (xy 212.829858 -317.507516) (xy 212.777896 -317.519376)
			(xy 212.724746 -317.52336) (xy 212.671596 -317.519376) (xy 212.619634 -317.507516) (xy 212.57002 -317.488044)
			(xy 212.523862 -317.461395) (xy 212.482191 -317.428164) (xy 212.445939 -317.389093) (xy 212.415915 -317.345056)
			(xy 212.392789 -317.297035) (xy 212.377079 -317.246105) (xy 212.369136 -317.193401) (xy 210.870556 -317.193401)
			(xy 210.862613 -317.246105) (xy 210.846903 -317.297035) (xy 210.823777 -317.345056) (xy 210.793753 -317.389093)
			(xy 210.757501 -317.428164) (xy 210.71583 -317.461395) (xy 210.669672 -317.488044) (xy 210.620058 -317.507516)
			(xy 210.568096 -317.519376) (xy 210.514946 -317.52336) (xy 210.461796 -317.519376) (xy 210.409834 -317.507516)
			(xy 210.36022 -317.488044) (xy 210.314062 -317.461395) (xy 210.272391 -317.428164) (xy 210.236139 -317.389093)
			(xy 210.206115 -317.345056) (xy 210.182989 -317.297035) (xy 210.167279 -317.246105) (xy 210.159336 -317.193401)
			(xy 207.426824 -317.193401) (xy 207.418881 -317.246105) (xy 207.403171 -317.297035) (xy 207.380045 -317.345056)
			(xy 207.350021 -317.389093) (xy 207.313769 -317.428164) (xy 207.272098 -317.461395) (xy 207.22594 -317.488044)
			(xy 207.176326 -317.507516) (xy 207.124364 -317.519376) (xy 207.071214 -317.52336) (xy 207.018064 -317.519376)
			(xy 206.966102 -317.507516) (xy 206.916488 -317.488044) (xy 206.87033 -317.461395) (xy 206.828659 -317.428164)
			(xy 206.792407 -317.389093) (xy 206.762383 -317.345056) (xy 206.739257 -317.297035) (xy 206.723547 -317.246105)
			(xy 206.715604 -317.193401) (xy 205.536556 -317.193401) (xy 205.528613 -317.246105) (xy 205.512903 -317.297035)
			(xy 205.489777 -317.345056) (xy 205.459753 -317.389093) (xy 205.423501 -317.428164) (xy 205.38183 -317.461395)
			(xy 205.335672 -317.488044) (xy 205.286058 -317.507516) (xy 205.234096 -317.519376) (xy 205.180946 -317.52336)
			(xy 205.127796 -317.519376) (xy 205.075834 -317.507516) (xy 205.02622 -317.488044) (xy 204.980062 -317.461395)
			(xy 204.938391 -317.428164) (xy 204.902139 -317.389093) (xy 204.872115 -317.345056) (xy 204.848989 -317.297035)
			(xy 204.833279 -317.246105) (xy 204.825336 -317.193401) (xy 203.326756 -317.193401) (xy 203.318813 -317.246105)
			(xy 203.303103 -317.297035) (xy 203.279977 -317.345056) (xy 203.249953 -317.389093) (xy 203.213701 -317.428164)
			(xy 203.17203 -317.461395) (xy 203.125872 -317.488044) (xy 203.076258 -317.507516) (xy 203.024296 -317.519376)
			(xy 202.971146 -317.52336) (xy 202.917996 -317.519376) (xy 202.866034 -317.507516) (xy 202.81642 -317.488044)
			(xy 202.770262 -317.461395) (xy 202.728591 -317.428164) (xy 202.692339 -317.389093) (xy 202.662315 -317.345056)
			(xy 202.639189 -317.297035) (xy 202.623479 -317.246105) (xy 202.615536 -317.193401) (xy 199.883024 -317.193401)
			(xy 199.875081 -317.246105) (xy 199.859371 -317.297035) (xy 199.836245 -317.345056) (xy 199.806221 -317.389093)
			(xy 199.769969 -317.428164) (xy 199.728298 -317.461395) (xy 199.68214 -317.488044) (xy 199.632526 -317.507516)
			(xy 199.580564 -317.519376) (xy 199.527414 -317.52336) (xy 199.474264 -317.519376) (xy 199.422302 -317.507516)
			(xy 199.372688 -317.488044) (xy 199.32653 -317.461395) (xy 199.284859 -317.428164) (xy 199.248607 -317.389093)
			(xy 199.218583 -317.345056) (xy 199.195457 -317.297035) (xy 199.179747 -317.246105) (xy 199.171804 -317.193401)
			(xy 197.992756 -317.193401) (xy 197.984813 -317.246105) (xy 197.969103 -317.297035) (xy 197.945977 -317.345056)
			(xy 197.915953 -317.389093) (xy 197.879701 -317.428164) (xy 197.83803 -317.461395) (xy 197.791872 -317.488044)
			(xy 197.742258 -317.507516) (xy 197.690296 -317.519376) (xy 197.637146 -317.52336) (xy 197.583996 -317.519376)
			(xy 197.532034 -317.507516) (xy 197.48242 -317.488044) (xy 197.436262 -317.461395) (xy 197.394591 -317.428164)
			(xy 197.358339 -317.389093) (xy 197.328315 -317.345056) (xy 197.305189 -317.297035) (xy 197.289479 -317.246105)
			(xy 197.281536 -317.193401) (xy 195.782956 -317.193401) (xy 195.775013 -317.246105) (xy 195.759303 -317.297035)
			(xy 195.736177 -317.345056) (xy 195.706153 -317.389093) (xy 195.669901 -317.428164) (xy 195.62823 -317.461395)
			(xy 195.582072 -317.488044) (xy 195.532458 -317.507516) (xy 195.480496 -317.519376) (xy 195.427346 -317.52336)
			(xy 195.374196 -317.519376) (xy 195.322234 -317.507516) (xy 195.27262 -317.488044) (xy 195.226462 -317.461395)
			(xy 195.184791 -317.428164) (xy 195.148539 -317.389093) (xy 195.118515 -317.345056) (xy 195.095389 -317.297035)
			(xy 195.079679 -317.246105) (xy 195.071736 -317.193401) (xy 192.339224 -317.193401) (xy 192.331281 -317.246105)
			(xy 192.315571 -317.297035) (xy 192.292445 -317.345056) (xy 192.262421 -317.389093) (xy 192.226169 -317.428164)
			(xy 192.184498 -317.461395) (xy 192.13834 -317.488044) (xy 192.088726 -317.507516) (xy 192.036764 -317.519376)
			(xy 191.983614 -317.52336) (xy 191.930464 -317.519376) (xy 191.878502 -317.507516) (xy 191.828888 -317.488044)
			(xy 191.78273 -317.461395) (xy 191.741059 -317.428164) (xy 191.704807 -317.389093) (xy 191.674783 -317.345056)
			(xy 191.651657 -317.297035) (xy 191.635947 -317.246105) (xy 191.628004 -317.193401) (xy 191.073899 -317.193401)
			(xy 191.066886 -317.224126) (xy 191.047409 -317.273747) (xy 191.020755 -317.319911) (xy 190.987517 -317.361585)
			(xy 190.948439 -317.39784) (xy 190.904393 -317.427866) (xy 190.856364 -317.450991) (xy 190.805425 -317.466698)
			(xy 190.752713 -317.474638) (xy 190.72606 -317.475108) (xy 190.701461 -317.47472) (xy 190.652733 -317.467936)
			(xy 190.605399 -317.454517) (xy 190.560361 -317.434718) (xy 190.518472 -317.408914) (xy 190.499238 -317.393574)
			(xy 190.486877 -317.38404) (xy 190.457934 -317.372374) (xy 190.426821 -317.369974) (xy 190.396432 -317.377064)
			(xy 190.369592 -317.392983) (xy 190.358776 -317.404242) (xy 190.34181 -317.422565) (xy 190.303635 -317.454754)
			(xy 190.261338 -317.481296) (xy 190.215749 -317.50167) (xy 190.16776 -317.515476) (xy 190.118314 -317.522444)
			(xy 190.093346 -317.52286) (xy 190.066689 -317.522486) (xy 190.01397 -317.514546) (xy 189.963023 -317.498837)
			(xy 189.914987 -317.475709) (xy 189.870934 -317.44568) (xy 189.83185 -317.40942) (xy 189.798607 -317.36774)
			(xy 189.771948 -317.32157) (xy 189.752469 -317.271942) (xy 189.740604 -317.219965) (xy 189.73662 -317.1668)
			(xy 188.239653 -317.1668) (xy 188.239156 -317.193401) (xy 188.231213 -317.246105) (xy 188.215503 -317.297035)
			(xy 188.192377 -317.345056) (xy 188.162353 -317.389093) (xy 188.126101 -317.428164) (xy 188.08443 -317.461395)
			(xy 188.038272 -317.488044) (xy 187.988658 -317.507516) (xy 187.936696 -317.519376) (xy 187.883546 -317.52336)
			(xy 187.830396 -317.519376) (xy 187.778434 -317.507516) (xy 187.72882 -317.488044) (xy 187.682662 -317.461395)
			(xy 187.640991 -317.428164) (xy 187.604739 -317.389093) (xy 187.574715 -317.345056) (xy 187.551589 -317.297035)
			(xy 187.535879 -317.246105) (xy 187.527936 -317.193401) (xy 184.795424 -317.193401) (xy 184.787481 -317.246105)
			(xy 184.771771 -317.297035) (xy 184.748645 -317.345056) (xy 184.718621 -317.389093) (xy 184.682369 -317.428164)
			(xy 184.640698 -317.461395) (xy 184.59454 -317.488044) (xy 184.544926 -317.507516) (xy 184.492964 -317.519376)
			(xy 184.439814 -317.52336) (xy 184.386664 -317.519376) (xy 184.334702 -317.507516) (xy 184.285088 -317.488044)
			(xy 184.23893 -317.461395) (xy 184.197259 -317.428164) (xy 184.161007 -317.389093) (xy 184.130983 -317.345056)
			(xy 184.107857 -317.297035) (xy 184.092147 -317.246105) (xy 184.084204 -317.193401) (xy 182.905156 -317.193401)
			(xy 182.897213 -317.246105) (xy 182.881503 -317.297035) (xy 182.858377 -317.345056) (xy 182.828353 -317.389093)
			(xy 182.792101 -317.428164) (xy 182.75043 -317.461395) (xy 182.704272 -317.488044) (xy 182.654658 -317.507516)
			(xy 182.602696 -317.519376) (xy 182.549546 -317.52336) (xy 182.496396 -317.519376) (xy 182.444434 -317.507516)
			(xy 182.39482 -317.488044) (xy 182.348662 -317.461395) (xy 182.306991 -317.428164) (xy 182.270739 -317.389093)
			(xy 182.240715 -317.345056) (xy 182.217589 -317.297035) (xy 182.201879 -317.246105) (xy 182.193936 -317.193401)
			(xy 180.695356 -317.193401) (xy 180.687413 -317.246105) (xy 180.671703 -317.297035) (xy 180.648577 -317.345056)
			(xy 180.618553 -317.389093) (xy 180.582301 -317.428164) (xy 180.54063 -317.461395) (xy 180.494472 -317.488044)
			(xy 180.444858 -317.507516) (xy 180.392896 -317.519376) (xy 180.339746 -317.52336) (xy 180.286596 -317.519376)
			(xy 180.234634 -317.507516) (xy 180.18502 -317.488044) (xy 180.138862 -317.461395) (xy 180.097191 -317.428164)
			(xy 180.060939 -317.389093) (xy 180.030915 -317.345056) (xy 180.007789 -317.297035) (xy 179.992079 -317.246105)
			(xy 179.984136 -317.193401) (xy 177.251624 -317.193401) (xy 177.243681 -317.246105) (xy 177.227971 -317.297035)
			(xy 177.204845 -317.345056) (xy 177.174821 -317.389093) (xy 177.138569 -317.428164) (xy 177.096898 -317.461395)
			(xy 177.05074 -317.488044) (xy 177.001126 -317.507516) (xy 176.949164 -317.519376) (xy 176.896014 -317.52336)
			(xy 176.842864 -317.519376) (xy 176.790902 -317.507516) (xy 176.741288 -317.488044) (xy 176.69513 -317.461395)
			(xy 176.653459 -317.428164) (xy 176.617207 -317.389093) (xy 176.587183 -317.345056) (xy 176.564057 -317.297035)
			(xy 176.548347 -317.246105) (xy 176.540404 -317.193401) (xy 175.361356 -317.193401) (xy 175.353413 -317.246105)
			(xy 175.337703 -317.297035) (xy 175.314577 -317.345056) (xy 175.284553 -317.389093) (xy 175.248301 -317.428164)
			(xy 175.20663 -317.461395) (xy 175.160472 -317.488044) (xy 175.110858 -317.507516) (xy 175.058896 -317.519376)
			(xy 175.005746 -317.52336) (xy 174.952596 -317.519376) (xy 174.900634 -317.507516) (xy 174.85102 -317.488044)
			(xy 174.804862 -317.461395) (xy 174.763191 -317.428164) (xy 174.726939 -317.389093) (xy 174.696915 -317.345056)
			(xy 174.673789 -317.297035) (xy 174.658079 -317.246105) (xy 174.650136 -317.193401) (xy 173.151556 -317.193401)
			(xy 173.143613 -317.246105) (xy 173.127903 -317.297035) (xy 173.104777 -317.345056) (xy 173.074753 -317.389093)
			(xy 173.038501 -317.428164) (xy 172.99683 -317.461395) (xy 172.950672 -317.488044) (xy 172.901058 -317.507516)
			(xy 172.849096 -317.519376) (xy 172.795946 -317.52336) (xy 172.742796 -317.519376) (xy 172.690834 -317.507516)
			(xy 172.64122 -317.488044) (xy 172.595062 -317.461395) (xy 172.553391 -317.428164) (xy 172.517139 -317.389093)
			(xy 172.487115 -317.345056) (xy 172.463989 -317.297035) (xy 172.448279 -317.246105) (xy 172.440336 -317.193401)
			(xy 171.942069 -317.193401) (xy 171.942506 -317.21679) (xy 171.942008 -317.243439) (xy 171.934065 -317.296143)
			(xy 171.918355 -317.347073) (xy 171.895229 -317.395094) (xy 171.865205 -317.439131) (xy 171.828953 -317.478202)
			(xy 171.787282 -317.511433) (xy 171.741124 -317.538082) (xy 171.69151 -317.557554) (xy 171.639548 -317.569414)
			(xy 171.586398 -317.573398) (xy 171.533248 -317.569414) (xy 171.481286 -317.557554) (xy 171.431672 -317.538082)
			(xy 171.385514 -317.511433) (xy 171.343843 -317.478202) (xy 171.307591 -317.439131) (xy 171.277567 -317.395094)
			(xy 171.254441 -317.347073) (xy 171.238731 -317.296143) (xy 171.230788 -317.243439) (xy 167.810015 -317.243439)
			(xy 167.809613 -317.246105) (xy 167.793903 -317.297035) (xy 167.770777 -317.345056) (xy 167.740753 -317.389093)
			(xy 167.704501 -317.428164) (xy 167.66283 -317.461395) (xy 167.616672 -317.488044) (xy 167.567058 -317.507516)
			(xy 167.515096 -317.519376) (xy 167.461946 -317.52336) (xy 167.408796 -317.519376) (xy 167.356834 -317.507516)
			(xy 167.30722 -317.488044) (xy 167.261062 -317.461395) (xy 167.219391 -317.428164) (xy 167.183139 -317.389093)
			(xy 167.153115 -317.345056) (xy 167.129989 -317.297035) (xy 167.114279 -317.246105) (xy 167.106336 -317.193401)
			(xy 165.607756 -317.193401) (xy 165.599813 -317.246105) (xy 165.584103 -317.297035) (xy 165.560977 -317.345056)
			(xy 165.530953 -317.389093) (xy 165.494701 -317.428164) (xy 165.45303 -317.461395) (xy 165.406872 -317.488044)
			(xy 165.357258 -317.507516) (xy 165.305296 -317.519376) (xy 165.252146 -317.52336) (xy 165.198996 -317.519376)
			(xy 165.147034 -317.507516) (xy 165.09742 -317.488044) (xy 165.051262 -317.461395) (xy 165.009591 -317.428164)
			(xy 164.973339 -317.389093) (xy 164.943315 -317.345056) (xy 164.920189 -317.297035) (xy 164.904479 -317.246105)
			(xy 164.896536 -317.193401) (xy 164.413908 -317.193401) (xy 164.413448 -317.218039) (xy 164.405505 -317.270743)
			(xy 164.389795 -317.321673) (xy 164.366669 -317.369694) (xy 164.336645 -317.413731) (xy 164.300393 -317.452802)
			(xy 164.258722 -317.486033) (xy 164.212564 -317.512682) (xy 164.16295 -317.532154) (xy 164.110988 -317.544014)
			(xy 164.057838 -317.547998) (xy 164.004688 -317.544014) (xy 163.952726 -317.532154) (xy 163.903112 -317.512682)
			(xy 163.856954 -317.486033) (xy 163.815283 -317.452802) (xy 163.779031 -317.413731) (xy 163.749007 -317.369694)
			(xy 163.725881 -317.321673) (xy 163.710171 -317.270743) (xy 163.702228 -317.218039) (xy 160.270702 -317.218039)
			(xy 160.261298 -317.263808) (xy 160.243582 -317.312598) (xy 160.218971 -317.3583) (xy 160.187987 -317.399946)
			(xy 160.151285 -317.436652) (xy 160.109644 -317.467643) (xy 160.063946 -317.492261) (xy 160.015158 -317.509984)
			(xy 159.964314 -317.520438) (xy 159.912492 -317.523401) (xy 159.860788 -317.51881) (xy 159.810298 -317.506762)
			(xy 159.786066 -317.49746) (xy 159.754824 -317.485014) (xy 159.708596 -317.531242) (xy 159.708596 -317.590932)
			(xy 216.59418 -317.590932) (xy 216.598251 -317.53531) (xy 216.610377 -317.480873) (xy 216.6303 -317.428782)
			(xy 216.657596 -317.380147) (xy 216.691682 -317.336004) (xy 216.731831 -317.297295) (xy 216.777189 -317.264844)
			(xy 216.826789 -317.239343) (xy 216.879573 -317.221336) (xy 216.934416 -317.211206) (xy 216.99015 -317.209169)
			(xy 217.045587 -317.215269) (xy 217.099544 -317.229375) (xy 217.150873 -317.251187) (xy 217.198479 -317.280241)
			(xy 217.241347 -317.315916) (xy 217.278564 -317.357453) (xy 217.309337 -317.403966) (xy 217.333009 -317.454463)
			(xy 217.349077 -317.50787) (xy 217.357197 -317.563046) (xy 217.357706 -317.590932) (xy 217.357197 -317.618818)
			(xy 217.349077 -317.673994) (xy 217.333009 -317.727401) (xy 217.309337 -317.777898) (xy 217.278564 -317.824411)
			(xy 217.241347 -317.865948) (xy 217.198479 -317.901623) (xy 217.179449 -317.913237) (xy 254.14477 -317.913237)
			(xy 254.14477 -317.859939) (xy 254.152713 -317.807235) (xy 254.168423 -317.756305) (xy 254.191549 -317.708284)
			(xy 254.221573 -317.664247) (xy 254.257825 -317.625176) (xy 254.299496 -317.591945) (xy 254.345654 -317.565296)
			(xy 254.395268 -317.545824) (xy 254.44723 -317.533964) (xy 254.50038 -317.529981) (xy 254.55353 -317.533964)
			(xy 254.605492 -317.545824) (xy 254.655106 -317.565296) (xy 254.659438 -317.567797) (xy 280.61919 -317.567797)
			(xy 280.61919 -317.514499) (xy 280.627133 -317.461795) (xy 280.642843 -317.410865) (xy 280.665969 -317.362844)
			(xy 280.695993 -317.318807) (xy 280.732245 -317.279736) (xy 280.773916 -317.246505) (xy 280.820074 -317.219856)
			(xy 280.869688 -317.200384) (xy 280.92165 -317.188524) (xy 280.9748 -317.184541) (xy 281.02795 -317.188524)
			(xy 281.079912 -317.200384) (xy 281.129526 -317.219856) (xy 281.175684 -317.246505) (xy 281.217355 -317.279736)
			(xy 281.253607 -317.318807) (xy 281.283631 -317.362844) (xy 281.306757 -317.410865) (xy 281.322467 -317.461795)
			(xy 281.33041 -317.514499) (xy 281.330908 -317.541148) (xy 281.33041 -317.567797) (xy 281.322467 -317.620501)
			(xy 281.306757 -317.671431) (xy 281.283631 -317.719452) (xy 281.253607 -317.763489) (xy 281.217355 -317.80256)
			(xy 281.175684 -317.835791) (xy 281.129526 -317.86244) (xy 281.079912 -317.881912) (xy 281.02795 -317.893772)
			(xy 280.9748 -317.897756) (xy 280.92165 -317.893772) (xy 280.869688 -317.881912) (xy 280.820074 -317.86244)
			(xy 280.773916 -317.835791) (xy 280.732245 -317.80256) (xy 280.695993 -317.763489) (xy 280.665969 -317.719452)
			(xy 280.642843 -317.671431) (xy 280.627133 -317.620501) (xy 280.61919 -317.567797) (xy 254.659438 -317.567797)
			(xy 254.701264 -317.591945) (xy 254.742935 -317.625176) (xy 254.779187 -317.664247) (xy 254.809211 -317.708284)
			(xy 254.832337 -317.756305) (xy 254.848047 -317.807235) (xy 254.85599 -317.859939) (xy 254.856488 -317.886588)
			(xy 254.85599 -317.913237) (xy 254.848047 -317.965941) (xy 254.832337 -318.016871) (xy 254.819617 -318.043285)
			(xy 258.720072 -318.043285) (xy 258.720072 -317.989987) (xy 258.728015 -317.937283) (xy 258.743725 -317.886353)
			(xy 258.766851 -317.838332) (xy 258.796875 -317.794295) (xy 258.833127 -317.755224) (xy 258.874798 -317.721993)
			(xy 258.920956 -317.695344) (xy 258.97057 -317.675872) (xy 259.022532 -317.664012) (xy 259.075682 -317.660029)
			(xy 259.128832 -317.664012) (xy 259.180794 -317.675872) (xy 259.230408 -317.695344) (xy 259.276566 -317.721993)
			(xy 259.318237 -317.755224) (xy 259.354489 -317.794295) (xy 259.384513 -317.838332) (xy 259.407639 -317.886353)
			(xy 259.423349 -317.937283) (xy 259.431292 -317.989987) (xy 259.43179 -318.016636) (xy 259.431292 -318.043285)
			(xy 259.423349 -318.095989) (xy 259.420959 -318.103737) (xy 268.73453 -318.103737) (xy 268.73453 -318.050439)
			(xy 268.742473 -317.997735) (xy 268.758183 -317.946805) (xy 268.781309 -317.898784) (xy 268.811333 -317.854747)
			(xy 268.847585 -317.815676) (xy 268.889256 -317.782445) (xy 268.935414 -317.755796) (xy 268.985028 -317.736324)
			(xy 269.03699 -317.724464) (xy 269.09014 -317.720481) (xy 269.14329 -317.724464) (xy 269.195252 -317.736324)
			(xy 269.244866 -317.755796) (xy 269.291024 -317.782445) (xy 269.332695 -317.815676) (xy 269.368947 -317.854747)
			(xy 269.398971 -317.898784) (xy 269.422097 -317.946805) (xy 269.437807 -317.997735) (xy 269.44575 -318.050439)
			(xy 269.446248 -318.077088) (xy 269.44575 -318.103737) (xy 269.444946 -318.109071) (xy 276.062938 -318.109071)
			(xy 276.062938 -318.055773) (xy 276.070881 -318.003069) (xy 276.086591 -317.952139) (xy 276.109717 -317.904118)
			(xy 276.139741 -317.860081) (xy 276.175993 -317.82101) (xy 276.217664 -317.787779) (xy 276.263822 -317.76113)
			(xy 276.313436 -317.741658) (xy 276.365398 -317.729798) (xy 276.418548 -317.725815) (xy 276.471698 -317.729798)
			(xy 276.52366 -317.741658) (xy 276.573274 -317.76113) (xy 276.619432 -317.787779) (xy 276.661103 -317.82101)
			(xy 276.697355 -317.860081) (xy 276.727379 -317.904118) (xy 276.750505 -317.952139) (xy 276.766215 -318.003069)
			(xy 276.772276 -318.043285) (xy 288.895272 -318.043285) (xy 288.895272 -317.989987) (xy 288.903215 -317.937283)
			(xy 288.918925 -317.886353) (xy 288.942051 -317.838332) (xy 288.972075 -317.794295) (xy 289.008327 -317.755224)
			(xy 289.049998 -317.721993) (xy 289.096156 -317.695344) (xy 289.14577 -317.675872) (xy 289.197732 -317.664012)
			(xy 289.250882 -317.660029) (xy 289.304032 -317.664012) (xy 289.355994 -317.675872) (xy 289.405608 -317.695344)
			(xy 289.451766 -317.721993) (xy 289.493437 -317.755224) (xy 289.529689 -317.794295) (xy 289.559713 -317.838332)
			(xy 289.582839 -317.886353) (xy 289.598549 -317.937283) (xy 289.606492 -317.989987) (xy 289.60699 -318.016636)
			(xy 289.606492 -318.043285) (xy 296.439072 -318.043285) (xy 296.439072 -317.989987) (xy 296.447015 -317.937283)
			(xy 296.462725 -317.886353) (xy 296.485851 -317.838332) (xy 296.515875 -317.794295) (xy 296.552127 -317.755224)
			(xy 296.593798 -317.721993) (xy 296.639956 -317.695344) (xy 296.68957 -317.675872) (xy 296.741532 -317.664012)
			(xy 296.794682 -317.660029) (xy 296.847832 -317.664012) (xy 296.899794 -317.675872) (xy 296.949408 -317.695344)
			(xy 296.995566 -317.721993) (xy 297.037237 -317.755224) (xy 297.073489 -317.794295) (xy 297.103513 -317.838332)
			(xy 297.126639 -317.886353) (xy 297.142349 -317.937283) (xy 297.150292 -317.989987) (xy 297.15079 -318.016636)
			(xy 297.150292 -318.043285) (xy 297.142349 -318.095989) (xy 297.126639 -318.146919) (xy 297.103513 -318.19494)
			(xy 297.073489 -318.238977) (xy 297.037237 -318.278048) (xy 296.995566 -318.311279) (xy 296.949408 -318.337928)
			(xy 296.899794 -318.3574) (xy 296.847832 -318.36926) (xy 296.794682 -318.373244) (xy 296.741532 -318.36926)
			(xy 296.68957 -318.3574) (xy 296.639956 -318.337928) (xy 296.593798 -318.311279) (xy 296.552127 -318.278048)
			(xy 296.515875 -318.238977) (xy 296.485851 -318.19494) (xy 296.462725 -318.146919) (xy 296.447015 -318.095989)
			(xy 296.439072 -318.043285) (xy 289.606492 -318.043285) (xy 289.598549 -318.095989) (xy 289.582839 -318.146919)
			(xy 289.559713 -318.19494) (xy 289.529689 -318.238977) (xy 289.493437 -318.278048) (xy 289.451766 -318.311279)
			(xy 289.405608 -318.337928) (xy 289.355994 -318.3574) (xy 289.304032 -318.36926) (xy 289.250882 -318.373244)
			(xy 289.197732 -318.36926) (xy 289.14577 -318.3574) (xy 289.096156 -318.337928) (xy 289.049998 -318.311279)
			(xy 289.008327 -318.278048) (xy 288.972075 -318.238977) (xy 288.942051 -318.19494) (xy 288.918925 -318.146919)
			(xy 288.903215 -318.095989) (xy 288.895272 -318.043285) (xy 276.772276 -318.043285) (xy 276.774158 -318.055773)
			(xy 276.774656 -318.082422) (xy 276.774158 -318.109071) (xy 276.766215 -318.161775) (xy 276.750505 -318.212705)
			(xy 276.727379 -318.260726) (xy 276.697355 -318.304763) (xy 276.661103 -318.343834) (xy 276.619432 -318.377065)
			(xy 276.573274 -318.403714) (xy 276.52366 -318.423186) (xy 276.471698 -318.435046) (xy 276.418548 -318.43903)
			(xy 276.365398 -318.435046) (xy 276.313436 -318.423186) (xy 276.263822 -318.403714) (xy 276.217664 -318.377065)
			(xy 276.175993 -318.343834) (xy 276.139741 -318.304763) (xy 276.109717 -318.260726) (xy 276.086591 -318.212705)
			(xy 276.070881 -318.161775) (xy 276.062938 -318.109071) (xy 269.444946 -318.109071) (xy 269.437807 -318.156441)
			(xy 269.422097 -318.207371) (xy 269.398971 -318.255392) (xy 269.368947 -318.299429) (xy 269.332695 -318.3385)
			(xy 269.291024 -318.371731) (xy 269.244866 -318.39838) (xy 269.195252 -318.417852) (xy 269.14329 -318.429712)
			(xy 269.09014 -318.433696) (xy 269.03699 -318.429712) (xy 268.985028 -318.417852) (xy 268.935414 -318.39838)
			(xy 268.889256 -318.371731) (xy 268.847585 -318.3385) (xy 268.811333 -318.299429) (xy 268.781309 -318.255392)
			(xy 268.758183 -318.207371) (xy 268.742473 -318.156441) (xy 268.73453 -318.103737) (xy 259.420959 -318.103737)
			(xy 259.407639 -318.146919) (xy 259.384513 -318.19494) (xy 259.354489 -318.238977) (xy 259.318237 -318.278048)
			(xy 259.276566 -318.311279) (xy 259.230408 -318.337928) (xy 259.180794 -318.3574) (xy 259.128832 -318.36926)
			(xy 259.075682 -318.373244) (xy 259.022532 -318.36926) (xy 258.97057 -318.3574) (xy 258.920956 -318.337928)
			(xy 258.874798 -318.311279) (xy 258.833127 -318.278048) (xy 258.796875 -318.238977) (xy 258.766851 -318.19494)
			(xy 258.743725 -318.146919) (xy 258.728015 -318.095989) (xy 258.720072 -318.043285) (xy 254.819617 -318.043285)
			(xy 254.809211 -318.064892) (xy 254.779187 -318.108929) (xy 254.742935 -318.148) (xy 254.701264 -318.181231)
			(xy 254.655106 -318.20788) (xy 254.605492 -318.227352) (xy 254.55353 -318.239212) (xy 254.50038 -318.243196)
			(xy 254.44723 -318.239212) (xy 254.395268 -318.227352) (xy 254.345654 -318.20788) (xy 254.299496 -318.181231)
			(xy 254.257825 -318.148) (xy 254.221573 -318.108929) (xy 254.191549 -318.064892) (xy 254.168423 -318.016871)
			(xy 254.152713 -317.965941) (xy 254.14477 -317.913237) (xy 217.179449 -317.913237) (xy 217.150873 -317.930677)
			(xy 217.099544 -317.952489) (xy 217.045587 -317.966595) (xy 216.99015 -317.972695) (xy 216.934416 -317.970658)
			(xy 216.879573 -317.960528) (xy 216.826789 -317.942521) (xy 216.777189 -317.91702) (xy 216.731831 -317.884569)
			(xy 216.691682 -317.84586) (xy 216.657596 -317.801717) (xy 216.6303 -317.753082) (xy 216.610377 -317.700991)
			(xy 216.598251 -317.646554) (xy 216.59418 -317.590932) (xy 159.708596 -317.590932) (xy 159.708596 -318.043285)
			(xy 161.452804 -318.043285) (xy 161.452804 -317.989987) (xy 161.460747 -317.937283) (xy 161.476457 -317.886353)
			(xy 161.499583 -317.838332) (xy 161.529607 -317.794295) (xy 161.565859 -317.755224) (xy 161.60753 -317.721993)
			(xy 161.653688 -317.695344) (xy 161.703302 -317.675872) (xy 161.755264 -317.664012) (xy 161.808414 -317.660029)
			(xy 161.861564 -317.664012) (xy 161.913526 -317.675872) (xy 161.96314 -317.695344) (xy 162.009298 -317.721993)
			(xy 162.050969 -317.755224) (xy 162.087221 -317.794295) (xy 162.117245 -317.838332) (xy 162.140371 -317.886353)
			(xy 162.156081 -317.937283) (xy 162.164024 -317.989987) (xy 162.164522 -318.016636) (xy 162.164024 -318.043285)
			(xy 168.996604 -318.043285) (xy 168.996604 -317.989987) (xy 169.004547 -317.937283) (xy 169.020257 -317.886353)
			(xy 169.043383 -317.838332) (xy 169.073407 -317.794295) (xy 169.109659 -317.755224) (xy 169.15133 -317.721993)
			(xy 169.197488 -317.695344) (xy 169.247102 -317.675872) (xy 169.299064 -317.664012) (xy 169.352214 -317.660029)
			(xy 169.405364 -317.664012) (xy 169.457326 -317.675872) (xy 169.50694 -317.695344) (xy 169.553098 -317.721993)
			(xy 169.594769 -317.755224) (xy 169.631021 -317.794295) (xy 169.661045 -317.838332) (xy 169.684171 -317.886353)
			(xy 169.699881 -317.937283) (xy 169.707824 -317.989987) (xy 169.708322 -318.016636) (xy 169.707824 -318.043285)
			(xy 169.699881 -318.095989) (xy 169.684171 -318.146919) (xy 169.679524 -318.156569) (xy 175.471572 -318.156569)
			(xy 175.471572 -318.103271) (xy 175.479515 -318.050567) (xy 175.495225 -317.999637) (xy 175.518351 -317.951616)
			(xy 175.548375 -317.907579) (xy 175.584627 -317.868508) (xy 175.626298 -317.835277) (xy 175.672456 -317.808628)
			(xy 175.72207 -317.789156) (xy 175.774032 -317.777296) (xy 175.827182 -317.773313) (xy 175.880332 -317.777296)
			(xy 175.932294 -317.789156) (xy 175.981908 -317.808628) (xy 176.028066 -317.835277) (xy 176.069737 -317.868508)
			(xy 176.105989 -317.907579) (xy 176.136013 -317.951616) (xy 176.159139 -317.999637) (xy 176.172603 -318.043285)
			(xy 178.723788 -318.043285) (xy 178.723788 -317.989987) (xy 178.731731 -317.937283) (xy 178.747441 -317.886353)
			(xy 178.770567 -317.838332) (xy 178.800591 -317.794295) (xy 178.836843 -317.755224) (xy 178.878514 -317.721993)
			(xy 178.924672 -317.695344) (xy 178.974286 -317.675872) (xy 179.026248 -317.664012) (xy 179.079398 -317.660029)
			(xy 179.132548 -317.664012) (xy 179.18451 -317.675872) (xy 179.234124 -317.695344) (xy 179.280282 -317.721993)
			(xy 179.321953 -317.755224) (xy 179.358205 -317.794295) (xy 179.388229 -317.838332) (xy 179.411355 -317.886353)
			(xy 179.427065 -317.937283) (xy 179.435008 -317.989987) (xy 179.435506 -318.016636) (xy 179.435008 -318.043285)
			(xy 186.326008 -318.043285) (xy 186.326008 -317.989987) (xy 186.333951 -317.937283) (xy 186.349661 -317.886353)
			(xy 186.372787 -317.838332) (xy 186.402811 -317.794295) (xy 186.439063 -317.755224) (xy 186.480734 -317.721993)
			(xy 186.526892 -317.695344) (xy 186.576506 -317.675872) (xy 186.628468 -317.664012) (xy 186.681618 -317.660029)
			(xy 186.734768 -317.664012) (xy 186.78673 -317.675872) (xy 186.836344 -317.695344) (xy 186.882502 -317.721993)
			(xy 186.924173 -317.755224) (xy 186.960425 -317.794295) (xy 186.990449 -317.838332) (xy 187.013575 -317.886353)
			(xy 187.029285 -317.937283) (xy 187.037228 -317.989987) (xy 187.037726 -318.016636) (xy 187.037228 -318.043285)
			(xy 191.628004 -318.043285) (xy 191.628004 -317.989987) (xy 191.635947 -317.937283) (xy 191.651657 -317.886353)
			(xy 191.674783 -317.838332) (xy 191.704807 -317.794295) (xy 191.741059 -317.755224) (xy 191.78273 -317.721993)
			(xy 191.828888 -317.695344) (xy 191.878502 -317.675872) (xy 191.930464 -317.664012) (xy 191.983614 -317.660029)
			(xy 192.036764 -317.664012) (xy 192.088726 -317.675872) (xy 192.13834 -317.695344) (xy 192.184498 -317.721993)
			(xy 192.226169 -317.755224) (xy 192.262421 -317.794295) (xy 192.292445 -317.838332) (xy 192.315571 -317.886353)
			(xy 192.331281 -317.937283) (xy 192.339224 -317.989987) (xy 192.339552 -318.007539) (xy 201.359405 -318.007539)
			(xy 201.364888 -317.95366) (xy 201.378467 -317.901233) (xy 201.399828 -317.851466) (xy 201.428479 -317.805508)
			(xy 201.463759 -317.764418) (xy 201.504854 -317.729145) (xy 201.550817 -317.700501) (xy 201.600588 -317.679148)
			(xy 201.653017 -317.665578) (xy 201.706897 -317.660104) (xy 201.760985 -317.662851) (xy 201.814033 -317.673758)
			(xy 201.864818 -317.692572) (xy 201.912168 -317.718859) (xy 201.954991 -317.752013) (xy 201.9923 -317.79127)
			(xy 202.023234 -317.835723) (xy 202.04708 -317.884348) (xy 202.063288 -317.936023) (xy 202.071483 -317.989557)
			(xy 202.071986 -318.016636) (xy 202.07145 -318.043285) (xy 208.909148 -318.043285) (xy 208.909148 -317.989987)
			(xy 208.917091 -317.937283) (xy 208.932801 -317.886353) (xy 208.955927 -317.838332) (xy 208.985951 -317.794295)
			(xy 209.022203 -317.755224) (xy 209.063874 -317.721993) (xy 209.110032 -317.695344) (xy 209.159646 -317.675872)
			(xy 209.211608 -317.664012) (xy 209.264758 -317.660029) (xy 209.317908 -317.664012) (xy 209.36987 -317.675872)
			(xy 209.419484 -317.695344) (xy 209.465642 -317.721993) (xy 209.507313 -317.755224) (xy 209.543565 -317.794295)
			(xy 209.573589 -317.838332) (xy 209.596715 -317.886353) (xy 209.612425 -317.937283) (xy 209.620368 -317.989987)
			(xy 209.620866 -318.016636) (xy 209.620368 -318.043285) (xy 214.259404 -318.043285) (xy 214.259404 -317.989987)
			(xy 214.267347 -317.937283) (xy 214.283057 -317.886353) (xy 214.306183 -317.838332) (xy 214.336207 -317.794295)
			(xy 214.372459 -317.755224) (xy 214.41413 -317.721993) (xy 214.460288 -317.695344) (xy 214.509902 -317.675872)
			(xy 214.561864 -317.664012) (xy 214.615014 -317.660029) (xy 214.668164 -317.664012) (xy 214.720126 -317.675872)
			(xy 214.76974 -317.695344) (xy 214.815898 -317.721993) (xy 214.857569 -317.755224) (xy 214.893821 -317.794295)
			(xy 214.923845 -317.838332) (xy 214.946971 -317.886353) (xy 214.962681 -317.937283) (xy 214.970624 -317.989987)
			(xy 214.971122 -318.016636) (xy 214.970624 -318.043285) (xy 214.962681 -318.095989) (xy 214.946971 -318.146919)
			(xy 214.923845 -318.19494) (xy 214.893821 -318.238977) (xy 214.857569 -318.278048) (xy 214.815898 -318.311279)
			(xy 214.76974 -318.337928) (xy 214.720126 -318.3574) (xy 214.668164 -318.36926) (xy 214.615014 -318.373244)
			(xy 214.561864 -318.36926) (xy 214.509902 -318.3574) (xy 214.460288 -318.337928) (xy 214.41413 -318.311279)
			(xy 214.372459 -318.278048) (xy 214.336207 -318.238977) (xy 214.306183 -318.19494) (xy 214.283057 -318.146919)
			(xy 214.267347 -318.095989) (xy 214.259404 -318.043285) (xy 209.620368 -318.043285) (xy 209.612425 -318.095989)
			(xy 209.596715 -318.146919) (xy 209.573589 -318.19494) (xy 209.543565 -318.238977) (xy 209.507313 -318.278048)
			(xy 209.465642 -318.311279) (xy 209.419484 -318.337928) (xy 209.36987 -318.3574) (xy 209.317908 -318.36926)
			(xy 209.264758 -318.373244) (xy 209.211608 -318.36926) (xy 209.159646 -318.3574) (xy 209.110032 -318.337928)
			(xy 209.063874 -318.311279) (xy 209.022203 -318.278048) (xy 208.985951 -318.238977) (xy 208.955927 -318.19494)
			(xy 208.932801 -318.146919) (xy 208.917091 -318.095989) (xy 208.909148 -318.043285) (xy 202.07145 -318.043285)
			(xy 202.071359 -318.047836) (xy 202.060495 -318.109283) (xy 202.050396 -318.13881) (xy 202.046157 -318.151897)
			(xy 202.043956 -318.179301) (xy 202.049146 -318.2063) (xy 202.061353 -318.230934) (xy 202.07969 -318.251419)
			(xy 202.102828 -318.266268) (xy 202.129089 -318.274404) (xy 202.156569 -318.275239) (xy 202.17003 -318.272414)
			(xy 202.190969 -318.267569) (xy 202.233631 -318.262353) (xy 202.25512 -318.262) (xy 202.282198 -318.262519)
			(xy 202.33573 -318.270723) (xy 202.387402 -318.286938) (xy 202.436022 -318.31079) (xy 202.48047 -318.34173)
			(xy 202.519721 -318.379044) (xy 202.552869 -318.421871) (xy 202.579149 -318.469223) (xy 202.597956 -318.520009)
			(xy 202.608856 -318.573057) (xy 202.611597 -318.627144) (xy 202.606117 -318.681023) (xy 202.592541 -318.73345)
			(xy 202.571183 -318.783217) (xy 202.542535 -318.829176) (xy 202.507259 -318.870267) (xy 202.480284 -318.893423)
			(xy 206.715604 -318.893423) (xy 206.715604 -318.840125) (xy 206.723547 -318.787421) (xy 206.739257 -318.736491)
			(xy 206.762383 -318.68847) (xy 206.792407 -318.644433) (xy 206.828659 -318.605362) (xy 206.87033 -318.572131)
			(xy 206.916488 -318.545482) (xy 206.966102 -318.52601) (xy 207.018064 -318.51415) (xy 207.071214 -318.510167)
			(xy 207.124364 -318.51415) (xy 207.176326 -318.52601) (xy 207.22594 -318.545482) (xy 207.272098 -318.572131)
			(xy 207.313769 -318.605362) (xy 207.350021 -318.644433) (xy 207.376391 -318.683111) (xy 209.575644 -318.683111)
			(xy 209.575644 -318.629813) (xy 209.583587 -318.577109) (xy 209.599297 -318.526179) (xy 209.622423 -318.478158)
			(xy 209.652447 -318.434121) (xy 209.688699 -318.39505) (xy 209.73037 -318.361819) (xy 209.776528 -318.33517)
			(xy 209.826142 -318.315698) (xy 209.878104 -318.303838) (xy 209.931254 -318.299855) (xy 209.984404 -318.303838)
			(xy 210.036366 -318.315698) (xy 210.08598 -318.33517) (xy 210.132138 -318.361819) (xy 210.173809 -318.39505)
			(xy 210.210061 -318.434121) (xy 210.240085 -318.478158) (xy 210.263211 -318.526179) (xy 210.278921 -318.577109)
			(xy 210.286864 -318.629813) (xy 210.287362 -318.656462) (xy 210.286864 -318.683111) (xy 210.278921 -318.735815)
			(xy 210.263211 -318.786745) (xy 210.240085 -318.834766) (xy 210.210061 -318.878803) (xy 210.196496 -318.893423)
			(xy 258.720072 -318.893423) (xy 258.720072 -318.840125) (xy 258.728015 -318.787421) (xy 258.743725 -318.736491)
			(xy 258.766851 -318.68847) (xy 258.796875 -318.644433) (xy 258.833127 -318.605362) (xy 258.874798 -318.572131)
			(xy 258.920956 -318.545482) (xy 258.97057 -318.52601) (xy 259.022532 -318.51415) (xy 259.075682 -318.510167)
			(xy 259.128832 -318.51415) (xy 259.180794 -318.52601) (xy 259.230408 -318.545482) (xy 259.276566 -318.572131)
			(xy 259.318237 -318.605362) (xy 259.354489 -318.644433) (xy 259.384513 -318.68847) (xy 259.407639 -318.736491)
			(xy 259.423349 -318.787421) (xy 259.431292 -318.840125) (xy 259.43179 -318.866774) (xy 259.431292 -318.893423)
			(xy 259.423349 -318.946127) (xy 259.407639 -318.997057) (xy 259.384513 -319.045078) (xy 259.373441 -319.061317)
			(xy 261.33297 -319.061317) (xy 261.33297 -319.008019) (xy 261.340913 -318.955315) (xy 261.356623 -318.904385)
			(xy 261.379749 -318.856364) (xy 261.409773 -318.812327) (xy 261.446025 -318.773256) (xy 261.487696 -318.740025)
			(xy 261.533854 -318.713376) (xy 261.583468 -318.693904) (xy 261.63543 -318.682044) (xy 261.68858 -318.678061)
			(xy 261.74173 -318.682044) (xy 261.793692 -318.693904) (xy 261.843306 -318.713376) (xy 261.889464 -318.740025)
			(xy 261.931135 -318.773256) (xy 261.967387 -318.812327) (xy 261.997411 -318.856364) (xy 262.020537 -318.904385)
			(xy 262.036247 -318.955315) (xy 262.04419 -319.008019) (xy 262.044688 -319.034668) (xy 262.04419 -319.061317)
			(xy 262.036247 -319.114021) (xy 262.020537 -319.164951) (xy 261.997411 -319.212972) (xy 261.967387 -319.257009)
			(xy 261.931135 -319.29608) (xy 261.889464 -319.329311) (xy 261.843306 -319.35596) (xy 261.793692 -319.375432)
			(xy 261.74173 -319.387292) (xy 261.68858 -319.391276) (xy 261.63543 -319.387292) (xy 261.583468 -319.375432)
			(xy 261.533854 -319.35596) (xy 261.487696 -319.329311) (xy 261.446025 -319.29608) (xy 261.409773 -319.257009)
			(xy 261.379749 -319.212972) (xy 261.356623 -319.164951) (xy 261.340913 -319.114021) (xy 261.33297 -319.061317)
			(xy 259.373441 -319.061317) (xy 259.354489 -319.089115) (xy 259.318237 -319.128186) (xy 259.276566 -319.161417)
			(xy 259.230408 -319.188066) (xy 259.180794 -319.207538) (xy 259.128832 -319.219398) (xy 259.075682 -319.223382)
			(xy 259.022532 -319.219398) (xy 258.97057 -319.207538) (xy 258.920956 -319.188066) (xy 258.874798 -319.161417)
			(xy 258.833127 -319.128186) (xy 258.796875 -319.089115) (xy 258.766851 -319.045078) (xy 258.743725 -318.997057)
			(xy 258.728015 -318.946127) (xy 258.720072 -318.893423) (xy 210.196496 -318.893423) (xy 210.173809 -318.917874)
			(xy 210.132138 -318.951105) (xy 210.08598 -318.977754) (xy 210.036366 -318.997226) (xy 209.984404 -319.009086)
			(xy 209.931254 -319.01307) (xy 209.878104 -319.009086) (xy 209.826142 -318.997226) (xy 209.776528 -318.977754)
			(xy 209.73037 -318.951105) (xy 209.688699 -318.917874) (xy 209.652447 -318.878803) (xy 209.622423 -318.834766)
			(xy 209.599297 -318.786745) (xy 209.583587 -318.735815) (xy 209.575644 -318.683111) (xy 207.376391 -318.683111)
			(xy 207.380045 -318.68847) (xy 207.403171 -318.736491) (xy 207.418881 -318.787421) (xy 207.426824 -318.840125)
			(xy 207.427322 -318.866774) (xy 207.426824 -318.893423) (xy 207.418881 -318.946127) (xy 207.403171 -318.997057)
			(xy 207.380045 -319.045078) (xy 207.350021 -319.089115) (xy 207.313769 -319.128186) (xy 207.272098 -319.161417)
			(xy 207.22594 -319.188066) (xy 207.176326 -319.207538) (xy 207.124364 -319.219398) (xy 207.071214 -319.223382)
			(xy 207.018064 -319.219398) (xy 206.966102 -319.207538) (xy 206.916488 -319.188066) (xy 206.87033 -319.161417)
			(xy 206.828659 -319.128186) (xy 206.792407 -319.089115) (xy 206.762383 -319.045078) (xy 206.739257 -318.997057)
			(xy 206.723547 -318.946127) (xy 206.715604 -318.893423) (xy 202.480284 -318.893423) (xy 202.466166 -318.905542)
			(xy 202.420206 -318.934189) (xy 202.370439 -318.955545) (xy 202.318011 -318.969119) (xy 202.264132 -318.974598)
			(xy 202.210046 -318.971854) (xy 202.156998 -318.960953) (xy 202.106212 -318.942144) (xy 202.058861 -318.915862)
			(xy 202.016035 -318.882713) (xy 201.978723 -318.843461) (xy 201.947784 -318.799012) (xy 201.923933 -318.75039)
			(xy 201.90772 -318.698718) (xy 201.899518 -318.645186) (xy 201.899012 -318.618108) (xy 201.899651 -318.586908)
			(xy 201.910506 -318.525462) (xy 201.920602 -318.495934) (xy 201.924907 -318.482868) (xy 201.927097 -318.455456)
			(xy 201.921896 -318.428452) (xy 201.909679 -318.403815) (xy 201.891334 -318.383328) (xy 201.868188 -318.368479)
			(xy 201.84192 -318.360341) (xy 201.814432 -318.359505) (xy 201.800968 -318.36233) (xy 201.780029 -318.367174)
			(xy 201.737367 -318.372391) (xy 201.715878 -318.372744) (xy 201.688799 -318.372179) (xy 201.635267 -318.363974)
			(xy 201.583594 -318.347758) (xy 201.534973 -318.323905) (xy 201.490524 -318.292963) (xy 201.451274 -318.255648)
			(xy 201.418127 -318.212819) (xy 201.391848 -318.165465) (xy 201.373042 -318.114677) (xy 201.362144 -318.061627)
			(xy 201.359405 -318.007539) (xy 192.339552 -318.007539) (xy 192.339722 -318.016636) (xy 192.339224 -318.043285)
			(xy 192.331281 -318.095989) (xy 192.315571 -318.146919) (xy 192.292445 -318.19494) (xy 192.262421 -318.238977)
			(xy 192.226169 -318.278048) (xy 192.184498 -318.311279) (xy 192.13834 -318.337928) (xy 192.088726 -318.3574)
			(xy 192.036764 -318.36926) (xy 191.983614 -318.373244) (xy 191.930464 -318.36926) (xy 191.878502 -318.3574)
			(xy 191.828888 -318.337928) (xy 191.78273 -318.311279) (xy 191.741059 -318.278048) (xy 191.704807 -318.238977)
			(xy 191.674783 -318.19494) (xy 191.651657 -318.146919) (xy 191.635947 -318.095989) (xy 191.628004 -318.043285)
			(xy 187.037228 -318.043285) (xy 187.029285 -318.095989) (xy 187.013575 -318.146919) (xy 186.990449 -318.19494)
			(xy 186.960425 -318.238977) (xy 186.924173 -318.278048) (xy 186.882502 -318.311279) (xy 186.836344 -318.337928)
			(xy 186.78673 -318.3574) (xy 186.734768 -318.36926) (xy 186.681618 -318.373244) (xy 186.628468 -318.36926)
			(xy 186.576506 -318.3574) (xy 186.526892 -318.337928) (xy 186.480734 -318.311279) (xy 186.439063 -318.278048)
			(xy 186.402811 -318.238977) (xy 186.372787 -318.19494) (xy 186.349661 -318.146919) (xy 186.333951 -318.095989)
			(xy 186.326008 -318.043285) (xy 179.435008 -318.043285) (xy 179.427065 -318.095989) (xy 179.411355 -318.146919)
			(xy 179.388229 -318.19494) (xy 179.358205 -318.238977) (xy 179.321953 -318.278048) (xy 179.280282 -318.311279)
			(xy 179.234124 -318.337928) (xy 179.18451 -318.3574) (xy 179.132548 -318.36926) (xy 179.079398 -318.373244)
			(xy 179.026248 -318.36926) (xy 178.974286 -318.3574) (xy 178.924672 -318.337928) (xy 178.878514 -318.311279)
			(xy 178.836843 -318.278048) (xy 178.800591 -318.238977) (xy 178.770567 -318.19494) (xy 178.747441 -318.146919)
			(xy 178.731731 -318.095989) (xy 178.723788 -318.043285) (xy 176.172603 -318.043285) (xy 176.174849 -318.050567)
			(xy 176.182792 -318.103271) (xy 176.18329 -318.12992) (xy 176.182792 -318.156569) (xy 176.174849 -318.209273)
			(xy 176.159139 -318.260203) (xy 176.136013 -318.308224) (xy 176.105989 -318.352261) (xy 176.069737 -318.391332)
			(xy 176.028066 -318.424563) (xy 175.981908 -318.451212) (xy 175.932294 -318.470684) (xy 175.880332 -318.482544)
			(xy 175.827182 -318.486528) (xy 175.774032 -318.482544) (xy 175.72207 -318.470684) (xy 175.672456 -318.451212)
			(xy 175.626298 -318.424563) (xy 175.584627 -318.391332) (xy 175.548375 -318.352261) (xy 175.518351 -318.308224)
			(xy 175.495225 -318.260203) (xy 175.479515 -318.209273) (xy 175.471572 -318.156569) (xy 169.679524 -318.156569)
			(xy 169.661045 -318.19494) (xy 169.631021 -318.238977) (xy 169.594769 -318.278048) (xy 169.553098 -318.311279)
			(xy 169.50694 -318.337928) (xy 169.457326 -318.3574) (xy 169.405364 -318.36926) (xy 169.352214 -318.373244)
			(xy 169.299064 -318.36926) (xy 169.247102 -318.3574) (xy 169.197488 -318.337928) (xy 169.15133 -318.311279)
			(xy 169.109659 -318.278048) (xy 169.073407 -318.238977) (xy 169.043383 -318.19494) (xy 169.020257 -318.146919)
			(xy 169.004547 -318.095989) (xy 168.996604 -318.043285) (xy 162.164024 -318.043285) (xy 162.156081 -318.095989)
			(xy 162.140371 -318.146919) (xy 162.117245 -318.19494) (xy 162.087221 -318.238977) (xy 162.050969 -318.278048)
			(xy 162.009298 -318.311279) (xy 161.96314 -318.337928) (xy 161.913526 -318.3574) (xy 161.861564 -318.36926)
			(xy 161.808414 -318.373244) (xy 161.755264 -318.36926) (xy 161.703302 -318.3574) (xy 161.653688 -318.337928)
			(xy 161.60753 -318.311279) (xy 161.565859 -318.278048) (xy 161.529607 -318.238977) (xy 161.499583 -318.19494)
			(xy 161.476457 -318.146919) (xy 161.460747 -318.095989) (xy 161.452804 -318.043285) (xy 159.708596 -318.043285)
			(xy 159.708596 -318.428878) (xy 159.709034 -318.442452) (xy 159.716203 -318.468636) (xy 159.730014 -318.492009)
			(xy 159.749493 -318.51092) (xy 159.773263 -318.524034) (xy 159.799648 -318.530425) (xy 159.826785 -318.529643)
			(xy 159.839914 -318.52616) (xy 159.865212 -318.51894) (xy 159.917242 -318.511166) (xy 159.943546 -318.510666)
			(xy 159.970195 -318.511167) (xy 160.022897 -318.519117) (xy 160.073826 -318.534832) (xy 160.121843 -318.557962)
			(xy 160.127696 -318.561953) (xy 164.205148 -318.561953) (xy 164.205148 -318.508655) (xy 164.213091 -318.455951)
			(xy 164.228801 -318.405021) (xy 164.251927 -318.357) (xy 164.281951 -318.312963) (xy 164.318203 -318.273892)
			(xy 164.359874 -318.240661) (xy 164.406032 -318.214012) (xy 164.455646 -318.19454) (xy 164.507608 -318.18268)
			(xy 164.560758 -318.178697) (xy 164.613908 -318.18268) (xy 164.66587 -318.19454) (xy 164.715484 -318.214012)
			(xy 164.761642 -318.240661) (xy 164.803313 -318.273892) (xy 164.839565 -318.312963) (xy 164.869589 -318.357)
			(xy 164.892715 -318.405021) (xy 164.908425 -318.455951) (xy 164.916368 -318.508655) (xy 164.916866 -318.535304)
			(xy 164.916368 -318.561953) (xy 164.908425 -318.614657) (xy 164.892715 -318.665587) (xy 164.869589 -318.713608)
			(xy 164.839565 -318.757645) (xy 164.803313 -318.796716) (xy 164.761642 -318.829947) (xy 164.715484 -318.856596)
			(xy 164.66587 -318.876068) (xy 164.613908 -318.887928) (xy 164.560758 -318.891912) (xy 164.507608 -318.887928)
			(xy 164.455646 -318.876068) (xy 164.406032 -318.856596) (xy 164.359874 -318.829947) (xy 164.318203 -318.796716)
			(xy 164.281951 -318.757645) (xy 164.251927 -318.713608) (xy 164.228801 -318.665587) (xy 164.213091 -318.614657)
			(xy 164.205148 -318.561953) (xy 160.127696 -318.561953) (xy 160.165878 -318.587989) (xy 160.204946 -318.624244)
			(xy 160.238174 -318.665916) (xy 160.264821 -318.712074) (xy 160.284292 -318.761689) (xy 160.296151 -318.813651)
			(xy 160.300134 -318.8668) (xy 160.298139 -318.893423) (xy 168.996604 -318.893423) (xy 168.996604 -318.840125)
			(xy 169.004547 -318.787421) (xy 169.020257 -318.736491) (xy 169.043383 -318.68847) (xy 169.073407 -318.644433)
			(xy 169.109659 -318.605362) (xy 169.15133 -318.572131) (xy 169.197488 -318.545482) (xy 169.247102 -318.52601)
			(xy 169.299064 -318.51415) (xy 169.352214 -318.510167) (xy 169.405364 -318.51415) (xy 169.457326 -318.52601)
			(xy 169.50694 -318.545482) (xy 169.553098 -318.572131) (xy 169.594769 -318.605362) (xy 169.631021 -318.644433)
			(xy 169.661045 -318.68847) (xy 169.684171 -318.736491) (xy 169.699881 -318.787421) (xy 169.707824 -318.840125)
			(xy 169.708322 -318.866774) (xy 169.707824 -318.893423) (xy 176.540404 -318.893423) (xy 176.540404 -318.840125)
			(xy 176.548347 -318.787421) (xy 176.564057 -318.736491) (xy 176.587183 -318.68847) (xy 176.617207 -318.644433)
			(xy 176.653459 -318.605362) (xy 176.69513 -318.572131) (xy 176.741288 -318.545482) (xy 176.790902 -318.52601)
			(xy 176.842864 -318.51415) (xy 176.896014 -318.510167) (xy 176.949164 -318.51415) (xy 177.001126 -318.52601)
			(xy 177.05074 -318.545482) (xy 177.096898 -318.572131) (xy 177.138569 -318.605362) (xy 177.174821 -318.644433)
			(xy 177.204845 -318.68847) (xy 177.227971 -318.736491) (xy 177.243681 -318.787421) (xy 177.251624 -318.840125)
			(xy 177.252122 -318.866774) (xy 177.251624 -318.893423) (xy 177.243681 -318.946127) (xy 177.227971 -318.997057)
			(xy 177.204845 -319.045078) (xy 177.174821 -319.089115) (xy 177.138569 -319.128186) (xy 177.096898 -319.161417)
			(xy 177.05074 -319.188066) (xy 177.03651 -319.193651) (xy 179.093612 -319.193651) (xy 179.093612 -319.140353)
			(xy 179.101555 -319.087649) (xy 179.117265 -319.036719) (xy 179.140391 -318.988698) (xy 179.170415 -318.944661)
			(xy 179.206667 -318.90559) (xy 179.248338 -318.872359) (xy 179.294496 -318.84571) (xy 179.34411 -318.826238)
			(xy 179.396072 -318.814378) (xy 179.449222 -318.810395) (xy 179.502372 -318.814378) (xy 179.554334 -318.826238)
			(xy 179.603948 -318.84571) (xy 179.650106 -318.872359) (xy 179.67652 -318.893423) (xy 184.084204 -318.893423)
			(xy 184.084204 -318.840125) (xy 184.092147 -318.787421) (xy 184.107857 -318.736491) (xy 184.130983 -318.68847)
			(xy 184.161007 -318.644433) (xy 184.197259 -318.605362) (xy 184.23893 -318.572131) (xy 184.285088 -318.545482)
			(xy 184.334702 -318.52601) (xy 184.386664 -318.51415) (xy 184.439814 -318.510167) (xy 184.492964 -318.51415)
			(xy 184.544926 -318.52601) (xy 184.59454 -318.545482) (xy 184.640698 -318.572131) (xy 184.660742 -318.588115)
			(xy 190.15455 -318.588115) (xy 190.15455 -318.534817) (xy 190.162493 -318.482113) (xy 190.178203 -318.431183)
			(xy 190.201329 -318.383162) (xy 190.231353 -318.339125) (xy 190.267605 -318.300054) (xy 190.309276 -318.266823)
			(xy 190.355434 -318.240174) (xy 190.405048 -318.220702) (xy 190.45701 -318.208842) (xy 190.51016 -318.204859)
			(xy 190.56331 -318.208842) (xy 190.615272 -318.220702) (xy 190.664886 -318.240174) (xy 190.711044 -318.266823)
			(xy 190.752715 -318.300054) (xy 190.788967 -318.339125) (xy 190.818991 -318.383162) (xy 190.842117 -318.431183)
			(xy 190.857827 -318.482113) (xy 190.86577 -318.534817) (xy 190.866268 -318.561466) (xy 190.86577 -318.588115)
			(xy 190.857827 -318.640819) (xy 190.842117 -318.691749) (xy 190.818991 -318.73977) (xy 190.788967 -318.783807)
			(xy 190.752715 -318.822878) (xy 190.711044 -318.856109) (xy 190.664886 -318.882758) (xy 190.637712 -318.893423)
			(xy 191.64045 -318.893423) (xy 191.64045 -318.840125) (xy 191.648393 -318.787421) (xy 191.664103 -318.736491)
			(xy 191.687229 -318.68847) (xy 191.717253 -318.644433) (xy 191.753505 -318.605362) (xy 191.795176 -318.572131)
			(xy 191.841334 -318.545482) (xy 191.890948 -318.52601) (xy 191.94291 -318.51415) (xy 191.99606 -318.510167)
			(xy 192.04921 -318.51415) (xy 192.101172 -318.52601) (xy 192.150786 -318.545482) (xy 192.196944 -318.572131)
			(xy 192.238615 -318.605362) (xy 192.274867 -318.644433) (xy 192.304891 -318.68847) (xy 192.328017 -318.736491)
			(xy 192.343727 -318.787421) (xy 192.35167 -318.840125) (xy 192.352168 -318.866774) (xy 192.35167 -318.893423)
			(xy 192.343727 -318.946127) (xy 192.328017 -318.997057) (xy 192.316642 -319.020677) (xy 194.245982 -319.020677)
			(xy 194.245982 -318.967379) (xy 194.253925 -318.914675) (xy 194.269635 -318.863745) (xy 194.292761 -318.815724)
			(xy 194.322785 -318.771687) (xy 194.359037 -318.732616) (xy 194.400708 -318.699385) (xy 194.446866 -318.672736)
			(xy 194.49648 -318.653264) (xy 194.548442 -318.641404) (xy 194.601592 -318.637421) (xy 194.654742 -318.641404)
			(xy 194.706704 -318.653264) (xy 194.756318 -318.672736) (xy 194.802476 -318.699385) (xy 194.844147 -318.732616)
			(xy 194.880399 -318.771687) (xy 194.910423 -318.815724) (xy 194.933549 -318.863745) (xy 194.942704 -318.893423)
			(xy 199.171804 -318.893423) (xy 199.171804 -318.840125) (xy 199.179747 -318.787421) (xy 199.195457 -318.736491)
			(xy 199.218583 -318.68847) (xy 199.248607 -318.644433) (xy 199.284859 -318.605362) (xy 199.32653 -318.572131)
			(xy 199.372688 -318.545482) (xy 199.422302 -318.52601) (xy 199.474264 -318.51415) (xy 199.527414 -318.510167)
			(xy 199.580564 -318.51415) (xy 199.632526 -318.52601) (xy 199.68214 -318.545482) (xy 199.728298 -318.572131)
			(xy 199.769969 -318.605362) (xy 199.806221 -318.644433) (xy 199.836245 -318.68847) (xy 199.859371 -318.736491)
			(xy 199.875081 -318.787421) (xy 199.883024 -318.840125) (xy 199.883522 -318.866774) (xy 199.883024 -318.893423)
			(xy 199.875081 -318.946127) (xy 199.859371 -318.997057) (xy 199.836245 -319.045078) (xy 199.806221 -319.089115)
			(xy 199.769969 -319.128186) (xy 199.728298 -319.161417) (xy 199.68214 -319.188066) (xy 199.632526 -319.207538)
			(xy 199.580564 -319.219398) (xy 199.527414 -319.223382) (xy 199.474264 -319.219398) (xy 199.422302 -319.207538)
			(xy 199.372688 -319.188066) (xy 199.32653 -319.161417) (xy 199.284859 -319.128186) (xy 199.248607 -319.089115)
			(xy 199.218583 -319.045078) (xy 199.195457 -318.997057) (xy 199.179747 -318.946127) (xy 199.171804 -318.893423)
			(xy 194.942704 -318.893423) (xy 194.949259 -318.914675) (xy 194.957202 -318.967379) (xy 194.9577 -318.994028)
			(xy 194.957202 -319.020677) (xy 194.949259 -319.073381) (xy 194.933549 -319.124311) (xy 194.910423 -319.172332)
			(xy 194.880399 -319.216369) (xy 194.844147 -319.25544) (xy 194.802476 -319.288671) (xy 194.756318 -319.31532)
			(xy 194.706704 -319.334792) (xy 194.654742 -319.346652) (xy 194.601592 -319.350636) (xy 194.548442 -319.346652)
			(xy 194.49648 -319.334792) (xy 194.446866 -319.31532) (xy 194.400708 -319.288671) (xy 194.359037 -319.25544)
			(xy 194.322785 -319.216369) (xy 194.292761 -319.172332) (xy 194.269635 -319.124311) (xy 194.253925 -319.073381)
			(xy 194.245982 -319.020677) (xy 192.316642 -319.020677) (xy 192.304891 -319.045078) (xy 192.274867 -319.089115)
			(xy 192.238615 -319.128186) (xy 192.196944 -319.161417) (xy 192.150786 -319.188066) (xy 192.101172 -319.207538)
			(xy 192.04921 -319.219398) (xy 191.99606 -319.223382) (xy 191.94291 -319.219398) (xy 191.890948 -319.207538)
			(xy 191.841334 -319.188066) (xy 191.795176 -319.161417) (xy 191.753505 -319.128186) (xy 191.717253 -319.089115)
			(xy 191.687229 -319.045078) (xy 191.664103 -318.997057) (xy 191.648393 -318.946127) (xy 191.64045 -318.893423)
			(xy 190.637712 -318.893423) (xy 190.615272 -318.90223) (xy 190.56331 -318.91409) (xy 190.51016 -318.918074)
			(xy 190.45701 -318.91409) (xy 190.405048 -318.90223) (xy 190.355434 -318.882758) (xy 190.309276 -318.856109)
			(xy 190.267605 -318.822878) (xy 190.231353 -318.783807) (xy 190.201329 -318.73977) (xy 190.178203 -318.691749)
			(xy 190.162493 -318.640819) (xy 190.15455 -318.588115) (xy 184.660742 -318.588115) (xy 184.682369 -318.605362)
			(xy 184.718621 -318.644433) (xy 184.748645 -318.68847) (xy 184.771771 -318.736491) (xy 184.787481 -318.787421)
			(xy 184.795424 -318.840125) (xy 184.795922 -318.866774) (xy 184.795424 -318.893423) (xy 184.787481 -318.946127)
			(xy 184.771771 -318.997057) (xy 184.748645 -319.045078) (xy 184.718621 -319.089115) (xy 184.682369 -319.128186)
			(xy 184.640698 -319.161417) (xy 184.59454 -319.188066) (xy 184.544926 -319.207538) (xy 184.492964 -319.219398)
			(xy 184.439814 -319.223382) (xy 184.386664 -319.219398) (xy 184.334702 -319.207538) (xy 184.285088 -319.188066)
			(xy 184.23893 -319.161417) (xy 184.197259 -319.128186) (xy 184.161007 -319.089115) (xy 184.130983 -319.045078)
			(xy 184.107857 -318.997057) (xy 184.092147 -318.946127) (xy 184.084204 -318.893423) (xy 179.67652 -318.893423)
			(xy 179.691777 -318.90559) (xy 179.728029 -318.944661) (xy 179.758053 -318.988698) (xy 179.781179 -319.036719)
			(xy 179.796889 -319.087649) (xy 179.804832 -319.140353) (xy 179.80533 -319.167002) (xy 179.804832 -319.193651)
			(xy 179.796889 -319.246355) (xy 179.781179 -319.297285) (xy 179.769804 -319.320905) (xy 182.282074 -319.320905)
			(xy 182.282074 -319.267607) (xy 182.290017 -319.214903) (xy 182.305727 -319.163973) (xy 182.328853 -319.115952)
			(xy 182.358877 -319.071915) (xy 182.395129 -319.032844) (xy 182.4368 -318.999613) (xy 182.482958 -318.972964)
			(xy 182.532572 -318.953492) (xy 182.584534 -318.941632) (xy 182.637684 -318.937649) (xy 182.690834 -318.941632)
			(xy 182.742796 -318.953492) (xy 182.79241 -318.972964) (xy 182.838568 -318.999613) (xy 182.880239 -319.032844)
			(xy 182.916491 -319.071915) (xy 182.946515 -319.115952) (xy 182.969641 -319.163973) (xy 182.985351 -319.214903)
			(xy 182.993294 -319.267607) (xy 182.993792 -319.294256) (xy 182.993769 -319.295505) (xy 189.708272 -319.295505)
			(xy 189.708272 -319.242207) (xy 189.716215 -319.189503) (xy 189.731925 -319.138573) (xy 189.755051 -319.090552)
			(xy 189.785075 -319.046515) (xy 189.821327 -319.007444) (xy 189.862998 -318.974213) (xy 189.909156 -318.947564)
			(xy 189.95877 -318.928092) (xy 190.010732 -318.916232) (xy 190.063882 -318.912249) (xy 190.117032 -318.916232)
			(xy 190.168994 -318.928092) (xy 190.218608 -318.947564) (xy 190.264766 -318.974213) (xy 190.306437 -319.007444)
			(xy 190.342689 -319.046515) (xy 190.372713 -319.090552) (xy 190.395839 -319.138573) (xy 190.411549 -319.189503)
			(xy 190.419492 -319.242207) (xy 190.41999 -319.268856) (xy 190.419492 -319.295505) (xy 190.411549 -319.348209)
			(xy 190.404301 -319.371705) (xy 197.344274 -319.371705) (xy 197.344274 -319.318407) (xy 197.352217 -319.265703)
			(xy 197.367927 -319.214773) (xy 197.391053 -319.166752) (xy 197.421077 -319.122715) (xy 197.457329 -319.083644)
			(xy 197.499 -319.050413) (xy 197.545158 -319.023764) (xy 197.594772 -319.004292) (xy 197.646734 -318.992432)
			(xy 197.699884 -318.988449) (xy 197.753034 -318.992432) (xy 197.804996 -319.004292) (xy 197.85461 -319.023764)
			(xy 197.900768 -319.050413) (xy 197.942439 -319.083644) (xy 197.978691 -319.122715) (xy 198.008715 -319.166752)
			(xy 198.031841 -319.214773) (xy 198.047551 -319.265703) (xy 198.055494 -319.318407) (xy 198.055992 -319.345056)
			(xy 198.055494 -319.371705) (xy 198.047551 -319.424409) (xy 198.032468 -319.473305) (xy 204.888074 -319.473305)
			(xy 204.888074 -319.420007) (xy 204.896017 -319.367303) (xy 204.911727 -319.316373) (xy 204.934853 -319.268352)
			(xy 204.964877 -319.224315) (xy 205.001129 -319.185244) (xy 205.0428 -319.152013) (xy 205.088958 -319.125364)
			(xy 205.138572 -319.105892) (xy 205.190534 -319.094032) (xy 205.243684 -319.090049) (xy 205.296834 -319.094032)
			(xy 205.348796 -319.105892) (xy 205.39841 -319.125364) (xy 205.444568 -319.152013) (xy 205.486239 -319.185244)
			(xy 205.522491 -319.224315) (xy 205.552515 -319.268352) (xy 205.565591 -319.295505) (xy 212.457274 -319.295505)
			(xy 212.457274 -319.242207) (xy 212.465217 -319.189503) (xy 212.480927 -319.138573) (xy 212.504053 -319.090552)
			(xy 212.534077 -319.046515) (xy 212.570329 -319.007444) (xy 212.612 -318.974213) (xy 212.658158 -318.947564)
			(xy 212.707772 -318.928092) (xy 212.759734 -318.916232) (xy 212.812884 -318.912249) (xy 212.866034 -318.916232)
			(xy 212.917996 -318.928092) (xy 212.96761 -318.947564) (xy 213.013768 -318.974213) (xy 213.055439 -319.007444)
			(xy 213.091691 -319.046515) (xy 213.121715 -319.090552) (xy 213.144841 -319.138573) (xy 213.160551 -319.189503)
			(xy 213.168494 -319.242207) (xy 213.168575 -319.246562) (xy 213.671463 -319.246562) (xy 213.676943 -319.192674)
			(xy 213.690521 -319.140238) (xy 213.711882 -319.090463) (xy 213.740535 -319.044496) (xy 213.775819 -319.003399)
			(xy 213.816919 -318.968119) (xy 213.862888 -318.939469) (xy 213.912665 -318.918112) (xy 213.965102 -318.904538)
			(xy 214.01899 -318.899062) (xy 214.073086 -318.901809) (xy 214.126142 -318.912717) (xy 214.176934 -318.931533)
			(xy 214.224291 -318.957824) (xy 214.267121 -318.990983) (xy 214.304435 -319.030246) (xy 214.335373 -319.074707)
			(xy 214.359222 -319.12334) (xy 214.375431 -319.175023) (xy 214.383626 -319.228565) (xy 214.384128 -319.255648)
			(xy 214.38362 -319.27292) (xy 214.383405 -319.286782) (xy 214.384123 -319.289917) (xy 254.17017 -319.289917)
			(xy 254.17017 -319.236619) (xy 254.178113 -319.183915) (xy 254.193823 -319.132985) (xy 254.216949 -319.084964)
			(xy 254.246973 -319.040927) (xy 254.283225 -319.001856) (xy 254.324896 -318.968625) (xy 254.371054 -318.941976)
			(xy 254.420668 -318.922504) (xy 254.47263 -318.910644) (xy 254.52578 -318.906661) (xy 254.57893 -318.910644)
			(xy 254.630892 -318.922504) (xy 254.680506 -318.941976) (xy 254.726664 -318.968625) (xy 254.768335 -319.001856)
			(xy 254.804587 -319.040927) (xy 254.834611 -319.084964) (xy 254.857737 -319.132985) (xy 254.873447 -319.183915)
			(xy 254.88139 -319.236619) (xy 254.881888 -319.263268) (xy 254.88139 -319.289917) (xy 254.873447 -319.342621)
			(xy 254.869647 -319.354941) (xy 256.830312 -319.354941) (xy 256.830312 -319.301643) (xy 256.838255 -319.248939)
			(xy 256.853965 -319.198009) (xy 256.877091 -319.149988) (xy 256.907115 -319.105951) (xy 256.943367 -319.06688)
			(xy 256.985038 -319.033649) (xy 257.031196 -319.007) (xy 257.08081 -318.987528) (xy 257.132772 -318.975668)
			(xy 257.185922 -318.971685) (xy 257.239072 -318.975668) (xy 257.291034 -318.987528) (xy 257.340648 -319.007)
			(xy 257.386806 -319.033649) (xy 257.428477 -319.06688) (xy 257.464729 -319.105951) (xy 257.494753 -319.149988)
			(xy 257.517879 -319.198009) (xy 257.533589 -319.248939) (xy 257.541532 -319.301643) (xy 257.54203 -319.328292)
			(xy 257.541532 -319.354941) (xy 257.533589 -319.407645) (xy 257.527125 -319.428601) (xy 264.396464 -319.428601)
			(xy 264.396464 -319.375303) (xy 264.404407 -319.322599) (xy 264.420117 -319.271669) (xy 264.443243 -319.223648)
			(xy 264.473267 -319.179611) (xy 264.509519 -319.14054) (xy 264.55119 -319.107309) (xy 264.597348 -319.08066)
			(xy 264.646962 -319.061188) (xy 264.698924 -319.049328) (xy 264.752074 -319.045345) (xy 264.805224 -319.049328)
			(xy 264.857186 -319.061188) (xy 264.9068 -319.08066) (xy 264.952958 -319.107309) (xy 264.994629 -319.14054)
			(xy 265.030881 -319.179611) (xy 265.060905 -319.223648) (xy 265.084031 -319.271669) (xy 265.099741 -319.322599)
			(xy 265.107684 -319.375303) (xy 265.108182 -319.401952) (xy 265.107684 -319.428601) (xy 265.099741 -319.481305)
			(xy 265.084031 -319.532235) (xy 265.060905 -319.580256) (xy 265.030881 -319.624293) (xy 264.994629 -319.663364)
			(xy 264.952958 -319.696595) (xy 264.9068 -319.723244) (xy 264.857186 -319.742716) (xy 264.805224 -319.754576)
			(xy 264.752074 -319.75856) (xy 264.698924 -319.754576) (xy 264.646962 -319.742716) (xy 264.597348 -319.723244)
			(xy 264.55119 -319.696595) (xy 264.509519 -319.663364) (xy 264.473267 -319.624293) (xy 264.443243 -319.580256)
			(xy 264.420117 -319.532235) (xy 264.404407 -319.481305) (xy 264.396464 -319.428601) (xy 257.527125 -319.428601)
			(xy 257.517879 -319.458575) (xy 257.494753 -319.506596) (xy 257.464729 -319.550633) (xy 257.428477 -319.589704)
			(xy 257.386806 -319.622935) (xy 257.340648 -319.649584) (xy 257.291034 -319.669056) (xy 257.239072 -319.680916)
			(xy 257.185922 -319.6849) (xy 257.132772 -319.680916) (xy 257.08081 -319.669056) (xy 257.031196 -319.649584)
			(xy 256.985038 -319.622935) (xy 256.943367 -319.589704) (xy 256.907115 -319.550633) (xy 256.877091 -319.506596)
			(xy 256.853965 -319.458575) (xy 256.838255 -319.407645) (xy 256.830312 -319.354941) (xy 254.869647 -319.354941)
			(xy 254.857737 -319.393551) (xy 254.834611 -319.441572) (xy 254.804587 -319.485609) (xy 254.768335 -319.52468)
			(xy 254.726664 -319.557911) (xy 254.680506 -319.58456) (xy 254.630892 -319.604032) (xy 254.57893 -319.615892)
			(xy 254.52578 -319.619876) (xy 254.47263 -319.615892) (xy 254.420668 -319.604032) (xy 254.371054 -319.58456)
			(xy 254.324896 -319.557911) (xy 254.283225 -319.52468) (xy 254.246973 -319.485609) (xy 254.216949 -319.441572)
			(xy 254.193823 -319.393551) (xy 254.178113 -319.342621) (xy 254.17017 -319.289917) (xy 214.384123 -319.289917)
			(xy 214.389588 -319.313797) (xy 214.402801 -319.338158) (xy 214.422074 -319.358073) (xy 214.445989 -319.372078)
			(xy 214.472787 -319.379143) (xy 214.500498 -319.378748) (xy 214.513922 -319.375282) (xy 214.538626 -319.368399)
			(xy 214.589373 -319.361011) (xy 214.615014 -319.36055) (xy 214.642094 -319.361113) (xy 214.695628 -319.369316)
			(xy 214.747302 -319.385532) (xy 214.795926 -319.409385) (xy 214.840376 -319.440327) (xy 214.879628 -319.477643)
			(xy 214.912777 -319.520472) (xy 214.939058 -319.567828) (xy 214.957864 -319.618617) (xy 214.968763 -319.671668)
			(xy 214.971503 -319.725758) (xy 214.96602 -319.779639) (xy 214.952441 -319.832068) (xy 214.948006 -319.8424)
			(xy 265.583856 -319.8424) (xy 265.58784 -319.789241) (xy 265.599703 -319.73727) (xy 265.61918 -319.687648)
			(xy 265.645835 -319.641483) (xy 265.679074 -319.599806) (xy 265.718154 -319.56355) (xy 265.762201 -319.533524)
			(xy 265.810232 -319.510398) (xy 265.861173 -319.49469) (xy 265.913886 -319.48675) (xy 265.94054 -319.48628)
			(xy 265.970434 -319.486922) (xy 266.029384 -319.496903) (xy 266.085843 -319.516578) (xy 266.138228 -319.545396)
			(xy 266.162028 -319.563496) (xy 266.17374 -319.57209) (xy 266.20061 -319.583077) (xy 266.229486 -319.586052)
			(xy 266.258032 -319.580775) (xy 266.283936 -319.567673) (xy 266.305102 -319.547806) (xy 266.312904 -319.535556)
			(xy 266.326713 -319.513054) (xy 266.359973 -319.472055) (xy 266.398924 -319.436418) (xy 266.442711 -319.406925)
			(xy 266.490375 -319.384222) (xy 266.540868 -319.368809) (xy 266.593085 -319.361024) (xy 266.619482 -319.36055)
			(xy 266.646131 -319.361106) (xy 266.698834 -319.369047) (xy 266.705805 -319.371197) (xy 271.930104 -319.371197)
			(xy 271.930104 -319.317899) (xy 271.938047 -319.265195) (xy 271.953757 -319.214265) (xy 271.976883 -319.166244)
			(xy 272.006907 -319.122207) (xy 272.043159 -319.083136) (xy 272.08483 -319.049905) (xy 272.130988 -319.023256)
			(xy 272.180602 -319.003784) (xy 272.232564 -318.991924) (xy 272.285714 -318.987941) (xy 272.338864 -318.991924)
			(xy 272.390826 -319.003784) (xy 272.44044 -319.023256) (xy 272.486598 -319.049905) (xy 272.528269 -319.083136)
			(xy 272.564521 -319.122207) (xy 272.594545 -319.166244) (xy 272.617671 -319.214265) (xy 272.633381 -319.265195)
			(xy 272.641324 -319.317899) (xy 272.641561 -319.330557) (xy 279.439106 -319.330557) (xy 279.439106 -319.277259)
			(xy 279.447049 -319.224555) (xy 279.462759 -319.173625) (xy 279.485885 -319.125604) (xy 279.515909 -319.081567)
			(xy 279.552161 -319.042496) (xy 279.593832 -319.009265) (xy 279.63999 -318.982616) (xy 279.689604 -318.963144)
			(xy 279.741566 -318.951284) (xy 279.794716 -318.947301) (xy 279.847866 -318.951284) (xy 279.899828 -318.963144)
			(xy 279.949442 -318.982616) (xy 279.9956 -319.009265) (xy 280.037271 -319.042496) (xy 280.073523 -319.081567)
			(xy 280.103547 -319.125604) (xy 280.126673 -319.173625) (xy 280.142383 -319.224555) (xy 280.150326 -319.277259)
			(xy 280.150824 -319.303908) (xy 280.150326 -319.330557) (xy 280.147107 -319.351914) (xy 287.028128 -319.351914)
			(xy 287.028607 -319.324155) (xy 287.03722 -319.269311) (xy 287.05424 -319.216467) (xy 287.079253 -319.166904)
			(xy 287.111655 -319.121823) (xy 287.15066 -319.082317) (xy 287.195323 -319.049342) (xy 287.244562 -319.023697)
			(xy 287.297184 -319.006004) (xy 287.351915 -318.996691) (xy 287.379664 -318.995806) (xy 287.394311 -318.99506)
			(xy 287.422302 -318.986367) (xy 287.446676 -318.970088) (xy 287.465428 -318.947561) (xy 287.477017 -318.920639)
			(xy 287.479232 -318.906144) (xy 287.482807 -318.880522) (xy 287.496287 -318.83058) (xy 287.516854 -318.783115)
			(xy 287.544073 -318.739126) (xy 287.577372 -318.69954) (xy 287.61605 -318.66519) (xy 287.659293 -318.636799)
			(xy 287.706189 -318.614966) (xy 287.755751 -318.60015) (xy 287.806935 -318.592664) (xy 287.8328 -318.5922)
			(xy 287.858407 -318.592628) (xy 287.909093 -318.599971) (xy 287.958202 -318.614504) (xy 288.00472 -318.635929)
			(xy 288.047686 -318.663801) (xy 288.067242 -318.680338) (xy 288.079257 -318.690081) (xy 288.107527 -318.702588)
			(xy 288.138245 -318.706056) (xy 288.168592 -318.700166) (xy 288.195782 -318.685458) (xy 288.206942 -318.67475)
			(xy 288.224956 -318.656798) (xy 288.264943 -318.625372) (xy 288.30875 -318.599535) (xy 288.3556 -318.579746)
			(xy 288.404663 -318.566355) (xy 288.455071 -318.5596) (xy 288.4805 -318.55918) (xy 288.508768 -318.5597)
			(xy 288.564687 -318.568031) (xy 288.618763 -318.584525) (xy 288.669812 -318.608821) (xy 288.716715 -318.640387)
			(xy 288.758445 -318.678531) (xy 288.776664 -318.70015) (xy 288.785897 -318.710728) (xy 288.808855 -318.726872)
			(xy 288.835338 -318.736161) (xy 288.86335 -318.737896) (xy 288.890777 -318.731945) (xy 288.91555 -318.718757)
			(xy 288.935802 -318.699328) (xy 288.943288 -318.68745) (xy 288.957036 -318.664741) (xy 288.990275 -318.623349)
			(xy 289.029292 -318.587353) (xy 289.073223 -318.557551) (xy 289.121093 -318.534605) (xy 289.17184 -318.519023)
			(xy 289.224339 -318.511151) (xy 289.250882 -318.510666) (xy 289.277532 -318.51119) (xy 289.330237 -318.519131)
			(xy 289.38117 -318.53484) (xy 289.429193 -318.557964) (xy 289.473232 -318.587988) (xy 289.512305 -318.62424)
			(xy 289.545538 -318.665911) (xy 289.572189 -318.71207) (xy 289.591662 -318.761685) (xy 289.603523 -318.813649)
			(xy 289.607506 -318.8668) (xy 289.605511 -318.893423) (xy 296.439072 -318.893423) (xy 296.439072 -318.840125)
			(xy 296.447015 -318.787421) (xy 296.462725 -318.736491) (xy 296.485851 -318.68847) (xy 296.515875 -318.644433)
			(xy 296.552127 -318.605362) (xy 296.593798 -318.572131) (xy 296.639956 -318.545482) (xy 296.68957 -318.52601)
			(xy 296.741532 -318.51415) (xy 296.794682 -318.510167) (xy 296.847832 -318.51415) (xy 296.899794 -318.52601)
			(xy 296.949408 -318.545482) (xy 296.995566 -318.572131) (xy 297.037237 -318.605362) (xy 297.073489 -318.644433)
			(xy 297.103513 -318.68847) (xy 297.126639 -318.736491) (xy 297.142349 -318.787421) (xy 297.150292 -318.840125)
			(xy 297.15079 -318.866774) (xy 297.150292 -318.893423) (xy 297.143172 -318.940667) (xy 298.658778 -318.940667)
			(xy 298.658778 -318.887369) (xy 298.666721 -318.834665) (xy 298.682431 -318.783735) (xy 298.705557 -318.735714)
			(xy 298.735581 -318.691677) (xy 298.771833 -318.652606) (xy 298.813504 -318.619375) (xy 298.859662 -318.592726)
			(xy 298.909276 -318.573254) (xy 298.961238 -318.561394) (xy 299.014388 -318.557411) (xy 299.067538 -318.561394)
			(xy 299.1195 -318.573254) (xy 299.169114 -318.592726) (xy 299.215272 -318.619375) (xy 299.256943 -318.652606)
			(xy 299.293195 -318.691677) (xy 299.323219 -318.735714) (xy 299.346345 -318.783735) (xy 299.362055 -318.834665)
			(xy 299.369998 -318.887369) (xy 299.370496 -318.914018) (xy 299.369998 -318.940667) (xy 299.362055 -318.993371)
			(xy 299.346345 -319.044301) (xy 299.323219 -319.092322) (xy 299.293195 -319.136359) (xy 299.256943 -319.17543)
			(xy 299.215272 -319.208661) (xy 299.169114 -319.23531) (xy 299.1195 -319.254782) (xy 299.067538 -319.266642)
			(xy 299.014388 -319.270626) (xy 298.961238 -319.266642) (xy 298.909276 -319.254782) (xy 298.859662 -319.23531)
			(xy 298.813504 -319.208661) (xy 298.771833 -319.17543) (xy 298.735581 -319.136359) (xy 298.705557 -319.092322)
			(xy 298.682431 -319.044301) (xy 298.666721 -318.993371) (xy 298.658778 -318.940667) (xy 297.143172 -318.940667)
			(xy 297.142349 -318.946127) (xy 297.126639 -318.997057) (xy 297.103513 -319.045078) (xy 297.073489 -319.089115)
			(xy 297.037237 -319.128186) (xy 296.995566 -319.161417) (xy 296.949408 -319.188066) (xy 296.899794 -319.207538)
			(xy 296.847832 -319.219398) (xy 296.794682 -319.223382) (xy 296.741532 -319.219398) (xy 296.68957 -319.207538)
			(xy 296.639956 -319.188066) (xy 296.593798 -319.161417) (xy 296.552127 -319.128186) (xy 296.515875 -319.089115)
			(xy 296.485851 -319.045078) (xy 296.462725 -318.997057) (xy 296.447015 -318.946127) (xy 296.439072 -318.893423)
			(xy 289.605511 -318.893423) (xy 289.603523 -318.919951) (xy 289.591662 -318.971915) (xy 289.572189 -319.02153)
			(xy 289.545538 -319.067689) (xy 289.512305 -319.10936) (xy 289.473232 -319.145612) (xy 289.429193 -319.175636)
			(xy 289.38117 -319.19876) (xy 289.330237 -319.214469) (xy 289.277532 -319.22241) (xy 289.250882 -319.222882)
			(xy 289.225599 -319.222433) (xy 289.17554 -319.215295) (xy 289.126993 -319.201151) (xy 289.080934 -319.180284)
			(xy 289.038288 -319.153115) (xy 288.999912 -319.120189) (xy 288.982912 -319.10147) (xy 288.973287 -319.091278)
			(xy 288.949741 -319.076087) (xy 288.922956 -319.067858) (xy 288.894943 -319.067208) (xy 288.867805 -319.074186)
			(xy 288.84358 -319.088268) (xy 288.824087 -319.108397) (xy 288.81705 -319.12052) (xy 288.802732 -319.146263)
			(xy 288.7673 -319.193323) (xy 288.725058 -319.23438) (xy 288.677008 -319.268457) (xy 288.624292 -319.294745)
			(xy 288.568163 -319.31262) (xy 288.509954 -319.321657) (xy 288.4805 -319.322196) (xy 288.450882 -319.321602)
			(xy 288.392357 -319.312447) (xy 288.33595 -319.294358) (xy 288.283016 -319.267769) (xy 288.234827 -319.233318)
			(xy 288.213292 -319.212976) (xy 288.201843 -319.202609) (xy 288.174331 -319.188612) (xy 288.143898 -319.183452)
			(xy 288.11331 -319.1876) (xy 288.085349 -319.200677) (xy 288.073592 -319.21069) (xy 288.054113 -319.227914)
			(xy 288.011103 -319.257132) (xy 287.964301 -319.279783) (xy 287.914702 -319.295386) (xy 287.863361 -319.303609)
			(xy 287.837372 -319.304416) (xy 287.822719 -319.305088) (xy 287.794723 -319.313801) (xy 287.771561 -319.329287)
			(xy 291.379392 -319.329287) (xy 291.379392 -319.275989) (xy 291.387335 -319.223285) (xy 291.403045 -319.172355)
			(xy 291.426171 -319.124334) (xy 291.456195 -319.080297) (xy 291.492447 -319.041226) (xy 291.534118 -319.007995)
			(xy 291.580276 -318.981346) (xy 291.62989 -318.961874) (xy 291.681852 -318.950014) (xy 291.735002 -318.946031)
			(xy 291.788152 -318.950014) (xy 291.840114 -318.961874) (xy 291.889728 -318.981346) (xy 291.935886 -319.007995)
			(xy 291.977557 -319.041226) (xy 292.013809 -319.080297) (xy 292.043833 -319.124334) (xy 292.066959 -319.172355)
			(xy 292.082669 -319.223285) (xy 292.090612 -319.275989) (xy 292.09111 -319.302638) (xy 292.090612 -319.329287)
			(xy 292.082669 -319.381991) (xy 292.066959 -319.432921) (xy 292.043833 -319.480942) (xy 292.013809 -319.524979)
			(xy 291.977557 -319.56405) (xy 291.935886 -319.597281) (xy 291.889728 -319.62393) (xy 291.840114 -319.643402)
			(xy 291.788152 -319.655262) (xy 291.735002 -319.659246) (xy 291.681852 -319.655262) (xy 291.62989 -319.643402)
			(xy 291.580276 -319.62393) (xy 291.534118 -319.597281) (xy 291.492447 -319.56405) (xy 291.456195 -319.524979)
			(xy 291.426171 -319.480942) (xy 291.403045 -319.432921) (xy 291.387335 -319.381991) (xy 291.379392 -319.329287)
			(xy 287.771561 -319.329287) (xy 287.770348 -319.330098) (xy 287.751599 -319.352641) (xy 287.740015 -319.379577)
			(xy 287.737804 -319.394078) (xy 287.734308 -319.419712) (xy 287.720822 -319.46966) (xy 287.700248 -319.517129)
			(xy 287.67302 -319.56112) (xy 287.639712 -319.600708) (xy 287.601025 -319.635057) (xy 287.557773 -319.663445)
			(xy 287.510867 -319.685274) (xy 287.461297 -319.700084) (xy 287.410104 -319.707563) (xy 287.384236 -319.708022)
			(xy 287.356252 -319.707454) (xy 287.300973 -319.698704) (xy 287.247744 -319.681414) (xy 287.197875 -319.65601)
			(xy 287.152594 -319.623117) (xy 287.113016 -319.583544) (xy 287.080116 -319.538268) (xy 287.054705 -319.488402)
			(xy 287.037407 -319.435175) (xy 287.02865 -319.379898) (xy 287.028128 -319.351914) (xy 280.147107 -319.351914)
			(xy 280.142383 -319.383261) (xy 280.126673 -319.434191) (xy 280.103547 -319.482212) (xy 280.073523 -319.526249)
			(xy 280.037271 -319.56532) (xy 279.9956 -319.598551) (xy 279.949442 -319.6252) (xy 279.899828 -319.644672)
			(xy 279.847866 -319.656532) (xy 279.794716 -319.660516) (xy 279.741566 -319.656532) (xy 279.689604 -319.644672)
			(xy 279.63999 -319.6252) (xy 279.593832 -319.598551) (xy 279.552161 -319.56532) (xy 279.515909 -319.526249)
			(xy 279.485885 -319.482212) (xy 279.462759 -319.434191) (xy 279.447049 -319.383261) (xy 279.439106 -319.330557)
			(xy 272.641561 -319.330557) (xy 272.641822 -319.344548) (xy 272.641324 -319.371197) (xy 272.633381 -319.423901)
			(xy 272.617671 -319.474831) (xy 272.594545 -319.522852) (xy 272.564521 -319.566889) (xy 272.528269 -319.60596)
			(xy 272.486598 -319.639191) (xy 272.44044 -319.66584) (xy 272.390826 -319.685312) (xy 272.338864 -319.697172)
			(xy 272.285714 -319.701156) (xy 272.232564 -319.697172) (xy 272.180602 -319.685312) (xy 272.130988 -319.66584)
			(xy 272.08483 -319.639191) (xy 272.043159 -319.60596) (xy 272.006907 -319.566889) (xy 271.976883 -319.522852)
			(xy 271.953757 -319.474831) (xy 271.938047 -319.423901) (xy 271.930104 -319.371197) (xy 266.705805 -319.371197)
			(xy 266.749764 -319.384755) (xy 266.797785 -319.407878) (xy 266.841822 -319.4379) (xy 266.880893 -319.474151)
			(xy 266.914125 -319.51582) (xy 266.940774 -319.561977) (xy 266.960247 -319.61159) (xy 266.972107 -319.663551)
			(xy 266.97609 -319.7167) (xy 266.972107 -319.769849) (xy 266.964244 -319.8043) (xy 273.07948 -319.8043)
			(xy 273.083463 -319.751151) (xy 273.095323 -319.699188) (xy 273.114794 -319.649574) (xy 273.141443 -319.603415)
			(xy 273.174673 -319.561744) (xy 273.213742 -319.525491) (xy 273.257779 -319.495465) (xy 273.305798 -319.472338)
			(xy 273.356728 -319.456626) (xy 273.409431 -319.448679) (xy 273.43608 -319.44818) (xy 273.464857 -319.448735)
			(xy 273.521662 -319.457981) (xy 273.576238 -319.476252) (xy 273.627161 -319.503072) (xy 273.673101 -319.537739)
			(xy 273.693382 -319.558162) (xy 273.703036 -319.56762) (xy 273.726146 -319.581609) (xy 273.752118 -319.589035)
			(xy 273.77913 -319.589376) (xy 273.805282 -319.582608) (xy 273.828737 -319.569208) (xy 273.847848 -319.550116)
			(xy 273.854926 -319.538604) (xy 273.868632 -319.515743) (xy 273.901858 -319.474066) (xy 273.940927 -319.437809)
			(xy 273.984966 -319.407783) (xy 274.03299 -319.384658) (xy 274.083924 -319.368953) (xy 274.136631 -319.361017)
			(xy 274.163282 -319.36055) (xy 274.189931 -319.361106) (xy 274.242634 -319.369047) (xy 274.293564 -319.384755)
			(xy 274.341585 -319.407878) (xy 274.385622 -319.4379) (xy 274.424693 -319.474151) (xy 274.457925 -319.51582)
			(xy 274.484574 -319.561977) (xy 274.504047 -319.61159) (xy 274.515907 -319.663551) (xy 274.51989 -319.7167)
			(xy 274.517896 -319.743307) (xy 288.895272 -319.743307) (xy 288.895272 -319.690009) (xy 288.903215 -319.637305)
			(xy 288.918925 -319.586375) (xy 288.942051 -319.538354) (xy 288.972075 -319.494317) (xy 289.008327 -319.455246)
			(xy 289.049998 -319.422015) (xy 289.096156 -319.395366) (xy 289.14577 -319.375894) (xy 289.197732 -319.364034)
			(xy 289.250882 -319.360051) (xy 289.304032 -319.364034) (xy 289.355994 -319.375894) (xy 289.405608 -319.395366)
			(xy 289.451766 -319.422015) (xy 289.493437 -319.455246) (xy 289.529689 -319.494317) (xy 289.559713 -319.538354)
			(xy 289.582839 -319.586375) (xy 289.598549 -319.637305) (xy 289.606492 -319.690009) (xy 289.60699 -319.716658)
			(xy 289.606492 -319.743307) (xy 289.60098 -319.779883) (xy 294.5549 -319.779883) (xy 294.5549 -319.726585)
			(xy 294.562843 -319.673881) (xy 294.578553 -319.622951) (xy 294.601679 -319.57493) (xy 294.631703 -319.530893)
			(xy 294.667955 -319.491822) (xy 294.709626 -319.458591) (xy 294.755784 -319.431942) (xy 294.805398 -319.41247)
			(xy 294.85736 -319.40061) (xy 294.91051 -319.396627) (xy 294.96366 -319.40061) (xy 295.015622 -319.41247)
			(xy 295.065236 -319.431942) (xy 295.111394 -319.458591) (xy 295.153065 -319.491822) (xy 295.189317 -319.530893)
			(xy 295.219341 -319.57493) (xy 295.242467 -319.622951) (xy 295.258177 -319.673881) (xy 295.26612 -319.726585)
			(xy 295.266432 -319.743307) (xy 296.439072 -319.743307) (xy 296.439072 -319.690009) (xy 296.447015 -319.637305)
			(xy 296.462725 -319.586375) (xy 296.485851 -319.538354) (xy 296.515875 -319.494317) (xy 296.552127 -319.455246)
			(xy 296.593798 -319.422015) (xy 296.639956 -319.395366) (xy 296.68957 -319.375894) (xy 296.741532 -319.364034)
			(xy 296.794682 -319.360051) (xy 296.847832 -319.364034) (xy 296.899794 -319.375894) (xy 296.949408 -319.395366)
			(xy 296.995566 -319.422015) (xy 297.037237 -319.455246) (xy 297.073489 -319.494317) (xy 297.103513 -319.538354)
			(xy 297.126639 -319.586375) (xy 297.142349 -319.637305) (xy 297.150292 -319.690009) (xy 297.15079 -319.716658)
			(xy 297.150292 -319.743307) (xy 297.142349 -319.796011) (xy 297.126639 -319.846941) (xy 297.103513 -319.894962)
			(xy 297.073489 -319.938999) (xy 297.037237 -319.97807) (xy 296.995566 -320.011301) (xy 296.949408 -320.03795)
			(xy 296.899794 -320.057422) (xy 296.847832 -320.069282) (xy 296.794682 -320.073266) (xy 296.741532 -320.069282)
			(xy 296.68957 -320.057422) (xy 296.639956 -320.03795) (xy 296.593798 -320.011301) (xy 296.552127 -319.97807)
			(xy 296.515875 -319.938999) (xy 296.485851 -319.894962) (xy 296.462725 -319.846941) (xy 296.447015 -319.796011)
			(xy 296.439072 -319.743307) (xy 295.266432 -319.743307) (xy 295.266618 -319.753234) (xy 295.26612 -319.779883)
			(xy 295.258177 -319.832587) (xy 295.242467 -319.883517) (xy 295.219341 -319.931538) (xy 295.189317 -319.975575)
			(xy 295.153065 -320.014646) (xy 295.111394 -320.047877) (xy 295.065236 -320.074526) (xy 295.015622 -320.093998)
			(xy 294.96366 -320.105858) (xy 294.91051 -320.109842) (xy 294.85736 -320.105858) (xy 294.805398 -320.093998)
			(xy 294.755784 -320.074526) (xy 294.709626 -320.047877) (xy 294.667955 -320.014646) (xy 294.631703 -319.975575)
			(xy 294.601679 -319.931538) (xy 294.578553 -319.883517) (xy 294.562843 -319.832587) (xy 294.5549 -319.779883)
			(xy 289.60098 -319.779883) (xy 289.598549 -319.796011) (xy 289.582839 -319.846941) (xy 289.559713 -319.894962)
			(xy 289.529689 -319.938999) (xy 289.493437 -319.97807) (xy 289.451766 -320.011301) (xy 289.405608 -320.03795)
			(xy 289.355994 -320.057422) (xy 289.304032 -320.069282) (xy 289.250882 -320.073266) (xy 289.197732 -320.069282)
			(xy 289.14577 -320.057422) (xy 289.096156 -320.03795) (xy 289.049998 -320.011301) (xy 289.008327 -319.97807)
			(xy 288.972075 -319.938999) (xy 288.942051 -319.894962) (xy 288.918925 -319.846941) (xy 288.903215 -319.796011)
			(xy 288.895272 -319.743307) (xy 274.517896 -319.743307) (xy 274.515907 -319.769849) (xy 274.504047 -319.82181)
			(xy 274.484574 -319.871423) (xy 274.457925 -319.91758) (xy 274.424693 -319.959249) (xy 274.385622 -319.9955)
			(xy 274.341585 -320.025522) (xy 274.293564 -320.048645) (xy 274.242634 -320.064353) (xy 274.189931 -320.072294)
			(xy 274.163282 -320.072766) (xy 274.134503 -320.072252) (xy 274.077695 -320.062998) (xy 274.023118 -320.044718)
			(xy 273.972196 -320.017889) (xy 273.926259 -319.983212) (xy 273.90598 -319.962784) (xy 273.896355 -319.953296)
			(xy 273.873237 -319.939318) (xy 273.847258 -319.931901) (xy 273.820244 -319.931567) (xy 273.79409 -319.938338)
			(xy 273.770633 -319.95174) (xy 273.751517 -319.970831) (xy 273.744436 -319.982342) (xy 273.730704 -320.005186)
			(xy 273.69748 -320.04686) (xy 273.658414 -320.083117) (xy 273.61438 -320.113144) (xy 273.566361 -320.136271)
			(xy 273.515432 -320.151982) (xy 273.462729 -320.159924) (xy 273.43608 -320.160396) (xy 273.409431 -320.159921)
			(xy 273.356728 -320.151974) (xy 273.305798 -320.136262) (xy 273.257779 -320.113135) (xy 273.213742 -320.083109)
			(xy 273.174673 -320.046856) (xy 273.141443 -320.005185) (xy 273.114794 -319.959026) (xy 273.095323 -319.909412)
			(xy 273.083463 -319.857449) (xy 273.07948 -319.8043) (xy 266.964244 -319.8043) (xy 266.960247 -319.82181)
			(xy 266.940774 -319.871423) (xy 266.914125 -319.91758) (xy 266.880893 -319.959249) (xy 266.841822 -319.9955)
			(xy 266.797785 -320.025522) (xy 266.749764 -320.048645) (xy 266.698834 -320.064353) (xy 266.646131 -320.072294)
			(xy 266.619482 -320.072766) (xy 266.589586 -320.072156) (xy 266.530636 -320.062164) (xy 266.474177 -320.042479)
			(xy 266.421793 -320.013653) (xy 266.397994 -319.99555) (xy 266.386351 -319.986854) (xy 266.359458 -319.97587)
			(xy 266.33056 -319.972906) (xy 266.301997 -319.978202) (xy 266.276083 -319.99133) (xy 266.254916 -320.011225)
			(xy 266.247118 -320.02349) (xy 266.233311 -320.045992) (xy 266.200049 -320.086989) (xy 266.161097 -320.122625)
			(xy 266.117309 -320.152117) (xy 266.069646 -320.174819) (xy 266.019153 -320.190233) (xy 265.966937 -320.198021)
			(xy 265.94054 -320.198496) (xy 265.913886 -320.19805) (xy 265.861173 -320.19011) (xy 265.810232 -320.174402)
			(xy 265.762201 -320.151276) (xy 265.718154 -320.12125) (xy 265.679074 -320.084994) (xy 265.645835 -320.043317)
			(xy 265.61918 -319.997152) (xy 265.599703 -319.94753) (xy 265.58784 -319.895559) (xy 265.583856 -319.8424)
			(xy 214.948006 -319.8424) (xy 214.93108 -319.881836) (xy 214.902428 -319.927796) (xy 214.867147 -319.968887)
			(xy 214.826051 -320.004161) (xy 214.780086 -320.032806) (xy 214.730315 -320.05416) (xy 214.677883 -320.06773)
			(xy 214.624002 -320.073204) (xy 214.569912 -320.070456) (xy 214.516863 -320.059549) (xy 214.466077 -320.040734)
			(xy 214.418726 -320.014446) (xy 214.375901 -319.981291) (xy 214.338591 -319.942032) (xy 214.307657 -319.897577)
			(xy 214.283811 -319.84895) (xy 214.267603 -319.797273) (xy 214.259408 -319.743738) (xy 214.258906 -319.716658)
			(xy 214.259414 -319.699386) (xy 214.25958 -319.685526) (xy 214.253401 -319.658518) (xy 214.240194 -319.634162)
			(xy 214.22093 -319.61425) (xy 214.197025 -319.600245) (xy 214.170237 -319.593176) (xy 214.142534 -319.593563)
			(xy 214.129112 -319.597024) (xy 214.104406 -319.6039) (xy 214.05366 -319.611292) (xy 214.02802 -319.611756)
			(xy 214.000937 -319.611224) (xy 213.947396 -319.603024) (xy 213.895714 -319.586811) (xy 213.847083 -319.562959)
			(xy 213.802624 -319.532017) (xy 213.763365 -319.4947) (xy 213.730209 -319.451868) (xy 213.703922 -319.404509)
			(xy 213.685109 -319.353715) (xy 213.674206 -319.300658) (xy 213.671463 -319.246562) (xy 213.168575 -319.246562)
			(xy 213.168992 -319.268856) (xy 213.168494 -319.295505) (xy 213.160551 -319.348209) (xy 213.144841 -319.399139)
			(xy 213.121715 -319.44716) (xy 213.091691 -319.491197) (xy 213.055439 -319.530268) (xy 213.013768 -319.563499)
			(xy 212.96761 -319.590148) (xy 212.917996 -319.60962) (xy 212.866034 -319.62148) (xy 212.812884 -319.625464)
			(xy 212.759734 -319.62148) (xy 212.707772 -319.60962) (xy 212.658158 -319.590148) (xy 212.612 -319.563499)
			(xy 212.570329 -319.530268) (xy 212.534077 -319.491197) (xy 212.504053 -319.44716) (xy 212.480927 -319.399139)
			(xy 212.465217 -319.348209) (xy 212.457274 -319.295505) (xy 205.565591 -319.295505) (xy 205.575641 -319.316373)
			(xy 205.591351 -319.367303) (xy 205.599294 -319.420007) (xy 205.599792 -319.446656) (xy 205.599294 -319.473305)
			(xy 205.591351 -319.526009) (xy 205.575641 -319.576939) (xy 205.552515 -319.62496) (xy 205.522491 -319.668997)
			(xy 205.486239 -319.708068) (xy 205.444568 -319.741299) (xy 205.44109 -319.743307) (xy 206.00415 -319.743307)
			(xy 206.00415 -319.690009) (xy 206.012093 -319.637305) (xy 206.027803 -319.586375) (xy 206.050929 -319.538354)
			(xy 206.080953 -319.494317) (xy 206.117205 -319.455246) (xy 206.158876 -319.422015) (xy 206.205034 -319.395366)
			(xy 206.254648 -319.375894) (xy 206.30661 -319.364034) (xy 206.35976 -319.360051) (xy 206.41291 -319.364034)
			(xy 206.464872 -319.375894) (xy 206.514486 -319.395366) (xy 206.560644 -319.422015) (xy 206.602315 -319.455246)
			(xy 206.638567 -319.494317) (xy 206.668591 -319.538354) (xy 206.691717 -319.586375) (xy 206.707427 -319.637305)
			(xy 206.71537 -319.690009) (xy 206.715868 -319.716658) (xy 206.71537 -319.743307) (xy 206.707427 -319.796011)
			(xy 206.691717 -319.846941) (xy 206.668591 -319.894962) (xy 206.638567 -319.938999) (xy 206.602315 -319.97807)
			(xy 206.560644 -320.011301) (xy 206.514486 -320.03795) (xy 206.464872 -320.057422) (xy 206.41291 -320.069282)
			(xy 206.35976 -320.073266) (xy 206.30661 -320.069282) (xy 206.254648 -320.057422) (xy 206.205034 -320.03795)
			(xy 206.158876 -320.011301) (xy 206.117205 -319.97807) (xy 206.080953 -319.938999) (xy 206.050929 -319.894962)
			(xy 206.027803 -319.846941) (xy 206.012093 -319.796011) (xy 206.00415 -319.743307) (xy 205.44109 -319.743307)
			(xy 205.39841 -319.767948) (xy 205.348796 -319.78742) (xy 205.296834 -319.79928) (xy 205.243684 -319.803264)
			(xy 205.190534 -319.79928) (xy 205.138572 -319.78742) (xy 205.088958 -319.767948) (xy 205.0428 -319.741299)
			(xy 205.001129 -319.708068) (xy 204.964877 -319.668997) (xy 204.934853 -319.62496) (xy 204.911727 -319.576939)
			(xy 204.896017 -319.526009) (xy 204.888074 -319.473305) (xy 198.032468 -319.473305) (xy 198.031841 -319.475339)
			(xy 198.008715 -319.52336) (xy 197.978691 -319.567397) (xy 197.942439 -319.606468) (xy 197.900768 -319.639699)
			(xy 197.85461 -319.666348) (xy 197.804996 -319.68582) (xy 197.753034 -319.69768) (xy 197.699884 -319.701664)
			(xy 197.646734 -319.69768) (xy 197.594772 -319.68582) (xy 197.545158 -319.666348) (xy 197.499 -319.639699)
			(xy 197.457329 -319.606468) (xy 197.421077 -319.567397) (xy 197.391053 -319.52336) (xy 197.367927 -319.475339)
			(xy 197.352217 -319.424409) (xy 197.344274 -319.371705) (xy 190.404301 -319.371705) (xy 190.395839 -319.399139)
			(xy 190.372713 -319.44716) (xy 190.342689 -319.491197) (xy 190.306437 -319.530268) (xy 190.264766 -319.563499)
			(xy 190.218608 -319.590148) (xy 190.168994 -319.60962) (xy 190.117032 -319.62148) (xy 190.063882 -319.625464)
			(xy 190.010732 -319.62148) (xy 189.95877 -319.60962) (xy 189.909156 -319.590148) (xy 189.862998 -319.563499)
			(xy 189.821327 -319.530268) (xy 189.785075 -319.491197) (xy 189.755051 -319.44716) (xy 189.731925 -319.399139)
			(xy 189.716215 -319.348209) (xy 189.708272 -319.295505) (xy 182.993769 -319.295505) (xy 182.993294 -319.320905)
			(xy 182.985351 -319.373609) (xy 182.969641 -319.424539) (xy 182.946515 -319.47256) (xy 182.916491 -319.516597)
			(xy 182.880239 -319.555668) (xy 182.838568 -319.588899) (xy 182.79241 -319.615548) (xy 182.742796 -319.63502)
			(xy 182.690834 -319.64688) (xy 182.637684 -319.650864) (xy 182.584534 -319.64688) (xy 182.532572 -319.63502)
			(xy 182.482958 -319.615548) (xy 182.4368 -319.588899) (xy 182.395129 -319.555668) (xy 182.358877 -319.516597)
			(xy 182.328853 -319.47256) (xy 182.305727 -319.424539) (xy 182.290017 -319.373609) (xy 182.282074 -319.320905)
			(xy 179.769804 -319.320905) (xy 179.758053 -319.345306) (xy 179.728029 -319.389343) (xy 179.691777 -319.428414)
			(xy 179.650106 -319.461645) (xy 179.603948 -319.488294) (xy 179.554334 -319.507766) (xy 179.502372 -319.519626)
			(xy 179.449222 -319.52361) (xy 179.396072 -319.519626) (xy 179.34411 -319.507766) (xy 179.294496 -319.488294)
			(xy 179.248338 -319.461645) (xy 179.206667 -319.428414) (xy 179.170415 -319.389343) (xy 179.140391 -319.345306)
			(xy 179.117265 -319.297285) (xy 179.101555 -319.246355) (xy 179.093612 -319.193651) (xy 177.03651 -319.193651)
			(xy 177.001126 -319.207538) (xy 176.949164 -319.219398) (xy 176.896014 -319.223382) (xy 176.842864 -319.219398)
			(xy 176.790902 -319.207538) (xy 176.741288 -319.188066) (xy 176.69513 -319.161417) (xy 176.653459 -319.128186)
			(xy 176.617207 -319.089115) (xy 176.587183 -319.045078) (xy 176.564057 -318.997057) (xy 176.548347 -318.946127)
			(xy 176.540404 -318.893423) (xy 169.707824 -318.893423) (xy 169.699881 -318.946127) (xy 169.684171 -318.997057)
			(xy 169.661045 -319.045078) (xy 169.631021 -319.089115) (xy 169.594769 -319.128186) (xy 169.553098 -319.161417)
			(xy 169.50694 -319.188066) (xy 169.457326 -319.207538) (xy 169.405364 -319.219398) (xy 169.352214 -319.223382)
			(xy 169.299064 -319.219398) (xy 169.247102 -319.207538) (xy 169.197488 -319.188066) (xy 169.15133 -319.161417)
			(xy 169.109659 -319.128186) (xy 169.073407 -319.089115) (xy 169.043383 -319.045078) (xy 169.020257 -318.997057)
			(xy 169.004547 -318.946127) (xy 168.996604 -318.893423) (xy 160.298139 -318.893423) (xy 160.296151 -318.919949)
			(xy 160.284292 -318.971911) (xy 160.264821 -319.021526) (xy 160.238174 -319.067684) (xy 160.204946 -319.109356)
			(xy 160.165878 -319.145611) (xy 160.121843 -319.175638) (xy 160.073826 -319.198768) (xy 160.022897 -319.214483)
			(xy 159.970195 -319.222433) (xy 159.943546 -319.222882) (xy 159.917242 -319.22239) (xy 159.865212 -319.214611)
			(xy 159.839914 -319.207388) (xy 159.826798 -319.203825) (xy 159.799643 -319.203014) (xy 159.773235 -319.209397)
			(xy 159.749449 -319.222523) (xy 159.729969 -319.241461) (xy 159.716178 -319.264868) (xy 159.709052 -319.291085)
			(xy 159.708596 -319.30467) (xy 159.708596 -319.676526) (xy 160.008824 -319.976754) (xy 160.665414 -319.976754)
			(xy 160.679607 -319.976283) (xy 160.706894 -319.968462) (xy 160.730973 -319.953429) (xy 160.74998 -319.932346)
			(xy 160.762447 -319.906845) (xy 160.767409 -319.878896) (xy 160.764483 -319.850661) (xy 160.759648 -319.837308)
			(xy 160.751508 -319.816118) (xy 160.740069 -319.772191) (xy 160.734323 -319.727163) (xy 160.733994 -319.704466)
			(xy 160.734545 -319.676485) (xy 160.743305 -319.621212) (xy 160.760602 -319.567989) (xy 160.786012 -319.518128)
			(xy 160.818909 -319.472855) (xy 160.858483 -319.433286) (xy 160.903759 -319.400393) (xy 160.953623 -319.374989)
			(xy 161.006847 -319.357696) (xy 161.062121 -319.348943) (xy 161.090102 -319.348358) (xy 161.117532 -319.348862)
			(xy 161.171746 -319.357266) (xy 161.224032 -319.373875) (xy 161.273157 -319.398297) (xy 161.317962 -319.429956)
			(xy 161.338006 -319.448688) (xy 161.348895 -319.458553) (xy 161.374938 -319.472131) (xy 161.40377 -319.477729)
			(xy 161.433002 -319.474882) (xy 161.460212 -319.463828) (xy 161.483147 -319.445481) (xy 161.49193 -319.433702)
			(xy 161.50874 -319.410569) (xy 161.548499 -319.369476) (xy 161.594308 -319.335256) (xy 161.644992 -319.308788)
			(xy 161.699252 -319.290749) (xy 161.755695 -319.281604) (xy 161.784284 -319.281048) (xy 161.812269 -319.281596)
			(xy 161.867551 -319.290348) (xy 161.920783 -319.307641) (xy 161.970655 -319.333048) (xy 162.015938 -319.365943)
			(xy 162.055518 -319.405516) (xy 162.088421 -319.450794) (xy 162.099894 -319.473305) (xy 167.169074 -319.473305)
			(xy 167.169074 -319.420007) (xy 167.177017 -319.367303) (xy 167.192727 -319.316373) (xy 167.215853 -319.268352)
			(xy 167.245877 -319.224315) (xy 167.282129 -319.185244) (xy 167.3238 -319.152013) (xy 167.369958 -319.125364)
			(xy 167.419572 -319.105892) (xy 167.471534 -319.094032) (xy 167.524684 -319.090049) (xy 167.577834 -319.094032)
			(xy 167.629796 -319.105892) (xy 167.67941 -319.125364) (xy 167.725568 -319.152013) (xy 167.767239 -319.185244)
			(xy 167.803491 -319.224315) (xy 167.833515 -319.268352) (xy 167.856641 -319.316373) (xy 167.872351 -319.367303)
			(xy 167.880294 -319.420007) (xy 167.880792 -319.446656) (xy 167.880294 -319.473305) (xy 167.872351 -319.526009)
			(xy 167.856641 -319.576939) (xy 167.833515 -319.62496) (xy 167.803491 -319.668997) (xy 167.767239 -319.708068)
			(xy 167.725568 -319.741299) (xy 167.67941 -319.767948) (xy 167.629796 -319.78742) (xy 167.577834 -319.79928)
			(xy 167.524684 -319.803264) (xy 167.471534 -319.79928) (xy 167.419572 -319.78742) (xy 167.369958 -319.767948)
			(xy 167.3238 -319.741299) (xy 167.282129 -319.708068) (xy 167.245877 -319.668997) (xy 167.215853 -319.62496)
			(xy 167.192727 -319.576939) (xy 167.177017 -319.526009) (xy 167.169074 -319.473305) (xy 162.099894 -319.473305)
			(xy 162.113836 -319.500662) (xy 162.131137 -319.553891) (xy 162.1399 -319.609171) (xy 162.140392 -319.637156)
			(xy 162.140016 -319.661505) (xy 162.133417 -319.709754) (xy 162.120296 -319.75665) (xy 162.100899 -319.801318)
			(xy 162.088576 -319.822322) (xy 162.081925 -319.834039) (xy 162.074415 -319.859904) (xy 162.073928 -319.886833)
			(xy 162.080497 -319.912953) (xy 162.093665 -319.936448) (xy 162.112517 -319.955684) (xy 162.135742 -319.969323)
			(xy 162.161724 -319.976417) (xy 162.17519 -319.976754) (xy 162.497262 -319.976754) (xy 162.793405 -320.272897)
			(xy 164.15765 -320.272897) (xy 164.15765 -320.219599) (xy 164.165593 -320.166895) (xy 164.181303 -320.115965)
			(xy 164.204429 -320.067944) (xy 164.234453 -320.023907) (xy 164.270705 -319.984836) (xy 164.312376 -319.951605)
			(xy 164.358534 -319.924956) (xy 164.408148 -319.905484) (xy 164.46011 -319.893624) (xy 164.51326 -319.889641)
			(xy 164.56641 -319.893624) (xy 164.618372 -319.905484) (xy 164.667887 -319.924917) (xy 168.46041 -319.924917)
			(xy 168.46041 -319.871619) (xy 168.468353 -319.818915) (xy 168.484063 -319.767985) (xy 168.507189 -319.719964)
			(xy 168.537213 -319.675927) (xy 168.573465 -319.636856) (xy 168.615136 -319.603625) (xy 168.661294 -319.576976)
			(xy 168.710908 -319.557504) (xy 168.76287 -319.545644) (xy 168.81602 -319.541661) (xy 168.86917 -319.545644)
			(xy 168.886086 -319.549505) (xy 171.360074 -319.549505) (xy 171.360074 -319.496207) (xy 171.368017 -319.443503)
			(xy 171.383727 -319.392573) (xy 171.406853 -319.344552) (xy 171.436877 -319.300515) (xy 171.473129 -319.261444)
			(xy 171.5148 -319.228213) (xy 171.560958 -319.201564) (xy 171.610572 -319.182092) (xy 171.662534 -319.170232)
			(xy 171.715684 -319.166249) (xy 171.768834 -319.170232) (xy 171.820796 -319.182092) (xy 171.87041 -319.201564)
			(xy 171.916568 -319.228213) (xy 171.958239 -319.261444) (xy 171.989842 -319.295505) (xy 174.629054 -319.295505)
			(xy 174.629054 -319.242207) (xy 174.636997 -319.189503) (xy 174.652707 -319.138573) (xy 174.675833 -319.090552)
			(xy 174.705857 -319.046515) (xy 174.742109 -319.007444) (xy 174.78378 -318.974213) (xy 174.829938 -318.947564)
			(xy 174.879552 -318.928092) (xy 174.931514 -318.916232) (xy 174.984664 -318.912249) (xy 175.037814 -318.916232)
			(xy 175.089776 -318.928092) (xy 175.13939 -318.947564) (xy 175.185548 -318.974213) (xy 175.227219 -319.007444)
			(xy 175.263471 -319.046515) (xy 175.293495 -319.090552) (xy 175.316621 -319.138573) (xy 175.332331 -319.189503)
			(xy 175.340274 -319.242207) (xy 175.340772 -319.268856) (xy 175.340274 -319.295505) (xy 175.332331 -319.348209)
			(xy 175.316621 -319.399139) (xy 175.293495 -319.44716) (xy 175.263471 -319.491197) (xy 175.227219 -319.530268)
			(xy 175.185548 -319.563499) (xy 175.13939 -319.590148) (xy 175.089776 -319.60962) (xy 175.037814 -319.62148)
			(xy 174.984664 -319.625464) (xy 174.931514 -319.62148) (xy 174.879552 -319.60962) (xy 174.829938 -319.590148)
			(xy 174.78378 -319.563499) (xy 174.742109 -319.530268) (xy 174.705857 -319.491197) (xy 174.675833 -319.44716)
			(xy 174.652707 -319.399139) (xy 174.636997 -319.348209) (xy 174.629054 -319.295505) (xy 171.989842 -319.295505)
			(xy 171.994491 -319.300515) (xy 172.024515 -319.344552) (xy 172.047641 -319.392573) (xy 172.063351 -319.443503)
			(xy 172.071294 -319.496207) (xy 172.071792 -319.522856) (xy 172.071294 -319.549505) (xy 172.063351 -319.602209)
			(xy 172.047641 -319.653139) (xy 172.024515 -319.70116) (xy 171.99578 -319.743307) (xy 183.46419 -319.743307)
			(xy 183.46419 -319.690009) (xy 183.472133 -319.637305) (xy 183.487843 -319.586375) (xy 183.510969 -319.538354)
			(xy 183.540993 -319.494317) (xy 183.577245 -319.455246) (xy 183.618916 -319.422015) (xy 183.665074 -319.395366)
			(xy 183.714688 -319.375894) (xy 183.76665 -319.364034) (xy 183.8198 -319.360051) (xy 183.87295 -319.364034)
			(xy 183.924912 -319.375894) (xy 183.974526 -319.395366) (xy 184.020684 -319.422015) (xy 184.062355 -319.455246)
			(xy 184.098607 -319.494317) (xy 184.128631 -319.538354) (xy 184.151757 -319.586375) (xy 184.167467 -319.637305)
			(xy 184.17541 -319.690009) (xy 184.175908 -319.716658) (xy 184.17541 -319.743307) (xy 184.167467 -319.796011)
			(xy 184.151757 -319.846941) (xy 184.128631 -319.894962) (xy 184.12033 -319.907137) (xy 198.55941 -319.907137)
			(xy 198.55941 -319.853839) (xy 198.567353 -319.801135) (xy 198.583063 -319.750205) (xy 198.606189 -319.702184)
			(xy 198.636213 -319.658147) (xy 198.672465 -319.619076) (xy 198.714136 -319.585845) (xy 198.760294 -319.559196)
			(xy 198.809908 -319.539724) (xy 198.86187 -319.527864) (xy 198.91502 -319.523881) (xy 198.96817 -319.527864)
			(xy 199.020132 -319.539724) (xy 199.069746 -319.559196) (xy 199.115904 -319.585845) (xy 199.157575 -319.619076)
			(xy 199.193827 -319.658147) (xy 199.223851 -319.702184) (xy 199.246977 -319.750205) (xy 199.262687 -319.801135)
			(xy 199.27063 -319.853839) (xy 199.271128 -319.880488) (xy 199.27063 -319.907137) (xy 199.262687 -319.959841)
			(xy 199.246977 -320.010771) (xy 199.223851 -320.058792) (xy 199.193827 -320.102829) (xy 199.157575 -320.1419)
			(xy 199.115904 -320.175131) (xy 199.069746 -320.20178) (xy 199.020132 -320.221252) (xy 198.96817 -320.233112)
			(xy 198.91502 -320.237096) (xy 198.86187 -320.233112) (xy 198.809908 -320.221252) (xy 198.760294 -320.20178)
			(xy 198.714136 -320.175131) (xy 198.672465 -320.1419) (xy 198.636213 -320.102829) (xy 198.606189 -320.058792)
			(xy 198.583063 -320.010771) (xy 198.567353 -319.959841) (xy 198.55941 -319.907137) (xy 184.12033 -319.907137)
			(xy 184.098607 -319.938999) (xy 184.062355 -319.97807) (xy 184.020684 -320.011301) (xy 183.974526 -320.03795)
			(xy 183.924912 -320.057422) (xy 183.87295 -320.069282) (xy 183.8198 -320.073266) (xy 183.76665 -320.069282)
			(xy 183.714688 -320.057422) (xy 183.665074 -320.03795) (xy 183.618916 -320.011301) (xy 183.577245 -319.97807)
			(xy 183.540993 -319.938999) (xy 183.510969 -319.894962) (xy 183.487843 -319.846941) (xy 183.472133 -319.796011)
			(xy 183.46419 -319.743307) (xy 171.99578 -319.743307) (xy 171.994491 -319.745197) (xy 171.958239 -319.784268)
			(xy 171.916568 -319.817499) (xy 171.87041 -319.844148) (xy 171.820796 -319.86362) (xy 171.768834 -319.87548)
			(xy 171.715684 -319.879464) (xy 171.662534 -319.87548) (xy 171.610572 -319.86362) (xy 171.560958 -319.844148)
			(xy 171.5148 -319.817499) (xy 171.473129 -319.784268) (xy 171.436877 -319.745197) (xy 171.406853 -319.70116)
			(xy 171.383727 -319.653139) (xy 171.368017 -319.602209) (xy 171.360074 -319.549505) (xy 168.886086 -319.549505)
			(xy 168.921132 -319.557504) (xy 168.970746 -319.576976) (xy 169.016904 -319.603625) (xy 169.058575 -319.636856)
			(xy 169.094827 -319.675927) (xy 169.124851 -319.719964) (xy 169.147977 -319.767985) (xy 169.163687 -319.818915)
			(xy 169.17163 -319.871619) (xy 169.172128 -319.898268) (xy 169.17163 -319.924917) (xy 169.163687 -319.977621)
			(xy 169.147977 -320.028551) (xy 169.124851 -320.076572) (xy 169.094827 -320.120609) (xy 169.058575 -320.15968)
			(xy 169.016904 -320.192911) (xy 168.970746 -320.21956) (xy 168.921132 -320.239032) (xy 168.86917 -320.250892)
			(xy 168.81602 -320.254876) (xy 168.76287 -320.250892) (xy 168.710908 -320.239032) (xy 168.661294 -320.21956)
			(xy 168.615136 -320.192911) (xy 168.573465 -320.15968) (xy 168.537213 -320.120609) (xy 168.507189 -320.076572)
			(xy 168.484063 -320.028551) (xy 168.468353 -319.977621) (xy 168.46041 -319.924917) (xy 164.667887 -319.924917)
			(xy 164.667986 -319.924956) (xy 164.714144 -319.951605) (xy 164.755815 -319.984836) (xy 164.792067 -320.023907)
			(xy 164.822091 -320.067944) (xy 164.845217 -320.115965) (xy 164.860927 -320.166895) (xy 164.86887 -320.219599)
			(xy 164.869368 -320.246248) (xy 164.86887 -320.272897) (xy 164.860927 -320.325601) (xy 164.845217 -320.376531)
			(xy 164.822091 -320.424552) (xy 164.792067 -320.468589) (xy 164.755815 -320.50766) (xy 164.714144 -320.540891)
			(xy 164.667986 -320.56754) (xy 164.618372 -320.587012) (xy 164.56641 -320.598872) (xy 164.51326 -320.602856)
			(xy 164.46011 -320.598872) (xy 164.408148 -320.587012) (xy 164.358534 -320.56754) (xy 164.312376 -320.540891)
			(xy 164.270705 -320.50766) (xy 164.234453 -320.468589) (xy 164.204429 -320.424552) (xy 164.181303 -320.376531)
			(xy 164.165593 -320.325601) (xy 164.15765 -320.272897) (xy 162.793405 -320.272897) (xy 163.481745 -320.961237)
			(xy 167.63999 -320.961237) (xy 167.63999 -320.907939) (xy 167.647933 -320.855235) (xy 167.663643 -320.804305)
			(xy 167.686769 -320.756284) (xy 167.716793 -320.712247) (xy 167.753045 -320.673176) (xy 167.794716 -320.639945)
			(xy 167.840874 -320.613296) (xy 167.890488 -320.593824) (xy 167.94245 -320.581964) (xy 167.9956 -320.577981)
			(xy 168.04875 -320.581964) (xy 168.100712 -320.593824) (xy 168.150326 -320.613296) (xy 168.196484 -320.639945)
			(xy 168.238155 -320.673176) (xy 168.274407 -320.712247) (xy 168.304431 -320.756284) (xy 168.327557 -320.804305)
			(xy 168.343267 -320.855235) (xy 168.35121 -320.907939) (xy 168.351708 -320.934588) (xy 168.35121 -320.961237)
			(xy 168.343267 -321.013941) (xy 168.327557 -321.064871) (xy 168.304431 -321.112892) (xy 168.274407 -321.156929)
			(xy 168.258701 -321.173856) (xy 168.971976 -321.173856) (xy 168.97251 -321.146594) (xy 168.98082 -321.092708)
			(xy 168.997254 -321.04072) (xy 169.021427 -320.991848) (xy 169.052773 -320.947237) (xy 169.07129 -320.927222)
			(xy 169.081209 -320.916226) (xy 169.09478 -320.88992) (xy 169.100227 -320.860826) (xy 169.097091 -320.831392)
			(xy 169.085637 -320.804098) (xy 169.076624 -320.792348) (xy 169.061457 -320.773185) (xy 169.035972 -320.731484)
			(xy 169.016427 -320.68669) (xy 169.00319 -320.639645) (xy 168.996509 -320.591232) (xy 168.996106 -320.566796)
			(xy 168.996604 -320.540147) (xy 169.004547 -320.487443) (xy 169.020257 -320.436513) (xy 169.043383 -320.388492)
			(xy 169.073407 -320.344455) (xy 169.109659 -320.305384) (xy 169.15133 -320.272153) (xy 169.197488 -320.245504)
			(xy 169.247102 -320.226032) (xy 169.299064 -320.214172) (xy 169.352214 -320.210189) (xy 169.405364 -320.214172)
			(xy 169.457326 -320.226032) (xy 169.50694 -320.245504) (xy 169.553098 -320.272153) (xy 169.594769 -320.305384)
			(xy 169.631021 -320.344455) (xy 169.661045 -320.388492) (xy 169.684171 -320.436513) (xy 169.699881 -320.487443)
			(xy 169.707824 -320.540147) (xy 169.708322 -320.566796) (xy 169.707831 -320.593445) (xy 171.85131 -320.593445)
			(xy 171.85131 -320.540147) (xy 171.859253 -320.487443) (xy 171.874963 -320.436513) (xy 171.898089 -320.388492)
			(xy 171.928113 -320.344455) (xy 171.964365 -320.305384) (xy 172.006036 -320.272153) (xy 172.052194 -320.245504)
			(xy 172.101808 -320.226032) (xy 172.15377 -320.214172) (xy 172.20692 -320.210189) (xy 172.26007 -320.214172)
			(xy 172.312032 -320.226032) (xy 172.361646 -320.245504) (xy 172.407804 -320.272153) (xy 172.449475 -320.305384)
			(xy 172.485727 -320.344455) (xy 172.515751 -320.388492) (xy 172.534608 -320.427649) (xy 175.944883 -320.427649)
			(xy 175.950365 -320.373766) (xy 175.963943 -320.321333) (xy 175.985305 -320.271562) (xy 176.013958 -320.2256)
			(xy 176.04924 -320.184506) (xy 176.090338 -320.149229) (xy 176.136305 -320.120583) (xy 176.186079 -320.099228)
			(xy 176.238513 -320.085656) (xy 176.292397 -320.080182) (xy 176.346489 -320.08293) (xy 176.399542 -320.093838)
			(xy 176.45033 -320.112653) (xy 176.497684 -320.138943) (xy 176.54051 -320.172101) (xy 176.577821 -320.211361)
			(xy 176.608757 -320.255819) (xy 176.632604 -320.304449) (xy 176.648811 -320.356129) (xy 176.657006 -320.409667)
			(xy 176.657508 -320.436748) (xy 176.657214 -320.457191) (xy 176.6525 -320.497805) (xy 176.64811 -320.517774)
			(xy 176.64542 -320.531376) (xy 176.646629 -320.559064) (xy 176.649155 -320.5668) (xy 178.755764 -320.5668)
			(xy 178.759748 -320.513644) (xy 178.771609 -320.461676) (xy 178.791084 -320.412057) (xy 178.817737 -320.365894)
			(xy 178.850973 -320.32422) (xy 178.890049 -320.287964) (xy 178.934092 -320.257938) (xy 178.982119 -320.234812)
			(xy 179.033056 -320.219102) (xy 179.085766 -320.21116) (xy 179.112418 -320.210688) (xy 179.140505 -320.211212)
			(xy 179.195981 -320.220047) (xy 179.249383 -320.237479) (xy 179.299386 -320.263077) (xy 179.344753 -320.296206)
			(xy 179.384357 -320.336044) (xy 179.401216 -320.358516) (xy 179.409643 -320.369387) (xy 179.43112 -320.386554)
			(xy 179.456394 -320.397377) (xy 179.483639 -320.401074) (xy 179.510884 -320.397377) (xy 179.536158 -320.386554)
			(xy 179.557635 -320.369387) (xy 179.566062 -320.358516) (xy 179.582909 -320.336033) (xy 179.622506 -320.296183)
			(xy 179.667872 -320.263048) (xy 179.71788 -320.237451) (xy 179.771289 -320.220029) (xy 179.826771 -320.211213)
			(xy 179.85486 -320.210688) (xy 179.881513 -320.211166) (xy 179.934224 -320.219106) (xy 179.985162 -320.234813)
			(xy 180.033191 -320.257938) (xy 180.077236 -320.287963) (xy 180.116314 -320.324217) (xy 180.149551 -320.365892)
			(xy 180.176206 -320.412055) (xy 180.195682 -320.461675) (xy 180.207544 -320.513644) (xy 180.211528 -320.5668)
			(xy 180.209531 -320.593445) (xy 184.084204 -320.593445) (xy 184.084204 -320.540147) (xy 184.092147 -320.487443)
			(xy 184.107857 -320.436513) (xy 184.130983 -320.388492) (xy 184.161007 -320.344455) (xy 184.197259 -320.305384)
			(xy 184.23893 -320.272153) (xy 184.285088 -320.245504) (xy 184.334702 -320.226032) (xy 184.386664 -320.214172)
			(xy 184.439814 -320.210189) (xy 184.492964 -320.214172) (xy 184.544926 -320.226032) (xy 184.59454 -320.245504)
			(xy 184.640698 -320.272153) (xy 184.682369 -320.305384) (xy 184.718621 -320.344455) (xy 184.748645 -320.388492)
			(xy 184.771771 -320.436513) (xy 184.787481 -320.487443) (xy 184.795424 -320.540147) (xy 184.795922 -320.566796)
			(xy 184.795424 -320.593445) (xy 186.98971 -320.593445) (xy 186.98971 -320.540147) (xy 186.997653 -320.487443)
			(xy 187.013363 -320.436513) (xy 187.036489 -320.388492) (xy 187.066513 -320.344455) (xy 187.102765 -320.305384)
			(xy 187.144436 -320.272153) (xy 187.190594 -320.245504) (xy 187.240208 -320.226032) (xy 187.29217 -320.214172)
			(xy 187.34532 -320.210189) (xy 187.39847 -320.214172) (xy 187.450432 -320.226032) (xy 187.500046 -320.245504)
			(xy 187.546204 -320.272153) (xy 187.587875 -320.305384) (xy 187.624127 -320.344455) (xy 187.650679 -320.3834)
			(xy 190.905401 -320.3834) (xy 190.909383 -320.330252) (xy 190.921243 -320.27829) (xy 190.940715 -320.228677)
			(xy 190.967364 -320.18252) (xy 191.000594 -320.140851) (xy 191.039664 -320.104599) (xy 191.0837 -320.074576)
			(xy 191.13172 -320.051451) (xy 191.182649 -320.035741) (xy 191.235351 -320.027798) (xy 191.262 -320.0273)
			(xy 191.28869 -320.027759) (xy 191.341473 -320.035726) (xy 191.392475 -320.051483) (xy 191.440554 -320.074674)
			(xy 191.484633 -320.104783) (xy 191.523724 -320.141133) (xy 191.556952 -320.18291) (xy 191.583572 -320.229179)
			(xy 191.593724 -320.253868) (xy 191.599213 -320.266562) (xy 191.615757 -320.288704) (xy 191.637635 -320.305595)
			(xy 191.663243 -320.315997) (xy 191.690702 -320.319148) (xy 191.718 -320.314816) (xy 191.743135 -320.303318)
			(xy 191.753998 -320.294762) (xy 191.773344 -320.278968) (xy 191.81563 -320.252395) (xy 191.861211 -320.231986)
			(xy 191.909196 -320.21814) (xy 191.958643 -320.211128) (xy 191.983614 -320.210688) (xy 192.010262 -320.211195)
			(xy 192.062963 -320.21914) (xy 192.113892 -320.234851) (xy 192.16191 -320.257977) (xy 192.205945 -320.288001)
			(xy 192.245013 -320.324253) (xy 192.278243 -320.365923) (xy 192.30489 -320.412079) (xy 192.324361 -320.461692)
			(xy 192.336221 -320.513652) (xy 192.340204 -320.5668) (xy 192.338207 -320.593445) (xy 194.48271 -320.593445)
			(xy 194.48271 -320.540147) (xy 194.490653 -320.487443) (xy 194.506363 -320.436513) (xy 194.529489 -320.388492)
			(xy 194.559513 -320.344455) (xy 194.595765 -320.305384) (xy 194.637436 -320.272153) (xy 194.683594 -320.245504)
			(xy 194.733208 -320.226032) (xy 194.78517 -320.214172) (xy 194.83832 -320.210189) (xy 194.89147 -320.214172)
			(xy 194.943432 -320.226032) (xy 194.993046 -320.245504) (xy 195.039204 -320.272153) (xy 195.080875 -320.305384)
			(xy 195.117127 -320.344455) (xy 195.147151 -320.388492) (xy 195.170277 -320.436513) (xy 195.185987 -320.487443)
			(xy 195.19393 -320.540147) (xy 195.194428 -320.566796) (xy 195.19393 -320.593445) (xy 199.171804 -320.593445)
			(xy 199.171804 -320.540147) (xy 199.179747 -320.487443) (xy 199.195457 -320.436513) (xy 199.218583 -320.388492)
			(xy 199.248607 -320.344455) (xy 199.284859 -320.305384) (xy 199.32653 -320.272153) (xy 199.372688 -320.245504)
			(xy 199.422302 -320.226032) (xy 199.474264 -320.214172) (xy 199.527414 -320.210189) (xy 199.580564 -320.214172)
			(xy 199.632526 -320.226032) (xy 199.68214 -320.245504) (xy 199.728298 -320.272153) (xy 199.769969 -320.305384)
			(xy 199.806221 -320.344455) (xy 199.836245 -320.388492) (xy 199.859371 -320.436513) (xy 199.875081 -320.487443)
			(xy 199.883024 -320.540147) (xy 199.883522 -320.566796) (xy 199.883024 -320.593445) (xy 202.05191 -320.593445)
			(xy 202.05191 -320.540147) (xy 202.059853 -320.487443) (xy 202.075563 -320.436513) (xy 202.098689 -320.388492)
			(xy 202.128713 -320.344455) (xy 202.164965 -320.305384) (xy 202.206636 -320.272153) (xy 202.252794 -320.245504)
			(xy 202.302408 -320.226032) (xy 202.35437 -320.214172) (xy 202.40752 -320.210189) (xy 202.46067 -320.214172)
			(xy 202.512632 -320.226032) (xy 202.562246 -320.245504) (xy 202.608404 -320.272153) (xy 202.650075 -320.305384)
			(xy 202.686327 -320.344455) (xy 202.716351 -320.388492) (xy 202.739477 -320.436513) (xy 202.755187 -320.487443)
			(xy 202.76313 -320.540147) (xy 202.763628 -320.566796) (xy 202.76313 -320.593445) (xy 206.715604 -320.593445)
			(xy 206.715604 -320.540147) (xy 206.723547 -320.487443) (xy 206.739257 -320.436513) (xy 206.762383 -320.388492)
			(xy 206.792407 -320.344455) (xy 206.828659 -320.305384) (xy 206.87033 -320.272153) (xy 206.916488 -320.245504)
			(xy 206.966102 -320.226032) (xy 207.018064 -320.214172) (xy 207.071214 -320.210189) (xy 207.124364 -320.214172)
			(xy 207.176326 -320.226032) (xy 207.22594 -320.245504) (xy 207.272098 -320.272153) (xy 207.313769 -320.305384)
			(xy 207.350021 -320.344455) (xy 207.380045 -320.388492) (xy 207.403171 -320.436513) (xy 207.418881 -320.487443)
			(xy 207.426824 -320.540147) (xy 207.427322 -320.566796) (xy 207.426824 -320.593445) (xy 209.63889 -320.593445)
			(xy 209.63889 -320.540147) (xy 209.646833 -320.487443) (xy 209.662543 -320.436513) (xy 209.685669 -320.388492)
			(xy 209.715693 -320.344455) (xy 209.751945 -320.305384) (xy 209.793616 -320.272153) (xy 209.839774 -320.245504)
			(xy 209.889388 -320.226032) (xy 209.94135 -320.214172) (xy 209.9945 -320.210189) (xy 210.04765 -320.214172)
			(xy 210.099612 -320.226032) (xy 210.149226 -320.245504) (xy 210.195384 -320.272153) (xy 210.237055 -320.305384)
			(xy 210.273307 -320.344455) (xy 210.303331 -320.388492) (xy 210.326457 -320.436513) (xy 210.342167 -320.487443)
			(xy 210.35011 -320.540147) (xy 210.350608 -320.566796) (xy 210.35011 -320.593445) (xy 214.259404 -320.593445)
			(xy 214.259404 -320.540147) (xy 214.267347 -320.487443) (xy 214.283057 -320.436513) (xy 214.306183 -320.388492)
			(xy 214.336207 -320.344455) (xy 214.372459 -320.305384) (xy 214.41413 -320.272153) (xy 214.460288 -320.245504)
			(xy 214.509902 -320.226032) (xy 214.561864 -320.214172) (xy 214.615014 -320.210189) (xy 214.668164 -320.214172)
			(xy 214.720126 -320.226032) (xy 214.76974 -320.245504) (xy 214.815898 -320.272153) (xy 214.857569 -320.305384)
			(xy 214.893821 -320.344455) (xy 214.923845 -320.388492) (xy 214.946971 -320.436513) (xy 214.962681 -320.487443)
			(xy 214.970624 -320.540147) (xy 214.971122 -320.566796) (xy 214.970624 -320.593445) (xy 254.620004 -320.593445)
			(xy 254.620004 -320.540147) (xy 254.627947 -320.487443) (xy 254.643657 -320.436513) (xy 254.666783 -320.388492)
			(xy 254.696807 -320.344455) (xy 254.733059 -320.305384) (xy 254.77473 -320.272153) (xy 254.820888 -320.245504)
			(xy 254.870502 -320.226032) (xy 254.922464 -320.214172) (xy 254.975614 -320.210189) (xy 255.028764 -320.214172)
			(xy 255.080726 -320.226032) (xy 255.13034 -320.245504) (xy 255.176498 -320.272153) (xy 255.218169 -320.305384)
			(xy 255.254421 -320.344455) (xy 255.284445 -320.388492) (xy 255.307571 -320.436513) (xy 255.323281 -320.487443)
			(xy 255.331224 -320.540147) (xy 255.331722 -320.566796) (xy 255.331224 -320.593445) (xy 258.720072 -320.593445)
			(xy 258.720072 -320.540147) (xy 258.728015 -320.487443) (xy 258.743725 -320.436513) (xy 258.766851 -320.388492)
			(xy 258.796875 -320.344455) (xy 258.833127 -320.305384) (xy 258.874798 -320.272153) (xy 258.920956 -320.245504)
			(xy 258.97057 -320.226032) (xy 259.022532 -320.214172) (xy 259.075682 -320.210189) (xy 259.128832 -320.214172)
			(xy 259.180794 -320.226032) (xy 259.230408 -320.245504) (xy 259.276566 -320.272153) (xy 259.318237 -320.305384)
			(xy 259.354489 -320.344455) (xy 259.384513 -320.388492) (xy 259.388782 -320.397357) (xy 261.47521 -320.397357)
			(xy 261.47521 -320.344059) (xy 261.483153 -320.291355) (xy 261.498863 -320.240425) (xy 261.521989 -320.192404)
			(xy 261.552013 -320.148367) (xy 261.588265 -320.109296) (xy 261.629936 -320.076065) (xy 261.676094 -320.049416)
			(xy 261.725708 -320.029944) (xy 261.77767 -320.018084) (xy 261.83082 -320.014101) (xy 261.88397 -320.018084)
			(xy 261.935932 -320.029944) (xy 261.985546 -320.049416) (xy 262.031704 -320.076065) (xy 262.073375 -320.109296)
			(xy 262.109627 -320.148367) (xy 262.139651 -320.192404) (xy 262.162777 -320.240425) (xy 262.178487 -320.291355)
			(xy 262.18643 -320.344059) (xy 262.186928 -320.370708) (xy 262.18643 -320.397357) (xy 262.178487 -320.450061)
			(xy 262.162777 -320.500991) (xy 262.139651 -320.549012) (xy 262.109627 -320.593049) (xy 262.073375 -320.63212)
			(xy 262.031704 -320.665351) (xy 261.985546 -320.692) (xy 261.935932 -320.711472) (xy 261.88397 -320.723332)
			(xy 261.83082 -320.727316) (xy 261.77767 -320.723332) (xy 261.725708 -320.711472) (xy 261.676094 -320.692)
			(xy 261.629936 -320.665351) (xy 261.588265 -320.63212) (xy 261.552013 -320.593049) (xy 261.521989 -320.549012)
			(xy 261.498863 -320.500991) (xy 261.483153 -320.450061) (xy 261.47521 -320.397357) (xy 259.388782 -320.397357)
			(xy 259.407639 -320.436513) (xy 259.423349 -320.487443) (xy 259.431292 -320.540147) (xy 259.43179 -320.566796)
			(xy 259.431292 -320.593445) (xy 259.423349 -320.646149) (xy 259.407639 -320.697079) (xy 259.384513 -320.7451)
			(xy 259.354489 -320.789137) (xy 259.318237 -320.828208) (xy 259.276566 -320.861439) (xy 259.230408 -320.888088)
			(xy 259.180794 -320.90756) (xy 259.128832 -320.91942) (xy 259.075682 -320.923404) (xy 259.022532 -320.91942)
			(xy 258.97057 -320.90756) (xy 258.920956 -320.888088) (xy 258.874798 -320.861439) (xy 258.833127 -320.828208)
			(xy 258.796875 -320.789137) (xy 258.766851 -320.7451) (xy 258.743725 -320.697079) (xy 258.728015 -320.646149)
			(xy 258.720072 -320.593445) (xy 255.331224 -320.593445) (xy 255.323281 -320.646149) (xy 255.307571 -320.697079)
			(xy 255.284445 -320.7451) (xy 255.254421 -320.789137) (xy 255.218169 -320.828208) (xy 255.176498 -320.861439)
			(xy 255.13034 -320.888088) (xy 255.080726 -320.90756) (xy 255.028764 -320.91942) (xy 254.975614 -320.923404)
			(xy 254.922464 -320.91942) (xy 254.870502 -320.90756) (xy 254.820888 -320.888088) (xy 254.77473 -320.861439)
			(xy 254.733059 -320.828208) (xy 254.696807 -320.789137) (xy 254.666783 -320.7451) (xy 254.643657 -320.697079)
			(xy 254.627947 -320.646149) (xy 254.620004 -320.593445) (xy 214.970624 -320.593445) (xy 214.962681 -320.646149)
			(xy 214.946971 -320.697079) (xy 214.923845 -320.7451) (xy 214.893821 -320.789137) (xy 214.857569 -320.828208)
			(xy 214.815898 -320.861439) (xy 214.76974 -320.888088) (xy 214.720126 -320.90756) (xy 214.668164 -320.91942)
			(xy 214.615014 -320.923404) (xy 214.561864 -320.91942) (xy 214.509902 -320.90756) (xy 214.460288 -320.888088)
			(xy 214.41413 -320.861439) (xy 214.372459 -320.828208) (xy 214.336207 -320.789137) (xy 214.306183 -320.7451)
			(xy 214.283057 -320.697079) (xy 214.267347 -320.646149) (xy 214.259404 -320.593445) (xy 210.35011 -320.593445)
			(xy 210.342167 -320.646149) (xy 210.326457 -320.697079) (xy 210.303331 -320.7451) (xy 210.273307 -320.789137)
			(xy 210.237055 -320.828208) (xy 210.195384 -320.861439) (xy 210.149226 -320.888088) (xy 210.099612 -320.90756)
			(xy 210.04765 -320.91942) (xy 209.9945 -320.923404) (xy 209.94135 -320.91942) (xy 209.889388 -320.90756)
			(xy 209.839774 -320.888088) (xy 209.793616 -320.861439) (xy 209.751945 -320.828208) (xy 209.715693 -320.789137)
			(xy 209.685669 -320.7451) (xy 209.662543 -320.697079) (xy 209.646833 -320.646149) (xy 209.63889 -320.593445)
			(xy 207.426824 -320.593445) (xy 207.418881 -320.646149) (xy 207.403171 -320.697079) (xy 207.380045 -320.7451)
			(xy 207.350021 -320.789137) (xy 207.313769 -320.828208) (xy 207.272098 -320.861439) (xy 207.22594 -320.888088)
			(xy 207.176326 -320.90756) (xy 207.124364 -320.91942) (xy 207.071214 -320.923404) (xy 207.018064 -320.91942)
			(xy 206.966102 -320.90756) (xy 206.916488 -320.888088) (xy 206.87033 -320.861439) (xy 206.828659 -320.828208)
			(xy 206.792407 -320.789137) (xy 206.762383 -320.7451) (xy 206.739257 -320.697079) (xy 206.723547 -320.646149)
			(xy 206.715604 -320.593445) (xy 202.76313 -320.593445) (xy 202.755187 -320.646149) (xy 202.739477 -320.697079)
			(xy 202.716351 -320.7451) (xy 202.686327 -320.789137) (xy 202.650075 -320.828208) (xy 202.608404 -320.861439)
			(xy 202.562246 -320.888088) (xy 202.512632 -320.90756) (xy 202.46067 -320.91942) (xy 202.40752 -320.923404)
			(xy 202.35437 -320.91942) (xy 202.302408 -320.90756) (xy 202.252794 -320.888088) (xy 202.206636 -320.861439)
			(xy 202.164965 -320.828208) (xy 202.128713 -320.789137) (xy 202.098689 -320.7451) (xy 202.075563 -320.697079)
			(xy 202.059853 -320.646149) (xy 202.05191 -320.593445) (xy 199.883024 -320.593445) (xy 199.875081 -320.646149)
			(xy 199.859371 -320.697079) (xy 199.836245 -320.7451) (xy 199.806221 -320.789137) (xy 199.769969 -320.828208)
			(xy 199.728298 -320.861439) (xy 199.68214 -320.888088) (xy 199.632526 -320.90756) (xy 199.580564 -320.91942)
			(xy 199.527414 -320.923404) (xy 199.474264 -320.91942) (xy 199.422302 -320.90756) (xy 199.372688 -320.888088)
			(xy 199.32653 -320.861439) (xy 199.284859 -320.828208) (xy 199.248607 -320.789137) (xy 199.218583 -320.7451)
			(xy 199.195457 -320.697079) (xy 199.179747 -320.646149) (xy 199.171804 -320.593445) (xy 195.19393 -320.593445)
			(xy 195.185987 -320.646149) (xy 195.170277 -320.697079) (xy 195.147151 -320.7451) (xy 195.117127 -320.789137)
			(xy 195.080875 -320.828208) (xy 195.039204 -320.861439) (xy 194.993046 -320.888088) (xy 194.943432 -320.90756)
			(xy 194.89147 -320.91942) (xy 194.83832 -320.923404) (xy 194.78517 -320.91942) (xy 194.733208 -320.90756)
			(xy 194.683594 -320.888088) (xy 194.637436 -320.861439) (xy 194.595765 -320.828208) (xy 194.559513 -320.789137)
			(xy 194.529489 -320.7451) (xy 194.506363 -320.697079) (xy 194.490653 -320.646149) (xy 194.48271 -320.593445)
			(xy 192.338207 -320.593445) (xy 192.336221 -320.619948) (xy 192.324361 -320.671908) (xy 192.30489 -320.721521)
			(xy 192.278243 -320.767677) (xy 192.245013 -320.809347) (xy 192.205945 -320.845599) (xy 192.16191 -320.875623)
			(xy 192.113892 -320.898749) (xy 192.062963 -320.91446) (xy 192.010262 -320.922405) (xy 191.983614 -320.922904)
			(xy 191.956924 -320.92243) (xy 191.904143 -320.914465) (xy 191.853141 -320.898711) (xy 191.805062 -320.875521)
			(xy 191.760983 -320.845415) (xy 191.721892 -320.809067) (xy 191.688663 -320.767291) (xy 191.662042 -320.721024)
			(xy 191.65189 -320.696336) (xy 191.646381 -320.683652) (xy 191.62984 -320.661511) (xy 191.607966 -320.64462)
			(xy 191.582363 -320.634216) (xy 191.554906 -320.631064) (xy 191.527611 -320.635394) (xy 191.502478 -320.646888)
			(xy 191.491616 -320.655442) (xy 191.472266 -320.67123) (xy 191.429981 -320.697804) (xy 191.3844 -320.718214)
			(xy 191.336417 -320.732062) (xy 191.28697 -320.739075) (xy 191.262 -320.739516) (xy 191.235351 -320.739002)
			(xy 191.182649 -320.731059) (xy 191.13172 -320.715349) (xy 191.0837 -320.692224) (xy 191.039664 -320.662201)
			(xy 191.000594 -320.625949) (xy 190.967364 -320.58428) (xy 190.940715 -320.538123) (xy 190.921243 -320.48851)
			(xy 190.909383 -320.436548) (xy 190.905401 -320.3834) (xy 187.650679 -320.3834) (xy 187.654151 -320.388492)
			(xy 187.677277 -320.436513) (xy 187.692987 -320.487443) (xy 187.70093 -320.540147) (xy 187.701428 -320.566796)
			(xy 187.70093 -320.593445) (xy 187.692987 -320.646149) (xy 187.677277 -320.697079) (xy 187.654151 -320.7451)
			(xy 187.624127 -320.789137) (xy 187.587875 -320.828208) (xy 187.546204 -320.861439) (xy 187.500046 -320.888088)
			(xy 187.450432 -320.90756) (xy 187.39847 -320.91942) (xy 187.34532 -320.923404) (xy 187.29217 -320.91942)
			(xy 187.240208 -320.90756) (xy 187.190594 -320.888088) (xy 187.144436 -320.861439) (xy 187.102765 -320.828208)
			(xy 187.066513 -320.789137) (xy 187.036489 -320.7451) (xy 187.013363 -320.697079) (xy 186.997653 -320.646149)
			(xy 186.98971 -320.593445) (xy 184.795424 -320.593445) (xy 184.787481 -320.646149) (xy 184.771771 -320.697079)
			(xy 184.748645 -320.7451) (xy 184.718621 -320.789137) (xy 184.682369 -320.828208) (xy 184.640698 -320.861439)
			(xy 184.59454 -320.888088) (xy 184.544926 -320.90756) (xy 184.492964 -320.91942) (xy 184.439814 -320.923404)
			(xy 184.386664 -320.91942) (xy 184.334702 -320.90756) (xy 184.285088 -320.888088) (xy 184.23893 -320.861439)
			(xy 184.197259 -320.828208) (xy 184.161007 -320.789137) (xy 184.130983 -320.7451) (xy 184.107857 -320.697079)
			(xy 184.092147 -320.646149) (xy 184.084204 -320.593445) (xy 180.209531 -320.593445) (xy 180.207544 -320.619956)
			(xy 180.195682 -320.671925) (xy 180.176206 -320.721545) (xy 180.149551 -320.767708) (xy 180.116314 -320.809383)
			(xy 180.077236 -320.845637) (xy 180.033191 -320.875662) (xy 179.985162 -320.898787) (xy 179.934224 -320.914494)
			(xy 179.881513 -320.922434) (xy 179.85486 -320.922904) (xy 179.826772 -320.922399) (xy 179.771295 -320.913561)
			(xy 179.717893 -320.896125) (xy 179.667889 -320.870523) (xy 179.622523 -320.837391) (xy 179.58292 -320.797549)
			(xy 179.566062 -320.775076) (xy 179.557662 -320.764161) (xy 179.536206 -320.746911) (xy 179.510917 -320.736031)
			(xy 179.483639 -320.732314) (xy 179.456361 -320.736031) (xy 179.431072 -320.746911) (xy 179.409616 -320.764161)
			(xy 179.401216 -320.775076) (xy 179.38438 -320.797567) (xy 179.344781 -320.837418) (xy 179.299413 -320.870552)
			(xy 179.249402 -320.896147) (xy 179.195992 -320.913568) (xy 179.140508 -320.922381) (xy 179.112418 -320.922904)
			(xy 179.085766 -320.92244) (xy 179.033056 -320.914498) (xy 178.982119 -320.898788) (xy 178.934092 -320.875662)
			(xy 178.890049 -320.845636) (xy 178.850973 -320.80938) (xy 178.817737 -320.767706) (xy 178.791084 -320.721543)
			(xy 178.771609 -320.671924) (xy 178.759748 -320.619956) (xy 178.755764 -320.5668) (xy 176.649155 -320.5668)
			(xy 176.655233 -320.58541) (xy 176.670598 -320.608477) (xy 176.691594 -320.626567) (xy 176.716679 -320.638353)
			(xy 176.744008 -320.642966) (xy 176.757838 -320.64198) (xy 176.795684 -320.639948) (xy 176.822766 -320.640481)
			(xy 176.876307 -320.64868) (xy 176.927988 -320.664894) (xy 176.976618 -320.688746) (xy 177.021075 -320.719688)
			(xy 177.060334 -320.757005) (xy 177.093489 -320.799836) (xy 177.119776 -320.847195) (xy 177.138587 -320.897988)
			(xy 177.149491 -320.951044) (xy 177.152233 -321.005139) (xy 177.146753 -321.059026) (xy 177.133175 -321.111461)
			(xy 177.111814 -321.161236) (xy 177.083161 -321.207202) (xy 177.047878 -321.248298) (xy 177.006779 -321.283578)
			(xy 176.960811 -321.312227) (xy 176.912771 -321.332839) (xy 179.978548 -321.332839) (xy 179.978548 -321.279541)
			(xy 179.986491 -321.226837) (xy 180.002201 -321.175907) (xy 180.025327 -321.127886) (xy 180.055351 -321.083849)
			(xy 180.091603 -321.044778) (xy 180.133274 -321.011547) (xy 180.179432 -320.984898) (xy 180.229046 -320.965426)
			(xy 180.281008 -320.953566) (xy 180.334158 -320.949583) (xy 180.387308 -320.953566) (xy 180.43927 -320.965426)
			(xy 180.488884 -320.984898) (xy 180.535042 -321.011547) (xy 180.576713 -321.044778) (xy 180.612965 -321.083849)
			(xy 180.642989 -321.127886) (xy 180.666115 -321.175907) (xy 180.681825 -321.226837) (xy 180.689768 -321.279541)
			(xy 180.690266 -321.30619) (xy 180.689768 -321.332839) (xy 180.681825 -321.385543) (xy 180.666115 -321.436473)
			(xy 180.662813 -321.443329) (xy 184.075568 -321.443329) (xy 184.075568 -321.390031) (xy 184.083511 -321.337327)
			(xy 184.099221 -321.286397) (xy 184.122347 -321.238376) (xy 184.152371 -321.194339) (xy 184.188623 -321.155268)
			(xy 184.230294 -321.122037) (xy 184.276452 -321.095388) (xy 184.326066 -321.075916) (xy 184.378028 -321.064056)
			(xy 184.431178 -321.060073) (xy 184.484328 -321.064056) (xy 184.53629 -321.075916) (xy 184.585904 -321.095388)
			(xy 184.632062 -321.122037) (xy 184.673733 -321.155268) (xy 184.709985 -321.194339) (xy 184.740009 -321.238376)
			(xy 184.763135 -321.286397) (xy 184.778845 -321.337327) (xy 184.786788 -321.390031) (xy 184.787286 -321.41668)
			(xy 184.786788 -321.443329) (xy 187.527428 -321.443329) (xy 187.527428 -321.390031) (xy 187.535371 -321.337327)
			(xy 187.551081 -321.286397) (xy 187.574207 -321.238376) (xy 187.604231 -321.194339) (xy 187.640483 -321.155268)
			(xy 187.682154 -321.122037) (xy 187.728312 -321.095388) (xy 187.777926 -321.075916) (xy 187.829888 -321.064056)
			(xy 187.883038 -321.060073) (xy 187.936188 -321.064056) (xy 187.98815 -321.075916) (xy 188.037764 -321.095388)
			(xy 188.083922 -321.122037) (xy 188.125593 -321.155268) (xy 188.161845 -321.194339) (xy 188.191869 -321.238376)
			(xy 188.214995 -321.286397) (xy 188.230705 -321.337327) (xy 188.238648 -321.390031) (xy 188.239146 -321.41668)
			(xy 188.238648 -321.443329) (xy 191.616828 -321.443329) (xy 191.616828 -321.390031) (xy 191.624771 -321.337327)
			(xy 191.640481 -321.286397) (xy 191.663607 -321.238376) (xy 191.693631 -321.194339) (xy 191.729883 -321.155268)
			(xy 191.771554 -321.122037) (xy 191.817712 -321.095388) (xy 191.867326 -321.075916) (xy 191.919288 -321.064056)
			(xy 191.972438 -321.060073) (xy 192.025588 -321.064056) (xy 192.07755 -321.075916) (xy 192.127164 -321.095388)
			(xy 192.173322 -321.122037) (xy 192.214993 -321.155268) (xy 192.251245 -321.194339) (xy 192.281269 -321.238376)
			(xy 192.304395 -321.286397) (xy 192.320105 -321.337327) (xy 192.328048 -321.390031) (xy 192.328546 -321.41668)
			(xy 192.328048 -321.443329) (xy 195.071736 -321.443329) (xy 195.071736 -321.390031) (xy 195.079679 -321.337327)
			(xy 195.095389 -321.286397) (xy 195.118515 -321.238376) (xy 195.148539 -321.194339) (xy 195.184791 -321.155268)
			(xy 195.226462 -321.122037) (xy 195.27262 -321.095388) (xy 195.322234 -321.075916) (xy 195.374196 -321.064056)
			(xy 195.427346 -321.060073) (xy 195.480496 -321.064056) (xy 195.532458 -321.075916) (xy 195.582072 -321.095388)
			(xy 195.62823 -321.122037) (xy 195.669901 -321.155268) (xy 195.706153 -321.194339) (xy 195.736177 -321.238376)
			(xy 195.759303 -321.286397) (xy 195.775013 -321.337327) (xy 195.782956 -321.390031) (xy 195.783454 -321.41668)
			(xy 195.782956 -321.443329) (xy 199.171804 -321.443329) (xy 199.171804 -321.390031) (xy 199.179747 -321.337327)
			(xy 199.195457 -321.286397) (xy 199.218583 -321.238376) (xy 199.248607 -321.194339) (xy 199.284859 -321.155268)
			(xy 199.32653 -321.122037) (xy 199.372688 -321.095388) (xy 199.422302 -321.075916) (xy 199.474264 -321.064056)
			(xy 199.527414 -321.060073) (xy 199.580564 -321.064056) (xy 199.632526 -321.075916) (xy 199.68214 -321.095388)
			(xy 199.728298 -321.122037) (xy 199.769969 -321.155268) (xy 199.806221 -321.194339) (xy 199.836245 -321.238376)
			(xy 199.859371 -321.286397) (xy 199.875081 -321.337327) (xy 199.883024 -321.390031) (xy 199.883522 -321.41668)
			(xy 199.883024 -321.443329) (xy 202.615536 -321.443329) (xy 202.615536 -321.390031) (xy 202.623479 -321.337327)
			(xy 202.639189 -321.286397) (xy 202.662315 -321.238376) (xy 202.692339 -321.194339) (xy 202.728591 -321.155268)
			(xy 202.770262 -321.122037) (xy 202.81642 -321.095388) (xy 202.866034 -321.075916) (xy 202.917996 -321.064056)
			(xy 202.971146 -321.060073) (xy 203.024296 -321.064056) (xy 203.076258 -321.075916) (xy 203.125872 -321.095388)
			(xy 203.17203 -321.122037) (xy 203.213701 -321.155268) (xy 203.249953 -321.194339) (xy 203.279977 -321.238376)
			(xy 203.303103 -321.286397) (xy 203.318813 -321.337327) (xy 203.326756 -321.390031) (xy 203.327254 -321.41668)
			(xy 203.326756 -321.443329) (xy 206.715604 -321.443329) (xy 206.715604 -321.390031) (xy 206.723547 -321.337327)
			(xy 206.739257 -321.286397) (xy 206.762383 -321.238376) (xy 206.792407 -321.194339) (xy 206.828659 -321.155268)
			(xy 206.87033 -321.122037) (xy 206.916488 -321.095388) (xy 206.966102 -321.075916) (xy 207.018064 -321.064056)
			(xy 207.071214 -321.060073) (xy 207.124364 -321.064056) (xy 207.176326 -321.075916) (xy 207.22594 -321.095388)
			(xy 207.272098 -321.122037) (xy 207.313769 -321.155268) (xy 207.350021 -321.194339) (xy 207.380045 -321.238376)
			(xy 207.403171 -321.286397) (xy 207.418881 -321.337327) (xy 207.426824 -321.390031) (xy 207.427322 -321.41668)
			(xy 207.426824 -321.443329) (xy 210.159336 -321.443329) (xy 210.159336 -321.390031) (xy 210.167279 -321.337327)
			(xy 210.182989 -321.286397) (xy 210.206115 -321.238376) (xy 210.236139 -321.194339) (xy 210.272391 -321.155268)
			(xy 210.314062 -321.122037) (xy 210.36022 -321.095388) (xy 210.409834 -321.075916) (xy 210.461796 -321.064056)
			(xy 210.514946 -321.060073) (xy 210.568096 -321.064056) (xy 210.620058 -321.075916) (xy 210.669672 -321.095388)
			(xy 210.71583 -321.122037) (xy 210.757501 -321.155268) (xy 210.793753 -321.194339) (xy 210.823777 -321.238376)
			(xy 210.846903 -321.286397) (xy 210.862613 -321.337327) (xy 210.870556 -321.390031) (xy 210.871054 -321.41668)
			(xy 210.870556 -321.443329) (xy 214.259404 -321.443329) (xy 214.259404 -321.390031) (xy 214.267347 -321.337327)
			(xy 214.283057 -321.286397) (xy 214.306183 -321.238376) (xy 214.336207 -321.194339) (xy 214.372459 -321.155268)
			(xy 214.41413 -321.122037) (xy 214.460288 -321.095388) (xy 214.509902 -321.075916) (xy 214.561864 -321.064056)
			(xy 214.615014 -321.060073) (xy 214.668164 -321.064056) (xy 214.720126 -321.075916) (xy 214.76974 -321.095388)
			(xy 214.815898 -321.122037) (xy 214.857569 -321.155268) (xy 214.893821 -321.194339) (xy 214.923845 -321.238376)
			(xy 214.946971 -321.286397) (xy 214.959109 -321.325748) (xy 247.496582 -321.325748) (xy 247.500653 -321.270126)
			(xy 247.512779 -321.215689) (xy 247.532702 -321.163598) (xy 247.559998 -321.114963) (xy 247.594084 -321.07082)
			(xy 247.634233 -321.032111) (xy 247.679591 -320.99966) (xy 247.729191 -320.974159) (xy 247.781975 -320.956152)
			(xy 247.836818 -320.946022) (xy 247.892552 -320.943985) (xy 247.947989 -320.950085) (xy 247.961499 -320.953617)
			(xy 265.05661 -320.953617) (xy 265.05661 -320.900319) (xy 265.064553 -320.847615) (xy 265.080263 -320.796685)
			(xy 265.103389 -320.748664) (xy 265.133413 -320.704627) (xy 265.169665 -320.665556) (xy 265.211336 -320.632325)
			(xy 265.257494 -320.605676) (xy 265.307108 -320.586204) (xy 265.35907 -320.574344) (xy 265.41222 -320.570361)
			(xy 265.46537 -320.574344) (xy 265.517332 -320.586204) (xy 265.535782 -320.593445) (xy 266.263872 -320.593445)
			(xy 266.263872 -320.540147) (xy 266.271815 -320.487443) (xy 266.287525 -320.436513) (xy 266.310651 -320.388492)
			(xy 266.340675 -320.344455) (xy 266.376927 -320.305384) (xy 266.418598 -320.272153) (xy 266.464756 -320.245504)
			(xy 266.51437 -320.226032) (xy 266.566332 -320.214172) (xy 266.619482 -320.210189) (xy 266.672632 -320.214172)
			(xy 266.724594 -320.226032) (xy 266.774208 -320.245504) (xy 266.820366 -320.272153) (xy 266.862037 -320.305384)
			(xy 266.898289 -320.344455) (xy 266.928313 -320.388492) (xy 266.951439 -320.436513) (xy 266.967149 -320.487443)
			(xy 266.975092 -320.540147) (xy 266.97559 -320.566796) (xy 266.975092 -320.593445) (xy 269.22221 -320.593445)
			(xy 269.22221 -320.540147) (xy 269.230153 -320.487443) (xy 269.245863 -320.436513) (xy 269.268989 -320.388492)
			(xy 269.299013 -320.344455) (xy 269.335265 -320.305384) (xy 269.376936 -320.272153) (xy 269.423094 -320.245504)
			(xy 269.472708 -320.226032) (xy 269.52467 -320.214172) (xy 269.57782 -320.210189) (xy 269.63097 -320.214172)
			(xy 269.682932 -320.226032) (xy 269.732546 -320.245504) (xy 269.778704 -320.272153) (xy 269.820375 -320.305384)
			(xy 269.856627 -320.344455) (xy 269.886651 -320.388492) (xy 269.909777 -320.436513) (xy 269.925487 -320.487443)
			(xy 269.93343 -320.540147) (xy 269.933928 -320.566796) (xy 269.93343 -320.593445) (xy 273.807672 -320.593445)
			(xy 273.807672 -320.540147) (xy 273.815615 -320.487443) (xy 273.831325 -320.436513) (xy 273.854451 -320.388492)
			(xy 273.884475 -320.344455) (xy 273.920727 -320.305384) (xy 273.962398 -320.272153) (xy 274.008556 -320.245504)
			(xy 274.05817 -320.226032) (xy 274.110132 -320.214172) (xy 274.163282 -320.210189) (xy 274.216432 -320.214172)
			(xy 274.268394 -320.226032) (xy 274.318008 -320.245504) (xy 274.364166 -320.272153) (xy 274.405837 -320.305384)
			(xy 274.442089 -320.344455) (xy 274.472113 -320.388492) (xy 274.495239 -320.436513) (xy 274.510949 -320.487443)
			(xy 274.518892 -320.540147) (xy 274.51939 -320.566796) (xy 274.518892 -320.593445) (xy 276.75839 -320.593445)
			(xy 276.75839 -320.540147) (xy 276.766333 -320.487443) (xy 276.782043 -320.436513) (xy 276.805169 -320.388492)
			(xy 276.835193 -320.344455) (xy 276.871445 -320.305384) (xy 276.913116 -320.272153) (xy 276.959274 -320.245504)
			(xy 277.008888 -320.226032) (xy 277.06085 -320.214172) (xy 277.114 -320.210189) (xy 277.16715 -320.214172)
			(xy 277.219112 -320.226032) (xy 277.268726 -320.245504) (xy 277.314884 -320.272153) (xy 277.356555 -320.305384)
			(xy 277.392807 -320.344455) (xy 277.422831 -320.388492) (xy 277.445957 -320.436513) (xy 277.461667 -320.487443)
			(xy 277.46961 -320.540147) (xy 277.470108 -320.566796) (xy 277.46961 -320.593445) (xy 277.461667 -320.646149)
			(xy 277.445957 -320.697079) (xy 277.422831 -320.7451) (xy 277.392807 -320.789137) (xy 277.356555 -320.828208)
			(xy 277.314884 -320.861439) (xy 277.268726 -320.888088) (xy 277.219112 -320.90756) (xy 277.16715 -320.91942)
			(xy 277.114 -320.923404) (xy 277.06085 -320.91942) (xy 277.008888 -320.90756) (xy 276.959274 -320.888088)
			(xy 276.913116 -320.861439) (xy 276.871445 -320.828208) (xy 276.835193 -320.789137) (xy 276.805169 -320.7451)
			(xy 276.782043 -320.697079) (xy 276.766333 -320.646149) (xy 276.75839 -320.593445) (xy 274.518892 -320.593445)
			(xy 274.510949 -320.646149) (xy 274.495239 -320.697079) (xy 274.472113 -320.7451) (xy 274.442089 -320.789137)
			(xy 274.405837 -320.828208) (xy 274.364166 -320.861439) (xy 274.318008 -320.888088) (xy 274.268394 -320.90756)
			(xy 274.216432 -320.91942) (xy 274.163282 -320.923404) (xy 274.110132 -320.91942) (xy 274.05817 -320.90756)
			(xy 274.008556 -320.888088) (xy 273.962398 -320.861439) (xy 273.920727 -320.828208) (xy 273.884475 -320.789137)
			(xy 273.854451 -320.7451) (xy 273.831325 -320.697079) (xy 273.815615 -320.646149) (xy 273.807672 -320.593445)
			(xy 269.93343 -320.593445) (xy 269.925487 -320.646149) (xy 269.909777 -320.697079) (xy 269.886651 -320.7451)
			(xy 269.856627 -320.789137) (xy 269.820375 -320.828208) (xy 269.778704 -320.861439) (xy 269.732546 -320.888088)
			(xy 269.682932 -320.90756) (xy 269.63097 -320.91942) (xy 269.57782 -320.923404) (xy 269.52467 -320.91942)
			(xy 269.472708 -320.90756) (xy 269.423094 -320.888088) (xy 269.376936 -320.861439) (xy 269.335265 -320.828208)
			(xy 269.299013 -320.789137) (xy 269.268989 -320.7451) (xy 269.245863 -320.697079) (xy 269.230153 -320.646149)
			(xy 269.22221 -320.593445) (xy 266.975092 -320.593445) (xy 266.967149 -320.646149) (xy 266.951439 -320.697079)
			(xy 266.928313 -320.7451) (xy 266.898289 -320.789137) (xy 266.862037 -320.828208) (xy 266.820366 -320.861439)
			(xy 266.774208 -320.888088) (xy 266.724594 -320.90756) (xy 266.672632 -320.91942) (xy 266.619482 -320.923404)
			(xy 266.566332 -320.91942) (xy 266.51437 -320.90756) (xy 266.464756 -320.888088) (xy 266.418598 -320.861439)
			(xy 266.376927 -320.828208) (xy 266.340675 -320.789137) (xy 266.310651 -320.7451) (xy 266.287525 -320.697079)
			(xy 266.271815 -320.646149) (xy 266.263872 -320.593445) (xy 265.535782 -320.593445) (xy 265.566946 -320.605676)
			(xy 265.613104 -320.632325) (xy 265.654775 -320.665556) (xy 265.691027 -320.704627) (xy 265.721051 -320.748664)
			(xy 265.744177 -320.796685) (xy 265.759887 -320.847615) (xy 265.76783 -320.900319) (xy 265.768328 -320.926968)
			(xy 265.76783 -320.953617) (xy 265.759887 -321.006321) (xy 265.756557 -321.017117) (xy 272.56231 -321.017117)
			(xy 272.56231 -320.963819) (xy 272.570253 -320.911115) (xy 272.585963 -320.860185) (xy 272.609089 -320.812164)
			(xy 272.639113 -320.768127) (xy 272.675365 -320.729056) (xy 272.717036 -320.695825) (xy 272.763194 -320.669176)
			(xy 272.812808 -320.649704) (xy 272.86477 -320.637844) (xy 272.91792 -320.633861) (xy 272.97107 -320.637844)
			(xy 273.023032 -320.649704) (xy 273.072646 -320.669176) (xy 273.118804 -320.695825) (xy 273.160475 -320.729056)
			(xy 273.196727 -320.768127) (xy 273.226751 -320.812164) (xy 273.249877 -320.860185) (xy 273.265587 -320.911115)
			(xy 273.27353 -320.963819) (xy 273.273861 -320.981557) (xy 279.94101 -320.981557) (xy 279.94101 -320.928259)
			(xy 279.948953 -320.875555) (xy 279.964663 -320.824625) (xy 279.987789 -320.776604) (xy 280.017813 -320.732567)
			(xy 280.054065 -320.693496) (xy 280.095736 -320.660265) (xy 280.141894 -320.633616) (xy 280.191508 -320.614144)
			(xy 280.24347 -320.602284) (xy 280.29662 -320.598301) (xy 280.34977 -320.602284) (xy 280.401732 -320.614144)
			(xy 280.451346 -320.633616) (xy 280.497504 -320.660265) (xy 280.539175 -320.693496) (xy 280.575427 -320.732567)
			(xy 280.605451 -320.776604) (xy 280.614256 -320.794888) (xy 281.342592 -320.794888) (xy 281.34309 -320.768239)
			(xy 281.351033 -320.715535) (xy 281.366743 -320.664605) (xy 281.389869 -320.616584) (xy 281.419893 -320.572547)
			(xy 281.456145 -320.533476) (xy 281.497816 -320.500245) (xy 281.543974 -320.473596) (xy 281.593588 -320.454124)
			(xy 281.64555 -320.442264) (xy 281.6987 -320.438281) (xy 281.75185 -320.442264) (xy 281.803812 -320.454124)
			(xy 281.853426 -320.473596) (xy 281.899584 -320.500245) (xy 281.941255 -320.533476) (xy 281.963793 -320.557767)
			(xy 284.326682 -320.557767) (xy 284.332162 -320.503885) (xy 284.345737 -320.451453) (xy 284.367095 -320.401682)
			(xy 284.395743 -320.355719) (xy 284.431022 -320.314625) (xy 284.472116 -320.279346) (xy 284.518079 -320.250697)
			(xy 284.567849 -320.229338) (xy 284.620281 -320.215762) (xy 284.674163 -320.210283) (xy 284.728254 -320.213025)
			(xy 284.781305 -320.223927) (xy 284.832094 -320.242737) (xy 284.879449 -320.269021) (xy 284.922278 -320.302172)
			(xy 284.959593 -320.341427) (xy 284.990534 -320.385879) (xy 285.014386 -320.434504) (xy 285.0306 -320.48618)
			(xy 285.038802 -320.539716) (xy 285.039308 -320.566796) (xy 285.038872 -320.592492) (xy 285.03149 -320.64335)
			(xy 285.016892 -320.692625) (xy 285.006542 -320.716148) (xy 285.000606 -320.73027) (xy 284.996587 -320.760625)
			(xy 285.001747 -320.790806) (xy 285.015621 -320.818102) (xy 285.036963 -320.840058) (xy 285.063853 -320.854702)
			(xy 285.093876 -320.860717) (xy 285.109158 -320.859658) (xy 285.14548 -320.85788) (xy 285.172562 -320.858376)
			(xy 285.226102 -320.866575) (xy 285.277784 -320.882788) (xy 285.326414 -320.906639) (xy 285.370871 -320.937579)
			(xy 285.410131 -320.974895) (xy 285.443287 -321.017726) (xy 285.469575 -321.065083) (xy 285.486155 -321.109848)
			(xy 288.690812 -321.109848) (xy 288.691276 -321.083011) (xy 288.699318 -321.029943) (xy 288.715243 -320.978686)
			(xy 288.738687 -320.930403) (xy 288.76912 -320.88619) (xy 288.80585 -320.847052) (xy 288.848044 -320.813877)
			(xy 288.871152 -320.800222) (xy 288.883314 -320.792712) (xy 288.903247 -320.772242) (xy 288.916742 -320.747059)
			(xy 288.922747 -320.719126) (xy 288.920794 -320.690622) (xy 288.916364 -320.677032) (xy 288.906279 -320.647501)
			(xy 288.895422 -320.586056) (xy 288.894774 -320.554858) (xy 288.895272 -320.528209) (xy 288.903215 -320.475505)
			(xy 288.918925 -320.424575) (xy 288.942051 -320.376554) (xy 288.972075 -320.332517) (xy 289.008327 -320.293446)
			(xy 289.049998 -320.260215) (xy 289.096156 -320.233566) (xy 289.14577 -320.214094) (xy 289.197732 -320.202234)
			(xy 289.250882 -320.198251) (xy 289.304032 -320.202234) (xy 289.355994 -320.214094) (xy 289.405608 -320.233566)
			(xy 289.451766 -320.260215) (xy 289.493437 -320.293446) (xy 289.529689 -320.332517) (xy 289.559713 -320.376554)
			(xy 289.582839 -320.424575) (xy 289.598549 -320.475505) (xy 289.606492 -320.528209) (xy 289.60699 -320.554858)
			(xy 289.60653 -320.581695) (xy 289.604749 -320.593445) (xy 291.84599 -320.593445) (xy 291.84599 -320.540147)
			(xy 291.853933 -320.487443) (xy 291.869643 -320.436513) (xy 291.892769 -320.388492) (xy 291.922793 -320.344455)
			(xy 291.959045 -320.305384) (xy 292.000716 -320.272153) (xy 292.046874 -320.245504) (xy 292.096488 -320.226032)
			(xy 292.14845 -320.214172) (xy 292.2016 -320.210189) (xy 292.25475 -320.214172) (xy 292.306712 -320.226032)
			(xy 292.356326 -320.245504) (xy 292.402484 -320.272153) (xy 292.444155 -320.305384) (xy 292.480407 -320.344455)
			(xy 292.510431 -320.388492) (xy 292.533557 -320.436513) (xy 292.549267 -320.487443) (xy 292.55721 -320.540147)
			(xy 292.557708 -320.566796) (xy 292.55721 -320.593445) (xy 296.439072 -320.593445) (xy 296.439072 -320.540147)
			(xy 296.447015 -320.487443) (xy 296.462725 -320.436513) (xy 296.485851 -320.388492) (xy 296.515875 -320.344455)
			(xy 296.552127 -320.305384) (xy 296.593798 -320.272153) (xy 296.639956 -320.245504) (xy 296.68957 -320.226032)
			(xy 296.741532 -320.214172) (xy 296.794682 -320.210189) (xy 296.847832 -320.214172) (xy 296.899794 -320.226032)
			(xy 296.949408 -320.245504) (xy 296.995566 -320.272153) (xy 297.037237 -320.305384) (xy 297.073489 -320.344455)
			(xy 297.103513 -320.388492) (xy 297.126639 -320.436513) (xy 297.142349 -320.487443) (xy 297.150292 -320.540147)
			(xy 297.15079 -320.566796) (xy 297.150292 -320.593445) (xy 297.142349 -320.646149) (xy 297.126639 -320.697079)
			(xy 297.103513 -320.7451) (xy 297.073489 -320.789137) (xy 297.037237 -320.828208) (xy 296.995566 -320.861439)
			(xy 296.949408 -320.888088) (xy 296.899794 -320.90756) (xy 296.847832 -320.91942) (xy 296.794682 -320.923404)
			(xy 296.741532 -320.91942) (xy 296.68957 -320.90756) (xy 296.639956 -320.888088) (xy 296.593798 -320.861439)
			(xy 296.552127 -320.828208) (xy 296.515875 -320.789137) (xy 296.485851 -320.7451) (xy 296.462725 -320.697079)
			(xy 296.447015 -320.646149) (xy 296.439072 -320.593445) (xy 292.55721 -320.593445) (xy 292.549267 -320.646149)
			(xy 292.533557 -320.697079) (xy 292.510431 -320.7451) (xy 292.480407 -320.789137) (xy 292.444155 -320.828208)
			(xy 292.402484 -320.861439) (xy 292.356326 -320.888088) (xy 292.306712 -320.90756) (xy 292.25475 -320.91942)
			(xy 292.2016 -320.923404) (xy 292.14845 -320.91942) (xy 292.096488 -320.90756) (xy 292.046874 -320.888088)
			(xy 292.000716 -320.861439) (xy 291.959045 -320.828208) (xy 291.922793 -320.789137) (xy 291.892769 -320.7451)
			(xy 291.869643 -320.697079) (xy 291.853933 -320.646149) (xy 291.84599 -320.593445) (xy 289.604749 -320.593445)
			(xy 289.598487 -320.634763) (xy 289.582562 -320.686021) (xy 289.559116 -320.734304) (xy 289.528683 -320.778516)
			(xy 289.491952 -320.817654) (xy 289.449759 -320.850829) (xy 289.42665 -320.864484) (xy 289.414484 -320.871989)
			(xy 289.394551 -320.89246) (xy 289.381057 -320.917644) (xy 289.375053 -320.945579) (xy 289.377007 -320.974084)
			(xy 289.381438 -320.987674) (xy 289.391524 -321.017204) (xy 289.402381 -321.07865) (xy 289.403028 -321.109848)
			(xy 289.40253 -321.136497) (xy 289.394587 -321.189201) (xy 289.378877 -321.240131) (xy 289.355751 -321.288152)
			(xy 289.325727 -321.332189) (xy 289.289475 -321.37126) (xy 289.247804 -321.404491) (xy 289.201646 -321.43114)
			(xy 289.170589 -321.443329) (xy 292.339004 -321.443329) (xy 292.339004 -321.390031) (xy 292.346947 -321.337327)
			(xy 292.362657 -321.286397) (xy 292.385783 -321.238376) (xy 292.415807 -321.194339) (xy 292.452059 -321.155268)
			(xy 292.49373 -321.122037) (xy 292.539888 -321.095388) (xy 292.589502 -321.075916) (xy 292.641464 -321.064056)
			(xy 292.694614 -321.060073) (xy 292.747764 -321.064056) (xy 292.799726 -321.075916) (xy 292.84934 -321.095388)
			(xy 292.895498 -321.122037) (xy 292.937169 -321.155268) (xy 292.973421 -321.194339) (xy 293.003445 -321.238376)
			(xy 293.026571 -321.286397) (xy 293.042281 -321.337327) (xy 293.050224 -321.390031) (xy 293.050722 -321.41668)
			(xy 293.050224 -321.443329) (xy 296.439072 -321.443329) (xy 296.439072 -321.390031) (xy 296.447015 -321.337327)
			(xy 296.462725 -321.286397) (xy 296.485851 -321.238376) (xy 296.515875 -321.194339) (xy 296.552127 -321.155268)
			(xy 296.593798 -321.122037) (xy 296.639956 -321.095388) (xy 296.68957 -321.075916) (xy 296.741532 -321.064056)
			(xy 296.794682 -321.060073) (xy 296.847832 -321.064056) (xy 296.899794 -321.075916) (xy 296.949408 -321.095388)
			(xy 296.995566 -321.122037) (xy 297.037237 -321.155268) (xy 297.073489 -321.194339) (xy 297.103513 -321.238376)
			(xy 297.126639 -321.286397) (xy 297.142349 -321.337327) (xy 297.150292 -321.390031) (xy 297.15079 -321.41668)
			(xy 297.150292 -321.443329) (xy 297.142349 -321.496033) (xy 297.131409 -321.5315) (xy 299.155056 -321.5315)
			(xy 299.15904 -321.478343) (xy 299.170902 -321.426374) (xy 299.190377 -321.376753) (xy 299.217031 -321.330589)
			(xy 299.250268 -321.288913) (xy 299.289345 -321.252657) (xy 299.33339 -321.222631) (xy 299.381418 -321.199504)
			(xy 299.432356 -321.183794) (xy 299.485067 -321.175852) (xy 299.51172 -321.17538) (xy 299.539399 -321.175919)
			(xy 299.594091 -321.184481) (xy 299.646801 -321.201397) (xy 299.696263 -321.226259) (xy 299.741285 -321.258469)
			(xy 299.761402 -321.277488) (xy 299.771387 -321.286697) (xy 299.795056 -321.299997) (xy 299.821397 -321.306576)
			(xy 299.84854 -321.305967) (xy 299.874559 -321.298211) (xy 299.897607 -321.283861) (xy 299.916047 -321.263934)
			(xy 299.922692 -321.252088) (xy 299.936 -321.227737) (xy 299.968957 -321.183096) (xy 300.008442 -321.14411)
			(xy 300.053499 -321.111724) (xy 300.103036 -321.086722) (xy 300.155853 -321.069711) (xy 300.21067 -321.061102)
			(xy 300.238414 -321.060572) (xy 300.265061 -321.061111) (xy 300.31776 -321.069056) (xy 300.368686 -321.084766)
			(xy 300.416702 -321.107891) (xy 300.460735 -321.137914) (xy 300.499801 -321.174164) (xy 300.533029 -321.215832)
			(xy 300.559676 -321.261986) (xy 300.579146 -321.311597) (xy 300.591004 -321.363555) (xy 300.594987 -321.4167)
			(xy 300.591004 -321.469845) (xy 300.579146 -321.521803) (xy 300.559676 -321.571414) (xy 300.533029 -321.617568)
			(xy 300.499801 -321.659236) (xy 300.460735 -321.695486) (xy 300.416702 -321.725509) (xy 300.368686 -321.748634)
			(xy 300.31776 -321.764344) (xy 300.265061 -321.772289) (xy 300.238414 -321.772788) (xy 300.210733 -321.772299)
			(xy 300.156038 -321.763726) (xy 300.103327 -321.746799) (xy 300.053867 -321.721926) (xy 300.008847 -321.689704)
			(xy 299.988732 -321.67068) (xy 299.978825 -321.661378) (xy 299.955136 -321.64807) (xy 299.928774 -321.641493)
			(xy 299.901611 -321.642114) (xy 299.875576 -321.649888) (xy 299.852521 -321.664264) (xy 299.834082 -321.68422)
			(xy 299.827442 -321.69608) (xy 299.814169 -321.720451) (xy 299.781208 -321.765095) (xy 299.741718 -321.804082)
			(xy 299.696655 -321.836467) (xy 299.647112 -321.861465) (xy 299.594289 -321.87847) (xy 299.539467 -321.887071)
			(xy 299.51172 -321.887596) (xy 299.485067 -321.887148) (xy 299.432356 -321.879206) (xy 299.381418 -321.863496)
			(xy 299.33339 -321.840369) (xy 299.289345 -321.810343) (xy 299.250268 -321.774087) (xy 299.217031 -321.732411)
			(xy 299.190377 -321.686247) (xy 299.170902 -321.636626) (xy 299.15904 -321.584657) (xy 299.155056 -321.5315)
			(xy 297.131409 -321.5315) (xy 297.126639 -321.546963) (xy 297.103513 -321.594984) (xy 297.073489 -321.639021)
			(xy 297.037237 -321.678092) (xy 296.995566 -321.711323) (xy 296.949408 -321.737972) (xy 296.899794 -321.757444)
			(xy 296.847832 -321.769304) (xy 296.794682 -321.773288) (xy 296.741532 -321.769304) (xy 296.68957 -321.757444)
			(xy 296.639956 -321.737972) (xy 296.593798 -321.711323) (xy 296.552127 -321.678092) (xy 296.515875 -321.639021)
			(xy 296.485851 -321.594984) (xy 296.462725 -321.546963) (xy 296.447015 -321.496033) (xy 296.439072 -321.443329)
			(xy 293.050224 -321.443329) (xy 293.042281 -321.496033) (xy 293.026571 -321.546963) (xy 293.003445 -321.594984)
			(xy 292.973421 -321.639021) (xy 292.937169 -321.678092) (xy 292.895498 -321.711323) (xy 292.84934 -321.737972)
			(xy 292.799726 -321.757444) (xy 292.747764 -321.769304) (xy 292.694614 -321.773288) (xy 292.641464 -321.769304)
			(xy 292.589502 -321.757444) (xy 292.539888 -321.737972) (xy 292.49373 -321.711323) (xy 292.452059 -321.678092)
			(xy 292.415807 -321.639021) (xy 292.385783 -321.594984) (xy 292.362657 -321.546963) (xy 292.346947 -321.496033)
			(xy 292.339004 -321.443329) (xy 289.170589 -321.443329) (xy 289.152032 -321.450612) (xy 289.10007 -321.462472)
			(xy 289.04692 -321.466456) (xy 288.99377 -321.462472) (xy 288.941808 -321.450612) (xy 288.892194 -321.43114)
			(xy 288.846036 -321.404491) (xy 288.804365 -321.37126) (xy 288.768113 -321.332189) (xy 288.738089 -321.288152)
			(xy 288.714963 -321.240131) (xy 288.699253 -321.189201) (xy 288.69131 -321.136497) (xy 288.690812 -321.109848)
			(xy 285.486155 -321.109848) (xy 285.488388 -321.115876) (xy 285.499293 -321.168931) (xy 285.502038 -321.223026)
			(xy 285.496559 -321.276912) (xy 285.482984 -321.329348) (xy 285.461625 -321.379123) (xy 285.432975 -321.42509)
			(xy 285.397694 -321.466188) (xy 285.356597 -321.50147) (xy 285.31063 -321.530121) (xy 285.260856 -321.551481)
			(xy 285.20842 -321.565058) (xy 285.154534 -321.570538) (xy 285.100439 -321.567794) (xy 285.047383 -321.55689)
			(xy 284.996591 -321.538078) (xy 284.949233 -321.511791) (xy 284.906401 -321.478636) (xy 284.869084 -321.439378)
			(xy 284.838143 -321.394921) (xy 284.814291 -321.346291) (xy 284.798077 -321.29461) (xy 284.789877 -321.24107)
			(xy 284.789372 -321.213988) (xy 284.789804 -321.188292) (xy 284.797188 -321.137434) (xy 284.811788 -321.088159)
			(xy 284.822138 -321.064636) (xy 284.828113 -321.050528) (xy 284.83213 -321.020166) (xy 284.826967 -320.989978)
			(xy 284.813086 -320.962678) (xy 284.791737 -320.940719) (xy 284.764838 -320.926076) (xy 284.734807 -320.920064)
			(xy 284.719522 -320.921126) (xy 284.6832 -320.922904) (xy 284.65612 -320.922402) (xy 284.602584 -320.914201)
			(xy 284.550908 -320.897987) (xy 284.502282 -320.874136) (xy 284.45783 -320.843196) (xy 284.418575 -320.805881)
			(xy 284.385423 -320.763053) (xy 284.359139 -320.715698) (xy 284.340328 -320.664909) (xy 284.329426 -320.611858)
			(xy 284.326682 -320.557767) (xy 281.963793 -320.557767) (xy 281.977507 -320.572547) (xy 282.007531 -320.616584)
			(xy 282.030657 -320.664605) (xy 282.046367 -320.715535) (xy 282.05431 -320.768239) (xy 282.054808 -320.794888)
			(xy 282.054343 -320.821001) (xy 282.046717 -320.872667) (xy 282.031626 -320.922665) (xy 282.009394 -320.969922)
			(xy 281.980498 -321.013426) (xy 281.963368 -321.03314) (xy 281.953556 -321.044803) (xy 281.940685 -321.072414)
			(xy 281.936525 -321.102593) (xy 281.941447 -321.132656) (xy 281.955012 -321.159933) (xy 281.965146 -321.171316)
			(xy 281.983425 -321.191307) (xy 282.014382 -321.235754) (xy 282.038249 -321.284379) (xy 282.054474 -321.336057)
			(xy 282.062682 -321.389597) (xy 282.06319 -321.41668) (xy 282.062692 -321.443329) (xy 282.054749 -321.496033)
			(xy 282.039039 -321.546963) (xy 282.015913 -321.594984) (xy 281.985889 -321.639021) (xy 281.949637 -321.678092)
			(xy 281.907966 -321.711323) (xy 281.861808 -321.737972) (xy 281.812194 -321.757444) (xy 281.760232 -321.769304)
			(xy 281.707082 -321.773288) (xy 281.653932 -321.769304) (xy 281.60197 -321.757444) (xy 281.552356 -321.737972)
			(xy 281.506198 -321.711323) (xy 281.464527 -321.678092) (xy 281.428275 -321.639021) (xy 281.398251 -321.594984)
			(xy 281.375125 -321.546963) (xy 281.359415 -321.496033) (xy 281.351472 -321.443329) (xy 281.350974 -321.41668)
			(xy 281.351424 -321.390567) (xy 281.359055 -321.3389) (xy 281.37415 -321.288902) (xy 281.396385 -321.241645)
			(xy 281.425283 -321.198142) (xy 281.442414 -321.178428) (xy 281.452259 -321.16679) (xy 281.465129 -321.13917)
			(xy 281.469284 -321.108983) (xy 281.464353 -321.078914) (xy 281.450776 -321.051635) (xy 281.440636 -321.040252)
			(xy 281.422339 -321.020277) (xy 281.391385 -320.975825) (xy 281.367522 -320.927197) (xy 281.351301 -320.875515)
			(xy 281.343097 -320.821972) (xy 281.342592 -320.794888) (xy 280.614256 -320.794888) (xy 280.628577 -320.824625)
			(xy 280.644287 -320.875555) (xy 280.65223 -320.928259) (xy 280.652728 -320.954908) (xy 280.65223 -320.981557)
			(xy 280.644287 -321.034261) (xy 280.628577 -321.085191) (xy 280.605451 -321.133212) (xy 280.575427 -321.177249)
			(xy 280.539175 -321.21632) (xy 280.497504 -321.249551) (xy 280.451346 -321.2762) (xy 280.401732 -321.295672)
			(xy 280.34977 -321.307532) (xy 280.29662 -321.311516) (xy 280.24347 -321.307532) (xy 280.191508 -321.295672)
			(xy 280.141894 -321.2762) (xy 280.095736 -321.249551) (xy 280.054065 -321.21632) (xy 280.017813 -321.177249)
			(xy 279.987789 -321.133212) (xy 279.964663 -321.085191) (xy 279.948953 -321.034261) (xy 279.94101 -320.981557)
			(xy 273.273861 -320.981557) (xy 273.274028 -320.990468) (xy 273.27353 -321.017117) (xy 273.265587 -321.069821)
			(xy 273.249877 -321.120751) (xy 273.226751 -321.168772) (xy 273.196727 -321.212809) (xy 273.160475 -321.25188)
			(xy 273.118804 -321.285111) (xy 273.072646 -321.31176) (xy 273.023032 -321.331232) (xy 272.97107 -321.343092)
			(xy 272.91792 -321.347076) (xy 272.86477 -321.343092) (xy 272.812808 -321.331232) (xy 272.763194 -321.31176)
			(xy 272.717036 -321.285111) (xy 272.675365 -321.25188) (xy 272.639113 -321.212809) (xy 272.609089 -321.168772)
			(xy 272.585963 -321.120751) (xy 272.570253 -321.069821) (xy 272.56231 -321.017117) (xy 265.756557 -321.017117)
			(xy 265.744177 -321.057251) (xy 265.721051 -321.105272) (xy 265.691027 -321.149309) (xy 265.654775 -321.18838)
			(xy 265.613104 -321.221611) (xy 265.566946 -321.24826) (xy 265.517332 -321.267732) (xy 265.46537 -321.279592)
			(xy 265.41222 -321.283576) (xy 265.35907 -321.279592) (xy 265.307108 -321.267732) (xy 265.257494 -321.24826)
			(xy 265.211336 -321.221611) (xy 265.169665 -321.18838) (xy 265.133413 -321.149309) (xy 265.103389 -321.105272)
			(xy 265.080263 -321.057251) (xy 265.064553 -321.006321) (xy 265.05661 -320.953617) (xy 247.961499 -320.953617)
			(xy 248.001946 -320.964191) (xy 248.053275 -320.986003) (xy 248.100881 -321.015057) (xy 248.143749 -321.050732)
			(xy 248.180966 -321.092269) (xy 248.211739 -321.138782) (xy 248.235411 -321.189279) (xy 248.251479 -321.242686)
			(xy 248.259599 -321.297862) (xy 248.260108 -321.325748) (xy 248.259599 -321.353634) (xy 248.251479 -321.40881)
			(xy 248.241094 -321.443329) (xy 254.620004 -321.443329) (xy 254.620004 -321.390031) (xy 254.627947 -321.337327)
			(xy 254.643657 -321.286397) (xy 254.666783 -321.238376) (xy 254.696807 -321.194339) (xy 254.733059 -321.155268)
			(xy 254.77473 -321.122037) (xy 254.820888 -321.095388) (xy 254.870502 -321.075916) (xy 254.922464 -321.064056)
			(xy 254.975614 -321.060073) (xy 255.028764 -321.064056) (xy 255.080726 -321.075916) (xy 255.13034 -321.095388)
			(xy 255.176498 -321.122037) (xy 255.218169 -321.155268) (xy 255.254421 -321.194339) (xy 255.284445 -321.238376)
			(xy 255.307571 -321.286397) (xy 255.323281 -321.337327) (xy 255.331224 -321.390031) (xy 255.331722 -321.41668)
			(xy 255.331224 -321.443329) (xy 258.720072 -321.443329) (xy 258.720072 -321.390031) (xy 258.728015 -321.337327)
			(xy 258.743725 -321.286397) (xy 258.766851 -321.238376) (xy 258.796875 -321.194339) (xy 258.833127 -321.155268)
			(xy 258.874798 -321.122037) (xy 258.920956 -321.095388) (xy 258.97057 -321.075916) (xy 259.022532 -321.064056)
			(xy 259.075682 -321.060073) (xy 259.128832 -321.064056) (xy 259.180794 -321.075916) (xy 259.230408 -321.095388)
			(xy 259.276566 -321.122037) (xy 259.318237 -321.155268) (xy 259.354489 -321.194339) (xy 259.384513 -321.238376)
			(xy 259.407639 -321.286397) (xy 259.423349 -321.337327) (xy 259.431292 -321.390031) (xy 259.43179 -321.41668)
			(xy 259.431292 -321.443329) (xy 259.423349 -321.496033) (xy 259.407639 -321.546963) (xy 259.384513 -321.594984)
			(xy 259.354489 -321.639021) (xy 259.318237 -321.678092) (xy 259.291893 -321.6991) (xy 261.461496 -321.6991)
			(xy 261.465479 -321.645949) (xy 261.47734 -321.593985) (xy 261.496813 -321.54437) (xy 261.523464 -321.498212)
			(xy 261.556697 -321.456541) (xy 261.59577 -321.420289) (xy 261.63981 -321.390265) (xy 261.687832 -321.367141)
			(xy 261.738765 -321.351433) (xy 261.79147 -321.343492) (xy 261.81812 -321.34302) (xy 261.844355 -321.343479)
			(xy 261.896263 -321.351139) (xy 261.946479 -321.366348) (xy 261.993914 -321.388776) (xy 262.015986 -321.402964)
			(xy 262.027996 -321.410429) (xy 262.05491 -321.419073) (xy 262.083162 -321.420013) (xy 262.11059 -321.413176)
			(xy 262.135096 -321.399086) (xy 262.154803 -321.378821) (xy 262.168204 -321.353932) (xy 262.171688 -321.340226)
			(xy 262.177956 -321.314158) (xy 262.197167 -321.264107) (xy 262.223667 -321.217504) (xy 262.256856 -321.175402)
			(xy 262.295985 -321.138753) (xy 262.340167 -321.108388) (xy 262.388404 -321.084992) (xy 262.439604 -321.069095)
			(xy 262.492608 -321.061057) (xy 262.519414 -321.060572) (xy 262.546061 -321.061111) (xy 262.59876 -321.069056)
			(xy 262.649686 -321.084766) (xy 262.697702 -321.107891) (xy 262.741735 -321.137914) (xy 262.780801 -321.174164)
			(xy 262.814029 -321.215832) (xy 262.840676 -321.261986) (xy 262.860146 -321.311597) (xy 262.872004 -321.363555)
			(xy 262.875987 -321.4167) (xy 262.873991 -321.443329) (xy 266.263872 -321.443329) (xy 266.263872 -321.390031)
			(xy 266.271815 -321.337327) (xy 266.287525 -321.286397) (xy 266.310651 -321.238376) (xy 266.340675 -321.194339)
			(xy 266.376927 -321.155268) (xy 266.418598 -321.122037) (xy 266.464756 -321.095388) (xy 266.51437 -321.075916)
			(xy 266.566332 -321.064056) (xy 266.619482 -321.060073) (xy 266.672632 -321.064056) (xy 266.724594 -321.075916)
			(xy 266.774208 -321.095388) (xy 266.820366 -321.122037) (xy 266.862037 -321.155268) (xy 266.898289 -321.194339)
			(xy 266.928313 -321.238376) (xy 266.951439 -321.286397) (xy 266.967149 -321.337327) (xy 266.975092 -321.390031)
			(xy 266.97559 -321.41668) (xy 266.975092 -321.443329) (xy 269.707604 -321.443329) (xy 269.707604 -321.390031)
			(xy 269.715547 -321.337327) (xy 269.731257 -321.286397) (xy 269.754383 -321.238376) (xy 269.784407 -321.194339)
			(xy 269.820659 -321.155268) (xy 269.86233 -321.122037) (xy 269.908488 -321.095388) (xy 269.958102 -321.075916)
			(xy 270.010064 -321.064056) (xy 270.063214 -321.060073) (xy 270.116364 -321.064056) (xy 270.168326 -321.075916)
			(xy 270.21794 -321.095388) (xy 270.264098 -321.122037) (xy 270.305769 -321.155268) (xy 270.342021 -321.194339)
			(xy 270.372045 -321.238376) (xy 270.395171 -321.286397) (xy 270.410881 -321.337327) (xy 270.418824 -321.390031)
			(xy 270.419322 -321.41668) (xy 270.418824 -321.443329) (xy 273.807672 -321.443329) (xy 273.807672 -321.390031)
			(xy 273.815615 -321.337327) (xy 273.831325 -321.286397) (xy 273.854451 -321.238376) (xy 273.884475 -321.194339)
			(xy 273.920727 -321.155268) (xy 273.962398 -321.122037) (xy 274.008556 -321.095388) (xy 274.05817 -321.075916)
			(xy 274.110132 -321.064056) (xy 274.163282 -321.060073) (xy 274.216432 -321.064056) (xy 274.268394 -321.075916)
			(xy 274.318008 -321.095388) (xy 274.364166 -321.122037) (xy 274.405837 -321.155268) (xy 274.442089 -321.194339)
			(xy 274.472113 -321.238376) (xy 274.495239 -321.286397) (xy 274.510949 -321.337327) (xy 274.518892 -321.390031)
			(xy 274.51939 -321.41668) (xy 274.518892 -321.443329) (xy 277.251404 -321.443329) (xy 277.251404 -321.390031)
			(xy 277.259347 -321.337327) (xy 277.275057 -321.286397) (xy 277.298183 -321.238376) (xy 277.328207 -321.194339)
			(xy 277.364459 -321.155268) (xy 277.40613 -321.122037) (xy 277.452288 -321.095388) (xy 277.501902 -321.075916)
			(xy 277.553864 -321.064056) (xy 277.607014 -321.060073) (xy 277.660164 -321.064056) (xy 277.712126 -321.075916)
			(xy 277.76174 -321.095388) (xy 277.807898 -321.122037) (xy 277.849569 -321.155268) (xy 277.885821 -321.194339)
			(xy 277.915845 -321.238376) (xy 277.938971 -321.286397) (xy 277.954681 -321.337327) (xy 277.962624 -321.390031)
			(xy 277.963122 -321.41668) (xy 277.962624 -321.443329) (xy 277.954681 -321.496033) (xy 277.938971 -321.546963)
			(xy 277.915845 -321.594984) (xy 277.885821 -321.639021) (xy 277.849569 -321.678092) (xy 277.807898 -321.711323)
			(xy 277.76174 -321.737972) (xy 277.712126 -321.757444) (xy 277.660164 -321.769304) (xy 277.607014 -321.773288)
			(xy 277.553864 -321.769304) (xy 277.501902 -321.757444) (xy 277.452288 -321.737972) (xy 277.40613 -321.711323)
			(xy 277.364459 -321.678092) (xy 277.328207 -321.639021) (xy 277.298183 -321.594984) (xy 277.275057 -321.546963)
			(xy 277.259347 -321.496033) (xy 277.251404 -321.443329) (xy 274.518892 -321.443329) (xy 274.510949 -321.496033)
			(xy 274.495239 -321.546963) (xy 274.472113 -321.594984) (xy 274.442089 -321.639021) (xy 274.405837 -321.678092)
			(xy 274.364166 -321.711323) (xy 274.318008 -321.737972) (xy 274.268394 -321.757444) (xy 274.216432 -321.769304)
			(xy 274.163282 -321.773288) (xy 274.110132 -321.769304) (xy 274.05817 -321.757444) (xy 274.008556 -321.737972)
			(xy 273.962398 -321.711323) (xy 273.920727 -321.678092) (xy 273.884475 -321.639021) (xy 273.854451 -321.594984)
			(xy 273.831325 -321.546963) (xy 273.815615 -321.496033) (xy 273.807672 -321.443329) (xy 270.418824 -321.443329)
			(xy 270.410881 -321.496033) (xy 270.395171 -321.546963) (xy 270.372045 -321.594984) (xy 270.342021 -321.639021)
			(xy 270.305769 -321.678092) (xy 270.264098 -321.711323) (xy 270.21794 -321.737972) (xy 270.168326 -321.757444)
			(xy 270.116364 -321.769304) (xy 270.063214 -321.773288) (xy 270.010064 -321.769304) (xy 269.958102 -321.757444)
			(xy 269.908488 -321.737972) (xy 269.86233 -321.711323) (xy 269.820659 -321.678092) (xy 269.784407 -321.639021)
			(xy 269.754383 -321.594984) (xy 269.731257 -321.546963) (xy 269.715547 -321.496033) (xy 269.707604 -321.443329)
			(xy 266.975092 -321.443329) (xy 266.967149 -321.496033) (xy 266.951439 -321.546963) (xy 266.928313 -321.594984)
			(xy 266.898289 -321.639021) (xy 266.862037 -321.678092) (xy 266.820366 -321.711323) (xy 266.774208 -321.737972)
			(xy 266.724594 -321.757444) (xy 266.672632 -321.769304) (xy 266.619482 -321.773288) (xy 266.566332 -321.769304)
			(xy 266.51437 -321.757444) (xy 266.464756 -321.737972) (xy 266.418598 -321.711323) (xy 266.376927 -321.678092)
			(xy 266.340675 -321.639021) (xy 266.310651 -321.594984) (xy 266.287525 -321.546963) (xy 266.271815 -321.496033)
			(xy 266.263872 -321.443329) (xy 262.873991 -321.443329) (xy 262.872004 -321.469845) (xy 262.860146 -321.521803)
			(xy 262.840676 -321.571414) (xy 262.814029 -321.617568) (xy 262.780801 -321.659236) (xy 262.741735 -321.695486)
			(xy 262.697702 -321.725509) (xy 262.649686 -321.748634) (xy 262.59876 -321.764344) (xy 262.546061 -321.772289)
			(xy 262.519414 -321.772788) (xy 262.493178 -321.77236) (xy 262.441269 -321.764691) (xy 262.391052 -321.749473)
			(xy 262.343619 -321.727037) (xy 262.321548 -321.712844) (xy 262.309516 -321.705416) (xy 262.28261 -321.696766)
			(xy 262.254363 -321.69582) (xy 262.226938 -321.70265) (xy 262.202434 -321.716735) (xy 262.182729 -321.736995)
			(xy 262.169329 -321.761879) (xy 262.165846 -321.775582) (xy 262.159644 -321.801668) (xy 262.140428 -321.851723)
			(xy 262.113921 -321.898329) (xy 262.080723 -321.940433) (xy 262.041586 -321.977081) (xy 261.997395 -322.007444)
			(xy 261.949149 -322.030835) (xy 261.897941 -322.046726) (xy 261.844929 -322.054756) (xy 261.81812 -322.055236)
			(xy 261.79147 -322.054708) (xy 261.738765 -322.046767) (xy 261.687832 -322.031059) (xy 261.63981 -322.007935)
			(xy 261.59577 -321.977911) (xy 261.556697 -321.941659) (xy 261.523464 -321.899988) (xy 261.496813 -321.85383)
			(xy 261.47734 -321.804215) (xy 261.465479 -321.752251) (xy 261.461496 -321.6991) (xy 259.291893 -321.6991)
			(xy 259.276566 -321.711323) (xy 259.230408 -321.737972) (xy 259.180794 -321.757444) (xy 259.128832 -321.769304)
			(xy 259.075682 -321.773288) (xy 259.022532 -321.769304) (xy 258.97057 -321.757444) (xy 258.920956 -321.737972)
			(xy 258.874798 -321.711323) (xy 258.833127 -321.678092) (xy 258.796875 -321.639021) (xy 258.766851 -321.594984)
			(xy 258.743725 -321.546963) (xy 258.728015 -321.496033) (xy 258.720072 -321.443329) (xy 255.331224 -321.443329)
			(xy 255.323281 -321.496033) (xy 255.307571 -321.546963) (xy 255.284445 -321.594984) (xy 255.254421 -321.639021)
			(xy 255.218169 -321.678092) (xy 255.176498 -321.711323) (xy 255.13034 -321.737972) (xy 255.080726 -321.757444)
			(xy 255.028764 -321.769304) (xy 254.975614 -321.773288) (xy 254.922464 -321.769304) (xy 254.870502 -321.757444)
			(xy 254.820888 -321.737972) (xy 254.77473 -321.711323) (xy 254.733059 -321.678092) (xy 254.696807 -321.639021)
			(xy 254.666783 -321.594984) (xy 254.643657 -321.546963) (xy 254.627947 -321.496033) (xy 254.620004 -321.443329)
			(xy 248.241094 -321.443329) (xy 248.235411 -321.462217) (xy 248.211739 -321.512714) (xy 248.180966 -321.559227)
			(xy 248.143749 -321.600764) (xy 248.100881 -321.636439) (xy 248.053275 -321.665493) (xy 248.001946 -321.687305)
			(xy 247.947989 -321.701411) (xy 247.892552 -321.707511) (xy 247.836818 -321.705474) (xy 247.781975 -321.695344)
			(xy 247.729191 -321.677337) (xy 247.679591 -321.651836) (xy 247.634233 -321.619385) (xy 247.594084 -321.580676)
			(xy 247.559998 -321.536533) (xy 247.532702 -321.487898) (xy 247.512779 -321.435807) (xy 247.500653 -321.38137)
			(xy 247.496582 -321.325748) (xy 214.959109 -321.325748) (xy 214.962681 -321.337327) (xy 214.970624 -321.390031)
			(xy 214.971122 -321.41668) (xy 214.970624 -321.443329) (xy 214.962681 -321.496033) (xy 214.946971 -321.546963)
			(xy 214.923845 -321.594984) (xy 214.893821 -321.639021) (xy 214.857569 -321.678092) (xy 214.815898 -321.711323)
			(xy 214.76974 -321.737972) (xy 214.720126 -321.757444) (xy 214.668164 -321.769304) (xy 214.615014 -321.773288)
			(xy 214.561864 -321.769304) (xy 214.509902 -321.757444) (xy 214.460288 -321.737972) (xy 214.41413 -321.711323)
			(xy 214.372459 -321.678092) (xy 214.336207 -321.639021) (xy 214.306183 -321.594984) (xy 214.283057 -321.546963)
			(xy 214.267347 -321.496033) (xy 214.259404 -321.443329) (xy 210.870556 -321.443329) (xy 210.862613 -321.496033)
			(xy 210.846903 -321.546963) (xy 210.823777 -321.594984) (xy 210.793753 -321.639021) (xy 210.757501 -321.678092)
			(xy 210.71583 -321.711323) (xy 210.669672 -321.737972) (xy 210.620058 -321.757444) (xy 210.568096 -321.769304)
			(xy 210.514946 -321.773288) (xy 210.461796 -321.769304) (xy 210.409834 -321.757444) (xy 210.36022 -321.737972)
			(xy 210.314062 -321.711323) (xy 210.272391 -321.678092) (xy 210.236139 -321.639021) (xy 210.206115 -321.594984)
			(xy 210.182989 -321.546963) (xy 210.167279 -321.496033) (xy 210.159336 -321.443329) (xy 207.426824 -321.443329)
			(xy 207.418881 -321.496033) (xy 207.403171 -321.546963) (xy 207.380045 -321.594984) (xy 207.350021 -321.639021)
			(xy 207.313769 -321.678092) (xy 207.272098 -321.711323) (xy 207.22594 -321.737972) (xy 207.176326 -321.757444)
			(xy 207.124364 -321.769304) (xy 207.071214 -321.773288) (xy 207.018064 -321.769304) (xy 206.966102 -321.757444)
			(xy 206.916488 -321.737972) (xy 206.87033 -321.711323) (xy 206.828659 -321.678092) (xy 206.792407 -321.639021)
			(xy 206.762383 -321.594984) (xy 206.739257 -321.546963) (xy 206.723547 -321.496033) (xy 206.715604 -321.443329)
			(xy 203.326756 -321.443329) (xy 203.318813 -321.496033) (xy 203.303103 -321.546963) (xy 203.279977 -321.594984)
			(xy 203.249953 -321.639021) (xy 203.213701 -321.678092) (xy 203.17203 -321.711323) (xy 203.125872 -321.737972)
			(xy 203.076258 -321.757444) (xy 203.024296 -321.769304) (xy 202.971146 -321.773288) (xy 202.917996 -321.769304)
			(xy 202.866034 -321.757444) (xy 202.81642 -321.737972) (xy 202.770262 -321.711323) (xy 202.728591 -321.678092)
			(xy 202.692339 -321.639021) (xy 202.662315 -321.594984) (xy 202.639189 -321.546963) (xy 202.623479 -321.496033)
			(xy 202.615536 -321.443329) (xy 199.883024 -321.443329) (xy 199.875081 -321.496033) (xy 199.859371 -321.546963)
			(xy 199.836245 -321.594984) (xy 199.806221 -321.639021) (xy 199.769969 -321.678092) (xy 199.728298 -321.711323)
			(xy 199.68214 -321.737972) (xy 199.632526 -321.757444) (xy 199.580564 -321.769304) (xy 199.527414 -321.773288)
			(xy 199.474264 -321.769304) (xy 199.422302 -321.757444) (xy 199.372688 -321.737972) (xy 199.32653 -321.711323)
			(xy 199.284859 -321.678092) (xy 199.248607 -321.639021) (xy 199.218583 -321.594984) (xy 199.195457 -321.546963)
			(xy 199.179747 -321.496033) (xy 199.171804 -321.443329) (xy 195.782956 -321.443329) (xy 195.775013 -321.496033)
			(xy 195.759303 -321.546963) (xy 195.736177 -321.594984) (xy 195.706153 -321.639021) (xy 195.669901 -321.678092)
			(xy 195.62823 -321.711323) (xy 195.582072 -321.737972) (xy 195.532458 -321.757444) (xy 195.480496 -321.769304)
			(xy 195.427346 -321.773288) (xy 195.374196 -321.769304) (xy 195.322234 -321.757444) (xy 195.27262 -321.737972)
			(xy 195.226462 -321.711323) (xy 195.184791 -321.678092) (xy 195.148539 -321.639021) (xy 195.118515 -321.594984)
			(xy 195.095389 -321.546963) (xy 195.079679 -321.496033) (xy 195.071736 -321.443329) (xy 192.328048 -321.443329)
			(xy 192.320105 -321.496033) (xy 192.304395 -321.546963) (xy 192.281269 -321.594984) (xy 192.251245 -321.639021)
			(xy 192.214993 -321.678092) (xy 192.173322 -321.711323) (xy 192.127164 -321.737972) (xy 192.07755 -321.757444)
			(xy 192.025588 -321.769304) (xy 191.972438 -321.773288) (xy 191.919288 -321.769304) (xy 191.867326 -321.757444)
			(xy 191.817712 -321.737972) (xy 191.771554 -321.711323) (xy 191.729883 -321.678092) (xy 191.693631 -321.639021)
			(xy 191.663607 -321.594984) (xy 191.640481 -321.546963) (xy 191.624771 -321.496033) (xy 191.616828 -321.443329)
			(xy 188.238648 -321.443329) (xy 188.230705 -321.496033) (xy 188.214995 -321.546963) (xy 188.191869 -321.594984)
			(xy 188.161845 -321.639021) (xy 188.125593 -321.678092) (xy 188.083922 -321.711323) (xy 188.037764 -321.737972)
			(xy 187.98815 -321.757444) (xy 187.936188 -321.769304) (xy 187.883038 -321.773288) (xy 187.829888 -321.769304)
			(xy 187.777926 -321.757444) (xy 187.728312 -321.737972) (xy 187.682154 -321.711323) (xy 187.640483 -321.678092)
			(xy 187.604231 -321.639021) (xy 187.574207 -321.594984) (xy 187.551081 -321.546963) (xy 187.535371 -321.496033)
			(xy 187.527428 -321.443329) (xy 184.786788 -321.443329) (xy 184.778845 -321.496033) (xy 184.763135 -321.546963)
			(xy 184.740009 -321.594984) (xy 184.709985 -321.639021) (xy 184.673733 -321.678092) (xy 184.632062 -321.711323)
			(xy 184.585904 -321.737972) (xy 184.53629 -321.757444) (xy 184.484328 -321.769304) (xy 184.431178 -321.773288)
			(xy 184.378028 -321.769304) (xy 184.326066 -321.757444) (xy 184.276452 -321.737972) (xy 184.230294 -321.711323)
			(xy 184.188623 -321.678092) (xy 184.152371 -321.639021) (xy 184.122347 -321.594984) (xy 184.099221 -321.546963)
			(xy 184.083511 -321.496033) (xy 184.075568 -321.443329) (xy 180.662813 -321.443329) (xy 180.642989 -321.484494)
			(xy 180.612965 -321.528531) (xy 180.576713 -321.567602) (xy 180.535042 -321.600833) (xy 180.488884 -321.627482)
			(xy 180.43927 -321.646954) (xy 180.387308 -321.658814) (xy 180.334158 -321.662798) (xy 180.281008 -321.658814)
			(xy 180.229046 -321.646954) (xy 180.179432 -321.627482) (xy 180.133274 -321.600833) (xy 180.091603 -321.567602)
			(xy 180.055351 -321.528531) (xy 180.025327 -321.484494) (xy 180.002201 -321.436473) (xy 179.986491 -321.385543)
			(xy 179.978548 -321.332839) (xy 176.912771 -321.332839) (xy 176.911035 -321.333584) (xy 176.858598 -321.347158)
			(xy 176.804711 -321.352634) (xy 176.750616 -321.349887) (xy 176.697561 -321.33898) (xy 176.646769 -321.320164)
			(xy 176.599413 -321.293874) (xy 176.556584 -321.260715) (xy 176.51927 -321.221453) (xy 176.488332 -321.176994)
			(xy 176.464483 -321.128362) (xy 176.448274 -321.07668) (xy 176.440078 -321.023138) (xy 176.439576 -320.996056)
			(xy 176.439871 -320.975613) (xy 176.444584 -320.934999) (xy 176.448974 -320.91503) (xy 176.451677 -320.90143)
			(xy 176.450469 -320.873738) (xy 176.441865 -320.84739) (xy 176.426498 -320.824321) (xy 176.405498 -320.80623)
			(xy 176.380409 -320.794446) (xy 176.353078 -320.789836) (xy 176.339246 -320.790824) (xy 176.3014 -320.792856)
			(xy 176.274319 -320.792302) (xy 176.220782 -320.7841) (xy 176.169104 -320.767886) (xy 176.120477 -320.744033)
			(xy 176.076024 -320.713091) (xy 176.036768 -320.675774) (xy 176.003617 -320.632944) (xy 175.977333 -320.585587)
			(xy 175.958524 -320.534795) (xy 175.947624 -320.481742) (xy 175.944883 -320.427649) (xy 172.534608 -320.427649)
			(xy 172.538877 -320.436513) (xy 172.554587 -320.487443) (xy 172.56253 -320.540147) (xy 172.563028 -320.566796)
			(xy 172.56253 -320.593445) (xy 172.554587 -320.646149) (xy 172.538877 -320.697079) (xy 172.515751 -320.7451)
			(xy 172.485727 -320.789137) (xy 172.449475 -320.828208) (xy 172.407804 -320.861439) (xy 172.361646 -320.888088)
			(xy 172.312032 -320.90756) (xy 172.26007 -320.91942) (xy 172.20692 -320.923404) (xy 172.15377 -320.91942)
			(xy 172.101808 -320.90756) (xy 172.052194 -320.888088) (xy 172.006036 -320.861439) (xy 171.964365 -320.828208)
			(xy 171.928113 -320.789137) (xy 171.898089 -320.7451) (xy 171.874963 -320.697079) (xy 171.859253 -320.646149)
			(xy 171.85131 -320.593445) (xy 169.707831 -320.593445) (xy 169.70782 -320.594059) (xy 169.699503 -320.647947)
			(xy 169.683061 -320.699935) (xy 169.658881 -320.748806) (xy 169.627528 -320.793416) (xy 169.609008 -320.81343)
			(xy 169.599135 -320.824464) (xy 169.58556 -320.850756) (xy 169.580104 -320.87984) (xy 169.583228 -320.909265)
			(xy 169.594668 -320.936554) (xy 169.603674 -320.948304) (xy 169.618819 -320.967484) (xy 169.644307 -321.009181)
			(xy 169.663856 -321.05397) (xy 169.677099 -321.101011) (xy 169.683786 -321.149421) (xy 169.684192 -321.173856)
			(xy 169.683694 -321.200505) (xy 169.675751 -321.253209) (xy 169.660041 -321.304139) (xy 169.648788 -321.327505)
			(xy 172.376074 -321.327505) (xy 172.376074 -321.274207) (xy 172.384017 -321.221503) (xy 172.399727 -321.170573)
			(xy 172.422853 -321.122552) (xy 172.452877 -321.078515) (xy 172.489129 -321.039444) (xy 172.5308 -321.006213)
			(xy 172.576958 -320.979564) (xy 172.626572 -320.960092) (xy 172.678534 -320.948232) (xy 172.731684 -320.944249)
			(xy 172.784834 -320.948232) (xy 172.836796 -320.960092) (xy 172.88641 -320.979564) (xy 172.932568 -321.006213)
			(xy 172.974239 -321.039444) (xy 173.010491 -321.078515) (xy 173.040515 -321.122552) (xy 173.063641 -321.170573)
			(xy 173.079351 -321.221503) (xy 173.087294 -321.274207) (xy 173.087792 -321.300856) (xy 173.087294 -321.327505)
			(xy 173.079351 -321.380209) (xy 173.063641 -321.431139) (xy 173.040515 -321.47916) (xy 173.010491 -321.523197)
			(xy 172.974239 -321.562268) (xy 172.932568 -321.595499) (xy 172.88641 -321.622148) (xy 172.836796 -321.64162)
			(xy 172.784834 -321.65348) (xy 172.731684 -321.657464) (xy 172.678534 -321.65348) (xy 172.626572 -321.64162)
			(xy 172.576958 -321.622148) (xy 172.5308 -321.595499) (xy 172.489129 -321.562268) (xy 172.452877 -321.523197)
			(xy 172.422853 -321.47916) (xy 172.399727 -321.431139) (xy 172.384017 -321.380209) (xy 172.376074 -321.327505)
			(xy 169.648788 -321.327505) (xy 169.636915 -321.35216) (xy 169.606891 -321.396197) (xy 169.570639 -321.435268)
			(xy 169.528968 -321.468499) (xy 169.48281 -321.495148) (xy 169.433196 -321.51462) (xy 169.381234 -321.52648)
			(xy 169.328084 -321.530464) (xy 169.274934 -321.52648) (xy 169.222972 -321.51462) (xy 169.173358 -321.495148)
			(xy 169.1272 -321.468499) (xy 169.085529 -321.435268) (xy 169.049277 -321.396197) (xy 169.019253 -321.35216)
			(xy 168.996127 -321.304139) (xy 168.980417 -321.253209) (xy 168.972474 -321.200505) (xy 168.971976 -321.173856)
			(xy 168.258701 -321.173856) (xy 168.238155 -321.196) (xy 168.196484 -321.229231) (xy 168.150326 -321.25588)
			(xy 168.100712 -321.275352) (xy 168.04875 -321.287212) (xy 167.9956 -321.291196) (xy 167.94245 -321.287212)
			(xy 167.890488 -321.275352) (xy 167.840874 -321.25588) (xy 167.794716 -321.229231) (xy 167.753045 -321.196)
			(xy 167.716793 -321.156929) (xy 167.686769 -321.112892) (xy 167.663643 -321.064871) (xy 167.647933 -321.013941)
			(xy 167.63999 -320.961237) (xy 163.481745 -320.961237) (xy 164.305721 -321.785213) (xy 164.639488 -321.785213)
			(xy 164.639488 -321.731915) (xy 164.647431 -321.679211) (xy 164.663141 -321.628281) (xy 164.686267 -321.58026)
			(xy 164.716291 -321.536223) (xy 164.752543 -321.497152) (xy 164.794214 -321.463921) (xy 164.840372 -321.437272)
			(xy 164.889986 -321.4178) (xy 164.941948 -321.40594) (xy 164.995098 -321.401957) (xy 165.048248 -321.40594)
			(xy 165.10021 -321.4178) (xy 165.149824 -321.437272) (xy 165.195982 -321.463921) (xy 165.237653 -321.497152)
			(xy 165.273905 -321.536223) (xy 165.303929 -321.58026) (xy 165.327055 -321.628281) (xy 165.342765 -321.679211)
			(xy 165.350708 -321.731915) (xy 165.351206 -321.758564) (xy 165.350708 -321.785213) (xy 165.342765 -321.837917)
			(xy 165.327055 -321.888847) (xy 165.303929 -321.936868) (xy 165.273905 -321.980905) (xy 165.237653 -322.019976)
			(xy 165.195982 -322.053207) (xy 165.160388 -322.073757) (xy 280.75635 -322.073757) (xy 280.75635 -322.020459)
			(xy 280.764293 -321.967755) (xy 280.780003 -321.916825) (xy 280.803129 -321.868804) (xy 280.833153 -321.824767)
			(xy 280.869405 -321.785696) (xy 280.911076 -321.752465) (xy 280.957234 -321.725816) (xy 281.006848 -321.706344)
			(xy 281.05881 -321.694484) (xy 281.11196 -321.690501) (xy 281.16511 -321.694484) (xy 281.217072 -321.706344)
			(xy 281.266686 -321.725816) (xy 281.312844 -321.752465) (xy 281.354515 -321.785696) (xy 281.390767 -321.824767)
			(xy 281.420791 -321.868804) (xy 281.443917 -321.916825) (xy 281.459627 -321.967755) (xy 281.46757 -322.020459)
			(xy 281.468068 -322.047108) (xy 281.46757 -322.073757) (xy 281.459627 -322.126461) (xy 281.443917 -322.177391)
			(xy 281.420791 -322.225412) (xy 281.390767 -322.269449) (xy 281.354515 -322.30852) (xy 281.312844 -322.341751)
			(xy 281.266686 -322.3684) (xy 281.217072 -322.387872) (xy 281.16511 -322.399732) (xy 281.11196 -322.403716)
			(xy 281.05881 -322.399732) (xy 281.006848 -322.387872) (xy 280.957234 -322.3684) (xy 280.911076 -322.341751)
			(xy 280.869405 -322.30852) (xy 280.833153 -322.269449) (xy 280.803129 -322.225412) (xy 280.780003 -322.177391)
			(xy 280.764293 -322.126461) (xy 280.75635 -322.073757) (xy 165.160388 -322.073757) (xy 165.149824 -322.079856)
			(xy 165.10021 -322.099328) (xy 165.048248 -322.111188) (xy 164.995098 -322.115172) (xy 164.941948 -322.111188)
			(xy 164.889986 -322.099328) (xy 164.840372 -322.079856) (xy 164.794214 -322.053207) (xy 164.752543 -322.019976)
			(xy 164.716291 -321.980905) (xy 164.686267 -321.936868) (xy 164.663141 -321.888847) (xy 164.647431 -321.837917)
			(xy 164.639488 -321.785213) (xy 164.305721 -321.785213) (xy 165.197515 -322.677007) (xy 288.747444 -322.677007)
			(xy 288.747444 -322.623709) (xy 288.755387 -322.571005) (xy 288.771097 -322.520075) (xy 288.794223 -322.472054)
			(xy 288.824247 -322.428017) (xy 288.860499 -322.388946) (xy 288.90217 -322.355715) (xy 288.948328 -322.329066)
			(xy 288.997942 -322.309594) (xy 289.049904 -322.297734) (xy 289.103054 -322.293751) (xy 289.156204 -322.297734)
			(xy 289.208166 -322.309594) (xy 289.25778 -322.329066) (xy 289.303938 -322.355715) (xy 289.345609 -322.388946)
			(xy 289.381861 -322.428017) (xy 289.411885 -322.472054) (xy 289.435011 -322.520075) (xy 289.436957 -322.526385)
			(xy 291.155364 -322.526385) (xy 291.155364 -322.473087) (xy 291.163307 -322.420383) (xy 291.179017 -322.369453)
			(xy 291.202143 -322.321432) (xy 291.232167 -322.277395) (xy 291.268419 -322.238324) (xy 291.31009 -322.205093)
			(xy 291.356248 -322.178444) (xy 291.405862 -322.158972) (xy 291.457824 -322.147112) (xy 291.510974 -322.143129)
			(xy 291.564124 -322.147112) (xy 291.616086 -322.158972) (xy 291.6657 -322.178444) (xy 291.711858 -322.205093)
			(xy 291.753529 -322.238324) (xy 291.789781 -322.277395) (xy 291.819805 -322.321432) (xy 291.842931 -322.369453)
			(xy 291.858641 -322.420383) (xy 291.866584 -322.473087) (xy 291.867082 -322.499736) (xy 291.866584 -322.526385)
			(xy 292.349164 -322.526385) (xy 292.349164 -322.473087) (xy 292.357107 -322.420383) (xy 292.372817 -322.369453)
			(xy 292.395943 -322.321432) (xy 292.425967 -322.277395) (xy 292.462219 -322.238324) (xy 292.50389 -322.205093)
			(xy 292.550048 -322.178444) (xy 292.599662 -322.158972) (xy 292.651624 -322.147112) (xy 292.704774 -322.143129)
			(xy 292.757924 -322.147112) (xy 292.809886 -322.158972) (xy 292.8595 -322.178444) (xy 292.905658 -322.205093)
			(xy 292.947329 -322.238324) (xy 292.983581 -322.277395) (xy 293.013605 -322.321432) (xy 293.036731 -322.369453)
			(xy 293.052441 -322.420383) (xy 293.060384 -322.473087) (xy 293.060882 -322.499736) (xy 293.060384 -322.526385)
			(xy 294.736764 -322.526385) (xy 294.736764 -322.473087) (xy 294.744707 -322.420383) (xy 294.760417 -322.369453)
			(xy 294.783543 -322.321432) (xy 294.813567 -322.277395) (xy 294.849819 -322.238324) (xy 294.89149 -322.205093)
			(xy 294.937648 -322.178444) (xy 294.987262 -322.158972) (xy 295.039224 -322.147112) (xy 295.092374 -322.143129)
			(xy 295.145524 -322.147112) (xy 295.197486 -322.158972) (xy 295.2471 -322.178444) (xy 295.293258 -322.205093)
			(xy 295.334929 -322.238324) (xy 295.371181 -322.277395) (xy 295.401205 -322.321432) (xy 295.424331 -322.369453)
			(xy 295.440041 -322.420383) (xy 295.447984 -322.473087) (xy 295.448482 -322.499736) (xy 295.447984 -322.526385)
			(xy 295.440041 -322.579089) (xy 295.429268 -322.614015) (xy 298.568608 -322.614015) (xy 298.568608 -322.560717)
			(xy 298.576551 -322.508013) (xy 298.592261 -322.457083) (xy 298.615387 -322.409062) (xy 298.645411 -322.365025)
			(xy 298.681663 -322.325954) (xy 298.723334 -322.292723) (xy 298.769492 -322.266074) (xy 298.819106 -322.246602)
			(xy 298.871068 -322.234742) (xy 298.924218 -322.230759) (xy 298.977368 -322.234742) (xy 299.02933 -322.246602)
			(xy 299.078944 -322.266074) (xy 299.125102 -322.292723) (xy 299.166773 -322.325954) (xy 299.203025 -322.365025)
			(xy 299.233049 -322.409062) (xy 299.256175 -322.457083) (xy 299.271885 -322.508013) (xy 299.279828 -322.560717)
			(xy 299.280326 -322.587366) (xy 299.279828 -322.614015) (xy 299.271885 -322.666719) (xy 299.256175 -322.717649)
			(xy 299.233049 -322.76567) (xy 299.203025 -322.809707) (xy 299.166773 -322.848778) (xy 299.125102 -322.882009)
			(xy 299.078944 -322.908658) (xy 299.02933 -322.92813) (xy 298.977368 -322.93999) (xy 298.924218 -322.943974)
			(xy 298.871068 -322.93999) (xy 298.819106 -322.92813) (xy 298.769492 -322.908658) (xy 298.723334 -322.882009)
			(xy 298.681663 -322.848778) (xy 298.645411 -322.809707) (xy 298.615387 -322.76567) (xy 298.592261 -322.717649)
			(xy 298.576551 -322.666719) (xy 298.568608 -322.614015) (xy 295.429268 -322.614015) (xy 295.424331 -322.630019)
			(xy 295.401205 -322.67804) (xy 295.371181 -322.722077) (xy 295.334929 -322.761148) (xy 295.293258 -322.794379)
			(xy 295.2471 -322.821028) (xy 295.197486 -322.8405) (xy 295.145524 -322.85236) (xy 295.092374 -322.856344)
			(xy 295.039224 -322.85236) (xy 294.987262 -322.8405) (xy 294.937648 -322.821028) (xy 294.89149 -322.794379)
			(xy 294.849819 -322.761148) (xy 294.813567 -322.722077) (xy 294.783543 -322.67804) (xy 294.760417 -322.630019)
			(xy 294.744707 -322.579089) (xy 294.736764 -322.526385) (xy 293.060384 -322.526385) (xy 293.052441 -322.579089)
			(xy 293.036731 -322.630019) (xy 293.013605 -322.67804) (xy 292.983581 -322.722077) (xy 292.947329 -322.761148)
			(xy 292.905658 -322.794379) (xy 292.8595 -322.821028) (xy 292.809886 -322.8405) (xy 292.757924 -322.85236)
			(xy 292.704774 -322.856344) (xy 292.651624 -322.85236) (xy 292.599662 -322.8405) (xy 292.550048 -322.821028)
			(xy 292.50389 -322.794379) (xy 292.462219 -322.761148) (xy 292.425967 -322.722077) (xy 292.395943 -322.67804)
			(xy 292.372817 -322.630019) (xy 292.357107 -322.579089) (xy 292.349164 -322.526385) (xy 291.866584 -322.526385)
			(xy 291.858641 -322.579089) (xy 291.842931 -322.630019) (xy 291.819805 -322.67804) (xy 291.789781 -322.722077)
			(xy 291.753529 -322.761148) (xy 291.711858 -322.794379) (xy 291.6657 -322.821028) (xy 291.616086 -322.8405)
			(xy 291.564124 -322.85236) (xy 291.510974 -322.856344) (xy 291.457824 -322.85236) (xy 291.405862 -322.8405)
			(xy 291.356248 -322.821028) (xy 291.31009 -322.794379) (xy 291.268419 -322.761148) (xy 291.232167 -322.722077)
			(xy 291.202143 -322.67804) (xy 291.179017 -322.630019) (xy 291.163307 -322.579089) (xy 291.155364 -322.526385)
			(xy 289.436957 -322.526385) (xy 289.450721 -322.571005) (xy 289.458664 -322.623709) (xy 289.459162 -322.650358)
			(xy 289.458664 -322.677007) (xy 289.450721 -322.729711) (xy 289.435011 -322.780641) (xy 289.411885 -322.828662)
			(xy 289.381861 -322.872699) (xy 289.345609 -322.91177) (xy 289.303938 -322.945001) (xy 289.25778 -322.97165)
			(xy 289.208166 -322.991122) (xy 289.156204 -323.002982) (xy 289.103054 -323.006966) (xy 289.049904 -323.002982)
			(xy 288.997942 -322.991122) (xy 288.948328 -322.97165) (xy 288.90217 -322.945001) (xy 288.860499 -322.91177)
			(xy 288.824247 -322.872699) (xy 288.794223 -322.828662) (xy 288.771097 -322.780641) (xy 288.755387 -322.729711)
			(xy 288.747444 -322.677007) (xy 165.197515 -322.677007) (xy 165.702742 -323.182234) (xy 165.710108 -323.189074)
			(xy 165.728641 -323.196816) (xy 165.748725 -323.196816) (xy 165.767258 -323.189074) (xy 165.774624 -323.182234)
			(xy 165.794799 -323.162912) (xy 165.840044 -323.130154) (xy 165.889845 -323.104852) (xy 165.942982 -323.087627)
			(xy 165.998155 -323.078898) (xy 166.026084 -323.078348) (xy 166.052494 -323.078826) (xy 166.104734 -323.086625)
			(xy 166.15525 -323.102054) (xy 166.202933 -323.124774) (xy 166.246738 -323.154287) (xy 166.285704 -323.189947)
			(xy 166.30269 -323.210174) (xy 166.312627 -323.221567) (xy 166.33768 -323.238458) (xy 166.366576 -323.247289)
			(xy 166.396792 -323.247289) (xy 166.425688 -323.238458) (xy 166.450741 -323.221567) (xy 166.460678 -323.210174)
			(xy 166.477684 -323.189964) (xy 166.516646 -323.154304) (xy 166.560446 -323.124789) (xy 166.608126 -323.102067)
			(xy 166.658638 -323.086635) (xy 166.710876 -323.078832) (xy 166.737284 -323.078348) (xy 166.763939 -323.07882)
			(xy 166.816654 -323.086764) (xy 166.867597 -323.102475) (xy 166.915629 -323.125604) (xy 166.959677 -323.155634)
			(xy 166.998757 -323.191893) (xy 167.031996 -323.233572) (xy 167.058652 -323.27974) (xy 167.078129 -323.329365)
			(xy 167.089992 -323.381339) (xy 167.093976 -323.4345) (xy 169.733448 -323.4345) (xy 169.737432 -323.381345)
			(xy 169.749293 -323.329378) (xy 169.768766 -323.279759) (xy 169.795417 -323.233596) (xy 169.828651 -323.191921)
			(xy 169.867724 -323.155664) (xy 169.911765 -323.125636) (xy 169.959789 -323.102507) (xy 170.010724 -323.086794)
			(xy 170.063432 -323.078847) (xy 170.090084 -323.078348) (xy 170.116492 -323.078855) (xy 170.168728 -323.086653)
			(xy 170.21924 -323.10208) (xy 170.266919 -323.124798) (xy 170.310721 -323.15431) (xy 170.349683 -323.189966)
			(xy 170.36669 -323.210174) (xy 170.376627 -323.221567) (xy 170.40168 -323.238458) (xy 170.430576 -323.247289)
			(xy 170.460792 -323.247289) (xy 170.489688 -323.238458) (xy 170.514741 -323.221567) (xy 170.524678 -323.210174)
			(xy 170.541682 -323.189962) (xy 170.580644 -323.154302) (xy 170.624445 -323.124786) (xy 170.672125 -323.102064)
			(xy 170.722637 -323.086632) (xy 170.774875 -323.078829) (xy 170.801284 -323.078348) (xy 170.827933 -323.078908)
			(xy 170.880635 -323.086849) (xy 170.931565 -323.102557) (xy 170.979585 -323.12568) (xy 171.023622 -323.155703)
			(xy 171.062692 -323.191953) (xy 171.095923 -323.233622) (xy 171.122573 -323.279778) (xy 171.142045 -323.329391)
			(xy 171.153905 -323.381352) (xy 171.157888 -323.4345) (xy 173.213248 -323.4345) (xy 173.217232 -323.381345)
			(xy 173.229093 -323.329378) (xy 173.248566 -323.279759) (xy 173.275217 -323.233596) (xy 173.308451 -323.191921)
			(xy 173.347524 -323.155664) (xy 173.391565 -323.125636) (xy 173.439589 -323.102507) (xy 173.490524 -323.086794)
			(xy 173.543232 -323.078847) (xy 173.569884 -323.078348) (xy 173.596292 -323.078855) (xy 173.648528 -323.086653)
			(xy 173.69904 -323.10208) (xy 173.746719 -323.124798) (xy 173.790521 -323.15431) (xy 173.829483 -323.189966)
			(xy 173.84649 -323.210174) (xy 173.856427 -323.221567) (xy 173.88148 -323.238458) (xy 173.910376 -323.247289)
			(xy 173.940592 -323.247289) (xy 173.969488 -323.238458) (xy 173.994541 -323.221567) (xy 174.004478 -323.210174)
			(xy 174.021482 -323.189962) (xy 174.060444 -323.154302) (xy 174.104245 -323.124786) (xy 174.151925 -323.102064)
			(xy 174.202437 -323.086632) (xy 174.254675 -323.078829) (xy 174.281084 -323.078348) (xy 174.307733 -323.078908)
			(xy 174.360435 -323.086849) (xy 174.411365 -323.102557) (xy 174.459385 -323.12568) (xy 174.503422 -323.155703)
			(xy 174.542492 -323.191953) (xy 174.575723 -323.233622) (xy 174.602373 -323.279778) (xy 174.621845 -323.329391)
			(xy 174.633705 -323.381352) (xy 174.637688 -323.4345) (xy 177.277248 -323.4345) (xy 177.281232 -323.381345)
			(xy 177.293093 -323.329378) (xy 177.312566 -323.279759) (xy 177.339217 -323.233596) (xy 177.372451 -323.191921)
			(xy 177.411524 -323.155664) (xy 177.455565 -323.125636) (xy 177.503589 -323.102507) (xy 177.554524 -323.086794)
			(xy 177.607232 -323.078847) (xy 177.633884 -323.078348) (xy 177.660292 -323.078855) (xy 177.712528 -323.086653)
			(xy 177.76304 -323.10208) (xy 177.810719 -323.124798) (xy 177.854521 -323.15431) (xy 177.893483 -323.189966)
			(xy 177.91049 -323.210174) (xy 177.920427 -323.221567) (xy 177.94548 -323.238458) (xy 177.974376 -323.247289)
			(xy 178.004592 -323.247289) (xy 178.033488 -323.238458) (xy 178.058541 -323.221567) (xy 178.068478 -323.210174)
			(xy 178.085482 -323.189962) (xy 178.124444 -323.154302) (xy 178.168245 -323.124786) (xy 178.215925 -323.102064)
			(xy 178.266437 -323.086632) (xy 178.318675 -323.078829) (xy 178.345084 -323.078348) (xy 178.371733 -323.078908)
			(xy 178.424435 -323.086849) (xy 178.475365 -323.102557) (xy 178.523385 -323.12568) (xy 178.567422 -323.155703)
			(xy 178.606492 -323.191953) (xy 178.639723 -323.233622) (xy 178.666373 -323.279778) (xy 178.685845 -323.329391)
			(xy 178.697705 -323.381352) (xy 178.701688 -323.4345) (xy 180.757048 -323.4345) (xy 180.761032 -323.381345)
			(xy 180.772893 -323.329378) (xy 180.792366 -323.279759) (xy 180.819017 -323.233596) (xy 180.852251 -323.191921)
			(xy 180.891324 -323.155664) (xy 180.935365 -323.125636) (xy 180.983389 -323.102507) (xy 181.034324 -323.086794)
			(xy 181.087032 -323.078847) (xy 181.113684 -323.078348) (xy 181.140092 -323.078855) (xy 181.192328 -323.086653)
			(xy 181.24284 -323.10208) (xy 181.290519 -323.124798) (xy 181.334321 -323.15431) (xy 181.373283 -323.189966)
			(xy 181.39029 -323.210174) (xy 181.400227 -323.221567) (xy 181.42528 -323.238458) (xy 181.454176 -323.247289)
			(xy 181.484392 -323.247289) (xy 181.513288 -323.238458) (xy 181.538341 -323.221567) (xy 181.548278 -323.210174)
			(xy 181.565282 -323.189962) (xy 181.604244 -323.154302) (xy 181.648045 -323.124786) (xy 181.695725 -323.102064)
			(xy 181.746237 -323.086632) (xy 181.798475 -323.078829) (xy 181.824884 -323.078348) (xy 181.851533 -323.078908)
			(xy 181.904235 -323.086849) (xy 181.955165 -323.102557) (xy 182.003185 -323.12568) (xy 182.047222 -323.155703)
			(xy 182.086292 -323.191953) (xy 182.119523 -323.233622) (xy 182.146173 -323.279778) (xy 182.165645 -323.329391)
			(xy 182.177505 -323.381352) (xy 182.181488 -323.4345) (xy 184.821048 -323.4345) (xy 184.825032 -323.381345)
			(xy 184.836893 -323.329378) (xy 184.856366 -323.279759) (xy 184.883017 -323.233596) (xy 184.916251 -323.191921)
			(xy 184.955324 -323.155664) (xy 184.999365 -323.125636) (xy 185.047389 -323.102507) (xy 185.098324 -323.086794)
			(xy 185.151032 -323.078847) (xy 185.177684 -323.078348) (xy 185.204244 -323.078854) (xy 185.256773 -323.086754)
			(xy 185.307547 -323.102366) (xy 185.35544 -323.125345) (xy 185.399389 -323.155181) (xy 185.419238 -323.172836)
			(xy 185.43009 -323.182141) (xy 185.455638 -323.194934) (xy 185.483732 -323.200142) (xy 185.512167 -323.197356)
			(xy 185.538716 -323.186796) (xy 185.550302 -323.178424) (xy 185.57389 -323.160911) (xy 185.625591 -323.133021)
			(xy 185.681169 -323.113995) (xy 185.739116 -323.10435) (xy 185.768488 -323.103748) (xy 185.795136 -323.104308)
			(xy 185.847838 -323.11225) (xy 185.898768 -323.127958) (xy 185.946787 -323.151082) (xy 185.990824 -323.181104)
			(xy 186.029894 -323.217354) (xy 186.063124 -323.259023) (xy 186.089773 -323.305179) (xy 186.109245 -323.354792)
			(xy 186.121105 -323.406752) (xy 186.123184 -323.4345) (xy 188.300848 -323.4345) (xy 188.304832 -323.381345)
			(xy 188.316693 -323.329378) (xy 188.336166 -323.279759) (xy 188.362817 -323.233596) (xy 188.396051 -323.191921)
			(xy 188.435124 -323.155664) (xy 188.479165 -323.125636) (xy 188.527189 -323.102507) (xy 188.578124 -323.086794)
			(xy 188.630832 -323.078847) (xy 188.657484 -323.078348) (xy 188.683892 -323.078855) (xy 188.736128 -323.086653)
			(xy 188.78664 -323.10208) (xy 188.834319 -323.124798) (xy 188.878121 -323.15431) (xy 188.917083 -323.189966)
			(xy 188.93409 -323.210174) (xy 188.944027 -323.221567) (xy 188.96908 -323.238458) (xy 188.997976 -323.247289)
			(xy 189.028192 -323.247289) (xy 189.057088 -323.238458) (xy 189.082141 -323.221567) (xy 189.092078 -323.210174)
			(xy 189.109082 -323.189962) (xy 189.148044 -323.154302) (xy 189.191845 -323.124786) (xy 189.239525 -323.102064)
			(xy 189.290037 -323.086632) (xy 189.342275 -323.078829) (xy 189.368684 -323.078348) (xy 189.395333 -323.078908)
			(xy 189.448035 -323.086849) (xy 189.498965 -323.102557) (xy 189.546985 -323.12568) (xy 189.591022 -323.155703)
			(xy 189.630092 -323.191953) (xy 189.663323 -323.233622) (xy 189.689973 -323.279778) (xy 189.709445 -323.329391)
			(xy 189.721305 -323.381352) (xy 189.725288 -323.4345) (xy 192.364848 -323.4345) (xy 192.368832 -323.381345)
			(xy 192.380693 -323.329378) (xy 192.400166 -323.279759) (xy 192.426817 -323.233596) (xy 192.460051 -323.191921)
			(xy 192.499124 -323.155664) (xy 192.543165 -323.125636) (xy 192.591189 -323.102507) (xy 192.642124 -323.086794)
			(xy 192.694832 -323.078847) (xy 192.721484 -323.078348) (xy 192.747892 -323.078855) (xy 192.800128 -323.086653)
			(xy 192.85064 -323.10208) (xy 192.898319 -323.124798) (xy 192.942121 -323.15431) (xy 192.981083 -323.189966)
			(xy 192.99809 -323.210174) (xy 193.008027 -323.221567) (xy 193.03308 -323.238458) (xy 193.061976 -323.247289)
			(xy 193.092192 -323.247289) (xy 193.121088 -323.238458) (xy 193.146141 -323.221567) (xy 193.156078 -323.210174)
			(xy 193.173082 -323.189962) (xy 193.212044 -323.154302) (xy 193.255845 -323.124786) (xy 193.303525 -323.102064)
			(xy 193.354037 -323.086632) (xy 193.406275 -323.078829) (xy 193.432684 -323.078348) (xy 193.459333 -323.078908)
			(xy 193.512035 -323.086849) (xy 193.562965 -323.102557) (xy 193.610985 -323.12568) (xy 193.655022 -323.155703)
			(xy 193.694092 -323.191953) (xy 193.727323 -323.233622) (xy 193.753973 -323.279778) (xy 193.773445 -323.329391)
			(xy 193.785305 -323.381352) (xy 193.789288 -323.4345) (xy 195.844648 -323.4345) (xy 195.848632 -323.381345)
			(xy 195.860493 -323.329378) (xy 195.879966 -323.279759) (xy 195.906617 -323.233596) (xy 195.939851 -323.191921)
			(xy 195.978924 -323.155664) (xy 196.022965 -323.125636) (xy 196.070989 -323.102507) (xy 196.121924 -323.086794)
			(xy 196.174632 -323.078847) (xy 196.201284 -323.078348) (xy 196.227692 -323.078855) (xy 196.279928 -323.086653)
			(xy 196.33044 -323.10208) (xy 196.378119 -323.124798) (xy 196.421921 -323.15431) (xy 196.460883 -323.189966)
			(xy 196.47789 -323.210174) (xy 196.487827 -323.221567) (xy 196.51288 -323.238458) (xy 196.541776 -323.247289)
			(xy 196.571992 -323.247289) (xy 196.600888 -323.238458) (xy 196.625941 -323.221567) (xy 196.635878 -323.210174)
			(xy 196.652882 -323.189962) (xy 196.691844 -323.154302) (xy 196.735645 -323.124786) (xy 196.783325 -323.102064)
			(xy 196.833837 -323.086632) (xy 196.886075 -323.078829) (xy 196.912484 -323.078348) (xy 196.939133 -323.078908)
			(xy 196.991835 -323.086849) (xy 197.042765 -323.102557) (xy 197.090785 -323.12568) (xy 197.134822 -323.155703)
			(xy 197.173892 -323.191953) (xy 197.207123 -323.233622) (xy 197.233773 -323.279778) (xy 197.253245 -323.329391)
			(xy 197.265105 -323.381352) (xy 197.269088 -323.4345) (xy 199.908648 -323.4345) (xy 199.912632 -323.381345)
			(xy 199.924493 -323.329378) (xy 199.943966 -323.279759) (xy 199.970617 -323.233596) (xy 200.003851 -323.191921)
			(xy 200.042924 -323.155664) (xy 200.086965 -323.125636) (xy 200.134989 -323.102507) (xy 200.185924 -323.086794)
			(xy 200.238632 -323.078847) (xy 200.265284 -323.078348) (xy 200.291692 -323.078855) (xy 200.343928 -323.086653)
			(xy 200.39444 -323.10208) (xy 200.442119 -323.124798) (xy 200.485921 -323.15431) (xy 200.524883 -323.189966)
			(xy 200.54189 -323.210174) (xy 200.551827 -323.221567) (xy 200.57688 -323.238458) (xy 200.605776 -323.247289)
			(xy 200.635992 -323.247289) (xy 200.664888 -323.238458) (xy 200.689941 -323.221567) (xy 200.699878 -323.210174)
			(xy 200.716882 -323.189962) (xy 200.755844 -323.154302) (xy 200.799645 -323.124786) (xy 200.847325 -323.102064)
			(xy 200.897837 -323.086632) (xy 200.950075 -323.078829) (xy 200.976484 -323.078348) (xy 201.003133 -323.078908)
			(xy 201.055835 -323.086849) (xy 201.106765 -323.102557) (xy 201.154785 -323.12568) (xy 201.198822 -323.155703)
			(xy 201.237892 -323.191953) (xy 201.271123 -323.233622) (xy 201.297773 -323.279778) (xy 201.317245 -323.329391)
			(xy 201.329105 -323.381352) (xy 201.333088 -323.4345) (xy 203.388448 -323.4345) (xy 203.392432 -323.381345)
			(xy 203.404293 -323.329378) (xy 203.423766 -323.279759) (xy 203.450417 -323.233596) (xy 203.483651 -323.191921)
			(xy 203.522724 -323.155664) (xy 203.566765 -323.125636) (xy 203.614789 -323.102507) (xy 203.665724 -323.086794)
			(xy 203.718432 -323.078847) (xy 203.745084 -323.078348) (xy 203.771492 -323.078855) (xy 203.823728 -323.086653)
			(xy 203.87424 -323.10208) (xy 203.921919 -323.124798) (xy 203.965721 -323.15431) (xy 204.004683 -323.189966)
			(xy 204.02169 -323.210174) (xy 204.031627 -323.221567) (xy 204.05668 -323.238458) (xy 204.085576 -323.247289)
			(xy 204.115792 -323.247289) (xy 204.144688 -323.238458) (xy 204.169741 -323.221567) (xy 204.179678 -323.210174)
			(xy 204.196682 -323.189962) (xy 204.235644 -323.154302) (xy 204.279445 -323.124786) (xy 204.327125 -323.102064)
			(xy 204.377637 -323.086632) (xy 204.429875 -323.078829) (xy 204.456284 -323.078348) (xy 204.482933 -323.078908)
			(xy 204.535635 -323.086849) (xy 204.586565 -323.102557) (xy 204.634585 -323.12568) (xy 204.678622 -323.155703)
			(xy 204.717692 -323.191953) (xy 204.750923 -323.233622) (xy 204.777573 -323.279778) (xy 204.797045 -323.329391)
			(xy 204.808905 -323.381352) (xy 204.812888 -323.4345) (xy 207.452448 -323.4345) (xy 207.456432 -323.381345)
			(xy 207.468293 -323.329378) (xy 207.487766 -323.279759) (xy 207.514417 -323.233596) (xy 207.547651 -323.191921)
			(xy 207.586724 -323.155664) (xy 207.630765 -323.125636) (xy 207.678789 -323.102507) (xy 207.729724 -323.086794)
			(xy 207.782432 -323.078847) (xy 207.809084 -323.078348) (xy 207.835492 -323.078855) (xy 207.887728 -323.086653)
			(xy 207.93824 -323.10208) (xy 207.985919 -323.124798) (xy 208.029721 -323.15431) (xy 208.068683 -323.189966)
			(xy 208.08569 -323.210174) (xy 208.095627 -323.221567) (xy 208.12068 -323.238458) (xy 208.149576 -323.247289)
			(xy 208.179792 -323.247289) (xy 208.208688 -323.238458) (xy 208.233741 -323.221567) (xy 208.243678 -323.210174)
			(xy 208.260682 -323.189962) (xy 208.299644 -323.154302) (xy 208.343445 -323.124786) (xy 208.391125 -323.102064)
			(xy 208.441637 -323.086632) (xy 208.493875 -323.078829) (xy 208.520284 -323.078348) (xy 208.546933 -323.078908)
			(xy 208.599635 -323.086849) (xy 208.650565 -323.102557) (xy 208.698585 -323.12568) (xy 208.742622 -323.155703)
			(xy 208.781692 -323.191953) (xy 208.814923 -323.233622) (xy 208.841573 -323.279778) (xy 208.861045 -323.329391)
			(xy 208.872905 -323.381352) (xy 208.876888 -323.4345) (xy 210.932248 -323.4345) (xy 210.936232 -323.381345)
			(xy 210.948093 -323.329378) (xy 210.967566 -323.279759) (xy 210.994217 -323.233596) (xy 211.027451 -323.191921)
			(xy 211.066524 -323.155664) (xy 211.110565 -323.125636) (xy 211.158589 -323.102507) (xy 211.209524 -323.086794)
			(xy 211.262232 -323.078847) (xy 211.288884 -323.078348) (xy 211.315292 -323.078855) (xy 211.367528 -323.086653)
			(xy 211.41804 -323.10208) (xy 211.465719 -323.124798) (xy 211.509521 -323.15431) (xy 211.548483 -323.189966)
			(xy 211.56549 -323.210174) (xy 211.575427 -323.221567) (xy 211.60048 -323.238458) (xy 211.629376 -323.247289)
			(xy 211.659592 -323.247289) (xy 211.688488 -323.238458) (xy 211.713541 -323.221567) (xy 211.723478 -323.210174)
			(xy 211.740482 -323.189962) (xy 211.779444 -323.154302) (xy 211.823245 -323.124786) (xy 211.870925 -323.102064)
			(xy 211.921437 -323.086632) (xy 211.973675 -323.078829) (xy 212.000084 -323.078348) (xy 212.026733 -323.078908)
			(xy 212.079435 -323.086849) (xy 212.130365 -323.102557) (xy 212.178385 -323.12568) (xy 212.222422 -323.155703)
			(xy 212.261492 -323.191953) (xy 212.294723 -323.233622) (xy 212.321373 -323.279778) (xy 212.340845 -323.329391)
			(xy 212.347443 -323.3583) (xy 212.811848 -323.3583) (xy 212.815832 -323.305145) (xy 212.827693 -323.253178)
			(xy 212.847166 -323.203559) (xy 212.873817 -323.157396) (xy 212.907051 -323.115721) (xy 212.946124 -323.079464)
			(xy 212.990165 -323.049436) (xy 213.038189 -323.026307) (xy 213.089124 -323.010594) (xy 213.141832 -323.002647)
			(xy 213.168484 -323.002148) (xy 213.194892 -323.002655) (xy 213.247128 -323.010453) (xy 213.29764 -323.02588)
			(xy 213.345319 -323.048598) (xy 213.389121 -323.07811) (xy 213.428083 -323.113766) (xy 213.44509 -323.133974)
			(xy 213.455027 -323.145367) (xy 213.48008 -323.162258) (xy 213.508976 -323.171089) (xy 213.539192 -323.171089)
			(xy 213.568088 -323.162258) (xy 213.593141 -323.145367) (xy 213.603078 -323.133974) (xy 213.620082 -323.113762)
			(xy 213.659044 -323.078102) (xy 213.702845 -323.048586) (xy 213.750525 -323.025864) (xy 213.801037 -323.010432)
			(xy 213.853275 -323.002629) (xy 213.879684 -323.002148) (xy 213.906333 -323.002708) (xy 213.959035 -323.010649)
			(xy 214.009965 -323.026357) (xy 214.057985 -323.04948) (xy 214.102022 -323.079503) (xy 214.141092 -323.115753)
			(xy 214.174323 -323.157422) (xy 214.200973 -323.203578) (xy 214.220445 -323.253191) (xy 214.232305 -323.305152)
			(xy 214.236288 -323.3583) (xy 214.232305 -323.411448) (xy 214.230832 -323.4179) (xy 257.227639 -323.4179)
			(xy 257.231621 -323.364758) (xy 257.24348 -323.312803) (xy 257.262949 -323.263196) (xy 257.289594 -323.217044)
			(xy 257.32282 -323.175379) (xy 257.361885 -323.139132) (xy 257.405916 -323.109111) (xy 257.453929 -323.085988)
			(xy 257.504853 -323.07028) (xy 257.557548 -323.062336) (xy 257.584194 -323.061838) (xy 257.60922 -323.062245)
			(xy 257.658779 -323.069254) (xy 257.706868 -323.083133) (xy 257.752539 -323.10361) (xy 257.794893 -323.130281)
			(xy 257.833095 -323.16262) (xy 257.866391 -323.199991) (xy 257.880612 -323.220588) (xy 257.888945 -323.232217)
			(xy 257.910781 -323.250684) (xy 257.936878 -323.262376) (xy 257.965194 -323.266377) (xy 257.99351 -323.262376)
			(xy 258.019607 -323.250684) (xy 258.041443 -323.232217) (xy 258.049776 -323.220588) (xy 258.064018 -323.200007)
			(xy 258.097311 -323.162638) (xy 258.13551 -323.1303) (xy 258.17786 -323.103629) (xy 258.223528 -323.083152)
			(xy 258.271614 -323.069272) (xy 258.32117 -323.062263) (xy 258.346194 -323.061838) (xy 258.372849 -323.062219)
			(xy 258.425563 -323.070164) (xy 258.476505 -323.085876) (xy 258.524536 -323.109006) (xy 258.568582 -323.139036)
			(xy 258.607662 -323.175295) (xy 258.6409 -323.216974) (xy 258.667555 -323.263142) (xy 258.687031 -323.312766)
			(xy 258.698894 -323.364739) (xy 258.702878 -323.4179) (xy 258.702016 -323.4294) (xy 259.456968 -323.4294)
			(xy 259.460951 -323.376251) (xy 259.47281 -323.32429) (xy 259.49228 -323.274676) (xy 259.518927 -323.228517)
			(xy 259.552155 -323.186846) (xy 259.591222 -323.150591) (xy 259.635256 -323.120564) (xy 259.683274 -323.097434)
			(xy 259.734202 -323.081719) (xy 259.786903 -323.073769) (xy 259.813552 -323.073268) (xy 259.839959 -323.07379)
			(xy 259.892195 -323.081584) (xy 259.942707 -323.097008) (xy 259.990387 -323.119723) (xy 260.034188 -323.149232)
			(xy 260.073151 -323.184887) (xy 260.090158 -323.205094) (xy 260.100095 -323.216487) (xy 260.125148 -323.233378)
			(xy 260.154044 -323.242209) (xy 260.18426 -323.242209) (xy 260.213156 -323.233378) (xy 260.238209 -323.216487)
			(xy 260.248146 -323.205094) (xy 260.265172 -323.184902) (xy 260.304129 -323.149239) (xy 260.347925 -323.119721)
			(xy 260.3956 -323.096994) (xy 260.44611 -323.081558) (xy 260.498344 -323.073751) (xy 260.524752 -323.073268)
			(xy 260.551404 -323.073786) (xy 260.604113 -323.081724) (xy 260.655049 -323.09743) (xy 260.703076 -323.120552)
			(xy 260.74712 -323.150576) (xy 260.786197 -323.186828) (xy 260.819433 -323.2285) (xy 260.846087 -323.274661)
			(xy 260.865562 -323.324279) (xy 260.877424 -323.376246) (xy 260.881408 -323.4294) (xy 262.936768 -323.4294)
			(xy 262.940751 -323.376251) (xy 262.95261 -323.32429) (xy 262.97208 -323.274676) (xy 262.998727 -323.228517)
			(xy 263.031955 -323.186846) (xy 263.071022 -323.150591) (xy 263.115056 -323.120564) (xy 263.163074 -323.097434)
			(xy 263.214002 -323.081719) (xy 263.266703 -323.073769) (xy 263.293352 -323.073268) (xy 263.319759 -323.07379)
			(xy 263.371995 -323.081584) (xy 263.422507 -323.097008) (xy 263.470187 -323.119723) (xy 263.513988 -323.149232)
			(xy 263.552951 -323.184887) (xy 263.569958 -323.205094) (xy 263.579895 -323.216487) (xy 263.604948 -323.233378)
			(xy 263.633844 -323.242209) (xy 263.66406 -323.242209) (xy 263.692956 -323.233378) (xy 263.718009 -323.216487)
			(xy 263.727946 -323.205094) (xy 263.744972 -323.184902) (xy 263.783929 -323.149239) (xy 263.827725 -323.119721)
			(xy 263.8754 -323.096994) (xy 263.92591 -323.081558) (xy 263.978144 -323.073751) (xy 264.004552 -323.073268)
			(xy 264.031204 -323.073786) (xy 264.083913 -323.081724) (xy 264.134849 -323.09743) (xy 264.182876 -323.120552)
			(xy 264.22692 -323.150576) (xy 264.265997 -323.186828) (xy 264.299233 -323.2285) (xy 264.325887 -323.274661)
			(xy 264.345362 -323.324279) (xy 264.357224 -323.376246) (xy 264.361208 -323.4294) (xy 267.000768 -323.4294)
			(xy 267.004751 -323.376251) (xy 267.01661 -323.32429) (xy 267.03608 -323.274676) (xy 267.062727 -323.228517)
			(xy 267.095955 -323.186846) (xy 267.135022 -323.150591) (xy 267.179056 -323.120564) (xy 267.227074 -323.097434)
			(xy 267.278002 -323.081719) (xy 267.330703 -323.073769) (xy 267.357352 -323.073268) (xy 267.383759 -323.07379)
			(xy 267.435995 -323.081584) (xy 267.486507 -323.097008) (xy 267.534187 -323.119723) (xy 267.577988 -323.149232)
			(xy 267.616951 -323.184887) (xy 267.633958 -323.205094) (xy 267.643895 -323.216487) (xy 267.668948 -323.233378)
			(xy 267.697844 -323.242209) (xy 267.72806 -323.242209) (xy 267.756956 -323.233378) (xy 267.782009 -323.216487)
			(xy 267.791946 -323.205094) (xy 267.808972 -323.184902) (xy 267.847929 -323.149239) (xy 267.891725 -323.119721)
			(xy 267.9394 -323.096994) (xy 267.98991 -323.081558) (xy 268.042144 -323.073751) (xy 268.068552 -323.073268)
			(xy 268.095204 -323.073786) (xy 268.147913 -323.081724) (xy 268.198849 -323.09743) (xy 268.246876 -323.120552)
			(xy 268.29092 -323.150576) (xy 268.329997 -323.186828) (xy 268.363233 -323.2285) (xy 268.389887 -323.274661)
			(xy 268.409362 -323.324279) (xy 268.421224 -323.376246) (xy 268.425208 -323.4294) (xy 270.480568 -323.4294)
			(xy 270.484551 -323.376251) (xy 270.49641 -323.32429) (xy 270.51588 -323.274676) (xy 270.542527 -323.228517)
			(xy 270.575755 -323.186846) (xy 270.614822 -323.150591) (xy 270.658856 -323.120564) (xy 270.706874 -323.097434)
			(xy 270.757802 -323.081719) (xy 270.810503 -323.073769) (xy 270.837152 -323.073268) (xy 270.863559 -323.07379)
			(xy 270.915795 -323.081584) (xy 270.966307 -323.097008) (xy 271.013987 -323.119723) (xy 271.057788 -323.149232)
			(xy 271.096751 -323.184887) (xy 271.113758 -323.205094) (xy 271.123695 -323.216487) (xy 271.148748 -323.233378)
			(xy 271.177644 -323.242209) (xy 271.20786 -323.242209) (xy 271.236756 -323.233378) (xy 271.261809 -323.216487)
			(xy 271.271746 -323.205094) (xy 271.288772 -323.184902) (xy 271.327729 -323.149239) (xy 271.371525 -323.119721)
			(xy 271.4192 -323.096994) (xy 271.46971 -323.081558) (xy 271.521944 -323.073751) (xy 271.548352 -323.073268)
			(xy 271.575004 -323.073786) (xy 271.627713 -323.081724) (xy 271.678649 -323.09743) (xy 271.726676 -323.120552)
			(xy 271.77072 -323.150576) (xy 271.809797 -323.186828) (xy 271.843033 -323.2285) (xy 271.869687 -323.274661)
			(xy 271.889162 -323.324279) (xy 271.901024 -323.376246) (xy 271.905008 -323.4294) (xy 274.544568 -323.4294)
			(xy 274.548551 -323.376251) (xy 274.56041 -323.32429) (xy 274.57988 -323.274676) (xy 274.606527 -323.228517)
			(xy 274.639755 -323.186846) (xy 274.678822 -323.150591) (xy 274.722856 -323.120564) (xy 274.770874 -323.097434)
			(xy 274.821802 -323.081719) (xy 274.874503 -323.073769) (xy 274.901152 -323.073268) (xy 274.927559 -323.07379)
			(xy 274.979795 -323.081584) (xy 275.030307 -323.097008) (xy 275.077987 -323.119723) (xy 275.121788 -323.149232)
			(xy 275.160751 -323.184887) (xy 275.177758 -323.205094) (xy 275.187695 -323.216487) (xy 275.212748 -323.233378)
			(xy 275.241644 -323.242209) (xy 275.27186 -323.242209) (xy 275.300756 -323.233378) (xy 275.325809 -323.216487)
			(xy 275.335746 -323.205094) (xy 275.352772 -323.184902) (xy 275.391729 -323.149239) (xy 275.435525 -323.119721)
			(xy 275.4832 -323.096994) (xy 275.53371 -323.081558) (xy 275.585944 -323.073751) (xy 275.612352 -323.073268)
			(xy 275.639004 -323.073786) (xy 275.691713 -323.081724) (xy 275.742649 -323.09743) (xy 275.790676 -323.120552)
			(xy 275.83472 -323.150576) (xy 275.873797 -323.186828) (xy 275.907033 -323.2285) (xy 275.933687 -323.274661)
			(xy 275.953162 -323.324279) (xy 275.965024 -323.376246) (xy 275.969008 -323.4294) (xy 278.024368 -323.4294)
			(xy 278.028351 -323.376251) (xy 278.04021 -323.32429) (xy 278.05968 -323.274676) (xy 278.086327 -323.228517)
			(xy 278.119555 -323.186846) (xy 278.158622 -323.150591) (xy 278.202656 -323.120564) (xy 278.250674 -323.097434)
			(xy 278.301602 -323.081719) (xy 278.354303 -323.073769) (xy 278.380952 -323.073268) (xy 278.407359 -323.07379)
			(xy 278.459595 -323.081584) (xy 278.510107 -323.097008) (xy 278.557787 -323.119723) (xy 278.601588 -323.149232)
			(xy 278.640551 -323.184887) (xy 278.657558 -323.205094) (xy 278.667495 -323.216487) (xy 278.692548 -323.233378)
			(xy 278.721444 -323.242209) (xy 278.75166 -323.242209) (xy 278.780556 -323.233378) (xy 278.805609 -323.216487)
			(xy 278.815546 -323.205094) (xy 278.832572 -323.184902) (xy 278.871529 -323.149239) (xy 278.915325 -323.119721)
			(xy 278.963 -323.096994) (xy 279.01351 -323.081558) (xy 279.065744 -323.073751) (xy 279.092152 -323.073268)
			(xy 279.118804 -323.073786) (xy 279.171513 -323.081724) (xy 279.222449 -323.09743) (xy 279.270476 -323.120552)
			(xy 279.31452 -323.150576) (xy 279.353597 -323.186828) (xy 279.386833 -323.2285) (xy 279.413487 -323.274661)
			(xy 279.432962 -323.324279) (xy 279.444824 -323.376246) (xy 279.448808 -323.4294) (xy 282.088368 -323.4294)
			(xy 282.092351 -323.376251) (xy 282.10421 -323.32429) (xy 282.12368 -323.274676) (xy 282.150327 -323.228517)
			(xy 282.183555 -323.186846) (xy 282.222622 -323.150591) (xy 282.266656 -323.120564) (xy 282.314674 -323.097434)
			(xy 282.365602 -323.081719) (xy 282.418303 -323.073769) (xy 282.444952 -323.073268) (xy 282.471359 -323.07379)
			(xy 282.523595 -323.081584) (xy 282.574107 -323.097008) (xy 282.621787 -323.119723) (xy 282.665588 -323.149232)
			(xy 282.704551 -323.184887) (xy 282.721558 -323.205094) (xy 282.731495 -323.216487) (xy 282.756548 -323.233378)
			(xy 282.785444 -323.242209) (xy 282.81566 -323.242209) (xy 282.844556 -323.233378) (xy 282.869609 -323.216487)
			(xy 282.879546 -323.205094) (xy 282.896572 -323.184902) (xy 282.935529 -323.149239) (xy 282.979325 -323.119721)
			(xy 283.027 -323.096994) (xy 283.07751 -323.081558) (xy 283.129744 -323.073751) (xy 283.156152 -323.073268)
			(xy 283.182804 -323.073786) (xy 283.235513 -323.081724) (xy 283.286449 -323.09743) (xy 283.334476 -323.120552)
			(xy 283.37852 -323.150576) (xy 283.417597 -323.186828) (xy 283.450833 -323.2285) (xy 283.477487 -323.274661)
			(xy 283.496962 -323.324279) (xy 283.508824 -323.376246) (xy 283.512808 -323.4294) (xy 285.695168 -323.4294)
			(xy 285.699151 -323.376251) (xy 285.71101 -323.32429) (xy 285.73048 -323.274676) (xy 285.757127 -323.228517)
			(xy 285.790355 -323.186846) (xy 285.829422 -323.150591) (xy 285.873456 -323.120564) (xy 285.921474 -323.097434)
			(xy 285.972402 -323.081719) (xy 286.025103 -323.073769) (xy 286.051752 -323.073268) (xy 286.078159 -323.07379)
			(xy 286.130395 -323.081584) (xy 286.180907 -323.097008) (xy 286.228587 -323.119723) (xy 286.272388 -323.149232)
			(xy 286.311351 -323.184887) (xy 286.328358 -323.205094) (xy 286.338295 -323.216487) (xy 286.363348 -323.233378)
			(xy 286.392244 -323.242209) (xy 286.42246 -323.242209) (xy 286.451356 -323.233378) (xy 286.476409 -323.216487)
			(xy 286.486346 -323.205094) (xy 286.503372 -323.184902) (xy 286.542329 -323.149239) (xy 286.586125 -323.119721)
			(xy 286.6338 -323.096994) (xy 286.68431 -323.081558) (xy 286.736544 -323.073751) (xy 286.762952 -323.073268)
			(xy 286.789604 -323.073786) (xy 286.842313 -323.081724) (xy 286.893249 -323.09743) (xy 286.941276 -323.120552)
			(xy 286.98532 -323.150576) (xy 287.024397 -323.186828) (xy 287.057633 -323.2285) (xy 287.084287 -323.274661)
			(xy 287.103762 -323.324279) (xy 287.115624 -323.376246) (xy 287.119608 -323.4294) (xy 287.115624 -323.482554)
			(xy 287.103762 -323.534521) (xy 287.084287 -323.584139) (xy 287.057633 -323.6303) (xy 287.024397 -323.671972)
			(xy 286.98532 -323.708224) (xy 286.941276 -323.738248) (xy 286.893249 -323.76137) (xy 286.842313 -323.777076)
			(xy 286.789604 -323.785014) (xy 286.762952 -323.785484) (xy 286.736544 -323.784977) (xy 286.684307 -323.777182)
			(xy 286.633794 -323.761757) (xy 286.586114 -323.739038) (xy 286.542313 -323.709526) (xy 286.503352 -323.673867)
			(xy 286.486346 -323.653658) (xy 286.476409 -323.642265) (xy 286.451356 -323.625374) (xy 286.42246 -323.616543)
			(xy 286.392244 -323.616543) (xy 286.363348 -323.625374) (xy 286.338295 -323.642265) (xy 286.328358 -323.653658)
			(xy 286.311318 -323.673838) (xy 286.272366 -323.709504) (xy 286.228573 -323.739025) (xy 286.1809 -323.761754)
			(xy 286.130392 -323.777192) (xy 286.078159 -323.785) (xy 286.051752 -323.785484) (xy 286.025103 -323.785031)
			(xy 285.972402 -323.777081) (xy 285.921474 -323.761366) (xy 285.873456 -323.738236) (xy 285.829422 -323.708209)
			(xy 285.790355 -323.671954) (xy 285.757127 -323.630283) (xy 285.73048 -323.584124) (xy 285.71101 -323.53451)
			(xy 285.699151 -323.482549) (xy 285.695168 -323.4294) (xy 283.512808 -323.4294) (xy 283.508824 -323.482554)
			(xy 283.496962 -323.534521) (xy 283.477487 -323.584139) (xy 283.450833 -323.6303) (xy 283.417597 -323.671972)
			(xy 283.37852 -323.708224) (xy 283.334476 -323.738248) (xy 283.286449 -323.76137) (xy 283.235513 -323.777076)
			(xy 283.182804 -323.785014) (xy 283.156152 -323.785484) (xy 283.129744 -323.784977) (xy 283.077507 -323.777182)
			(xy 283.026994 -323.761757) (xy 282.979314 -323.739038) (xy 282.935513 -323.709526) (xy 282.896552 -323.673867)
			(xy 282.879546 -323.653658) (xy 282.869609 -323.642265) (xy 282.844556 -323.625374) (xy 282.81566 -323.616543)
			(xy 282.785444 -323.616543) (xy 282.756548 -323.625374) (xy 282.731495 -323.642265) (xy 282.721558 -323.653658)
			(xy 282.704518 -323.673838) (xy 282.665566 -323.709504) (xy 282.621773 -323.739025) (xy 282.5741 -323.761754)
			(xy 282.523592 -323.777192) (xy 282.471359 -323.785) (xy 282.444952 -323.785484) (xy 282.418303 -323.785031)
			(xy 282.365602 -323.777081) (xy 282.314674 -323.761366) (xy 282.266656 -323.738236) (xy 282.222622 -323.708209)
			(xy 282.183555 -323.671954) (xy 282.150327 -323.630283) (xy 282.12368 -323.584124) (xy 282.10421 -323.53451)
			(xy 282.092351 -323.482549) (xy 282.088368 -323.4294) (xy 279.448808 -323.4294) (xy 279.444824 -323.482554)
			(xy 279.432962 -323.534521) (xy 279.413487 -323.584139) (xy 279.386833 -323.6303) (xy 279.353597 -323.671972)
			(xy 279.31452 -323.708224) (xy 279.270476 -323.738248) (xy 279.222449 -323.76137) (xy 279.171513 -323.777076)
			(xy 279.118804 -323.785014) (xy 279.092152 -323.785484) (xy 279.065744 -323.784977) (xy 279.013507 -323.777182)
			(xy 278.962994 -323.761757) (xy 278.915314 -323.739038) (xy 278.871513 -323.709526) (xy 278.832552 -323.673867)
			(xy 278.815546 -323.653658) (xy 278.805609 -323.642265) (xy 278.780556 -323.625374) (xy 278.75166 -323.616543)
			(xy 278.721444 -323.616543) (xy 278.692548 -323.625374) (xy 278.667495 -323.642265) (xy 278.657558 -323.653658)
			(xy 278.640518 -323.673838) (xy 278.601566 -323.709504) (xy 278.557773 -323.739025) (xy 278.5101 -323.761754)
			(xy 278.459592 -323.777192) (xy 278.407359 -323.785) (xy 278.380952 -323.785484) (xy 278.354303 -323.785031)
			(xy 278.301602 -323.777081) (xy 278.250674 -323.761366) (xy 278.202656 -323.738236) (xy 278.158622 -323.708209)
			(xy 278.119555 -323.671954) (xy 278.086327 -323.630283) (xy 278.05968 -323.584124) (xy 278.04021 -323.53451)
			(xy 278.028351 -323.482549) (xy 278.024368 -323.4294) (xy 275.969008 -323.4294) (xy 275.965024 -323.482554)
			(xy 275.953162 -323.534521) (xy 275.933687 -323.584139) (xy 275.907033 -323.6303) (xy 275.873797 -323.671972)
			(xy 275.83472 -323.708224) (xy 275.790676 -323.738248) (xy 275.742649 -323.76137) (xy 275.691713 -323.777076)
			(xy 275.639004 -323.785014) (xy 275.612352 -323.785484) (xy 275.585944 -323.784977) (xy 275.533707 -323.777182)
			(xy 275.483194 -323.761757) (xy 275.435514 -323.739038) (xy 275.391713 -323.709526) (xy 275.352752 -323.673867)
			(xy 275.335746 -323.653658) (xy 275.325809 -323.642265) (xy 275.300756 -323.625374) (xy 275.27186 -323.616543)
			(xy 275.241644 -323.616543) (xy 275.212748 -323.625374) (xy 275.187695 -323.642265) (xy 275.177758 -323.653658)
			(xy 275.160718 -323.673838) (xy 275.121766 -323.709504) (xy 275.077973 -323.739025) (xy 275.0303 -323.761754)
			(xy 274.979792 -323.777192) (xy 274.927559 -323.785) (xy 274.901152 -323.785484) (xy 274.874503 -323.785031)
			(xy 274.821802 -323.777081) (xy 274.770874 -323.761366) (xy 274.722856 -323.738236) (xy 274.678822 -323.708209)
			(xy 274.639755 -323.671954) (xy 274.606527 -323.630283) (xy 274.57988 -323.584124) (xy 274.56041 -323.53451)
			(xy 274.548551 -323.482549) (xy 274.544568 -323.4294) (xy 271.905008 -323.4294) (xy 271.901024 -323.482554)
			(xy 271.889162 -323.534521) (xy 271.869687 -323.584139) (xy 271.843033 -323.6303) (xy 271.809797 -323.671972)
			(xy 271.77072 -323.708224) (xy 271.726676 -323.738248) (xy 271.678649 -323.76137) (xy 271.627713 -323.777076)
			(xy 271.575004 -323.785014) (xy 271.548352 -323.785484) (xy 271.521944 -323.784977) (xy 271.469707 -323.777182)
			(xy 271.419194 -323.761757) (xy 271.371514 -323.739038) (xy 271.327713 -323.709526) (xy 271.288752 -323.673867)
			(xy 271.271746 -323.653658) (xy 271.261809 -323.642265) (xy 271.236756 -323.625374) (xy 271.20786 -323.616543)
			(xy 271.177644 -323.616543) (xy 271.148748 -323.625374) (xy 271.123695 -323.642265) (xy 271.113758 -323.653658)
			(xy 271.096718 -323.673838) (xy 271.057766 -323.709504) (xy 271.013973 -323.739025) (xy 270.9663 -323.761754)
			(xy 270.915792 -323.777192) (xy 270.863559 -323.785) (xy 270.837152 -323.785484) (xy 270.810503 -323.785031)
			(xy 270.757802 -323.777081) (xy 270.706874 -323.761366) (xy 270.658856 -323.738236) (xy 270.614822 -323.708209)
			(xy 270.575755 -323.671954) (xy 270.542527 -323.630283) (xy 270.51588 -323.584124) (xy 270.49641 -323.53451)
			(xy 270.484551 -323.482549) (xy 270.480568 -323.4294) (xy 268.425208 -323.4294) (xy 268.421224 -323.482554)
			(xy 268.409362 -323.534521) (xy 268.389887 -323.584139) (xy 268.363233 -323.6303) (xy 268.329997 -323.671972)
			(xy 268.29092 -323.708224) (xy 268.246876 -323.738248) (xy 268.198849 -323.76137) (xy 268.147913 -323.777076)
			(xy 268.095204 -323.785014) (xy 268.068552 -323.785484) (xy 268.042144 -323.784977) (xy 267.989907 -323.777182)
			(xy 267.939394 -323.761757) (xy 267.891714 -323.739038) (xy 267.847913 -323.709526) (xy 267.808952 -323.673867)
			(xy 267.791946 -323.653658) (xy 267.782009 -323.642265) (xy 267.756956 -323.625374) (xy 267.72806 -323.616543)
			(xy 267.697844 -323.616543) (xy 267.668948 -323.625374) (xy 267.643895 -323.642265) (xy 267.633958 -323.653658)
			(xy 267.616918 -323.673838) (xy 267.577966 -323.709504) (xy 267.534173 -323.739025) (xy 267.4865 -323.761754)
			(xy 267.435992 -323.777192) (xy 267.383759 -323.785) (xy 267.357352 -323.785484) (xy 267.330703 -323.785031)
			(xy 267.278002 -323.777081) (xy 267.227074 -323.761366) (xy 267.179056 -323.738236) (xy 267.135022 -323.708209)
			(xy 267.095955 -323.671954) (xy 267.062727 -323.630283) (xy 267.03608 -323.584124) (xy 267.01661 -323.53451)
			(xy 267.004751 -323.482549) (xy 267.000768 -323.4294) (xy 264.361208 -323.4294) (xy 264.357224 -323.482554)
			(xy 264.345362 -323.534521) (xy 264.325887 -323.584139) (xy 264.299233 -323.6303) (xy 264.265997 -323.671972)
			(xy 264.22692 -323.708224) (xy 264.182876 -323.738248) (xy 264.134849 -323.76137) (xy 264.083913 -323.777076)
			(xy 264.031204 -323.785014) (xy 264.004552 -323.785484) (xy 263.978144 -323.784977) (xy 263.925907 -323.777182)
			(xy 263.875394 -323.761757) (xy 263.827714 -323.739038) (xy 263.783913 -323.709526) (xy 263.744952 -323.673867)
			(xy 263.727946 -323.653658) (xy 263.718009 -323.642265) (xy 263.692956 -323.625374) (xy 263.66406 -323.616543)
			(xy 263.633844 -323.616543) (xy 263.604948 -323.625374) (xy 263.579895 -323.642265) (xy 263.569958 -323.653658)
			(xy 263.552918 -323.673838) (xy 263.513966 -323.709504) (xy 263.470173 -323.739025) (xy 263.4225 -323.761754)
			(xy 263.371992 -323.777192) (xy 263.319759 -323.785) (xy 263.293352 -323.785484) (xy 263.266703 -323.785031)
			(xy 263.214002 -323.777081) (xy 263.163074 -323.761366) (xy 263.115056 -323.738236) (xy 263.071022 -323.708209)
			(xy 263.031955 -323.671954) (xy 262.998727 -323.630283) (xy 262.97208 -323.584124) (xy 262.95261 -323.53451)
			(xy 262.940751 -323.482549) (xy 262.936768 -323.4294) (xy 260.881408 -323.4294) (xy 260.877424 -323.482554)
			(xy 260.865562 -323.534521) (xy 260.846087 -323.584139) (xy 260.819433 -323.6303) (xy 260.786197 -323.671972)
			(xy 260.74712 -323.708224) (xy 260.703076 -323.738248) (xy 260.655049 -323.76137) (xy 260.604113 -323.777076)
			(xy 260.551404 -323.785014) (xy 260.524752 -323.785484) (xy 260.498344 -323.784977) (xy 260.446107 -323.777182)
			(xy 260.395594 -323.761757) (xy 260.347914 -323.739038) (xy 260.304113 -323.709526) (xy 260.265152 -323.673867)
			(xy 260.248146 -323.653658) (xy 260.238209 -323.642265) (xy 260.213156 -323.625374) (xy 260.18426 -323.616543)
			(xy 260.154044 -323.616543) (xy 260.125148 -323.625374) (xy 260.100095 -323.642265) (xy 260.090158 -323.653658)
			(xy 260.073118 -323.673838) (xy 260.034166 -323.709504) (xy 259.990373 -323.739025) (xy 259.9427 -323.761754)
			(xy 259.892192 -323.777192) (xy 259.839959 -323.785) (xy 259.813552 -323.785484) (xy 259.786903 -323.785031)
			(xy 259.734202 -323.777081) (xy 259.683274 -323.761366) (xy 259.635256 -323.738236) (xy 259.591222 -323.708209)
			(xy 259.552155 -323.671954) (xy 259.518927 -323.630283) (xy 259.49228 -323.584124) (xy 259.47281 -323.53451)
			(xy 259.460951 -323.482549) (xy 259.456968 -323.4294) (xy 258.702016 -323.4294) (xy 258.698894 -323.471061)
			(xy 258.687031 -323.523034) (xy 258.667555 -323.572658) (xy 258.6409 -323.618826) (xy 258.607662 -323.660505)
			(xy 258.568582 -323.696764) (xy 258.524536 -323.726794) (xy 258.476505 -323.749924) (xy 258.425563 -323.765636)
			(xy 258.372849 -323.773581) (xy 258.346194 -323.774054) (xy 258.321168 -323.773659) (xy 258.271608 -323.766649)
			(xy 258.223519 -323.752768) (xy 258.177847 -323.732289) (xy 258.135493 -323.705616) (xy 258.097292 -323.673275)
			(xy 258.063996 -323.635902) (xy 258.049776 -323.615304) (xy 258.041443 -323.603675) (xy 258.019607 -323.585208)
			(xy 257.99351 -323.573516) (xy 257.965194 -323.569515) (xy 257.936878 -323.573516) (xy 257.910781 -323.585208)
			(xy 257.888945 -323.603675) (xy 257.880612 -323.615304) (xy 257.866407 -323.635912) (xy 257.833104 -323.673276)
			(xy 257.794898 -323.705609) (xy 257.752541 -323.732274) (xy 257.706868 -323.752747) (xy 257.658778 -323.766623)
			(xy 257.60922 -323.77363) (xy 257.584194 -323.774054) (xy 257.557548 -323.773464) (xy 257.504853 -323.76552)
			(xy 257.453929 -323.749812) (xy 257.405916 -323.726689) (xy 257.361885 -323.696668) (xy 257.32282 -323.660421)
			(xy 257.289594 -323.618756) (xy 257.262949 -323.572604) (xy 257.24348 -323.522997) (xy 257.231621 -323.471042)
			(xy 257.227639 -323.4179) (xy 214.230832 -323.4179) (xy 214.220445 -323.463409) (xy 214.200973 -323.513022)
			(xy 214.174323 -323.559178) (xy 214.141092 -323.600847) (xy 214.102022 -323.637097) (xy 214.057985 -323.66712)
			(xy 214.009965 -323.690243) (xy 213.959035 -323.705951) (xy 213.906333 -323.713892) (xy 213.879684 -323.714364)
			(xy 213.853274 -323.713912) (xy 213.801034 -323.706107) (xy 213.750519 -323.690671) (xy 213.702839 -323.667943)
			(xy 213.65904 -323.63842) (xy 213.620082 -323.602752) (xy 213.603078 -323.582538) (xy 213.593141 -323.571145)
			(xy 213.568088 -323.554254) (xy 213.539192 -323.545423) (xy 213.508976 -323.545423) (xy 213.48008 -323.554254)
			(xy 213.455027 -323.571145) (xy 213.44509 -323.582538) (xy 213.428106 -323.602768) (xy 213.38914 -323.638426)
			(xy 213.345335 -323.667939) (xy 213.297651 -323.690659) (xy 213.247135 -323.706087) (xy 213.194894 -323.713886)
			(xy 213.168484 -323.714364) (xy 213.141832 -323.713953) (xy 213.089124 -323.706006) (xy 213.038189 -323.690293)
			(xy 212.990165 -323.667164) (xy 212.946124 -323.637136) (xy 212.907051 -323.600879) (xy 212.873817 -323.559204)
			(xy 212.847166 -323.513041) (xy 212.827693 -323.463422) (xy 212.815832 -323.411455) (xy 212.811848 -323.3583)
			(xy 212.347443 -323.3583) (xy 212.352705 -323.381352) (xy 212.356688 -323.4345) (xy 212.352705 -323.487648)
			(xy 212.340845 -323.539609) (xy 212.321373 -323.589222) (xy 212.294723 -323.635378) (xy 212.261492 -323.677047)
			(xy 212.222422 -323.713297) (xy 212.178385 -323.74332) (xy 212.130365 -323.766443) (xy 212.079435 -323.782151)
			(xy 212.026733 -323.790092) (xy 212.000084 -323.790564) (xy 211.973674 -323.790112) (xy 211.921434 -323.782307)
			(xy 211.870919 -323.766871) (xy 211.823239 -323.744143) (xy 211.77944 -323.71462) (xy 211.740482 -323.678952)
			(xy 211.723478 -323.658738) (xy 211.713541 -323.647345) (xy 211.688488 -323.630454) (xy 211.659592 -323.621623)
			(xy 211.629376 -323.621623) (xy 211.60048 -323.630454) (xy 211.575427 -323.647345) (xy 211.56549 -323.658738)
			(xy 211.548506 -323.678968) (xy 211.50954 -323.714626) (xy 211.465735 -323.744139) (xy 211.418051 -323.766859)
			(xy 211.367535 -323.782287) (xy 211.315294 -323.790086) (xy 211.288884 -323.790564) (xy 211.262232 -323.790153)
			(xy 211.209524 -323.782206) (xy 211.158589 -323.766493) (xy 211.110565 -323.743364) (xy 211.066524 -323.713336)
			(xy 211.027451 -323.677079) (xy 210.994217 -323.635404) (xy 210.967566 -323.589241) (xy 210.948093 -323.539622)
			(xy 210.936232 -323.487655) (xy 210.932248 -323.4345) (xy 208.876888 -323.4345) (xy 208.872905 -323.487648)
			(xy 208.861045 -323.539609) (xy 208.841573 -323.589222) (xy 208.814923 -323.635378) (xy 208.781692 -323.677047)
			(xy 208.742622 -323.713297) (xy 208.698585 -323.74332) (xy 208.650565 -323.766443) (xy 208.599635 -323.782151)
			(xy 208.546933 -323.790092) (xy 208.520284 -323.790564) (xy 208.493874 -323.790112) (xy 208.441634 -323.782307)
			(xy 208.391119 -323.766871) (xy 208.343439 -323.744143) (xy 208.29964 -323.71462) (xy 208.260682 -323.678952)
			(xy 208.243678 -323.658738) (xy 208.233741 -323.647345) (xy 208.208688 -323.630454) (xy 208.179792 -323.621623)
			(xy 208.149576 -323.621623) (xy 208.12068 -323.630454) (xy 208.095627 -323.647345) (xy 208.08569 -323.658738)
			(xy 208.068706 -323.678968) (xy 208.02974 -323.714626) (xy 207.985935 -323.744139) (xy 207.938251 -323.766859)
			(xy 207.887735 -323.782287) (xy 207.835494 -323.790086) (xy 207.809084 -323.790564) (xy 207.782432 -323.790153)
			(xy 207.729724 -323.782206) (xy 207.678789 -323.766493) (xy 207.630765 -323.743364) (xy 207.586724 -323.713336)
			(xy 207.547651 -323.677079) (xy 207.514417 -323.635404) (xy 207.487766 -323.589241) (xy 207.468293 -323.539622)
			(xy 207.456432 -323.487655) (xy 207.452448 -323.4345) (xy 204.812888 -323.4345) (xy 204.808905 -323.487648)
			(xy 204.797045 -323.539609) (xy 204.777573 -323.589222) (xy 204.750923 -323.635378) (xy 204.717692 -323.677047)
			(xy 204.678622 -323.713297) (xy 204.634585 -323.74332) (xy 204.586565 -323.766443) (xy 204.535635 -323.782151)
			(xy 204.482933 -323.790092) (xy 204.456284 -323.790564) (xy 204.429874 -323.790112) (xy 204.377634 -323.782307)
			(xy 204.327119 -323.766871) (xy 204.279439 -323.744143) (xy 204.23564 -323.71462) (xy 204.196682 -323.678952)
			(xy 204.179678 -323.658738) (xy 204.169741 -323.647345) (xy 204.144688 -323.630454) (xy 204.115792 -323.621623)
			(xy 204.085576 -323.621623) (xy 204.05668 -323.630454) (xy 204.031627 -323.647345) (xy 204.02169 -323.658738)
			(xy 204.004706 -323.678968) (xy 203.96574 -323.714626) (xy 203.921935 -323.744139) (xy 203.874251 -323.766859)
			(xy 203.823735 -323.782287) (xy 203.771494 -323.790086) (xy 203.745084 -323.790564) (xy 203.718432 -323.790153)
			(xy 203.665724 -323.782206) (xy 203.614789 -323.766493) (xy 203.566765 -323.743364) (xy 203.522724 -323.713336)
			(xy 203.483651 -323.677079) (xy 203.450417 -323.635404) (xy 203.423766 -323.589241) (xy 203.404293 -323.539622)
			(xy 203.392432 -323.487655) (xy 203.388448 -323.4345) (xy 201.333088 -323.4345) (xy 201.329105 -323.487648)
			(xy 201.317245 -323.539609) (xy 201.297773 -323.589222) (xy 201.271123 -323.635378) (xy 201.237892 -323.677047)
			(xy 201.198822 -323.713297) (xy 201.154785 -323.74332) (xy 201.106765 -323.766443) (xy 201.055835 -323.782151)
			(xy 201.003133 -323.790092) (xy 200.976484 -323.790564) (xy 200.950074 -323.790112) (xy 200.897834 -323.782307)
			(xy 200.847319 -323.766871) (xy 200.799639 -323.744143) (xy 200.75584 -323.71462) (xy 200.716882 -323.678952)
			(xy 200.699878 -323.658738) (xy 200.689941 -323.647345) (xy 200.664888 -323.630454) (xy 200.635992 -323.621623)
			(xy 200.605776 -323.621623) (xy 200.57688 -323.630454) (xy 200.551827 -323.647345) (xy 200.54189 -323.658738)
			(xy 200.524906 -323.678968) (xy 200.48594 -323.714626) (xy 200.442135 -323.744139) (xy 200.394451 -323.766859)
			(xy 200.343935 -323.782287) (xy 200.291694 -323.790086) (xy 200.265284 -323.790564) (xy 200.238632 -323.790153)
			(xy 200.185924 -323.782206) (xy 200.134989 -323.766493) (xy 200.086965 -323.743364) (xy 200.042924 -323.713336)
			(xy 200.003851 -323.677079) (xy 199.970617 -323.635404) (xy 199.943966 -323.589241) (xy 199.924493 -323.539622)
			(xy 199.912632 -323.487655) (xy 199.908648 -323.4345) (xy 197.269088 -323.4345) (xy 197.265105 -323.487648)
			(xy 197.253245 -323.539609) (xy 197.233773 -323.589222) (xy 197.207123 -323.635378) (xy 197.173892 -323.677047)
			(xy 197.134822 -323.713297) (xy 197.090785 -323.74332) (xy 197.042765 -323.766443) (xy 196.991835 -323.782151)
			(xy 196.939133 -323.790092) (xy 196.912484 -323.790564) (xy 196.886074 -323.790112) (xy 196.833834 -323.782307)
			(xy 196.783319 -323.766871) (xy 196.735639 -323.744143) (xy 196.69184 -323.71462) (xy 196.652882 -323.678952)
			(xy 196.635878 -323.658738) (xy 196.625941 -323.647345) (xy 196.600888 -323.630454) (xy 196.571992 -323.621623)
			(xy 196.541776 -323.621623) (xy 196.51288 -323.630454) (xy 196.487827 -323.647345) (xy 196.47789 -323.658738)
			(xy 196.460906 -323.678968) (xy 196.42194 -323.714626) (xy 196.378135 -323.744139) (xy 196.330451 -323.766859)
			(xy 196.279935 -323.782287) (xy 196.227694 -323.790086) (xy 196.201284 -323.790564) (xy 196.174632 -323.790153)
			(xy 196.121924 -323.782206) (xy 196.070989 -323.766493) (xy 196.022965 -323.743364) (xy 195.978924 -323.713336)
			(xy 195.939851 -323.677079) (xy 195.906617 -323.635404) (xy 195.879966 -323.589241) (xy 195.860493 -323.539622)
			(xy 195.848632 -323.487655) (xy 195.844648 -323.4345) (xy 193.789288 -323.4345) (xy 193.785305 -323.487648)
			(xy 193.773445 -323.539609) (xy 193.753973 -323.589222) (xy 193.727323 -323.635378) (xy 193.694092 -323.677047)
			(xy 193.655022 -323.713297) (xy 193.610985 -323.74332) (xy 193.562965 -323.766443) (xy 193.512035 -323.782151)
			(xy 193.459333 -323.790092) (xy 193.432684 -323.790564) (xy 193.406274 -323.790112) (xy 193.354034 -323.782307)
			(xy 193.303519 -323.766871) (xy 193.255839 -323.744143) (xy 193.21204 -323.71462) (xy 193.173082 -323.678952)
			(xy 193.156078 -323.658738) (xy 193.146141 -323.647345) (xy 193.121088 -323.630454) (xy 193.092192 -323.621623)
			(xy 193.061976 -323.621623) (xy 193.03308 -323.630454) (xy 193.008027 -323.647345) (xy 192.99809 -323.658738)
			(xy 192.981106 -323.678968) (xy 192.94214 -323.714626) (xy 192.898335 -323.744139) (xy 192.850651 -323.766859)
			(xy 192.800135 -323.782287) (xy 192.747894 -323.790086) (xy 192.721484 -323.790564) (xy 192.694832 -323.790153)
			(xy 192.642124 -323.782206) (xy 192.591189 -323.766493) (xy 192.543165 -323.743364) (xy 192.499124 -323.713336)
			(xy 192.460051 -323.677079) (xy 192.426817 -323.635404) (xy 192.400166 -323.589241) (xy 192.380693 -323.539622)
			(xy 192.368832 -323.487655) (xy 192.364848 -323.4345) (xy 189.725288 -323.4345) (xy 189.721305 -323.487648)
			(xy 189.709445 -323.539609) (xy 189.689973 -323.589222) (xy 189.663323 -323.635378) (xy 189.630092 -323.677047)
			(xy 189.591022 -323.713297) (xy 189.546985 -323.74332) (xy 189.498965 -323.766443) (xy 189.448035 -323.782151)
			(xy 189.395333 -323.790092) (xy 189.368684 -323.790564) (xy 189.342274 -323.790112) (xy 189.290034 -323.782307)
			(xy 189.239519 -323.766871) (xy 189.191839 -323.744143) (xy 189.14804 -323.71462) (xy 189.109082 -323.678952)
			(xy 189.092078 -323.658738) (xy 189.082141 -323.647345) (xy 189.057088 -323.630454) (xy 189.028192 -323.621623)
			(xy 188.997976 -323.621623) (xy 188.96908 -323.630454) (xy 188.944027 -323.647345) (xy 188.93409 -323.658738)
			(xy 188.917106 -323.678968) (xy 188.87814 -323.714626) (xy 188.834335 -323.744139) (xy 188.786651 -323.766859)
			(xy 188.736135 -323.782287) (xy 188.683894 -323.790086) (xy 188.657484 -323.790564) (xy 188.630832 -323.790153)
			(xy 188.578124 -323.782206) (xy 188.527189 -323.766493) (xy 188.479165 -323.743364) (xy 188.435124 -323.713336)
			(xy 188.396051 -323.677079) (xy 188.362817 -323.635404) (xy 188.336166 -323.589241) (xy 188.316693 -323.539622)
			(xy 188.304832 -323.487655) (xy 188.300848 -323.4345) (xy 186.123184 -323.4345) (xy 186.125088 -323.4599)
			(xy 186.121105 -323.513048) (xy 186.109245 -323.565008) (xy 186.089773 -323.614621) (xy 186.063124 -323.660777)
			(xy 186.029894 -323.702446) (xy 185.990824 -323.738696) (xy 185.946787 -323.768718) (xy 185.898768 -323.791842)
			(xy 185.847838 -323.80755) (xy 185.795136 -323.815492) (xy 185.768488 -323.815964) (xy 185.741928 -323.815472)
			(xy 185.689398 -323.807568) (xy 185.638624 -323.791952) (xy 185.590732 -323.76897) (xy 185.546783 -323.739132)
			(xy 185.526934 -323.721476) (xy 185.516102 -323.712144) (xy 185.490547 -323.699353) (xy 185.462448 -323.69415)
			(xy 185.434007 -323.696942) (xy 185.407456 -323.707511) (xy 185.39587 -323.715888) (xy 185.372292 -323.733415)
			(xy 185.320587 -323.761302) (xy 185.265006 -323.780324) (xy 185.207057 -323.789964) (xy 185.177684 -323.790564)
			(xy 185.151032 -323.790153) (xy 185.098324 -323.782206) (xy 185.047389 -323.766493) (xy 184.999365 -323.743364)
			(xy 184.955324 -323.713336) (xy 184.916251 -323.677079) (xy 184.883017 -323.635404) (xy 184.856366 -323.589241)
			(xy 184.836893 -323.539622) (xy 184.825032 -323.487655) (xy 184.821048 -323.4345) (xy 182.181488 -323.4345)
			(xy 182.177505 -323.487648) (xy 182.165645 -323.539609) (xy 182.146173 -323.589222) (xy 182.119523 -323.635378)
			(xy 182.086292 -323.677047) (xy 182.047222 -323.713297) (xy 182.003185 -323.74332) (xy 181.955165 -323.766443)
			(xy 181.904235 -323.782151) (xy 181.851533 -323.790092) (xy 181.824884 -323.790564) (xy 181.798474 -323.790112)
			(xy 181.746234 -323.782307) (xy 181.695719 -323.766871) (xy 181.648039 -323.744143) (xy 181.60424 -323.71462)
			(xy 181.565282 -323.678952) (xy 181.548278 -323.658738) (xy 181.538341 -323.647345) (xy 181.513288 -323.630454)
			(xy 181.484392 -323.621623) (xy 181.454176 -323.621623) (xy 181.42528 -323.630454) (xy 181.400227 -323.647345)
			(xy 181.39029 -323.658738) (xy 181.373306 -323.678968) (xy 181.33434 -323.714626) (xy 181.290535 -323.744139)
			(xy 181.242851 -323.766859) (xy 181.192335 -323.782287) (xy 181.140094 -323.790086) (xy 181.113684 -323.790564)
			(xy 181.087032 -323.790153) (xy 181.034324 -323.782206) (xy 180.983389 -323.766493) (xy 180.935365 -323.743364)
			(xy 180.891324 -323.713336) (xy 180.852251 -323.677079) (xy 180.819017 -323.635404) (xy 180.792366 -323.589241)
			(xy 180.772893 -323.539622) (xy 180.761032 -323.487655) (xy 180.757048 -323.4345) (xy 178.701688 -323.4345)
			(xy 178.697705 -323.487648) (xy 178.685845 -323.539609) (xy 178.666373 -323.589222) (xy 178.639723 -323.635378)
			(xy 178.606492 -323.677047) (xy 178.567422 -323.713297) (xy 178.523385 -323.74332) (xy 178.475365 -323.766443)
			(xy 178.424435 -323.782151) (xy 178.371733 -323.790092) (xy 178.345084 -323.790564) (xy 178.318674 -323.790112)
			(xy 178.266434 -323.782307) (xy 178.215919 -323.766871) (xy 178.168239 -323.744143) (xy 178.12444 -323.71462)
			(xy 178.085482 -323.678952) (xy 178.068478 -323.658738) (xy 178.058541 -323.647345) (xy 178.033488 -323.630454)
			(xy 178.004592 -323.621623) (xy 177.974376 -323.621623) (xy 177.94548 -323.630454) (xy 177.920427 -323.647345)
			(xy 177.91049 -323.658738) (xy 177.893506 -323.678968) (xy 177.85454 -323.714626) (xy 177.810735 -323.744139)
			(xy 177.763051 -323.766859) (xy 177.712535 -323.782287) (xy 177.660294 -323.790086) (xy 177.633884 -323.790564)
			(xy 177.607232 -323.790153) (xy 177.554524 -323.782206) (xy 177.503589 -323.766493) (xy 177.455565 -323.743364)
			(xy 177.411524 -323.713336) (xy 177.372451 -323.677079) (xy 177.339217 -323.635404) (xy 177.312566 -323.589241)
			(xy 177.293093 -323.539622) (xy 177.281232 -323.487655) (xy 177.277248 -323.4345) (xy 174.637688 -323.4345)
			(xy 174.633705 -323.487648) (xy 174.621845 -323.539609) (xy 174.602373 -323.589222) (xy 174.575723 -323.635378)
			(xy 174.542492 -323.677047) (xy 174.503422 -323.713297) (xy 174.459385 -323.74332) (xy 174.411365 -323.766443)
			(xy 174.360435 -323.782151) (xy 174.307733 -323.790092) (xy 174.281084 -323.790564) (xy 174.254674 -323.790112)
			(xy 174.202434 -323.782307) (xy 174.151919 -323.766871) (xy 174.104239 -323.744143) (xy 174.06044 -323.71462)
			(xy 174.021482 -323.678952) (xy 174.004478 -323.658738) (xy 173.994541 -323.647345) (xy 173.969488 -323.630454)
			(xy 173.940592 -323.621623) (xy 173.910376 -323.621623) (xy 173.88148 -323.630454) (xy 173.856427 -323.647345)
			(xy 173.84649 -323.658738) (xy 173.829506 -323.678968) (xy 173.79054 -323.714626) (xy 173.746735 -323.744139)
			(xy 173.699051 -323.766859) (xy 173.648535 -323.782287) (xy 173.596294 -323.790086) (xy 173.569884 -323.790564)
			(xy 173.543232 -323.790153) (xy 173.490524 -323.782206) (xy 173.439589 -323.766493) (xy 173.391565 -323.743364)
			(xy 173.347524 -323.713336) (xy 173.308451 -323.677079) (xy 173.275217 -323.635404) (xy 173.248566 -323.589241)
			(xy 173.229093 -323.539622) (xy 173.217232 -323.487655) (xy 173.213248 -323.4345) (xy 171.157888 -323.4345)
			(xy 171.153905 -323.487648) (xy 171.142045 -323.539609) (xy 171.122573 -323.589222) (xy 171.095923 -323.635378)
			(xy 171.062692 -323.677047) (xy 171.023622 -323.713297) (xy 170.979585 -323.74332) (xy 170.931565 -323.766443)
			(xy 170.880635 -323.782151) (xy 170.827933 -323.790092) (xy 170.801284 -323.790564) (xy 170.774874 -323.790112)
			(xy 170.722634 -323.782307) (xy 170.672119 -323.766871) (xy 170.624439 -323.744143) (xy 170.58064 -323.71462)
			(xy 170.541682 -323.678952) (xy 170.524678 -323.658738) (xy 170.514741 -323.647345) (xy 170.489688 -323.630454)
			(xy 170.460792 -323.621623) (xy 170.430576 -323.621623) (xy 170.40168 -323.630454) (xy 170.376627 -323.647345)
			(xy 170.36669 -323.658738) (xy 170.349706 -323.678968) (xy 170.31074 -323.714626) (xy 170.266935 -323.744139)
			(xy 170.219251 -323.766859) (xy 170.168735 -323.782287) (xy 170.116494 -323.790086) (xy 170.090084 -323.790564)
			(xy 170.063432 -323.790153) (xy 170.010724 -323.782206) (xy 169.959789 -323.766493) (xy 169.911765 -323.743364)
			(xy 169.867724 -323.713336) (xy 169.828651 -323.677079) (xy 169.795417 -323.635404) (xy 169.768766 -323.589241)
			(xy 169.749293 -323.539622) (xy 169.737432 -323.487655) (xy 169.733448 -323.4345) (xy 167.093976 -323.4345)
			(xy 167.089992 -323.487661) (xy 167.078129 -323.539635) (xy 167.058652 -323.58926) (xy 167.031996 -323.635428)
			(xy 166.998757 -323.677107) (xy 166.959677 -323.713366) (xy 166.915629 -323.743396) (xy 166.867597 -323.766525)
			(xy 166.816654 -323.782236) (xy 166.763939 -323.79018) (xy 166.737284 -323.790564) (xy 166.710875 -323.790083)
			(xy 166.658637 -323.782281) (xy 166.608124 -323.766849) (xy 166.560444 -323.744127) (xy 166.516642 -323.714612)
			(xy 166.477679 -323.678952) (xy 166.460678 -323.658738) (xy 166.450741 -323.647345) (xy 166.425688 -323.630454)
			(xy 166.396792 -323.621623) (xy 166.366576 -323.621623) (xy 166.33768 -323.630454) (xy 166.312627 -323.647345)
			(xy 166.30269 -323.658738) (xy 166.278306 -323.685916) (xy 166.242492 -323.721984) (xy 166.853108 -324.3326)
			(xy 216.190576 -324.3326) (xy 217.070178 -325.212202) (xy 217.070178 -326.151748) (xy 252.683772 -326.151748)
			(xy 252.684249 -326.125668) (xy 252.691361 -326.073994) (xy 252.705445 -326.02377) (xy 252.72624 -325.975933)
			(xy 252.753356 -325.931374) (xy 252.786289 -325.890924) (xy 252.824425 -325.855337) (xy 252.867053 -325.825277)
			(xy 252.89002 -325.812912) (xy 252.902193 -325.806125) (xy 252.922589 -325.787146) (xy 252.937095 -325.763359)
			(xy 252.944629 -325.736537) (xy 252.944631 -325.708677) (xy 252.9371 -325.681853) (xy 252.922598 -325.658065)
			(xy 252.902205 -325.639083) (xy 252.89002 -325.632318) (xy 252.867045 -325.619962) (xy 252.824403 -325.589911)
			(xy 252.786254 -325.554329) (xy 252.75331 -325.51388) (xy 252.726186 -325.469319) (xy 252.705388 -325.421476)
			(xy 252.691304 -325.371246) (xy 252.684197 -325.319566) (xy 252.683772 -325.293482) (xy 252.684242 -325.266543)
			(xy 252.691825 -325.2132) (xy 252.706837 -325.161455) (xy 252.728979 -325.112336) (xy 252.757812 -325.066821)
			(xy 252.792762 -325.025815) (xy 252.833133 -324.990135) (xy 252.878122 -324.960489) (xy 252.926835 -324.937467)
			(xy 252.978303 -324.921528) (xy 253.004828 -324.9168) (xy 253.019172 -324.914065) (xy 253.045489 -324.901424)
			(xy 253.067161 -324.881862) (xy 253.082423 -324.856974) (xy 253.090032 -324.828788) (xy 253.090172 -324.814184)
			(xy 253.090172 -324.805548) (xy 253.090658 -324.778297) (xy 253.098414 -324.724349) (xy 253.113769 -324.672054)
			(xy 253.136411 -324.622477) (xy 253.165877 -324.576627) (xy 253.201568 -324.535436) (xy 253.242759 -324.499745)
			(xy 253.288609 -324.470279) (xy 253.338186 -324.447637) (xy 253.390481 -324.432282) (xy 253.444429 -324.424526)
			(xy 253.498931 -324.424526) (xy 253.552879 -324.432282) (xy 253.605174 -324.447637) (xy 253.654751 -324.470279)
			(xy 253.700601 -324.499745) (xy 253.741792 -324.535436) (xy 253.777483 -324.576627) (xy 253.806949 -324.622477)
			(xy 253.829591 -324.672054) (xy 253.844946 -324.724349) (xy 253.852702 -324.778297) (xy 253.853188 -324.805548)
			(xy 253.852779 -324.83249) (xy 253.845191 -324.885836) (xy 253.830174 -324.937585) (xy 253.808025 -324.986706)
			(xy 253.779185 -325.032222) (xy 253.744228 -325.073228) (xy 253.70385 -325.108908) (xy 253.658853 -325.138552)
			(xy 253.610134 -325.16157) (xy 253.55866 -325.177505) (xy 253.532132 -325.18223) (xy 253.517814 -325.185073)
			(xy 253.491504 -325.197689) (xy 253.469832 -325.217224) (xy 253.454561 -325.242086) (xy 253.446938 -325.27025)
			(xy 253.446788 -325.284846) (xy 253.446788 -325.293482) (xy 253.446357 -325.319564) (xy 253.43924 -325.371241)
			(xy 253.42515 -325.421467) (xy 253.40435 -325.469305) (xy 253.377227 -325.513864) (xy 253.344287 -325.554313)
			(xy 253.306145 -325.589898) (xy 253.26351 -325.619955) (xy 253.24054 -325.632318) (xy 253.228408 -325.63913)
			(xy 253.208103 -325.658138) (xy 253.193671 -325.681915) (xy 253.186179 -325.7087) (xy 253.186181 -325.736514)
			(xy 253.193677 -325.763298) (xy 253.208112 -325.787072) (xy 253.228419 -325.806078) (xy 253.24054 -325.812912)
			(xy 253.263518 -325.825263) (xy 253.306163 -325.855313) (xy 253.344313 -325.890894) (xy 253.377258 -325.931344)
			(xy 253.404382 -325.975906) (xy 253.425179 -326.02375) (xy 253.439261 -326.073982) (xy 253.446365 -326.125664)
			(xy 253.446788 -326.151748) (xy 253.446213 -326.180936) (xy 253.437322 -326.238631) (xy 253.419752 -326.2943)
			(xy 253.393915 -326.346647) (xy 253.360411 -326.394451) (xy 253.340616 -326.415908) (xy 253.330627 -326.427116)
			(xy 253.317071 -326.453888) (xy 253.311888 -326.483444) (xy 253.315526 -326.51323) (xy 253.327671 -326.54067)
			(xy 253.347271 -326.563392) (xy 253.359666 -326.571864) (xy 253.382599 -326.586924) (xy 253.424253 -326.622632)
			(xy 253.460362 -326.663939) (xy 253.490184 -326.709991) (xy 253.513102 -326.75984) (xy 253.528644 -326.812457)
			(xy 253.536489 -326.866758) (xy 253.536958 -326.89419) (xy 253.536472 -326.921441) (xy 253.528716 -326.975389)
			(xy 253.513361 -327.027684) (xy 253.490719 -327.077261) (xy 253.470334 -327.10898) (xy 256.593721 -327.10898)
			(xy 256.593721 -327.02442) (xy 256.601524 -326.94022) (xy 256.617062 -326.857099) (xy 256.640204 -326.775767)
			(xy 256.670752 -326.696917) (xy 256.708445 -326.621222) (xy 256.752962 -326.549328) (xy 256.803923 -326.481848)
			(xy 256.860892 -326.419358) (xy 256.923385 -326.362392) (xy 256.990867 -326.311435) (xy 257.062764 -326.266922)
			(xy 257.138461 -326.229233) (xy 257.217312 -326.198689) (xy 257.298646 -326.175551) (xy 257.381767 -326.160017)
			(xy 257.465968 -326.152219) (xy 257.508248 -326.151748) (xy 258.752848 -326.151748) (xy 258.795121 -326.152326)
			(xy 258.879305 -326.160131) (xy 258.96241 -326.17567) (xy 259.043727 -326.198811) (xy 259.122562 -326.229355)
			(xy 259.198243 -326.267043) (xy 259.270123 -326.311553) (xy 259.337591 -326.362505) (xy 259.400069 -326.419465)
			(xy 259.457025 -326.481946) (xy 259.507974 -326.549416) (xy 259.55248 -326.621299) (xy 259.590164 -326.696982)
			(xy 259.620704 -326.775818) (xy 259.643841 -326.857136) (xy 259.659375 -326.940242) (xy 259.667176 -327.024427)
			(xy 259.667176 -327.108973) (xy 259.667175 -327.10898) (xy 264.137521 -327.10898) (xy 264.137521 -327.02442)
			(xy 264.145324 -326.94022) (xy 264.160862 -326.857099) (xy 264.184004 -326.775767) (xy 264.214552 -326.696917)
			(xy 264.252245 -326.621222) (xy 264.296762 -326.549328) (xy 264.347723 -326.481848) (xy 264.404692 -326.419358)
			(xy 264.467185 -326.362392) (xy 264.534667 -326.311435) (xy 264.606564 -326.266922) (xy 264.682261 -326.229233)
			(xy 264.761112 -326.198689) (xy 264.842446 -326.175551) (xy 264.925567 -326.160017) (xy 265.009768 -326.152219)
			(xy 265.052048 -326.151748) (xy 266.296648 -326.151748) (xy 266.339187 -326.152283) (xy 266.423898 -326.160196)
			(xy 266.507507 -326.175941) (xy 266.589294 -326.199381) (xy 266.668551 -326.230313) (xy 266.744593 -326.268471)
			(xy 266.816764 -326.313524) (xy 266.88444 -326.365084) (xy 266.947036 -326.422705) (xy 267.004011 -326.485889)
			(xy 267.054874 -326.55409) (xy 267.077444 -326.590152) (xy 267.08524 -326.602055) (xy 267.106189 -326.621294)
			(xy 267.131629 -326.634017) (xy 267.159588 -326.63924) (xy 267.187905 -326.636558) (xy 267.214387 -326.626179)
			(xy 267.236985 -326.608906) (xy 267.245846 -326.597772) (xy 267.263956 -326.574319) (xy 267.30622 -326.532792)
			(xy 267.3544 -326.498303) (xy 267.407335 -326.471683) (xy 267.463751 -326.453572) (xy 267.52229 -326.444408)
			(xy 267.551916 -326.443848) (xy 267.579163 -326.444423) (xy 267.633103 -326.452181) (xy 267.68539 -326.467535)
			(xy 267.734959 -326.490175) (xy 267.780802 -326.519638) (xy 267.821986 -326.555326) (xy 267.857671 -326.596511)
			(xy 267.887133 -326.642355) (xy 267.90977 -326.691925) (xy 267.925123 -326.744213) (xy 267.932878 -326.798153)
			(xy 267.932878 -326.825356) (xy 268.439898 -326.825356) (xy 268.443969 -326.769734) (xy 268.456095 -326.715297)
			(xy 268.476018 -326.663206) (xy 268.503314 -326.614571) (xy 268.5374 -326.570428) (xy 268.577549 -326.531719)
			(xy 268.622907 -326.499268) (xy 268.672507 -326.473767) (xy 268.725291 -326.45576) (xy 268.780134 -326.44563)
			(xy 268.835868 -326.443593) (xy 268.891305 -326.449693) (xy 268.945262 -326.463799) (xy 268.996591 -326.485611)
			(xy 269.044197 -326.514665) (xy 269.087065 -326.55034) (xy 269.124282 -326.591877) (xy 269.155055 -326.63839)
			(xy 269.178727 -326.688887) (xy 269.194795 -326.742294) (xy 269.202915 -326.79747) (xy 269.203424 -326.825356)
			(xy 269.709898 -326.825356) (xy 269.713969 -326.769734) (xy 269.726095 -326.715297) (xy 269.746018 -326.663206)
			(xy 269.773314 -326.614571) (xy 269.8074 -326.570428) (xy 269.847549 -326.531719) (xy 269.892907 -326.499268)
			(xy 269.942507 -326.473767) (xy 269.995291 -326.45576) (xy 270.050134 -326.44563) (xy 270.105868 -326.443593)
			(xy 270.161305 -326.449693) (xy 270.215262 -326.463799) (xy 270.266591 -326.485611) (xy 270.314197 -326.514665)
			(xy 270.357065 -326.55034) (xy 270.394282 -326.591877) (xy 270.425055 -326.63839) (xy 270.448727 -326.688887)
			(xy 270.464795 -326.742294) (xy 270.472915 -326.79747) (xy 270.473424 -326.825356) (xy 270.472915 -326.853242)
			(xy 270.464795 -326.908418) (xy 270.448727 -326.961825) (xy 270.425055 -327.012322) (xy 270.394282 -327.058835)
			(xy 270.357065 -327.100372) (xy 270.346721 -327.10898) (xy 271.681321 -327.10898) (xy 271.681321 -327.02442)
			(xy 271.689124 -326.94022) (xy 271.704662 -326.857099) (xy 271.727804 -326.775767) (xy 271.758352 -326.696917)
			(xy 271.796045 -326.621222) (xy 271.840562 -326.549328) (xy 271.891523 -326.481848) (xy 271.948492 -326.419358)
			(xy 272.010985 -326.362392) (xy 272.078467 -326.311435) (xy 272.150364 -326.266922) (xy 272.226061 -326.229233)
			(xy 272.304912 -326.198689) (xy 272.386246 -326.175551) (xy 272.469367 -326.160017) (xy 272.553568 -326.152219)
			(xy 272.595848 -326.151748) (xy 273.840448 -326.151748) (xy 273.882721 -326.152326) (xy 273.966905 -326.160131)
			(xy 274.05001 -326.17567) (xy 274.131327 -326.198811) (xy 274.210162 -326.229355) (xy 274.285843 -326.267043)
			(xy 274.357723 -326.311553) (xy 274.425191 -326.362505) (xy 274.487669 -326.419465) (xy 274.544625 -326.481946)
			(xy 274.595574 -326.549416) (xy 274.64008 -326.621299) (xy 274.677764 -326.696982) (xy 274.708304 -326.775818)
			(xy 274.731441 -326.857136) (xy 274.746975 -326.940242) (xy 274.754776 -327.024427) (xy 274.754776 -327.108973)
			(xy 274.747399 -327.188585) (xy 274.881346 -327.188585) (xy 274.885077 -327.135333) (xy 274.896195 -327.08312)
			(xy 274.914482 -327.032967) (xy 274.939581 -326.985852) (xy 274.971002 -326.942696) (xy 275.008131 -326.904341)
			(xy 275.028914 -326.887586) (xy 275.040741 -326.877713) (xy 275.058253 -326.852382) (xy 275.067424 -326.822983)
			(xy 275.067419 -326.792187) (xy 275.05824 -326.762792) (xy 275.04072 -326.737465) (xy 275.028914 -326.727566)
			(xy 275.006417 -326.709391) (xy 274.966682 -326.667368) (xy 274.933744 -326.61983) (xy 274.908358 -326.567866)
			(xy 274.891105 -326.512665) (xy 274.88238 -326.455493) (xy 274.881848 -326.426576) (xy 274.882334 -326.399325)
			(xy 274.89009 -326.345377) (xy 274.905445 -326.293082) (xy 274.928087 -326.243505) (xy 274.957553 -326.197655)
			(xy 274.993244 -326.156464) (xy 275.034435 -326.120773) (xy 275.080285 -326.091307) (xy 275.129862 -326.068665)
			(xy 275.182157 -326.05331) (xy 275.236105 -326.045554) (xy 275.290607 -326.045554) (xy 275.344555 -326.05331)
			(xy 275.39685 -326.068665) (xy 275.446427 -326.091307) (xy 275.492277 -326.120773) (xy 275.533468 -326.156464)
			(xy 275.569159 -326.197655) (xy 275.598625 -326.243505) (xy 275.621267 -326.293082) (xy 275.636622 -326.345377)
			(xy 275.644378 -326.399325) (xy 275.644864 -326.426576) (xy 276.405338 -326.426576) (xy 276.409409 -326.370954)
			(xy 276.421535 -326.316517) (xy 276.441458 -326.264426) (xy 276.468754 -326.215791) (xy 276.50284 -326.171648)
			(xy 276.542989 -326.132939) (xy 276.588347 -326.100488) (xy 276.637947 -326.074987) (xy 276.690731 -326.05698)
			(xy 276.745574 -326.04685) (xy 276.801308 -326.044813) (xy 276.856745 -326.050913) (xy 276.910702 -326.065019)
			(xy 276.962031 -326.086831) (xy 277.009637 -326.115885) (xy 277.052505 -326.15156) (xy 277.089722 -326.193097)
			(xy 277.120495 -326.23961) (xy 277.144167 -326.290107) (xy 277.160235 -326.343514) (xy 277.168355 -326.39869)
			(xy 277.168864 -326.426576) (xy 277.168355 -326.454462) (xy 277.160235 -326.509638) (xy 277.144167 -326.563045)
			(xy 277.120495 -326.613542) (xy 277.089722 -326.660055) (xy 277.052505 -326.701592) (xy 277.009637 -326.737267)
			(xy 276.962031 -326.766321) (xy 276.910702 -326.788133) (xy 276.856745 -326.802239) (xy 276.801308 -326.808339)
			(xy 276.745574 -326.806302) (xy 276.690731 -326.796172) (xy 276.637947 -326.778165) (xy 276.588347 -326.752664)
			(xy 276.542989 -326.720213) (xy 276.50284 -326.681504) (xy 276.468754 -326.637361) (xy 276.441458 -326.588726)
			(xy 276.421535 -326.536635) (xy 276.409409 -326.482198) (xy 276.405338 -326.426576) (xy 275.644864 -326.426576)
			(xy 275.644342 -326.455493) (xy 275.635616 -326.512665) (xy 275.618359 -326.567864) (xy 275.592969 -326.619826)
			(xy 275.560025 -326.66736) (xy 275.520284 -326.709376) (xy 275.497798 -326.727566) (xy 275.486018 -326.737491)
			(xy 275.468503 -326.762807) (xy 275.459326 -326.792193) (xy 275.459322 -326.822978) (xy 275.46849 -326.852366)
			(xy 275.485998 -326.877688) (xy 275.497798 -326.887586) (xy 275.518559 -326.904367) (xy 275.555693 -326.942715)
			(xy 275.587118 -326.985865) (xy 275.612221 -327.032976) (xy 275.63051 -327.083125) (xy 275.636017 -327.10898)
			(xy 279.225121 -327.10898) (xy 279.225121 -327.02442) (xy 279.232924 -326.94022) (xy 279.248462 -326.857099)
			(xy 279.271604 -326.775767) (xy 279.302152 -326.696917) (xy 279.339845 -326.621222) (xy 279.384362 -326.549328)
			(xy 279.435323 -326.481848) (xy 279.492292 -326.419358) (xy 279.554785 -326.362392) (xy 279.622267 -326.311435)
			(xy 279.694164 -326.266922) (xy 279.769861 -326.229233) (xy 279.848712 -326.198689) (xy 279.930046 -326.175551)
			(xy 280.013167 -326.160017) (xy 280.097368 -326.152219) (xy 280.139648 -326.151748) (xy 281.384248 -326.151748)
			(xy 281.426521 -326.152326) (xy 281.510705 -326.160131) (xy 281.59381 -326.17567) (xy 281.675127 -326.198811)
			(xy 281.753962 -326.229355) (xy 281.829643 -326.267043) (xy 281.901523 -326.311553) (xy 281.968991 -326.362505)
			(xy 282.031469 -326.419465) (xy 282.088425 -326.481946) (xy 282.139374 -326.549416) (xy 282.18388 -326.621299)
			(xy 282.221564 -326.696982) (xy 282.252104 -326.775818) (xy 282.275241 -326.857136) (xy 282.290775 -326.940242)
			(xy 282.298576 -327.024427) (xy 282.298576 -327.108973) (xy 282.298575 -327.10898) (xy 286.768921 -327.10898)
			(xy 286.768921 -327.02442) (xy 286.776724 -326.94022) (xy 286.792262 -326.857099) (xy 286.815404 -326.775767)
			(xy 286.845952 -326.696917) (xy 286.883645 -326.621222) (xy 286.928162 -326.549328) (xy 286.979123 -326.481848)
			(xy 287.036092 -326.419358) (xy 287.098585 -326.362392) (xy 287.166067 -326.311435) (xy 287.237964 -326.266922)
			(xy 287.313661 -326.229233) (xy 287.392512 -326.198689) (xy 287.473846 -326.175551) (xy 287.556967 -326.160017)
			(xy 287.641168 -326.152219) (xy 287.683448 -326.151748) (xy 288.928048 -326.151748) (xy 288.97123 -326.152272)
			(xy 289.057209 -326.160424) (xy 289.142038 -326.17664) (xy 289.224961 -326.200778) (xy 289.30524 -326.232622)
			(xy 289.382162 -326.271888) (xy 289.455042 -326.318228) (xy 289.523232 -326.371229) (xy 289.586123 -326.430419)
			(xy 289.643158 -326.495272) (xy 289.693829 -326.56521) (xy 289.737683 -326.639612) (xy 289.774333 -326.717814)
			(xy 289.789362 -326.7583) (xy 289.794953 -326.772118) (xy 289.8127 -326.796044) (xy 289.836588 -326.813842)
			(xy 289.864592 -326.824002) (xy 289.894336 -326.825661) (xy 289.923296 -326.818679) (xy 289.949016 -326.803649)
			(xy 289.959542 -326.793098) (xy 289.977631 -326.774176) (xy 290.018147 -326.741026) (xy 290.06281 -326.71372)
			(xy 290.110784 -326.692769) (xy 290.161169 -326.678565) (xy 290.213022 -326.671375) (xy 290.239196 -326.670924)
			(xy 290.266451 -326.671323) (xy 290.320407 -326.67908) (xy 290.37271 -326.694437) (xy 290.422295 -326.717081)
			(xy 290.468152 -326.746551) (xy 290.509349 -326.782248) (xy 290.545046 -326.823444) (xy 290.574517 -326.869302)
			(xy 290.597162 -326.918886) (xy 290.612519 -326.971189) (xy 290.620277 -327.025145) (xy 290.620277 -327.079655)
			(xy 290.616061 -327.10898) (xy 294.312721 -327.10898) (xy 294.312721 -327.02442) (xy 294.320524 -326.94022)
			(xy 294.336062 -326.857099) (xy 294.359204 -326.775767) (xy 294.389752 -326.696917) (xy 294.427445 -326.621222)
			(xy 294.471962 -326.549328) (xy 294.522923 -326.481848) (xy 294.579892 -326.419358) (xy 294.642385 -326.362392)
			(xy 294.709867 -326.311435) (xy 294.781764 -326.266922) (xy 294.857461 -326.229233) (xy 294.936312 -326.198689)
			(xy 295.017646 -326.175551) (xy 295.100767 -326.160017) (xy 295.184968 -326.152219) (xy 295.227248 -326.151748)
			(xy 296.471848 -326.151748) (xy 296.515156 -326.152233) (xy 296.601381 -326.160443) (xy 296.686445 -326.176765)
			(xy 296.769585 -326.201055) (xy 296.850057 -326.233093) (xy 296.927141 -326.272593) (xy 297.000146 -326.319203)
			(xy 297.06842 -326.372503) (xy 297.13135 -326.432018) (xy 297.188373 -326.497215) (xy 297.23898 -326.567508)
			(xy 297.282716 -326.642271) (xy 297.301412 -326.681338) (xy 297.308035 -326.694256) (xy 297.327147 -326.716079)
			(xy 297.351628 -326.731645) (xy 297.379498 -326.739695) (xy 297.408508 -326.739579) (xy 297.436313 -326.731307)
			(xy 297.460668 -326.715547) (xy 297.479607 -326.693571) (xy 297.48607 -326.680576) (xy 297.497789 -326.655904)
			(xy 297.527238 -326.609904) (xy 297.562945 -326.568572) (xy 297.60418 -326.532754) (xy 297.650101 -326.503181)
			(xy 297.699769 -326.480457) (xy 297.75217 -326.465047) (xy 297.806232 -326.457266) (xy 297.833542 -326.456802)
			(xy 297.862457 -326.457361) (xy 297.919627 -326.466082) (xy 297.974825 -326.483331) (xy 298.026787 -326.508715)
			(xy 298.074322 -326.541652) (xy 298.116341 -326.581386) (xy 298.134532 -326.603868) (xy 298.144429 -326.615673)
			(xy 298.169753 -326.633192) (xy 298.199146 -326.642368) (xy 298.229938 -326.642368) (xy 298.259331 -326.633192)
			(xy 298.284655 -326.615673) (xy 298.294552 -326.603868) (xy 298.312762 -326.581401) (xy 298.354779 -326.541666)
			(xy 298.40231 -326.508726) (xy 298.454267 -326.483335) (xy 298.509461 -326.466075) (xy 298.566627 -326.45734)
			(xy 298.595542 -326.456802) (xy 298.622792 -326.457271) (xy 298.676737 -326.465032) (xy 298.729028 -326.480391)
			(xy 298.778601 -326.503036) (xy 298.824447 -326.532504) (xy 298.865634 -326.568196) (xy 298.901321 -326.609386)
			(xy 298.930785 -326.655236) (xy 298.953423 -326.704812) (xy 298.968777 -326.757104) (xy 298.976532 -326.81105)
			(xy 298.976532 -326.86555) (xy 298.968777 -326.919496) (xy 298.953423 -326.971788) (xy 298.930785 -327.021364)
			(xy 298.901321 -327.067214) (xy 298.865634 -327.108404) (xy 298.824447 -327.144096) (xy 298.778601 -327.173564)
			(xy 298.729028 -327.196209) (xy 298.676737 -327.211568) (xy 298.622792 -327.219329) (xy 298.595542 -327.219818)
			(xy 298.566625 -327.2193) (xy 298.509452 -327.210575) (xy 298.454252 -327.193319) (xy 298.40229 -327.167928)
			(xy 298.354756 -327.134982) (xy 298.312741 -327.095239) (xy 298.294552 -327.072752) (xy 298.284655 -327.060947)
			(xy 298.259331 -327.043428) (xy 298.229938 -327.034252) (xy 298.199146 -327.034252) (xy 298.169753 -327.043428)
			(xy 298.144429 -327.060947) (xy 298.134532 -327.072752) (xy 298.116336 -327.095231) (xy 298.074316 -327.134964)
			(xy 298.026781 -327.167902) (xy 297.974821 -327.193291) (xy 297.919625 -327.210549) (xy 297.862457 -327.219281)
			(xy 297.833542 -327.219818) (xy 297.80771 -327.219382) (xy 297.756519 -327.21241) (xy 297.706739 -327.198589)
			(xy 297.659281 -327.17817) (xy 297.615016 -327.15153) (xy 297.574754 -327.119155) (xy 297.556682 -327.100692)
			(xy 297.546293 -327.090562) (xy 297.521243 -327.075956) (xy 297.493095 -327.068987) (xy 297.464124 -327.070219)
			(xy 297.43667 -327.079552) (xy 297.41295 -327.096232) (xy 297.394881 -327.118911) (xy 297.383922 -327.145758)
			(xy 297.38193 -327.160128) (xy 297.377219 -327.201858) (xy 297.36102 -327.284266) (xy 297.337337 -327.364843)
			(xy 297.306368 -327.44291) (xy 297.268373 -327.51781) (xy 297.223674 -327.588912) (xy 297.172646 -327.655618)
			(xy 297.115719 -327.717367) (xy 297.053372 -327.773637) (xy 296.98613 -327.823957) (xy 296.914559 -327.867901)
			(xy 296.839261 -327.905101) (xy 296.760871 -327.935242) (xy 296.680048 -327.958072) (xy 296.597473 -327.973398)
			(xy 296.513841 -327.981091) (xy 296.471848 -327.981564) (xy 295.227248 -327.981564) (xy 295.184968 -327.981181)
			(xy 295.100767 -327.973383) (xy 295.017646 -327.957849) (xy 294.936312 -327.934711) (xy 294.857461 -327.904167)
			(xy 294.781764 -327.866478) (xy 294.709867 -327.821965) (xy 294.642385 -327.771008) (xy 294.579892 -327.714042)
			(xy 294.522923 -327.651552) (xy 294.471962 -327.584072) (xy 294.427445 -327.512178) (xy 294.389752 -327.436483)
			(xy 294.359204 -327.357633) (xy 294.336062 -327.276301) (xy 294.320524 -327.19318) (xy 294.312721 -327.10898)
			(xy 290.616061 -327.10898) (xy 290.612519 -327.133611) (xy 290.597162 -327.185914) (xy 290.574517 -327.235498)
			(xy 290.545046 -327.281356) (xy 290.509349 -327.322552) (xy 290.468152 -327.358249) (xy 290.422295 -327.387719)
			(xy 290.37271 -327.410363) (xy 290.320407 -327.42572) (xy 290.266451 -327.433477) (xy 290.239196 -327.43394)
			(xy 290.213706 -327.433525) (xy 290.16318 -327.426746) (xy 290.114007 -327.413295) (xy 290.067065 -327.393412)
			(xy 290.023191 -327.367453) (xy 289.983166 -327.335879) (xy 289.96513 -327.317862) (xy 289.954395 -327.307508)
			(xy 289.92836 -327.292987) (xy 289.899243 -327.286593) (xy 289.869519 -327.288867) (xy 289.841714 -327.299618)
			(xy 289.818191 -327.317932) (xy 289.80095 -327.342251) (xy 289.795712 -327.356216) (xy 289.781336 -327.397747)
			(xy 289.74567 -327.478078) (xy 289.702461 -327.554616) (xy 289.65211 -327.626656) (xy 289.595079 -327.693534)
			(xy 289.531895 -327.754631) (xy 289.463142 -327.809385) (xy 289.389452 -327.857291) (xy 289.311507 -327.897906)
			(xy 289.230025 -327.930856) (xy 289.145757 -327.955837) (xy 289.059482 -327.972618) (xy 288.971994 -327.981045)
			(xy 288.928048 -327.981564) (xy 287.683448 -327.981564) (xy 287.641168 -327.981181) (xy 287.556967 -327.973383)
			(xy 287.473846 -327.957849) (xy 287.392512 -327.934711) (xy 287.313661 -327.904167) (xy 287.237964 -327.866478)
			(xy 287.166067 -327.821965) (xy 287.098585 -327.771008) (xy 287.036092 -327.714042) (xy 286.979123 -327.651552)
			(xy 286.928162 -327.584072) (xy 286.883645 -327.512178) (xy 286.845952 -327.436483) (xy 286.815404 -327.357633)
			(xy 286.792262 -327.276301) (xy 286.776724 -327.19318) (xy 286.768921 -327.10898) (xy 282.298575 -327.10898)
			(xy 282.290775 -327.193158) (xy 282.275241 -327.276264) (xy 282.252104 -327.357582) (xy 282.221564 -327.436418)
			(xy 282.18388 -327.512101) (xy 282.139374 -327.583984) (xy 282.088425 -327.651454) (xy 282.031469 -327.713935)
			(xy 281.968991 -327.770895) (xy 281.901524 -327.821847) (xy 281.829643 -327.866357) (xy 281.753962 -327.904045)
			(xy 281.675127 -327.934589) (xy 281.59381 -327.95773) (xy 281.510705 -327.973269) (xy 281.426521 -327.981074)
			(xy 281.384248 -327.981564) (xy 280.139648 -327.981564) (xy 280.097368 -327.981181) (xy 280.013167 -327.973383)
			(xy 279.930046 -327.957849) (xy 279.848712 -327.934711) (xy 279.769861 -327.904167) (xy 279.694164 -327.866478)
			(xy 279.622267 -327.821965) (xy 279.554785 -327.771008) (xy 279.492292 -327.714042) (xy 279.435323 -327.651552)
			(xy 279.384362 -327.584072) (xy 279.339845 -327.512178) (xy 279.302152 -327.436483) (xy 279.271604 -327.357633)
			(xy 279.248462 -327.276301) (xy 279.232924 -327.19318) (xy 279.225121 -327.10898) (xy 275.636017 -327.10898)
			(xy 275.64163 -327.135335) (xy 275.645362 -327.188585) (xy 275.641634 -327.241836) (xy 275.630518 -327.294046)
			(xy 275.612233 -327.344198) (xy 275.587134 -327.39131) (xy 275.555712 -327.434463) (xy 275.518581 -327.472814)
			(xy 275.497798 -327.489566) (xy 275.486018 -327.499491) (xy 275.468503 -327.524807) (xy 275.459326 -327.554193)
			(xy 275.459322 -327.584978) (xy 275.46849 -327.614366) (xy 275.485998 -327.639688) (xy 275.497798 -327.649586)
			(xy 275.520274 -327.667785) (xy 275.56001 -327.709803) (xy 275.59295 -327.757337) (xy 275.61834 -327.809296)
			(xy 275.635597 -327.864492) (xy 275.644328 -327.92166) (xy 275.644864 -327.950576) (xy 275.644378 -327.977827)
			(xy 275.636622 -328.031775) (xy 275.621267 -328.08407) (xy 275.598625 -328.133647) (xy 275.569159 -328.179497)
			(xy 275.533468 -328.220688) (xy 275.492277 -328.256379) (xy 275.446427 -328.285845) (xy 275.39685 -328.308487)
			(xy 275.344555 -328.323842) (xy 275.290607 -328.331598) (xy 275.236105 -328.331598) (xy 275.182157 -328.323842)
			(xy 275.129862 -328.308487) (xy 275.080285 -328.285845) (xy 275.034435 -328.256379) (xy 274.993244 -328.220688)
			(xy 274.957553 -328.179497) (xy 274.928087 -328.133647) (xy 274.905445 -328.08407) (xy 274.89009 -328.031775)
			(xy 274.882334 -327.977827) (xy 274.881848 -327.950576) (xy 274.882403 -327.92166) (xy 274.891122 -327.86449)
			(xy 274.908371 -327.809291) (xy 274.933756 -327.757329) (xy 274.966694 -327.709794) (xy 275.006431 -327.667777)
			(xy 275.028914 -327.649586) (xy 275.040741 -327.639713) (xy 275.058253 -327.614382) (xy 275.067424 -327.584983)
			(xy 275.067419 -327.554187) (xy 275.05824 -327.524792) (xy 275.04072 -327.499465) (xy 275.028914 -327.489566)
			(xy 275.008109 -327.47284) (xy 274.970983 -327.434481) (xy 274.939565 -327.391322) (xy 274.91447 -327.344206)
			(xy 274.896187 -327.294051) (xy 274.885073 -327.241838) (xy 274.881346 -327.188585) (xy 274.747399 -327.188585)
			(xy 274.746975 -327.193158) (xy 274.731441 -327.276264) (xy 274.708304 -327.357582) (xy 274.677764 -327.436418)
			(xy 274.64008 -327.512101) (xy 274.595574 -327.583984) (xy 274.544625 -327.651454) (xy 274.487669 -327.713935)
			(xy 274.425191 -327.770895) (xy 274.357724 -327.821847) (xy 274.285843 -327.866357) (xy 274.210162 -327.904045)
			(xy 274.131327 -327.934589) (xy 274.05001 -327.95773) (xy 273.966905 -327.973269) (xy 273.882721 -327.981074)
			(xy 273.840448 -327.981564) (xy 272.595848 -327.981564) (xy 272.553568 -327.981181) (xy 272.469367 -327.973383)
			(xy 272.386246 -327.957849) (xy 272.304912 -327.934711) (xy 272.226061 -327.904167) (xy 272.150364 -327.866478)
			(xy 272.078467 -327.821965) (xy 272.010985 -327.771008) (xy 271.948492 -327.714042) (xy 271.891523 -327.651552)
			(xy 271.840562 -327.584072) (xy 271.796045 -327.512178) (xy 271.758352 -327.436483) (xy 271.727804 -327.357633)
			(xy 271.704662 -327.276301) (xy 271.689124 -327.19318) (xy 271.681321 -327.10898) (xy 270.346721 -327.10898)
			(xy 270.314197 -327.136047) (xy 270.266591 -327.165101) (xy 270.215262 -327.186913) (xy 270.161305 -327.201019)
			(xy 270.105868 -327.207119) (xy 270.050134 -327.205082) (xy 269.995291 -327.194952) (xy 269.942507 -327.176945)
			(xy 269.892907 -327.151444) (xy 269.847549 -327.118993) (xy 269.8074 -327.080284) (xy 269.773314 -327.036141)
			(xy 269.746018 -326.987506) (xy 269.726095 -326.935415) (xy 269.713969 -326.880978) (xy 269.709898 -326.825356)
			(xy 269.203424 -326.825356) (xy 269.202915 -326.853242) (xy 269.194795 -326.908418) (xy 269.178727 -326.961825)
			(xy 269.155055 -327.012322) (xy 269.124282 -327.058835) (xy 269.087065 -327.100372) (xy 269.044197 -327.136047)
			(xy 268.996591 -327.165101) (xy 268.945262 -327.186913) (xy 268.891305 -327.201019) (xy 268.835868 -327.207119)
			(xy 268.780134 -327.205082) (xy 268.725291 -327.194952) (xy 268.672507 -327.176945) (xy 268.622907 -327.151444)
			(xy 268.577549 -327.118993) (xy 268.5374 -327.080284) (xy 268.503314 -327.036141) (xy 268.476018 -326.987506)
			(xy 268.456095 -326.935415) (xy 268.443969 -326.880978) (xy 268.439898 -326.825356) (xy 267.932878 -326.825356)
			(xy 267.932878 -326.852647) (xy 267.925123 -326.906587) (xy 267.90977 -326.958875) (xy 267.887133 -327.008445)
			(xy 267.857671 -327.054289) (xy 267.821986 -327.095474) (xy 267.780802 -327.131162) (xy 267.734959 -327.160625)
			(xy 267.68539 -327.183265) (xy 267.633103 -327.198619) (xy 267.579163 -327.206377) (xy 267.551916 -327.206864)
			(xy 267.525603 -327.206406) (xy 267.473481 -327.199137) (xy 267.422849 -327.184788) (xy 267.374662 -327.163631)
			(xy 267.352018 -327.150222) (xy 267.339667 -327.143194) (xy 267.312294 -327.135599) (xy 267.283889 -327.135825)
			(xy 267.256641 -327.143856) (xy 267.232652 -327.159071) (xy 267.213774 -327.180298) (xy 267.201461 -327.205898)
			(xy 267.198602 -327.219818) (xy 267.191007 -327.261924) (xy 267.168871 -327.344578) (xy 267.139113 -327.424804)
			(xy 267.101994 -327.501901) (xy 267.057838 -327.575194) (xy 267.007031 -327.644045) (xy 266.950018 -327.70785)
			(xy 266.887295 -327.766053) (xy 266.819412 -327.818145) (xy 266.746961 -327.863671) (xy 266.670576 -327.902232)
			(xy 266.590924 -327.933493) (xy 266.508701 -327.957179) (xy 266.424625 -327.973084) (xy 266.339431 -327.98107)
			(xy 266.296648 -327.981564) (xy 265.606022 -327.981564) (xy 265.592061 -327.982086) (xy 265.565182 -327.989646)
			(xy 265.541357 -328.004208) (xy 265.52237 -328.024681) (xy 265.509642 -328.049533) (xy 265.504124 -328.076904)
			(xy 265.50623 -328.104747) (xy 265.515801 -328.130977) (xy 265.532123 -328.153632) (xy 265.542776 -328.162666)
			(xy 265.564874 -328.18085) (xy 265.603875 -328.22273) (xy 265.636182 -328.269967) (xy 265.66107 -328.321499)
			(xy 265.677981 -328.376171) (xy 265.686534 -328.432756) (xy 265.687048 -328.46137) (xy 266.193522 -328.46137)
			(xy 266.197593 -328.405748) (xy 266.209719 -328.351311) (xy 266.229642 -328.29922) (xy 266.256938 -328.250585)
			(xy 266.291024 -328.206442) (xy 266.331173 -328.167733) (xy 266.376531 -328.135282) (xy 266.426131 -328.109781)
			(xy 266.478915 -328.091774) (xy 266.533758 -328.081644) (xy 266.589492 -328.079607) (xy 266.644929 -328.085707)
			(xy 266.681837 -328.095356) (xy 267.169898 -328.095356) (xy 267.173969 -328.039734) (xy 267.186095 -327.985297)
			(xy 267.206018 -327.933206) (xy 267.233314 -327.884571) (xy 267.2674 -327.840428) (xy 267.307549 -327.801719)
			(xy 267.352907 -327.769268) (xy 267.402507 -327.743767) (xy 267.455291 -327.72576) (xy 267.510134 -327.71563)
			(xy 267.565868 -327.713593) (xy 267.621305 -327.719693) (xy 267.675262 -327.733799) (xy 267.726591 -327.755611)
			(xy 267.774197 -327.784665) (xy 267.817065 -327.82034) (xy 267.854282 -327.861877) (xy 267.885055 -327.90839)
			(xy 267.908727 -327.958887) (xy 267.924795 -328.012294) (xy 267.932915 -328.06747) (xy 267.933424 -328.095356)
			(xy 268.439898 -328.095356) (xy 268.443969 -328.039734) (xy 268.456095 -327.985297) (xy 268.476018 -327.933206)
			(xy 268.503314 -327.884571) (xy 268.5374 -327.840428) (xy 268.577549 -327.801719) (xy 268.622907 -327.769268)
			(xy 268.672507 -327.743767) (xy 268.725291 -327.72576) (xy 268.780134 -327.71563) (xy 268.835868 -327.713593)
			(xy 268.891305 -327.719693) (xy 268.945262 -327.733799) (xy 268.996591 -327.755611) (xy 269.044197 -327.784665)
			(xy 269.087065 -327.82034) (xy 269.124282 -327.861877) (xy 269.155055 -327.90839) (xy 269.178727 -327.958887)
			(xy 269.194795 -328.012294) (xy 269.202915 -328.06747) (xy 269.203424 -328.095356) (xy 269.709898 -328.095356)
			(xy 269.713969 -328.039734) (xy 269.726095 -327.985297) (xy 269.746018 -327.933206) (xy 269.773314 -327.884571)
			(xy 269.8074 -327.840428) (xy 269.847549 -327.801719) (xy 269.892907 -327.769268) (xy 269.942507 -327.743767)
			(xy 269.995291 -327.72576) (xy 270.050134 -327.71563) (xy 270.105868 -327.713593) (xy 270.161305 -327.719693)
			(xy 270.215262 -327.733799) (xy 270.266591 -327.755611) (xy 270.314197 -327.784665) (xy 270.357065 -327.82034)
			(xy 270.394282 -327.861877) (xy 270.425055 -327.90839) (xy 270.448727 -327.958887) (xy 270.464795 -328.012294)
			(xy 270.472915 -328.06747) (xy 270.473424 -328.095356) (xy 270.472915 -328.123242) (xy 270.464795 -328.178418)
			(xy 270.448727 -328.231825) (xy 270.425055 -328.282322) (xy 270.394282 -328.328835) (xy 270.357065 -328.370372)
			(xy 270.314197 -328.406047) (xy 270.266591 -328.435101) (xy 270.215262 -328.456913) (xy 270.161305 -328.471019)
			(xy 270.105868 -328.477119) (xy 270.050134 -328.475082) (xy 269.995291 -328.464952) (xy 269.942507 -328.446945)
			(xy 269.892907 -328.421444) (xy 269.847549 -328.388993) (xy 269.8074 -328.350284) (xy 269.773314 -328.306141)
			(xy 269.746018 -328.257506) (xy 269.726095 -328.205415) (xy 269.713969 -328.150978) (xy 269.709898 -328.095356)
			(xy 269.203424 -328.095356) (xy 269.202915 -328.123242) (xy 269.194795 -328.178418) (xy 269.178727 -328.231825)
			(xy 269.155055 -328.282322) (xy 269.124282 -328.328835) (xy 269.087065 -328.370372) (xy 269.044197 -328.406047)
			(xy 268.996591 -328.435101) (xy 268.945262 -328.456913) (xy 268.891305 -328.471019) (xy 268.835868 -328.477119)
			(xy 268.780134 -328.475082) (xy 268.725291 -328.464952) (xy 268.672507 -328.446945) (xy 268.622907 -328.421444)
			(xy 268.577549 -328.388993) (xy 268.5374 -328.350284) (xy 268.503314 -328.306141) (xy 268.476018 -328.257506)
			(xy 268.456095 -328.205415) (xy 268.443969 -328.150978) (xy 268.439898 -328.095356) (xy 267.933424 -328.095356)
			(xy 267.932915 -328.123242) (xy 267.924795 -328.178418) (xy 267.908727 -328.231825) (xy 267.885055 -328.282322)
			(xy 267.854282 -328.328835) (xy 267.817065 -328.370372) (xy 267.774197 -328.406047) (xy 267.726591 -328.435101)
			(xy 267.675262 -328.456913) (xy 267.621305 -328.471019) (xy 267.565868 -328.477119) (xy 267.510134 -328.475082)
			(xy 267.455291 -328.464952) (xy 267.402507 -328.446945) (xy 267.352907 -328.421444) (xy 267.307549 -328.388993)
			(xy 267.2674 -328.350284) (xy 267.233314 -328.306141) (xy 267.206018 -328.257506) (xy 267.186095 -328.205415)
			(xy 267.173969 -328.150978) (xy 267.169898 -328.095356) (xy 266.681837 -328.095356) (xy 266.698886 -328.099813)
			(xy 266.750215 -328.121625) (xy 266.797821 -328.150679) (xy 266.840689 -328.186354) (xy 266.877906 -328.227891)
			(xy 266.908679 -328.274404) (xy 266.932351 -328.324901) (xy 266.948419 -328.378308) (xy 266.956539 -328.433484)
			(xy 266.957048 -328.46137) (xy 266.956539 -328.489256) (xy 266.948419 -328.544432) (xy 266.932351 -328.597839)
			(xy 266.908679 -328.648336) (xy 266.877906 -328.694849) (xy 266.840689 -328.736386) (xy 266.797821 -328.772061)
			(xy 266.750215 -328.801115) (xy 266.698886 -328.822927) (xy 266.644929 -328.837033) (xy 266.589492 -328.843133)
			(xy 266.533758 -328.841096) (xy 266.478915 -328.830966) (xy 266.426131 -328.812959) (xy 266.376531 -328.787458)
			(xy 266.331173 -328.755007) (xy 266.291024 -328.716298) (xy 266.256938 -328.672155) (xy 266.229642 -328.62352)
			(xy 266.209719 -328.571429) (xy 266.197593 -328.516992) (xy 266.193522 -328.46137) (xy 265.687048 -328.46137)
			(xy 265.686562 -328.488621) (xy 265.678806 -328.542569) (xy 265.663451 -328.594864) (xy 265.640809 -328.644441)
			(xy 265.611343 -328.690291) (xy 265.575652 -328.731482) (xy 265.534461 -328.767173) (xy 265.488611 -328.796639)
			(xy 265.439034 -328.819281) (xy 265.386739 -328.834636) (xy 265.332791 -328.842392) (xy 265.278289 -328.842392)
			(xy 265.224341 -328.834636) (xy 265.172046 -328.819281) (xy 265.122469 -328.796639) (xy 265.076619 -328.767173)
			(xy 265.035428 -328.731482) (xy 264.999737 -328.690291) (xy 264.970271 -328.644441) (xy 264.947629 -328.594864)
			(xy 264.932274 -328.542569) (xy 264.924518 -328.488621) (xy 264.924032 -328.46137) (xy 264.924564 -328.433701)
			(xy 264.932563 -328.378943) (xy 264.948389 -328.325916) (xy 264.971709 -328.275731) (xy 265.002036 -328.229442)
			(xy 265.038731 -328.188019) (xy 265.081026 -328.152333) (xy 265.128032 -328.123131) (xy 265.178765 -328.101027)
			(xy 265.232158 -328.086484) (xy 265.259566 -328.082656) (xy 265.304016 -328.077322) (xy 265.304016 -327.981564)
			(xy 265.052048 -327.981564) (xy 265.009768 -327.981181) (xy 264.925567 -327.973383) (xy 264.842446 -327.957849)
			(xy 264.761112 -327.934711) (xy 264.682261 -327.904167) (xy 264.606564 -327.866478) (xy 264.534667 -327.821965)
			(xy 264.467185 -327.771008) (xy 264.404692 -327.714042) (xy 264.347723 -327.651552) (xy 264.296762 -327.584072)
			(xy 264.252245 -327.512178) (xy 264.214552 -327.436483) (xy 264.184004 -327.357633) (xy 264.160862 -327.276301)
			(xy 264.145324 -327.19318) (xy 264.137521 -327.10898) (xy 259.667175 -327.10898) (xy 259.659375 -327.193158)
			(xy 259.643841 -327.276264) (xy 259.620704 -327.357582) (xy 259.590164 -327.436418) (xy 259.55248 -327.512101)
			(xy 259.507974 -327.583984) (xy 259.457025 -327.651454) (xy 259.400069 -327.713935) (xy 259.337591 -327.770895)
			(xy 259.270124 -327.821847) (xy 259.198243 -327.866357) (xy 259.122562 -327.904045) (xy 259.043727 -327.934589)
			(xy 258.96241 -327.95773) (xy 258.879305 -327.973269) (xy 258.795121 -327.981074) (xy 258.752848 -327.981564)
			(xy 257.508248 -327.981564) (xy 257.465968 -327.981181) (xy 257.381767 -327.973383) (xy 257.298646 -327.957849)
			(xy 257.217312 -327.934711) (xy 257.138461 -327.904167) (xy 257.062764 -327.866478) (xy 256.990867 -327.821965)
			(xy 256.923385 -327.771008) (xy 256.860892 -327.714042) (xy 256.803923 -327.651552) (xy 256.752962 -327.584072)
			(xy 256.708445 -327.512178) (xy 256.670752 -327.436483) (xy 256.640204 -327.357633) (xy 256.617062 -327.276301)
			(xy 256.601524 -327.19318) (xy 256.593721 -327.10898) (xy 253.470334 -327.10898) (xy 253.461253 -327.123111)
			(xy 253.425562 -327.164302) (xy 253.384371 -327.199993) (xy 253.338521 -327.229459) (xy 253.288944 -327.252101)
			(xy 253.236649 -327.267456) (xy 253.182701 -327.275212) (xy 253.128199 -327.275212) (xy 253.074251 -327.267456)
			(xy 253.021956 -327.252101) (xy 252.972379 -327.229459) (xy 252.926529 -327.199993) (xy 252.885338 -327.164302)
			(xy 252.849647 -327.123111) (xy 252.820181 -327.077261) (xy 252.797539 -327.027684) (xy 252.782184 -326.975389)
			(xy 252.774428 -326.921441) (xy 252.773942 -326.89419) (xy 252.774532 -326.865003) (xy 252.783419 -326.807308)
			(xy 252.800984 -326.751639) (xy 252.826819 -326.699292) (xy 252.86032 -326.651487) (xy 252.880114 -326.63003)
			(xy 252.890054 -326.618782) (xy 252.903608 -326.592023) (xy 252.908795 -326.562479) (xy 252.905166 -326.532703)
			(xy 252.893035 -326.505269) (xy 252.87345 -326.482548) (xy 252.861064 -326.474074) (xy 252.838155 -326.458979)
			(xy 252.7965 -326.423277) (xy 252.760387 -326.381978) (xy 252.730563 -326.335931) (xy 252.707641 -326.286088)
			(xy 252.692094 -326.233476) (xy 252.684244 -326.179179) (xy 252.683772 -326.151748) (xy 217.070178 -326.151748)
			(xy 217.070178 -327.372723) (xy 249.890273 -327.372723) (xy 249.890277 -327.318219) (xy 249.898038 -327.264271)
			(xy 249.913398 -327.211976) (xy 249.936044 -327.162399) (xy 249.965515 -327.116551) (xy 250.001211 -327.075363)
			(xy 250.042405 -327.039674) (xy 250.088259 -327.010211) (xy 250.13784 -326.987574) (xy 250.190137 -326.972224)
			(xy 250.244087 -326.964473) (xy 250.29859 -326.964478) (xy 250.352539 -326.97224) (xy 250.404833 -326.987601)
			(xy 250.454409 -327.010248) (xy 250.500257 -327.03972) (xy 250.541444 -327.075417) (xy 250.577132 -327.116613)
			(xy 250.606593 -327.162467) (xy 250.629229 -327.212048) (xy 250.644578 -327.264346) (xy 250.652328 -327.318296)
			(xy 250.652788 -327.345548) (xy 250.651772 -327.372218) (xy 250.651234 -327.386896) (xy 250.65763 -327.415552)
			(xy 250.671913 -327.441204) (xy 250.692902 -327.461735) (xy 250.718863 -327.475448) (xy 250.747653 -327.481211)
			(xy 250.776893 -327.478547) (xy 250.79071 -327.473564) (xy 250.81322 -327.465027) (xy 250.859844 -327.453023)
			(xy 250.907608 -327.446991) (xy 250.93168 -327.44664) (xy 250.958932 -327.447056) (xy 251.012882 -327.45481)
			(xy 251.06518 -327.470163) (xy 251.11476 -327.492802) (xy 251.160614 -327.522267) (xy 251.201808 -327.557957)
			(xy 251.237504 -327.599146) (xy 251.266974 -327.644996) (xy 251.28962 -327.694574) (xy 251.304979 -327.746869)
			(xy 251.31274 -327.800818) (xy 251.312744 -327.855323) (xy 251.304992 -327.909273) (xy 251.28964 -327.961571)
			(xy 251.267002 -328.011152) (xy 251.237539 -328.057007) (xy 251.20185 -328.098202) (xy 251.160661 -328.133898)
			(xy 251.114812 -328.16337) (xy 251.065235 -328.186017) (xy 251.01294 -328.201377) (xy 250.958991 -328.209139)
			(xy 250.904486 -328.209145) (xy 250.850536 -328.201394) (xy 250.798238 -328.186044) (xy 250.748656 -328.163407)
			(xy 250.702801 -328.133945) (xy 250.661605 -328.098256) (xy 250.625907 -328.057069) (xy 250.596435 -328.01122)
			(xy 250.573787 -327.961644) (xy 250.558425 -327.909349) (xy 250.550661 -327.8554) (xy 250.550172 -327.828148)
			(xy 250.551188 -327.801478) (xy 250.551785 -327.786799) (xy 250.545384 -327.758133) (xy 250.531094 -327.732473)
			(xy 250.510095 -327.711938) (xy 250.484121 -327.698226) (xy 250.45532 -327.692468) (xy 250.42607 -327.695142)
			(xy 250.41225 -327.700132) (xy 250.389744 -327.708681) (xy 250.343118 -327.72068) (xy 250.295353 -327.726707)
			(xy 250.27128 -327.727056) (xy 250.244028 -327.726523) (xy 250.19008 -327.718764) (xy 250.137785 -327.703405)
			(xy 250.088208 -327.680761) (xy 250.042358 -327.651291) (xy 250.001169 -327.615596) (xy 249.96548 -327.574402)
			(xy 249.936016 -327.528549) (xy 249.913378 -327.478969) (xy 249.898026 -327.426672) (xy 249.890273 -327.372723)
			(xy 217.070178 -327.372723) (xy 217.070178 -328.46137) (xy 263.653522 -328.46137) (xy 263.657593 -328.405748)
			(xy 263.669719 -328.351311) (xy 263.689642 -328.29922) (xy 263.716938 -328.250585) (xy 263.751024 -328.206442)
			(xy 263.791173 -328.167733) (xy 263.836531 -328.135282) (xy 263.886131 -328.109781) (xy 263.938915 -328.091774)
			(xy 263.993758 -328.081644) (xy 264.049492 -328.079607) (xy 264.104929 -328.085707) (xy 264.158886 -328.099813)
			(xy 264.210215 -328.121625) (xy 264.257821 -328.150679) (xy 264.300689 -328.186354) (xy 264.337906 -328.227891)
			(xy 264.368679 -328.274404) (xy 264.392351 -328.324901) (xy 264.408419 -328.378308) (xy 264.416539 -328.433484)
			(xy 264.417048 -328.46137) (xy 264.416539 -328.489256) (xy 264.408419 -328.544432) (xy 264.392351 -328.597839)
			(xy 264.368679 -328.648336) (xy 264.337906 -328.694849) (xy 264.300689 -328.736386) (xy 264.257821 -328.772061)
			(xy 264.210215 -328.801115) (xy 264.158886 -328.822927) (xy 264.104929 -328.837033) (xy 264.049492 -328.843133)
			(xy 263.993758 -328.841096) (xy 263.938915 -328.830966) (xy 263.886131 -328.812959) (xy 263.836531 -328.787458)
			(xy 263.791173 -328.755007) (xy 263.751024 -328.716298) (xy 263.716938 -328.672155) (xy 263.689642 -328.62352)
			(xy 263.669719 -328.571429) (xy 263.657593 -328.516992) (xy 263.653522 -328.46137) (xy 217.070178 -328.46137)
			(xy 217.070178 -342.930734) (xy 219.129356 -344.989912) (xy 247.998488 -344.989912) (xy 247.998488 -341.051896)
			(xy 247.998977 -341.013264) (xy 248.006794 -340.936395) (xy 248.022347 -340.860712) (xy 248.045477 -340.786991)
			(xy 248.075947 -340.715988) (xy 248.113444 -340.648432) (xy 248.157583 -340.585016) (xy 248.207911 -340.526391)
			(xy 248.263912 -340.473158) (xy 248.325011 -340.425864) (xy 248.390581 -340.384993) (xy 248.459949 -340.350966)
			(xy 248.532405 -340.324132) (xy 248.607203 -340.304765) (xy 248.683576 -340.293065) (xy 248.760742 -340.289152)
			(xy 248.837908 -340.293065) (xy 248.914281 -340.304765) (xy 248.989079 -340.324132) (xy 249.061535 -340.350966)
			(xy 249.130903 -340.384993) (xy 249.196473 -340.425864) (xy 249.257572 -340.473158) (xy 249.313573 -340.526391)
			(xy 249.363901 -340.585016) (xy 249.40804 -340.648432) (xy 249.445537 -340.715988) (xy 249.476007 -340.786991)
			(xy 249.499137 -340.860712) (xy 249.51469 -340.936395) (xy 249.522507 -341.013264) (xy 249.522996 -341.051896)
			(xy 249.522996 -344.989912) (xy 250.87707 -344.989912) (xy 252.11786 -346.230702) (xy 252.128841 -346.240882)
			(xy 252.155264 -346.254936) (xy 252.184627 -346.260728) (xy 252.214408 -346.257761) (xy 252.242051 -346.246289)
			(xy 252.265182 -346.227298) (xy 252.281816 -346.202417) (xy 252.290524 -346.173784) (xy 252.291088 -346.15882)
			(xy 252.291088 -329.709272) (xy 252.279004 -329.687455) (xy 252.259979 -329.641352) (xy 252.247127 -329.593163)
			(xy 252.240667 -329.543709) (xy 252.240288 -329.518772) (xy 252.240593 -329.497962) (xy 252.245175 -329.456594)
			(xy 252.249432 -329.436222) (xy 252.252147 -329.421858) (xy 252.250178 -329.392704) (xy 252.240043 -329.365297)
			(xy 252.222568 -329.341877) (xy 252.199183 -329.324356) (xy 252.171797 -329.314165) (xy 252.142646 -329.312137)
			(xy 252.128274 -329.31481) (xy 252.107902 -329.31907) (xy 252.066534 -329.323652) (xy 252.045724 -329.323954)
			(xy 252.018467 -329.323493) (xy 251.964507 -329.315738) (xy 251.9122 -329.300382) (xy 251.862611 -329.277738)
			(xy 251.816749 -329.248267) (xy 251.775548 -329.212569) (xy 251.739848 -329.171371) (xy 251.710374 -329.125511)
			(xy 251.687727 -329.075923) (xy 251.672368 -329.023617) (xy 251.664609 -328.969658) (xy 251.664609 -328.915143)
			(xy 251.672367 -328.861184) (xy 251.687726 -328.808878) (xy 251.710373 -328.75929) (xy 251.739847 -328.71343)
			(xy 251.775547 -328.672232) (xy 251.816748 -328.636534) (xy 251.862609 -328.607063) (xy 251.912198 -328.584419)
			(xy 251.964505 -328.569063) (xy 252.018465 -328.561307) (xy 252.07298 -328.561311) (xy 252.126939 -328.569072)
			(xy 252.179244 -328.584435) (xy 252.22883 -328.607084) (xy 252.274689 -328.636561) (xy 252.315885 -328.672264)
			(xy 252.35158 -328.713467) (xy 252.381048 -328.75933) (xy 252.403689 -328.80892) (xy 252.419042 -328.861228)
			(xy 252.426794 -328.915189) (xy 252.427232 -328.942446) (xy 252.426926 -328.963256) (xy 252.422343 -329.004623)
			(xy 252.418088 -329.024996) (xy 252.415375 -329.039357) (xy 252.417348 -329.068505) (xy 252.427485 -329.095904)
			(xy 252.444958 -329.119317) (xy 252.468341 -329.136831) (xy 252.495723 -329.147015) (xy 252.524868 -329.149038)
			(xy 252.539246 -329.146408) (xy 252.559618 -329.142149) (xy 252.600986 -329.13757) (xy 252.621796 -329.137264)
			(xy 252.649048 -329.137749) (xy 252.702998 -329.145505) (xy 252.755295 -329.16086) (xy 252.804874 -329.1835)
			(xy 252.850727 -329.212966) (xy 252.89192 -329.248657) (xy 252.927615 -329.289847) (xy 252.957084 -329.335698)
			(xy 252.979729 -329.385275) (xy 252.995088 -329.437571) (xy 253.002848 -329.49152) (xy 253.003304 -329.518772)
			(xy 253.002914 -329.543709) (xy 252.99645 -329.593161) (xy 252.983602 -329.64135) (xy 252.964589 -329.687456)
			(xy 252.952504 -329.709272) (xy 252.952504 -329.7555) (xy 255.548892 -329.7555) (xy 255.549362 -329.72803)
			(xy 255.557243 -329.673659) (xy 255.572841 -329.620981) (xy 255.595833 -329.571084) (xy 255.625745 -329.525002)
			(xy 255.661957 -329.483686) (xy 255.703722 -329.447992) (xy 255.726692 -329.43292) (xy 255.738753 -329.42467)
			(xy 255.758019 -329.402719) (xy 255.770287 -329.376214) (xy 255.774553 -329.347321) (xy 255.770468 -329.318401)
			(xy 255.758367 -329.29182) (xy 255.739239 -329.269749) (xy 255.7272 -329.26147) (xy 255.704491 -329.246315)
			(xy 255.663182 -329.210622) (xy 255.627381 -329.169405) (xy 255.59782 -329.123508) (xy 255.575102 -329.073865)
			(xy 255.559691 -329.021492) (xy 255.551902 -328.967457) (xy 255.551432 -328.94016) (xy 255.551918 -328.912909)
			(xy 255.559674 -328.858961) (xy 255.575029 -328.806666) (xy 255.597671 -328.757089) (xy 255.627137 -328.711239)
			(xy 255.662828 -328.670048) (xy 255.704019 -328.634357) (xy 255.749869 -328.604891) (xy 255.799446 -328.582249)
			(xy 255.851741 -328.566894) (xy 255.905689 -328.559138) (xy 255.960191 -328.559138) (xy 256.014139 -328.566894)
			(xy 256.066434 -328.582249) (xy 256.116011 -328.604891) (xy 256.161861 -328.634357) (xy 256.203052 -328.670048)
			(xy 256.238743 -328.711239) (xy 256.268209 -328.757089) (xy 256.290851 -328.806666) (xy 256.306206 -328.858961)
			(xy 256.308246 -328.873148) (xy 271.698504 -328.873148) (xy 271.698504 -328.818652) (xy 271.706259 -328.764711)
			(xy 271.721612 -328.712423) (xy 271.744249 -328.662851) (xy 271.77371 -328.617006) (xy 271.809395 -328.575819)
			(xy 271.850578 -328.54013) (xy 271.896421 -328.510665) (xy 271.945991 -328.488023) (xy 271.998278 -328.472666)
			(xy 272.052218 -328.464907) (xy 272.079466 -328.464418) (xy 272.106673 -328.464875) (xy 272.160536 -328.472596)
			(xy 272.212754 -328.487899) (xy 272.262264 -328.510474) (xy 272.308059 -328.539862) (xy 272.349209 -328.575464)
			(xy 272.384877 -328.616558) (xy 272.400014 -328.63917) (xy 272.408325 -328.651184) (xy 272.430433 -328.670262)
			(xy 272.457032 -328.682313) (xy 272.485952 -328.686355) (xy 272.514836 -328.682058) (xy 272.541327 -328.669772)
			(xy 272.563266 -328.650499) (xy 272.571464 -328.638408) (xy 272.586491 -328.61536) (xy 272.622174 -328.57348)
			(xy 272.663507 -328.537164) (xy 272.70963 -328.507165) (xy 272.759585 -328.484108) (xy 272.812337 -328.468469)
			(xy 272.866788 -328.460575) (xy 272.894298 -328.4601) (xy 272.92038 -328.460524) (xy 272.972057 -328.467643)
			(xy 273.022283 -328.481734) (xy 273.070121 -328.502536) (xy 273.11468 -328.52966) (xy 273.155128 -328.5626)
			(xy 273.190713 -328.600743) (xy 273.220771 -328.643378) (xy 273.233134 -328.666348) (xy 273.240428 -328.679396)
			(xy 273.261253 -328.700827) (xy 273.287388 -328.715313) (xy 273.316598 -328.721614) (xy 273.346382 -328.719192)
			(xy 273.374189 -328.708253) (xy 273.397641 -328.689735) (xy 273.406616 -328.677778) (xy 273.421963 -328.656589)
			(xy 273.457563 -328.618249) (xy 273.498069 -328.585133) (xy 273.542721 -328.557864) (xy 273.59068 -328.536953)
			(xy 273.641046 -328.522792) (xy 273.692876 -328.515646) (xy 273.719036 -328.515218) (xy 273.746287 -328.515654)
			(xy 273.800235 -328.523416) (xy 273.852529 -328.538775) (xy 273.902105 -328.56142) (xy 273.947954 -328.590889)
			(xy 273.989143 -328.626583) (xy 274.024833 -328.667775) (xy 274.054298 -328.713627) (xy 274.076938 -328.763205)
			(xy 274.092292 -328.8155) (xy 274.100048 -328.869449) (xy 274.100048 -328.923951) (xy 274.092292 -328.9779)
			(xy 274.076938 -329.030195) (xy 274.054298 -329.079773) (xy 274.024833 -329.125625) (xy 273.989143 -329.166817)
			(xy 273.947954 -329.202511) (xy 273.902105 -329.23198) (xy 273.852529 -329.254625) (xy 273.800235 -329.269984)
			(xy 273.746287 -329.277746) (xy 273.719036 -329.278234) (xy 273.692953 -329.277817) (xy 273.641274 -329.270702)
			(xy 273.591047 -329.256612) (xy 273.543207 -329.235811) (xy 273.498648 -329.208686) (xy 273.458199 -329.175743)
			(xy 273.422616 -329.137597) (xy 273.392561 -329.094958) (xy 273.3802 -329.071986) (xy 273.37286 -329.05897)
			(xy 273.352039 -329.037554) (xy 273.325914 -329.023078) (xy 273.296718 -329.016777) (xy 273.266947 -329.019191)
			(xy 273.239148 -329.030114) (xy 273.215697 -329.048611) (xy 273.206718 -329.060556) (xy 273.19136 -329.081737)
			(xy 273.155761 -329.120076) (xy 273.115256 -329.153191) (xy 273.070607 -329.18046) (xy 273.02265 -329.201373)
			(xy 272.972285 -329.215537) (xy 272.920457 -329.222685) (xy 272.894298 -329.223116) (xy 272.867091 -329.222672)
			(xy 272.813228 -329.214947) (xy 272.76101 -329.19964) (xy 272.711501 -329.177062) (xy 272.665706 -329.147673)
			(xy 272.624556 -329.11207) (xy 272.588888 -329.070976) (xy 272.57375 -329.048364) (xy 272.565488 -329.036311)
			(xy 272.543371 -329.017226) (xy 272.516761 -329.005172) (xy 272.487828 -329.001133) (xy 272.458934 -329.005438)
			(xy 272.432436 -329.017738) (xy 272.410496 -329.037027) (xy 272.4023 -329.049126) (xy 272.387242 -329.072152)
			(xy 272.351562 -329.114031) (xy 272.310235 -329.150347) (xy 272.264117 -329.180347) (xy 272.214167 -329.203409)
			(xy 272.161421 -329.219053) (xy 272.106974 -329.226954) (xy 272.079466 -329.227434) (xy 272.052218 -329.226893)
			(xy 271.998278 -329.219134) (xy 271.945991 -329.203777) (xy 271.896421 -329.181135) (xy 271.850578 -329.15167)
			(xy 271.809395 -329.115981) (xy 271.77371 -329.074794) (xy 271.744249 -329.028949) (xy 271.721612 -328.979377)
			(xy 271.706259 -328.927089) (xy 271.698504 -328.873148) (xy 256.308246 -328.873148) (xy 256.313962 -328.912909)
			(xy 256.314448 -328.94016) (xy 256.313974 -328.96763) (xy 256.306098 -329.022002) (xy 256.290503 -329.074682)
			(xy 256.267512 -329.124579) (xy 256.2376 -329.170662) (xy 256.201386 -329.211977) (xy 256.15962 -329.247669)
			(xy 256.136648 -329.26274) (xy 256.124526 -329.27091) (xy 256.105249 -329.292876) (xy 256.092979 -329.319399)
			(xy 256.088718 -329.348312) (xy 256.089009 -329.35037) (xy 263.653522 -329.35037) (xy 263.657593 -329.294748)
			(xy 263.669719 -329.240311) (xy 263.689642 -329.18822) (xy 263.716938 -329.139585) (xy 263.751024 -329.095442)
			(xy 263.791173 -329.056733) (xy 263.836531 -329.024282) (xy 263.886131 -328.998781) (xy 263.938915 -328.980774)
			(xy 263.993758 -328.970644) (xy 264.049492 -328.968607) (xy 264.104929 -328.974707) (xy 264.158886 -328.988813)
			(xy 264.210215 -329.010625) (xy 264.257821 -329.039679) (xy 264.300689 -329.075354) (xy 264.337906 -329.116891)
			(xy 264.368679 -329.163404) (xy 264.392351 -329.213901) (xy 264.408419 -329.267308) (xy 264.416539 -329.322484)
			(xy 264.417048 -329.35037) (xy 264.923522 -329.35037) (xy 264.927593 -329.294748) (xy 264.939719 -329.240311)
			(xy 264.959642 -329.18822) (xy 264.986938 -329.139585) (xy 265.021024 -329.095442) (xy 265.061173 -329.056733)
			(xy 265.106531 -329.024282) (xy 265.156131 -328.998781) (xy 265.208915 -328.980774) (xy 265.263758 -328.970644)
			(xy 265.319492 -328.968607) (xy 265.374929 -328.974707) (xy 265.428886 -328.988813) (xy 265.480215 -329.010625)
			(xy 265.527821 -329.039679) (xy 265.570689 -329.075354) (xy 265.607906 -329.116891) (xy 265.638679 -329.163404)
			(xy 265.662351 -329.213901) (xy 265.678419 -329.267308) (xy 265.686539 -329.322484) (xy 265.687048 -329.35037)
			(xy 266.193522 -329.35037) (xy 266.197593 -329.294748) (xy 266.209719 -329.240311) (xy 266.229642 -329.18822)
			(xy 266.256938 -329.139585) (xy 266.291024 -329.095442) (xy 266.331173 -329.056733) (xy 266.376531 -329.024282)
			(xy 266.426131 -328.998781) (xy 266.478915 -328.980774) (xy 266.533758 -328.970644) (xy 266.589492 -328.968607)
			(xy 266.644929 -328.974707) (xy 266.698886 -328.988813) (xy 266.750215 -329.010625) (xy 266.797821 -329.039679)
			(xy 266.840689 -329.075354) (xy 266.877906 -329.116891) (xy 266.908679 -329.163404) (xy 266.932351 -329.213901)
			(xy 266.948419 -329.267308) (xy 266.956539 -329.322484) (xy 266.957048 -329.35037) (xy 266.956774 -329.365356)
			(xy 267.169898 -329.365356) (xy 267.173969 -329.309734) (xy 267.186095 -329.255297) (xy 267.206018 -329.203206)
			(xy 267.233314 -329.154571) (xy 267.2674 -329.110428) (xy 267.307549 -329.071719) (xy 267.352907 -329.039268)
			(xy 267.402507 -329.013767) (xy 267.455291 -328.99576) (xy 267.510134 -328.98563) (xy 267.565868 -328.983593)
			(xy 267.621305 -328.989693) (xy 267.675262 -329.003799) (xy 267.726591 -329.025611) (xy 267.774197 -329.054665)
			(xy 267.817065 -329.09034) (xy 267.854282 -329.131877) (xy 267.885055 -329.17839) (xy 267.908727 -329.228887)
			(xy 267.918301 -329.260708) (xy 268.423642 -329.260708) (xy 268.427713 -329.205086) (xy 268.439839 -329.150649)
			(xy 268.459762 -329.098558) (xy 268.487058 -329.049923) (xy 268.521144 -329.00578) (xy 268.561293 -328.967071)
			(xy 268.606651 -328.93462) (xy 268.656251 -328.909119) (xy 268.709035 -328.891112) (xy 268.763878 -328.880982)
			(xy 268.819612 -328.878945) (xy 268.875049 -328.885045) (xy 268.929006 -328.899151) (xy 268.980335 -328.920963)
			(xy 269.027941 -328.950017) (xy 269.070809 -328.985692) (xy 269.108026 -329.027229) (xy 269.138799 -329.073742)
			(xy 269.162471 -329.124239) (xy 269.178539 -329.177646) (xy 269.186659 -329.232822) (xy 269.187168 -329.260708)
			(xy 269.186659 -329.288594) (xy 269.178539 -329.34377) (xy 269.172045 -329.365356) (xy 269.709898 -329.365356)
			(xy 269.713969 -329.309734) (xy 269.726095 -329.255297) (xy 269.746018 -329.203206) (xy 269.773314 -329.154571)
			(xy 269.8074 -329.110428) (xy 269.847549 -329.071719) (xy 269.892907 -329.039268) (xy 269.942507 -329.013767)
			(xy 269.995291 -328.99576) (xy 270.050134 -328.98563) (xy 270.105868 -328.983593) (xy 270.161305 -328.989693)
			(xy 270.215262 -329.003799) (xy 270.266591 -329.025611) (xy 270.314197 -329.054665) (xy 270.357065 -329.09034)
			(xy 270.394282 -329.131877) (xy 270.425055 -329.17839) (xy 270.448727 -329.228887) (xy 270.464795 -329.282294)
			(xy 270.472915 -329.33747) (xy 270.473424 -329.365356) (xy 270.472915 -329.393242) (xy 270.464795 -329.448418)
			(xy 270.448727 -329.501825) (xy 270.425055 -329.552322) (xy 270.394282 -329.598835) (xy 270.357065 -329.640372)
			(xy 270.314197 -329.676047) (xy 270.266591 -329.705101) (xy 270.215262 -329.726913) (xy 270.161305 -329.741019)
			(xy 270.105868 -329.747119) (xy 270.050134 -329.745082) (xy 269.995291 -329.734952) (xy 269.942507 -329.716945)
			(xy 269.892907 -329.691444) (xy 269.847549 -329.658993) (xy 269.8074 -329.620284) (xy 269.773314 -329.576141)
			(xy 269.746018 -329.527506) (xy 269.726095 -329.475415) (xy 269.713969 -329.420978) (xy 269.709898 -329.365356)
			(xy 269.172045 -329.365356) (xy 269.162471 -329.397177) (xy 269.138799 -329.447674) (xy 269.108026 -329.494187)
			(xy 269.070809 -329.535724) (xy 269.027941 -329.571399) (xy 268.980335 -329.600453) (xy 268.929006 -329.622265)
			(xy 268.875049 -329.636371) (xy 268.819612 -329.642471) (xy 268.763878 -329.640434) (xy 268.709035 -329.630304)
			(xy 268.656251 -329.612297) (xy 268.606651 -329.586796) (xy 268.561293 -329.554345) (xy 268.521144 -329.515636)
			(xy 268.487058 -329.471493) (xy 268.459762 -329.422858) (xy 268.439839 -329.370767) (xy 268.427713 -329.31633)
			(xy 268.423642 -329.260708) (xy 267.918301 -329.260708) (xy 267.924795 -329.282294) (xy 267.932915 -329.33747)
			(xy 267.933424 -329.365356) (xy 267.932915 -329.393242) (xy 267.924795 -329.448418) (xy 267.908727 -329.501825)
			(xy 267.885055 -329.552322) (xy 267.854282 -329.598835) (xy 267.817065 -329.640372) (xy 267.774197 -329.676047)
			(xy 267.726591 -329.705101) (xy 267.675262 -329.726913) (xy 267.621305 -329.741019) (xy 267.565868 -329.747119)
			(xy 267.510134 -329.745082) (xy 267.455291 -329.734952) (xy 267.402507 -329.716945) (xy 267.352907 -329.691444)
			(xy 267.307549 -329.658993) (xy 267.2674 -329.620284) (xy 267.233314 -329.576141) (xy 267.206018 -329.527506)
			(xy 267.186095 -329.475415) (xy 267.173969 -329.420978) (xy 267.169898 -329.365356) (xy 266.956774 -329.365356)
			(xy 266.956539 -329.378256) (xy 266.948419 -329.433432) (xy 266.932351 -329.486839) (xy 266.908679 -329.537336)
			(xy 266.877906 -329.583849) (xy 266.840689 -329.625386) (xy 266.797821 -329.661061) (xy 266.750215 -329.690115)
			(xy 266.698886 -329.711927) (xy 266.644929 -329.726033) (xy 266.589492 -329.732133) (xy 266.533758 -329.730096)
			(xy 266.478915 -329.719966) (xy 266.426131 -329.701959) (xy 266.376531 -329.676458) (xy 266.331173 -329.644007)
			(xy 266.291024 -329.605298) (xy 266.256938 -329.561155) (xy 266.229642 -329.51252) (xy 266.209719 -329.460429)
			(xy 266.197593 -329.405992) (xy 266.193522 -329.35037) (xy 265.687048 -329.35037) (xy 265.686539 -329.378256)
			(xy 265.678419 -329.433432) (xy 265.662351 -329.486839) (xy 265.638679 -329.537336) (xy 265.607906 -329.583849)
			(xy 265.570689 -329.625386) (xy 265.527821 -329.661061) (xy 265.480215 -329.690115) (xy 265.428886 -329.711927)
			(xy 265.374929 -329.726033) (xy 265.319492 -329.732133) (xy 265.263758 -329.730096) (xy 265.208915 -329.719966)
			(xy 265.156131 -329.701959) (xy 265.106531 -329.676458) (xy 265.061173 -329.644007) (xy 265.021024 -329.605298)
			(xy 264.986938 -329.561155) (xy 264.959642 -329.51252) (xy 264.939719 -329.460429) (xy 264.927593 -329.405992)
			(xy 264.923522 -329.35037) (xy 264.417048 -329.35037) (xy 264.416539 -329.378256) (xy 264.408419 -329.433432)
			(xy 264.392351 -329.486839) (xy 264.368679 -329.537336) (xy 264.337906 -329.583849) (xy 264.300689 -329.625386)
			(xy 264.257821 -329.661061) (xy 264.210215 -329.690115) (xy 264.158886 -329.711927) (xy 264.104929 -329.726033)
			(xy 264.049492 -329.732133) (xy 263.993758 -329.730096) (xy 263.938915 -329.719966) (xy 263.886131 -329.701959)
			(xy 263.836531 -329.676458) (xy 263.791173 -329.644007) (xy 263.751024 -329.605298) (xy 263.716938 -329.561155)
			(xy 263.689642 -329.51252) (xy 263.669719 -329.460429) (xy 263.657593 -329.405992) (xy 263.653522 -329.35037)
			(xy 256.089009 -329.35037) (xy 256.092815 -329.377247) (xy 256.104936 -329.40384) (xy 256.124088 -329.425914)
			(xy 256.13614 -329.43419) (xy 256.158886 -329.449292) (xy 256.200193 -329.484996) (xy 256.235989 -329.526222)
			(xy 256.265545 -329.572129) (xy 256.288257 -329.621779) (xy 256.303661 -329.67416) (xy 256.311442 -329.728201)
			(xy 256.311908 -329.7555) (xy 256.311422 -329.782751) (xy 256.303666 -329.836699) (xy 256.288311 -329.888994)
			(xy 256.265669 -329.938571) (xy 256.236203 -329.984421) (xy 256.200512 -330.025612) (xy 256.159321 -330.061303)
			(xy 256.113471 -330.090769) (xy 256.063894 -330.113411) (xy 256.011599 -330.128766) (xy 255.957651 -330.136522)
			(xy 255.903149 -330.136522) (xy 255.849201 -330.128766) (xy 255.796906 -330.113411) (xy 255.747329 -330.090769)
			(xy 255.701479 -330.061303) (xy 255.660288 -330.025612) (xy 255.624597 -329.984421) (xy 255.595131 -329.938571)
			(xy 255.572489 -329.888994) (xy 255.557134 -329.836699) (xy 255.549378 -329.782751) (xy 255.548892 -329.7555)
			(xy 252.952504 -329.7555) (xy 252.952504 -347.065092) (xy 265.97864 -360.091482) (xy 265.97864 -370.687346)
			(xy 278.495506 -383.204212) (xy 282.75026 -383.204212) (xy 282.776242 -383.204709) (xy 282.827561 -383.212868)
			(xy 282.876971 -383.22896) (xy 282.923252 -383.252589) (xy 282.965264 -383.283171) (xy 282.98394 -383.30124)
			(xy 284.24378 -384.56108) (xy 284.261795 -384.579801) (xy 284.292352 -384.621815) (xy 284.315971 -384.668088)
			(xy 284.33207 -384.717482) (xy 284.340255 -384.768785) (xy 284.340808 -384.79476) (xy 284.340808 -384.919474)
			(xy 284.913858 -385.492752) (xy 301.298862 -385.492752) (xy 301.302933 -385.43713) (xy 301.315059 -385.382693)
			(xy 301.334982 -385.330602) (xy 301.362278 -385.281967) (xy 301.396364 -385.237824) (xy 301.436513 -385.199115)
			(xy 301.481871 -385.166664) (xy 301.531471 -385.141163) (xy 301.584255 -385.123156) (xy 301.639098 -385.113026)
			(xy 301.694832 -385.110989) (xy 301.750269 -385.117089) (xy 301.804226 -385.131195) (xy 301.855555 -385.153007)
			(xy 301.903161 -385.182061) (xy 301.946029 -385.217736) (xy 301.983246 -385.259273) (xy 302.014019 -385.305786)
			(xy 302.037691 -385.356283) (xy 302.053759 -385.40969) (xy 302.061879 -385.464866) (xy 302.062388 -385.492752)
			(xy 302.061879 -385.520638) (xy 302.053759 -385.575814) (xy 302.037691 -385.629221) (xy 302.014019 -385.679718)
			(xy 301.983246 -385.726231) (xy 301.946029 -385.767768) (xy 301.903161 -385.803443) (xy 301.855555 -385.832497)
			(xy 301.804226 -385.854309) (xy 301.750269 -385.868415) (xy 301.694832 -385.874515) (xy 301.639098 -385.872478)
			(xy 301.584255 -385.862348) (xy 301.531471 -385.844341) (xy 301.481871 -385.81884) (xy 301.436513 -385.786389)
			(xy 301.396364 -385.74768) (xy 301.362278 -385.703537) (xy 301.334982 -385.654902) (xy 301.315059 -385.602811)
			(xy 301.302933 -385.548374) (xy 301.298862 -385.492752) (xy 284.913858 -385.492752) (xy 284.98038 -385.5593)
			(xy 284.98038 -386.635752) (xy 301.326802 -386.635752) (xy 301.330873 -386.58013) (xy 301.342999 -386.525693)
			(xy 301.362922 -386.473602) (xy 301.390218 -386.424967) (xy 301.424304 -386.380824) (xy 301.464453 -386.342115)
			(xy 301.509811 -386.309664) (xy 301.559411 -386.284163) (xy 301.612195 -386.266156) (xy 301.667038 -386.256026)
			(xy 301.722772 -386.253989) (xy 301.778209 -386.260089) (xy 301.832166 -386.274195) (xy 301.883495 -386.296007)
			(xy 301.931101 -386.325061) (xy 301.973969 -386.360736) (xy 302.011186 -386.402273) (xy 302.041959 -386.448786)
			(xy 302.065631 -386.499283) (xy 302.081699 -386.55269) (xy 302.089819 -386.607866) (xy 302.090328 -386.635752)
			(xy 302.089819 -386.663638) (xy 302.081699 -386.718814) (xy 302.065631 -386.772221) (xy 302.041959 -386.822718)
			(xy 302.011186 -386.869231) (xy 301.973969 -386.910768) (xy 301.931101 -386.946443) (xy 301.883495 -386.975497)
			(xy 301.832166 -386.997309) (xy 301.778209 -387.011415) (xy 301.722772 -387.017515) (xy 301.667038 -387.015478)
			(xy 301.612195 -387.005348) (xy 301.559411 -386.987341) (xy 301.509811 -386.96184) (xy 301.464453 -386.929389)
			(xy 301.424304 -386.89068) (xy 301.390218 -386.846537) (xy 301.362922 -386.797902) (xy 301.342999 -386.745811)
			(xy 301.330873 -386.691374) (xy 301.326802 -386.635752) (xy 284.98038 -386.635752) (xy 284.98038 -387.147562)
			(xy 285.878014 -387.147562) (xy 285.882085 -387.09194) (xy 285.894211 -387.037503) (xy 285.914134 -386.985412)
			(xy 285.94143 -386.936777) (xy 285.975516 -386.892634) (xy 286.015665 -386.853925) (xy 286.061023 -386.821474)
			(xy 286.110623 -386.795973) (xy 286.163407 -386.777966) (xy 286.21825 -386.767836) (xy 286.273984 -386.765799)
			(xy 286.329421 -386.771899) (xy 286.383378 -386.786005) (xy 286.434707 -386.807817) (xy 286.482313 -386.836871)
			(xy 286.525181 -386.872546) (xy 286.562398 -386.914083) (xy 286.593171 -386.960596) (xy 286.616843 -387.011093)
			(xy 286.632911 -387.0645) (xy 286.641031 -387.119676) (xy 286.64154 -387.147562) (xy 286.641117 -387.170751)
			(xy 288.098976 -387.170751) (xy 288.098976 -387.116249) (xy 288.106732 -387.062302) (xy 288.122087 -387.010007)
			(xy 288.144728 -386.96043) (xy 288.174193 -386.91458) (xy 288.209884 -386.87339) (xy 288.251074 -386.837698)
			(xy 288.296923 -386.808231) (xy 288.3465 -386.78559) (xy 288.398794 -386.770234) (xy 288.452741 -386.762476)
			(xy 288.479992 -386.76199) (xy 288.509328 -386.762512) (xy 288.567309 -386.771482) (xy 288.623233 -386.789228)
			(xy 288.675778 -386.81533) (xy 288.723705 -386.849173) (xy 288.745168 -386.869178) (xy 288.754974 -386.878143)
			(xy 288.778141 -386.891128) (xy 288.803879 -386.897678) (xy 288.830435 -386.897347) (xy 288.856002 -386.890158)
			(xy 288.878838 -386.8766) (xy 288.888424 -386.8674) (xy 288.906423 -386.84956) (xy 288.946338 -386.818333)
			(xy 288.990035 -386.792666) (xy 289.036746 -386.773011) (xy 289.085648 -386.759712) (xy 289.135881 -386.753005)
			(xy 289.16122 -386.752592) (xy 289.18847 -386.753079) (xy 289.242416 -386.760838) (xy 289.294708 -386.776195)
			(xy 289.344283 -386.798837) (xy 289.390131 -386.828304) (xy 289.431319 -386.863995) (xy 289.467008 -386.905185)
			(xy 289.496472 -386.951035) (xy 289.519112 -387.000611) (xy 289.534466 -387.052904) (xy 289.542222 -387.10685)
			(xy 289.542222 -387.143498) (xy 292.09822 -387.143498) (xy 292.102291 -387.087876) (xy 292.114417 -387.033439)
			(xy 292.13434 -386.981348) (xy 292.161636 -386.932713) (xy 292.195722 -386.88857) (xy 292.235871 -386.849861)
			(xy 292.281229 -386.81741) (xy 292.330829 -386.791909) (xy 292.383613 -386.773902) (xy 292.438456 -386.763772)
			(xy 292.49419 -386.761735) (xy 292.549627 -386.767835) (xy 292.603584 -386.781941) (xy 292.654913 -386.803753)
			(xy 292.702519 -386.832807) (xy 292.745387 -386.868482) (xy 292.782604 -386.910019) (xy 292.813377 -386.956532)
			(xy 292.837049 -387.007029) (xy 292.853117 -387.060436) (xy 292.861237 -387.115612) (xy 292.861746 -387.143498)
			(xy 293.097964 -387.143498) (xy 293.102035 -387.087876) (xy 293.114161 -387.033439) (xy 293.134084 -386.981348)
			(xy 293.16138 -386.932713) (xy 293.195466 -386.88857) (xy 293.235615 -386.849861) (xy 293.280973 -386.81741)
			(xy 293.330573 -386.791909) (xy 293.383357 -386.773902) (xy 293.4382 -386.763772) (xy 293.493934 -386.761735)
			(xy 293.549371 -386.767835) (xy 293.603328 -386.781941) (xy 293.654657 -386.803753) (xy 293.702263 -386.832807)
			(xy 293.745131 -386.868482) (xy 293.782348 -386.910019) (xy 293.813121 -386.956532) (xy 293.836793 -387.007029)
			(xy 293.852861 -387.060436) (xy 293.860981 -387.115612) (xy 293.86149 -387.143498) (xy 294.098216 -387.143498)
			(xy 294.102287 -387.087876) (xy 294.114413 -387.033439) (xy 294.134336 -386.981348) (xy 294.161632 -386.932713)
			(xy 294.195718 -386.88857) (xy 294.235867 -386.849861) (xy 294.281225 -386.81741) (xy 294.330825 -386.791909)
			(xy 294.383609 -386.773902) (xy 294.438452 -386.763772) (xy 294.494186 -386.761735) (xy 294.549623 -386.767835)
			(xy 294.60358 -386.781941) (xy 294.654909 -386.803753) (xy 294.702515 -386.832807) (xy 294.745383 -386.868482)
			(xy 294.7826 -386.910019) (xy 294.813373 -386.956532) (xy 294.837045 -387.007029) (xy 294.853113 -387.060436)
			(xy 294.861233 -387.115612) (xy 294.861742 -387.143498) (xy 295.098214 -387.143498) (xy 295.102285 -387.087876)
			(xy 295.114411 -387.033439) (xy 295.134334 -386.981348) (xy 295.16163 -386.932713) (xy 295.195716 -386.88857)
			(xy 295.235865 -386.849861) (xy 295.281223 -386.81741) (xy 295.330823 -386.791909) (xy 295.383607 -386.773902)
			(xy 295.43845 -386.763772) (xy 295.494184 -386.761735) (xy 295.549621 -386.767835) (xy 295.603578 -386.781941)
			(xy 295.654907 -386.803753) (xy 295.702513 -386.832807) (xy 295.745381 -386.868482) (xy 295.782598 -386.910019)
			(xy 295.813371 -386.956532) (xy 295.837043 -387.007029) (xy 295.853111 -387.060436) (xy 295.861231 -387.115612)
			(xy 295.86174 -387.143498) (xy 296.098212 -387.143498) (xy 296.102283 -387.087876) (xy 296.114409 -387.033439)
			(xy 296.134332 -386.981348) (xy 296.161628 -386.932713) (xy 296.195714 -386.88857) (xy 296.235863 -386.849861)
			(xy 296.281221 -386.81741) (xy 296.330821 -386.791909) (xy 296.383605 -386.773902) (xy 296.438448 -386.763772)
			(xy 296.494182 -386.761735) (xy 296.549619 -386.767835) (xy 296.603576 -386.781941) (xy 296.654905 -386.803753)
			(xy 296.702511 -386.832807) (xy 296.745379 -386.868482) (xy 296.782596 -386.910019) (xy 296.813369 -386.956532)
			(xy 296.837041 -387.007029) (xy 296.853109 -387.060436) (xy 296.861229 -387.115612) (xy 296.861738 -387.143498)
			(xy 296.861664 -387.147562) (xy 299.31817 -387.147562) (xy 299.322241 -387.09194) (xy 299.334367 -387.037503)
			(xy 299.35429 -386.985412) (xy 299.381586 -386.936777) (xy 299.415672 -386.892634) (xy 299.455821 -386.853925)
			(xy 299.501179 -386.821474) (xy 299.550779 -386.795973) (xy 299.603563 -386.777966) (xy 299.658406 -386.767836)
			(xy 299.71414 -386.765799) (xy 299.769577 -386.771899) (xy 299.823534 -386.786005) (xy 299.874863 -386.807817)
			(xy 299.922469 -386.836871) (xy 299.965337 -386.872546) (xy 300.002554 -386.914083) (xy 300.033327 -386.960596)
			(xy 300.056999 -387.011093) (xy 300.073067 -387.0645) (xy 300.081187 -387.119676) (xy 300.081696 -387.147562)
			(xy 300.081187 -387.175448) (xy 300.073067 -387.230624) (xy 300.056999 -387.284031) (xy 300.033327 -387.334528)
			(xy 300.002554 -387.381041) (xy 299.965337 -387.422578) (xy 299.922469 -387.458253) (xy 299.874863 -387.487307)
			(xy 299.823534 -387.509119) (xy 299.769577 -387.523225) (xy 299.71414 -387.529325) (xy 299.658406 -387.527288)
			(xy 299.603563 -387.517158) (xy 299.550779 -387.499151) (xy 299.501179 -387.47365) (xy 299.455821 -387.441199)
			(xy 299.415672 -387.40249) (xy 299.381586 -387.358347) (xy 299.35429 -387.309712) (xy 299.334367 -387.257621)
			(xy 299.322241 -387.203184) (xy 299.31817 -387.147562) (xy 296.861664 -387.147562) (xy 296.861229 -387.171384)
			(xy 296.853109 -387.22656) (xy 296.837041 -387.279967) (xy 296.813369 -387.330464) (xy 296.782596 -387.376977)
			(xy 296.745379 -387.418514) (xy 296.702511 -387.454189) (xy 296.654905 -387.483243) (xy 296.603576 -387.505055)
			(xy 296.549619 -387.519161) (xy 296.494182 -387.525261) (xy 296.438448 -387.523224) (xy 296.383605 -387.513094)
			(xy 296.330821 -387.495087) (xy 296.281221 -387.469586) (xy 296.235863 -387.437135) (xy 296.195714 -387.398426)
			(xy 296.161628 -387.354283) (xy 296.134332 -387.305648) (xy 296.114409 -387.253557) (xy 296.102283 -387.19912)
			(xy 296.098212 -387.143498) (xy 295.86174 -387.143498) (xy 295.861231 -387.171384) (xy 295.853111 -387.22656)
			(xy 295.837043 -387.279967) (xy 295.813371 -387.330464) (xy 295.782598 -387.376977) (xy 295.745381 -387.418514)
			(xy 295.702513 -387.454189) (xy 295.654907 -387.483243) (xy 295.603578 -387.505055) (xy 295.549621 -387.519161)
			(xy 295.494184 -387.525261) (xy 295.43845 -387.523224) (xy 295.383607 -387.513094) (xy 295.330823 -387.495087)
			(xy 295.281223 -387.469586) (xy 295.235865 -387.437135) (xy 295.195716 -387.398426) (xy 295.16163 -387.354283)
			(xy 295.134334 -387.305648) (xy 295.114411 -387.253557) (xy 295.102285 -387.19912) (xy 295.098214 -387.143498)
			(xy 294.861742 -387.143498) (xy 294.861233 -387.171384) (xy 294.853113 -387.22656) (xy 294.837045 -387.279967)
			(xy 294.813373 -387.330464) (xy 294.7826 -387.376977) (xy 294.745383 -387.418514) (xy 294.702515 -387.454189)
			(xy 294.654909 -387.483243) (xy 294.60358 -387.505055) (xy 294.549623 -387.519161) (xy 294.494186 -387.525261)
			(xy 294.438452 -387.523224) (xy 294.383609 -387.513094) (xy 294.330825 -387.495087) (xy 294.281225 -387.469586)
			(xy 294.235867 -387.437135) (xy 294.195718 -387.398426) (xy 294.161632 -387.354283) (xy 294.134336 -387.305648)
			(xy 294.114413 -387.253557) (xy 294.102287 -387.19912) (xy 294.098216 -387.143498) (xy 293.86149 -387.143498)
			(xy 293.860981 -387.171384) (xy 293.852861 -387.22656) (xy 293.836793 -387.279967) (xy 293.813121 -387.330464)
			(xy 293.782348 -387.376977) (xy 293.745131 -387.418514) (xy 293.702263 -387.454189) (xy 293.654657 -387.483243)
			(xy 293.603328 -387.505055) (xy 293.549371 -387.519161) (xy 293.493934 -387.525261) (xy 293.4382 -387.523224)
			(xy 293.383357 -387.513094) (xy 293.330573 -387.495087) (xy 293.280973 -387.469586) (xy 293.235615 -387.437135)
			(xy 293.195466 -387.398426) (xy 293.16138 -387.354283) (xy 293.134084 -387.305648) (xy 293.114161 -387.253557)
			(xy 293.102035 -387.19912) (xy 293.097964 -387.143498) (xy 292.861746 -387.143498) (xy 292.861237 -387.171384)
			(xy 292.853117 -387.22656) (xy 292.837049 -387.279967) (xy 292.813377 -387.330464) (xy 292.782604 -387.376977)
			(xy 292.745387 -387.418514) (xy 292.702519 -387.454189) (xy 292.654913 -387.483243) (xy 292.603584 -387.505055)
			(xy 292.549627 -387.519161) (xy 292.49419 -387.525261) (xy 292.438456 -387.523224) (xy 292.383613 -387.513094)
			(xy 292.330829 -387.495087) (xy 292.281229 -387.469586) (xy 292.235871 -387.437135) (xy 292.195722 -387.398426)
			(xy 292.161636 -387.354283) (xy 292.13434 -387.305648) (xy 292.114417 -387.253557) (xy 292.102291 -387.19912)
			(xy 292.09822 -387.143498) (xy 289.542222 -387.143498) (xy 289.542222 -387.16135) (xy 289.534466 -387.215296)
			(xy 289.519112 -387.267589) (xy 289.496472 -387.317165) (xy 289.467008 -387.363015) (xy 289.431319 -387.404205)
			(xy 289.390131 -387.439896) (xy 289.344283 -387.469363) (xy 289.294708 -387.492005) (xy 289.242416 -387.507362)
			(xy 289.18847 -387.515121) (xy 289.16122 -387.515608) (xy 289.131884 -387.515079) (xy 289.073903 -387.506111)
			(xy 289.01798 -387.488366) (xy 288.965435 -387.462266) (xy 288.917508 -387.428424) (xy 288.896044 -387.40842)
			(xy 288.886228 -387.399468) (xy 288.863064 -387.386482) (xy 288.837329 -387.37993) (xy 288.810775 -387.380259)
			(xy 288.78521 -387.387445) (xy 288.762374 -387.401) (xy 288.752788 -387.410198) (xy 288.734783 -387.428032)
			(xy 288.69487 -387.459259) (xy 288.651174 -387.484927) (xy 288.604464 -387.504584) (xy 288.555562 -387.517884)
			(xy 288.505331 -387.524592) (xy 288.479992 -387.525006) (xy 288.452741 -387.524524) (xy 288.398794 -387.516766)
			(xy 288.3465 -387.50141) (xy 288.296923 -387.478769) (xy 288.251074 -387.449302) (xy 288.209884 -387.41361)
			(xy 288.174193 -387.37242) (xy 288.144728 -387.32657) (xy 288.122087 -387.276993) (xy 288.106732 -387.224698)
			(xy 288.098976 -387.170751) (xy 286.641117 -387.170751) (xy 286.641031 -387.175448) (xy 286.632911 -387.230624)
			(xy 286.616843 -387.284031) (xy 286.593171 -387.334528) (xy 286.562398 -387.381041) (xy 286.525181 -387.422578)
			(xy 286.482313 -387.458253) (xy 286.434707 -387.487307) (xy 286.383378 -387.509119) (xy 286.329421 -387.523225)
			(xy 286.273984 -387.529325) (xy 286.21825 -387.527288) (xy 286.163407 -387.517158) (xy 286.110623 -387.499151)
			(xy 286.061023 -387.47365) (xy 286.015665 -387.441199) (xy 285.975516 -387.40249) (xy 285.94143 -387.358347)
			(xy 285.914134 -387.309712) (xy 285.894211 -387.257621) (xy 285.882085 -387.203184) (xy 285.878014 -387.147562)
			(xy 284.98038 -387.147562) (xy 284.98038 -387.778752) (xy 301.326802 -387.778752) (xy 301.330873 -387.72313)
			(xy 301.342999 -387.668693) (xy 301.362922 -387.616602) (xy 301.390218 -387.567967) (xy 301.424304 -387.523824)
			(xy 301.464453 -387.485115) (xy 301.509811 -387.452664) (xy 301.559411 -387.427163) (xy 301.612195 -387.409156)
			(xy 301.667038 -387.399026) (xy 301.722772 -387.396989) (xy 301.778209 -387.403089) (xy 301.832166 -387.417195)
			(xy 301.883495 -387.439007) (xy 301.931101 -387.468061) (xy 301.973969 -387.503736) (xy 302.011186 -387.545273)
			(xy 302.041959 -387.591786) (xy 302.065631 -387.642283) (xy 302.081699 -387.69569) (xy 302.089819 -387.750866)
			(xy 302.090328 -387.778752) (xy 302.089819 -387.806638) (xy 302.081699 -387.861814) (xy 302.065631 -387.915221)
			(xy 302.041959 -387.965718) (xy 302.011186 -388.012231) (xy 301.973969 -388.053768) (xy 301.931101 -388.089443)
			(xy 301.883495 -388.118497) (xy 301.832166 -388.140309) (xy 301.778209 -388.154415) (xy 301.722772 -388.160515)
			(xy 301.667038 -388.158478) (xy 301.612195 -388.148348) (xy 301.559411 -388.130341) (xy 301.509811 -388.10484)
			(xy 301.464453 -388.072389) (xy 301.424304 -388.03368) (xy 301.390218 -387.989537) (xy 301.362922 -387.940902)
			(xy 301.342999 -387.888811) (xy 301.330873 -387.834374) (xy 301.326802 -387.778752) (xy 284.98038 -387.778752)
			(xy 284.98038 -389.402263) (xy 286.566352 -389.402263) (xy 286.566352 -389.317541) (xy 286.574405 -389.233204)
			(xy 286.590439 -389.150014) (xy 286.614307 -389.068724) (xy 286.645795 -388.990072) (xy 286.684617 -388.914769)
			(xy 286.73042 -388.843497) (xy 286.782791 -388.776901) (xy 286.841256 -388.715586) (xy 286.905284 -388.660105)
			(xy 286.974296 -388.610962) (xy 287.047666 -388.568602) (xy 287.124731 -388.533407) (xy 287.204793 -388.505698)
			(xy 287.287126 -388.485724) (xy 287.370985 -388.473667) (xy 287.45561 -388.469636) (xy 287.540235 -388.473667)
			(xy 287.624094 -388.485724) (xy 287.706427 -388.505698) (xy 287.786489 -388.533407) (xy 287.863554 -388.568602)
			(xy 287.936924 -388.610962) (xy 288.005936 -388.660105) (xy 288.069964 -388.715586) (xy 288.128429 -388.776901)
			(xy 288.1808 -388.843497) (xy 288.226603 -388.914769) (xy 288.265425 -388.990072) (xy 288.296913 -389.068724)
			(xy 288.320781 -389.150014) (xy 288.336815 -389.233204) (xy 288.344868 -389.317541) (xy 288.345372 -389.359902)
			(xy 288.344868 -389.402263) (xy 297.615352 -389.402263) (xy 297.615352 -389.317541) (xy 297.623405 -389.233204)
			(xy 297.639439 -389.150014) (xy 297.663307 -389.068724) (xy 297.694795 -388.990072) (xy 297.733617 -388.914769)
			(xy 297.77942 -388.843497) (xy 297.831791 -388.776901) (xy 297.890256 -388.715586) (xy 297.954284 -388.660105)
			(xy 298.023296 -388.610962) (xy 298.096666 -388.568602) (xy 298.173731 -388.533407) (xy 298.253793 -388.505698)
			(xy 298.336126 -388.485724) (xy 298.419985 -388.473667) (xy 298.50461 -388.469636) (xy 298.589235 -388.473667)
			(xy 298.673094 -388.485724) (xy 298.755427 -388.505698) (xy 298.835489 -388.533407) (xy 298.912554 -388.568602)
			(xy 298.985924 -388.610962) (xy 299.054936 -388.660105) (xy 299.118964 -388.715586) (xy 299.177429 -388.776901)
			(xy 299.2298 -388.843497) (xy 299.275603 -388.914769) (xy 299.314425 -388.990072) (xy 299.345913 -389.068724)
			(xy 299.353026 -389.092948) (xy 301.298862 -389.092948) (xy 301.302933 -389.037326) (xy 301.315059 -388.982889)
			(xy 301.334982 -388.930798) (xy 301.362278 -388.882163) (xy 301.396364 -388.83802) (xy 301.436513 -388.799311)
			(xy 301.481871 -388.76686) (xy 301.531471 -388.741359) (xy 301.584255 -388.723352) (xy 301.639098 -388.713222)
			(xy 301.694832 -388.711185) (xy 301.750269 -388.717285) (xy 301.804226 -388.731391) (xy 301.855555 -388.753203)
			(xy 301.903161 -388.782257) (xy 301.946029 -388.817932) (xy 301.983246 -388.859469) (xy 302.014019 -388.905982)
			(xy 302.037691 -388.956479) (xy 302.053759 -389.009886) (xy 302.061879 -389.065062) (xy 302.062388 -389.092948)
			(xy 302.061879 -389.120834) (xy 302.053759 -389.17601) (xy 302.037691 -389.229417) (xy 302.014019 -389.279914)
			(xy 301.983246 -389.326427) (xy 301.946029 -389.367964) (xy 301.903161 -389.403639) (xy 301.855555 -389.432693)
			(xy 301.804226 -389.454505) (xy 301.750269 -389.468611) (xy 301.694832 -389.474711) (xy 301.639098 -389.472674)
			(xy 301.584255 -389.462544) (xy 301.531471 -389.444537) (xy 301.481871 -389.419036) (xy 301.436513 -389.386585)
			(xy 301.396364 -389.347876) (xy 301.362278 -389.303733) (xy 301.334982 -389.255098) (xy 301.315059 -389.203007)
			(xy 301.302933 -389.14857) (xy 301.298862 -389.092948) (xy 299.353026 -389.092948) (xy 299.369781 -389.150014)
			(xy 299.385815 -389.233204) (xy 299.393868 -389.317541) (xy 299.394372 -389.359902) (xy 299.393868 -389.402263)
			(xy 299.385815 -389.4866) (xy 299.369781 -389.56979) (xy 299.345913 -389.65108) (xy 299.314425 -389.729732)
			(xy 299.275603 -389.805035) (xy 299.2298 -389.876307) (xy 299.177429 -389.942903) (xy 299.118964 -390.004218)
			(xy 299.054936 -390.059699) (xy 298.985924 -390.108842) (xy 298.912554 -390.151202) (xy 298.835489 -390.186397)
			(xy 298.755427 -390.214106) (xy 298.673094 -390.23408) (xy 298.660102 -390.235948) (xy 301.298862 -390.235948)
			(xy 301.302933 -390.180326) (xy 301.315059 -390.125889) (xy 301.334982 -390.073798) (xy 301.362278 -390.025163)
			(xy 301.396364 -389.98102) (xy 301.436513 -389.942311) (xy 301.481871 -389.90986) (xy 301.531471 -389.884359)
			(xy 301.584255 -389.866352) (xy 301.639098 -389.856222) (xy 301.694832 -389.854185) (xy 301.750269 -389.860285)
			(xy 301.804226 -389.874391) (xy 301.855555 -389.896203) (xy 301.903161 -389.925257) (xy 301.946029 -389.960932)
			(xy 301.983246 -390.002469) (xy 302.014019 -390.048982) (xy 302.037691 -390.099479) (xy 302.053759 -390.152886)
			(xy 302.061879 -390.208062) (xy 302.062388 -390.235948) (xy 302.061879 -390.263834) (xy 302.053759 -390.31901)
			(xy 302.037691 -390.372417) (xy 302.014019 -390.422914) (xy 301.983246 -390.469427) (xy 301.946029 -390.510964)
			(xy 301.903161 -390.546639) (xy 301.855555 -390.575693) (xy 301.804226 -390.597505) (xy 301.750269 -390.611611)
			(xy 301.694832 -390.617711) (xy 301.639098 -390.615674) (xy 301.584255 -390.605544) (xy 301.531471 -390.587537)
			(xy 301.481871 -390.562036) (xy 301.436513 -390.529585) (xy 301.396364 -390.490876) (xy 301.362278 -390.446733)
			(xy 301.334982 -390.398098) (xy 301.315059 -390.346007) (xy 301.302933 -390.29157) (xy 301.298862 -390.235948)
			(xy 298.660102 -390.235948) (xy 298.589235 -390.246137) (xy 298.50461 -390.250169) (xy 298.419985 -390.246137)
			(xy 298.336126 -390.23408) (xy 298.253793 -390.214106) (xy 298.173731 -390.186397) (xy 298.096666 -390.151202)
			(xy 298.023296 -390.108842) (xy 297.954284 -390.059699) (xy 297.890256 -390.004218) (xy 297.831791 -389.942903)
			(xy 297.77942 -389.876307) (xy 297.733617 -389.805035) (xy 297.694795 -389.729732) (xy 297.663307 -389.65108)
			(xy 297.639439 -389.56979) (xy 297.623405 -389.4866) (xy 297.615352 -389.402263) (xy 288.344868 -389.402263)
			(xy 288.336815 -389.4866) (xy 288.320781 -389.56979) (xy 288.296913 -389.65108) (xy 288.265425 -389.729732)
			(xy 288.226603 -389.805035) (xy 288.1808 -389.876307) (xy 288.128429 -389.942903) (xy 288.069964 -390.004218)
			(xy 288.005936 -390.059699) (xy 287.936924 -390.108842) (xy 287.863554 -390.151202) (xy 287.786489 -390.186397)
			(xy 287.706427 -390.214106) (xy 287.624094 -390.23408) (xy 287.540235 -390.246137) (xy 287.45561 -390.250169)
			(xy 287.370985 -390.246137) (xy 287.287126 -390.23408) (xy 287.204793 -390.214106) (xy 287.124731 -390.186397)
			(xy 287.047666 -390.151202) (xy 286.974296 -390.108842) (xy 286.905284 -390.059699) (xy 286.841256 -390.004218)
			(xy 286.782791 -389.942903) (xy 286.73042 -389.876307) (xy 286.684617 -389.805035) (xy 286.645795 -389.729732)
			(xy 286.614307 -389.65108) (xy 286.590439 -389.56979) (xy 286.574405 -389.4866) (xy 286.566352 -389.402263)
			(xy 284.98038 -389.402263) (xy 284.98038 -390.74852) (xy 289.828732 -390.74852) (xy 289.829157 -390.717787)
			(xy 289.836564 -390.656768) (xy 289.851272 -390.597088) (xy 289.873068 -390.539615) (xy 289.901633 -390.485189)
			(xy 289.93655 -390.434604) (xy 289.97731 -390.388596) (xy 290.023319 -390.347837) (xy 290.073907 -390.312922)
			(xy 290.128334 -390.28436) (xy 290.185807 -390.262566) (xy 290.245488 -390.24786) (xy 290.306507 -390.240455)
			(xy 290.33724 -390.240012) (xy 290.369283 -390.240508) (xy 290.432859 -390.248584) (xy 290.494917 -390.264579)
			(xy 290.554476 -390.288239) (xy 290.610594 -390.31919) (xy 290.662381 -390.356941) (xy 290.709019 -390.400896)
			(xy 290.749768 -390.450359) (xy 290.783985 -390.504546) (xy 290.811128 -390.562601) (xy 290.830767 -390.623604)
			(xy 290.842591 -390.686591) (xy 290.844986 -390.718548) (xy 290.846452 -390.733661) (xy 290.857061 -390.762093)
			(xy 290.875562 -390.786147) (xy 290.900318 -390.803698) (xy 290.929141 -390.813192) (xy 290.9443 -390.814052)
			(xy 290.977155 -390.815239) (xy 291.042167 -390.825028) (xy 291.105376 -390.843112) (xy 291.165728 -390.86919)
			(xy 291.222216 -390.902827) (xy 291.2739 -390.943462) (xy 291.319917 -390.990417) (xy 291.359501 -391.04291)
			(xy 291.391992 -391.100065) (xy 291.416847 -391.160931) (xy 291.433653 -391.224491) (xy 291.442129 -391.289688)
			(xy 291.442648 -391.32256) (xy 291.442106 -391.353289) (xy 291.434703 -391.414298) (xy 291.42 -391.473971)
			(xy 291.398212 -391.531436) (xy 291.369656 -391.585856) (xy 291.334748 -391.636437) (xy 291.293998 -391.682441)
			(xy 291.248 -391.723199) (xy 291.197424 -391.758114) (xy 291.143009 -391.786679) (xy 291.085547 -391.808477)
			(xy 291.025877 -391.823189) (xy 290.964869 -391.830602) (xy 290.93414 -391.831068) (xy 290.902098 -391.830516)
			(xy 290.838523 -391.822449) (xy 290.776465 -391.806463) (xy 290.716905 -391.78281) (xy 290.660787 -391.751866)
			(xy 290.608999 -391.71412) (xy 290.56236 -391.670169) (xy 290.521609 -391.620711) (xy 290.487392 -391.566526)
			(xy 290.460249 -391.508474) (xy 290.440611 -391.447473) (xy 290.428788 -391.384488) (xy 290.426394 -391.352532)
			(xy 290.424962 -391.337414) (xy 290.414346 -391.308979) (xy 290.395837 -391.284924) (xy 290.371072 -391.267376)
			(xy 290.342242 -391.257886) (xy 290.32708 -391.257028) (xy 290.294229 -391.25578) (xy 290.229223 -391.24599)
			(xy 290.166019 -391.227907) (xy 290.105673 -391.201832) (xy 290.049188 -391.1682) (xy 289.997507 -391.127571)
			(xy 289.95149 -391.080623) (xy 289.911906 -391.028137) (xy 289.879413 -390.97099) (xy 289.854553 -390.910132)
			(xy 289.837741 -390.846579) (xy 289.829256 -390.78139) (xy 289.828732 -390.74852) (xy 284.98038 -390.74852)
			(xy 284.98038 -392.250168) (xy 301.298862 -392.250168) (xy 301.302933 -392.194546) (xy 301.315059 -392.140109)
			(xy 301.334982 -392.088018) (xy 301.362278 -392.039383) (xy 301.396364 -391.99524) (xy 301.436513 -391.956531)
			(xy 301.481871 -391.92408) (xy 301.531471 -391.898579) (xy 301.584255 -391.880572) (xy 301.639098 -391.870442)
			(xy 301.694832 -391.868405) (xy 301.750269 -391.874505) (xy 301.804226 -391.888611) (xy 301.855555 -391.910423)
			(xy 301.903161 -391.939477) (xy 301.946029 -391.975152) (xy 301.983246 -392.016689) (xy 302.014019 -392.063202)
			(xy 302.037691 -392.113699) (xy 302.053759 -392.167106) (xy 302.061879 -392.222282) (xy 302.062388 -392.250168)
			(xy 302.061879 -392.278054) (xy 302.053759 -392.33323) (xy 302.037691 -392.386637) (xy 302.014019 -392.437134)
			(xy 301.983246 -392.483647) (xy 301.946029 -392.525184) (xy 301.903161 -392.560859) (xy 301.855555 -392.589913)
			(xy 301.804226 -392.611725) (xy 301.750269 -392.625831) (xy 301.694832 -392.631931) (xy 301.639098 -392.629894)
			(xy 301.584255 -392.619764) (xy 301.531471 -392.601757) (xy 301.481871 -392.576256) (xy 301.436513 -392.543805)
			(xy 301.396364 -392.505096) (xy 301.362278 -392.460953) (xy 301.334982 -392.412318) (xy 301.315059 -392.360227)
			(xy 301.302933 -392.30579) (xy 301.298862 -392.250168) (xy 284.98038 -392.250168) (xy 284.98038 -393.77239)
			(xy 285.878014 -393.77239) (xy 285.882085 -393.716768) (xy 285.894211 -393.662331) (xy 285.914134 -393.61024)
			(xy 285.94143 -393.561605) (xy 285.975516 -393.517462) (xy 286.015665 -393.478753) (xy 286.061023 -393.446302)
			(xy 286.110623 -393.420801) (xy 286.163407 -393.402794) (xy 286.21825 -393.392664) (xy 286.273984 -393.390627)
			(xy 286.329421 -393.396727) (xy 286.383378 -393.410833) (xy 286.434707 -393.432645) (xy 286.482313 -393.461699)
			(xy 286.525181 -393.497374) (xy 286.562398 -393.538911) (xy 286.593171 -393.585424) (xy 286.616843 -393.635921)
			(xy 286.632911 -393.689328) (xy 286.641031 -393.744504) (xy 286.64154 -393.77239) (xy 286.641466 -393.776454)
			(xy 287.598102 -393.776454) (xy 287.602173 -393.720832) (xy 287.614299 -393.666395) (xy 287.634222 -393.614304)
			(xy 287.661518 -393.565669) (xy 287.695604 -393.521526) (xy 287.735753 -393.482817) (xy 287.781111 -393.450366)
			(xy 287.830711 -393.424865) (xy 287.883495 -393.406858) (xy 287.938338 -393.396728) (xy 287.994072 -393.394691)
			(xy 288.049509 -393.400791) (xy 288.103466 -393.414897) (xy 288.154795 -393.436709) (xy 288.202401 -393.465763)
			(xy 288.245269 -393.501438) (xy 288.282486 -393.542975) (xy 288.313259 -393.589488) (xy 288.336931 -393.639985)
			(xy 288.352999 -393.693392) (xy 288.361119 -393.748568) (xy 288.361628 -393.776454) (xy 289.471608 -393.776454)
			(xy 289.47211 -393.744493) (xy 289.480121 -393.681075) (xy 289.496018 -393.619161) (xy 289.51955 -393.559728)
			(xy 289.550344 -393.503713) (xy 289.587917 -393.451998) (xy 289.631674 -393.405401) (xy 289.680927 -393.364656)
			(xy 289.734898 -393.330405) (xy 289.792737 -393.303188) (xy 289.85353 -393.283435) (xy 289.91632 -393.271457)
			(xy 289.980116 -393.267444) (xy 290.043912 -393.271457) (xy 290.106702 -393.283435) (xy 290.167495 -393.303188)
			(xy 290.225334 -393.330405) (xy 290.279305 -393.364656) (xy 290.328558 -393.405401) (xy 290.372315 -393.451998)
			(xy 290.409888 -393.503713) (xy 290.440682 -393.559728) (xy 290.464214 -393.619161) (xy 290.480111 -393.681075)
			(xy 290.488122 -393.744493) (xy 290.488624 -393.776454) (xy 290.488623 -393.7765) (xy 291.470768 -393.7765)
			(xy 291.474784 -393.712663) (xy 291.48677 -393.649832) (xy 291.506536 -393.589) (xy 291.533771 -393.531124)
			(xy 291.568045 -393.477118) (xy 291.608817 -393.427834) (xy 291.655445 -393.384049) (xy 291.707193 -393.346453)
			(xy 291.763245 -393.315639) (xy 291.822717 -393.292094) (xy 291.884671 -393.276188) (xy 291.94813 -393.268172)
			(xy 291.980112 -393.267692) (xy 292.010658 -393.268138) (xy 292.071311 -393.275449) (xy 292.13065 -393.289975)
			(xy 292.187822 -393.311508) (xy 292.242001 -393.339737) (xy 292.292406 -393.374254) (xy 292.338312 -393.414564)
			(xy 292.379057 -393.460084) (xy 292.396926 -393.484862) (xy 292.405296 -393.496027) (xy 292.426903 -393.51367)
			(xy 292.452477 -393.52481) (xy 292.480111 -393.528618) (xy 292.507745 -393.52481) (xy 292.533319 -393.51367)
			(xy 292.554926 -393.496027) (xy 292.563296 -393.484862) (xy 292.582389 -393.458454) (xy 292.626241 -393.410247)
			(xy 292.675892 -393.368039) (xy 292.730528 -393.332518) (xy 292.789254 -393.304269) (xy 292.851108 -393.283754)
			(xy 292.915076 -393.271309) (xy 292.98011 -393.267138) (xy 293.045144 -393.271309) (xy 293.109112 -393.283754)
			(xy 293.170966 -393.304269) (xy 293.229692 -393.332518) (xy 293.284328 -393.368039) (xy 293.333979 -393.410247)
			(xy 293.377831 -393.458454) (xy 293.396924 -393.484862) (xy 293.405294 -393.496027) (xy 293.426901 -393.51367)
			(xy 293.452475 -393.52481) (xy 293.480109 -393.528618) (xy 293.507743 -393.52481) (xy 293.533317 -393.51367)
			(xy 293.554924 -393.496027) (xy 293.563294 -393.484862) (xy 293.582387 -393.458454) (xy 293.626239 -393.410247)
			(xy 293.67589 -393.368039) (xy 293.730526 -393.332518) (xy 293.789252 -393.304269) (xy 293.851106 -393.283754)
			(xy 293.915074 -393.271309) (xy 293.980108 -393.267138) (xy 294.045142 -393.271309) (xy 294.10911 -393.283754)
			(xy 294.170964 -393.304269) (xy 294.22969 -393.332518) (xy 294.284326 -393.368039) (xy 294.333977 -393.410247)
			(xy 294.377829 -393.458454) (xy 294.396922 -393.484862) (xy 294.405292 -393.496027) (xy 294.426899 -393.51367)
			(xy 294.452473 -393.52481) (xy 294.480107 -393.528618) (xy 294.507741 -393.52481) (xy 294.533315 -393.51367)
			(xy 294.554922 -393.496027) (xy 294.563292 -393.484862) (xy 294.582385 -393.458454) (xy 294.626237 -393.410247)
			(xy 294.675888 -393.368039) (xy 294.730524 -393.332518) (xy 294.78925 -393.304269) (xy 294.851104 -393.283754)
			(xy 294.915072 -393.271309) (xy 294.980106 -393.267138) (xy 295.04514 -393.271309) (xy 295.109108 -393.283754)
			(xy 295.170962 -393.304269) (xy 295.229688 -393.332518) (xy 295.284324 -393.368039) (xy 295.333975 -393.410247)
			(xy 295.377827 -393.458454) (xy 295.39692 -393.484862) (xy 295.40529 -393.496027) (xy 295.426897 -393.51367)
			(xy 295.452471 -393.52481) (xy 295.480105 -393.528618) (xy 295.507739 -393.52481) (xy 295.533313 -393.51367)
			(xy 295.55492 -393.496027) (xy 295.56329 -393.484862) (xy 295.582383 -393.458454) (xy 295.626235 -393.410247)
			(xy 295.675886 -393.368039) (xy 295.730522 -393.332518) (xy 295.789248 -393.304269) (xy 295.851102 -393.283754)
			(xy 295.91507 -393.271309) (xy 295.980104 -393.267138) (xy 296.045138 -393.271309) (xy 296.109106 -393.283754)
			(xy 296.17096 -393.304269) (xy 296.229686 -393.332518) (xy 296.284322 -393.368039) (xy 296.333973 -393.410247)
			(xy 296.377825 -393.458454) (xy 296.396918 -393.484862) (xy 296.405288 -393.496027) (xy 296.426895 -393.51367)
			(xy 296.452469 -393.52481) (xy 296.480103 -393.528618) (xy 296.507737 -393.52481) (xy 296.533311 -393.51367)
			(xy 296.554918 -393.496027) (xy 296.563288 -393.484862) (xy 296.581151 -393.46008) (xy 296.621903 -393.414568)
			(xy 296.667813 -393.374265) (xy 296.71822 -393.339752) (xy 296.772399 -393.311525) (xy 296.829568 -393.289992)
			(xy 296.888906 -393.275462) (xy 296.949557 -393.268144) (xy 296.980102 -393.267692) (xy 297.012076 -393.268286)
			(xy 297.07552 -393.276301) (xy 297.137459 -393.292204) (xy 297.196916 -393.315745) (xy 297.252954 -393.346553)
			(xy 297.304689 -393.384141) (xy 297.308892 -393.388088) (xy 301.298862 -393.388088) (xy 301.302933 -393.332466)
			(xy 301.315059 -393.278029) (xy 301.334982 -393.225938) (xy 301.362278 -393.177303) (xy 301.396364 -393.13316)
			(xy 301.436513 -393.094451) (xy 301.481871 -393.062) (xy 301.531471 -393.036499) (xy 301.584255 -393.018492)
			(xy 301.639098 -393.008362) (xy 301.694832 -393.006325) (xy 301.750269 -393.012425) (xy 301.804226 -393.026531)
			(xy 301.855555 -393.048343) (xy 301.903161 -393.077397) (xy 301.946029 -393.113072) (xy 301.983246 -393.154609)
			(xy 302.014019 -393.201122) (xy 302.037691 -393.251619) (xy 302.053759 -393.305026) (xy 302.061879 -393.360202)
			(xy 302.062388 -393.388088) (xy 302.061879 -393.415974) (xy 302.053759 -393.47115) (xy 302.037691 -393.524557)
			(xy 302.014019 -393.575054) (xy 301.983246 -393.621567) (xy 301.946029 -393.663104) (xy 301.903161 -393.698779)
			(xy 301.855555 -393.727833) (xy 301.804226 -393.749645) (xy 301.750269 -393.763751) (xy 301.694832 -393.769851)
			(xy 301.639098 -393.767814) (xy 301.584255 -393.757684) (xy 301.531471 -393.739677) (xy 301.481871 -393.714176)
			(xy 301.436513 -393.681725) (xy 301.396364 -393.643016) (xy 301.362278 -393.598873) (xy 301.334982 -393.550238)
			(xy 301.315059 -393.498147) (xy 301.302933 -393.44371) (xy 301.298862 -393.388088) (xy 297.308892 -393.388088)
			(xy 297.351305 -393.427916) (xy 297.392067 -393.477189) (xy 297.426332 -393.531182) (xy 297.45356 -393.589044)
			(xy 297.473321 -393.649863) (xy 297.485304 -393.712678) (xy 297.48906 -393.77239) (xy 299.31817 -393.77239)
			(xy 299.322241 -393.716768) (xy 299.334367 -393.662331) (xy 299.35429 -393.61024) (xy 299.381586 -393.561605)
			(xy 299.415672 -393.517462) (xy 299.455821 -393.478753) (xy 299.501179 -393.446302) (xy 299.550779 -393.420801)
			(xy 299.603563 -393.402794) (xy 299.658406 -393.392664) (xy 299.71414 -393.390627) (xy 299.769577 -393.396727)
			(xy 299.823534 -393.410833) (xy 299.874863 -393.432645) (xy 299.922469 -393.461699) (xy 299.965337 -393.497374)
			(xy 300.002554 -393.538911) (xy 300.033327 -393.585424) (xy 300.056999 -393.635921) (xy 300.073067 -393.689328)
			(xy 300.081187 -393.744504) (xy 300.081696 -393.77239) (xy 300.081187 -393.800276) (xy 300.073067 -393.855452)
			(xy 300.056999 -393.908859) (xy 300.033327 -393.959356) (xy 300.002554 -394.005869) (xy 299.965337 -394.047406)
			(xy 299.922469 -394.083081) (xy 299.874863 -394.112135) (xy 299.823534 -394.133947) (xy 299.769577 -394.148053)
			(xy 299.71414 -394.154153) (xy 299.658406 -394.152116) (xy 299.603563 -394.141986) (xy 299.550779 -394.123979)
			(xy 299.501179 -394.098478) (xy 299.455821 -394.066027) (xy 299.415672 -394.027318) (xy 299.381586 -393.983175)
			(xy 299.35429 -393.93454) (xy 299.334367 -393.882449) (xy 299.322241 -393.828012) (xy 299.31817 -393.77239)
			(xy 297.48906 -393.77239) (xy 297.489319 -393.7765) (xy 297.485304 -393.840322) (xy 297.473321 -393.903137)
			(xy 297.45356 -393.963956) (xy 297.426332 -394.021818) (xy 297.392067 -394.075811) (xy 297.351305 -394.125084)
			(xy 297.304689 -394.168859) (xy 297.252954 -394.206447) (xy 297.196916 -394.237255) (xy 297.137459 -394.260796)
			(xy 297.07552 -394.276699) (xy 297.012076 -394.284714) (xy 296.980102 -394.285216) (xy 296.949556 -394.284756)
			(xy 296.888904 -394.277447) (xy 296.829565 -394.262922) (xy 296.772394 -394.241392) (xy 296.718215 -394.213165)
			(xy 296.667809 -394.178649) (xy 296.621903 -394.138341) (xy 296.581158 -394.092823) (xy 296.563288 -394.068046)
			(xy 296.554946 -394.056837) (xy 296.53336 -394.03911) (xy 296.507771 -394.027912) (xy 296.480103 -394.024083)
			(xy 296.452435 -394.027912) (xy 296.426846 -394.03911) (xy 296.40526 -394.056837) (xy 296.396918 -394.068046)
			(xy 296.377825 -394.094454) (xy 296.333973 -394.142661) (xy 296.284322 -394.184869) (xy 296.229686 -394.22039)
			(xy 296.17096 -394.248639) (xy 296.109106 -394.269154) (xy 296.045138 -394.281599) (xy 295.980104 -394.28577)
			(xy 295.91507 -394.281599) (xy 295.851102 -394.269154) (xy 295.789248 -394.248639) (xy 295.730522 -394.22039)
			(xy 295.675886 -394.184869) (xy 295.626235 -394.142661) (xy 295.582383 -394.094454) (xy 295.56329 -394.068046)
			(xy 295.554948 -394.056837) (xy 295.533362 -394.03911) (xy 295.507773 -394.027912) (xy 295.480105 -394.024083)
			(xy 295.452437 -394.027912) (xy 295.426848 -394.03911) (xy 295.405262 -394.056837) (xy 295.39692 -394.068046)
			(xy 295.377827 -394.094454) (xy 295.333975 -394.142661) (xy 295.284324 -394.184869) (xy 295.229688 -394.22039)
			(xy 295.170962 -394.248639) (xy 295.109108 -394.269154) (xy 295.04514 -394.281599) (xy 294.980106 -394.28577)
			(xy 294.915072 -394.281599) (xy 294.851104 -394.269154) (xy 294.78925 -394.248639) (xy 294.730524 -394.22039)
			(xy 294.675888 -394.184869) (xy 294.626237 -394.142661) (xy 294.582385 -394.094454) (xy 294.563292 -394.068046)
			(xy 294.55495 -394.056837) (xy 294.533364 -394.03911) (xy 294.507775 -394.027912) (xy 294.480107 -394.024083)
			(xy 294.452439 -394.027912) (xy 294.42685 -394.03911) (xy 294.405264 -394.056837) (xy 294.396922 -394.068046)
			(xy 294.377829 -394.094454) (xy 294.333977 -394.142661) (xy 294.284326 -394.184869) (xy 294.22969 -394.22039)
			(xy 294.170964 -394.248639) (xy 294.10911 -394.269154) (xy 294.045142 -394.281599) (xy 293.980108 -394.28577)
			(xy 293.915074 -394.281599) (xy 293.851106 -394.269154) (xy 293.789252 -394.248639) (xy 293.730526 -394.22039)
			(xy 293.67589 -394.184869) (xy 293.626239 -394.142661) (xy 293.582387 -394.094454) (xy 293.563294 -394.068046)
			(xy 293.554952 -394.056837) (xy 293.533366 -394.03911) (xy 293.507777 -394.027912) (xy 293.480109 -394.024083)
			(xy 293.452441 -394.027912) (xy 293.426852 -394.03911) (xy 293.405266 -394.056837) (xy 293.396924 -394.068046)
			(xy 293.377831 -394.094454) (xy 293.333979 -394.142661) (xy 293.284328 -394.184869) (xy 293.229692 -394.22039)
			(xy 293.170966 -394.248639) (xy 293.109112 -394.269154) (xy 293.045144 -394.281599) (xy 292.98011 -394.28577)
			(xy 292.915076 -394.281599) (xy 292.851108 -394.269154) (xy 292.789254 -394.248639) (xy 292.730528 -394.22039)
			(xy 292.675892 -394.184869) (xy 292.626241 -394.142661) (xy 292.582389 -394.094454) (xy 292.563296 -394.068046)
			(xy 292.554954 -394.056837) (xy 292.533368 -394.03911) (xy 292.507779 -394.027912) (xy 292.480111 -394.024083)
			(xy 292.452443 -394.027912) (xy 292.426854 -394.03911) (xy 292.405268 -394.056837) (xy 292.396926 -394.068046)
			(xy 292.379057 -394.092823) (xy 292.338306 -394.138335) (xy 292.292396 -394.178638) (xy 292.24199 -394.213151)
			(xy 292.187812 -394.241378) (xy 292.130644 -394.262913) (xy 292.071307 -394.277444) (xy 292.010657 -394.284763)
			(xy 291.980112 -394.285216) (xy 291.94813 -394.284828) (xy 291.884671 -394.276812) (xy 291.822717 -394.260906)
			(xy 291.763245 -394.237361) (xy 291.707193 -394.206547) (xy 291.655445 -394.168951) (xy 291.608817 -394.125166)
			(xy 291.568045 -394.075882) (xy 291.533771 -394.021876) (xy 291.506536 -393.964) (xy 291.48677 -393.903168)
			(xy 291.474784 -393.840337) (xy 291.470768 -393.7765) (xy 290.488623 -393.7765) (xy 290.488229 -393.806099)
			(xy 290.48139 -393.864991) (xy 290.467743 -393.922687) (xy 290.447473 -393.978402) (xy 290.420855 -394.031379)
			(xy 290.388251 -394.080898) (xy 290.369498 -394.10386) (xy 290.389601 -394.127194) (xy 290.424645 -394.177845)
			(xy 290.453311 -394.232359) (xy 290.475177 -394.289939) (xy 290.489924 -394.349739) (xy 290.497335 -394.410884)
			(xy 290.497768 -394.44168) (xy 290.497266 -394.473641) (xy 290.489255 -394.537059) (xy 290.473358 -394.598973)
			(xy 290.457997 -394.637768) (xy 301.298862 -394.637768) (xy 301.302933 -394.582146) (xy 301.315059 -394.527709)
			(xy 301.334982 -394.475618) (xy 301.362278 -394.426983) (xy 301.396364 -394.38284) (xy 301.436513 -394.344131)
			(xy 301.481871 -394.31168) (xy 301.531471 -394.286179) (xy 301.584255 -394.268172) (xy 301.639098 -394.258042)
			(xy 301.694832 -394.256005) (xy 301.750269 -394.262105) (xy 301.804226 -394.276211) (xy 301.855555 -394.298023)
			(xy 301.903161 -394.327077) (xy 301.946029 -394.362752) (xy 301.983246 -394.404289) (xy 302.014019 -394.450802)
			(xy 302.037691 -394.501299) (xy 302.053759 -394.554706) (xy 302.061879 -394.609882) (xy 302.062388 -394.637768)
			(xy 302.061879 -394.665654) (xy 302.053759 -394.72083) (xy 302.037691 -394.774237) (xy 302.014019 -394.824734)
			(xy 301.983246 -394.871247) (xy 301.946029 -394.912784) (xy 301.903161 -394.948459) (xy 301.855555 -394.977513)
			(xy 301.804226 -394.999325) (xy 301.750269 -395.013431) (xy 301.694832 -395.019531) (xy 301.639098 -395.017494)
			(xy 301.584255 -395.007364) (xy 301.531471 -394.989357) (xy 301.481871 -394.963856) (xy 301.436513 -394.931405)
			(xy 301.396364 -394.892696) (xy 301.362278 -394.848553) (xy 301.334982 -394.799918) (xy 301.315059 -394.747827)
			(xy 301.302933 -394.69339) (xy 301.298862 -394.637768) (xy 290.457997 -394.637768) (xy 290.449826 -394.658406)
			(xy 290.419032 -394.714421) (xy 290.381459 -394.766136) (xy 290.337702 -394.812733) (xy 290.288449 -394.853478)
			(xy 290.234478 -394.887729) (xy 290.176639 -394.914946) (xy 290.115846 -394.934699) (xy 290.053056 -394.946677)
			(xy 289.98926 -394.950691) (xy 289.925464 -394.946677) (xy 289.862674 -394.934699) (xy 289.801881 -394.914946)
			(xy 289.744042 -394.887729) (xy 289.690071 -394.853478) (xy 289.640818 -394.812733) (xy 289.597061 -394.766136)
			(xy 289.559488 -394.714421) (xy 289.528694 -394.658406) (xy 289.505162 -394.598973) (xy 289.489265 -394.537059)
			(xy 289.481254 -394.473641) (xy 289.480752 -394.44168) (xy 289.481114 -394.412035) (xy 289.48796 -394.353141)
			(xy 289.501613 -394.295445) (xy 289.52189 -394.239729) (xy 289.548514 -394.186753) (xy 289.581122 -394.137236)
			(xy 289.599878 -394.114274) (xy 289.579756 -394.090955) (xy 289.544712 -394.040303) (xy 289.516047 -393.985785)
			(xy 289.494184 -393.928202) (xy 289.479442 -393.868398) (xy 289.472037 -393.807251) (xy 289.471608 -393.776454)
			(xy 288.361628 -393.776454) (xy 288.361119 -393.80434) (xy 288.352999 -393.859516) (xy 288.336931 -393.912923)
			(xy 288.313259 -393.96342) (xy 288.282486 -394.009933) (xy 288.245269 -394.05147) (xy 288.202401 -394.087145)
			(xy 288.154795 -394.116199) (xy 288.103466 -394.138011) (xy 288.049509 -394.152117) (xy 287.994072 -394.158217)
			(xy 287.938338 -394.15618) (xy 287.883495 -394.14605) (xy 287.830711 -394.128043) (xy 287.781111 -394.102542)
			(xy 287.735753 -394.070091) (xy 287.695604 -394.031382) (xy 287.661518 -393.987239) (xy 287.634222 -393.938604)
			(xy 287.614299 -393.886513) (xy 287.602173 -393.832076) (xy 287.598102 -393.776454) (xy 286.641466 -393.776454)
			(xy 286.641031 -393.800276) (xy 286.632911 -393.855452) (xy 286.616843 -393.908859) (xy 286.593171 -393.959356)
			(xy 286.562398 -394.005869) (xy 286.525181 -394.047406) (xy 286.482313 -394.083081) (xy 286.434707 -394.112135)
			(xy 286.383378 -394.133947) (xy 286.329421 -394.148053) (xy 286.273984 -394.154153) (xy 286.21825 -394.152116)
			(xy 286.163407 -394.141986) (xy 286.110623 -394.123979) (xy 286.061023 -394.098478) (xy 286.015665 -394.066027)
			(xy 285.975516 -394.027318) (xy 285.94143 -393.983175) (xy 285.914134 -393.93454) (xy 285.894211 -393.882449)
			(xy 285.882085 -393.828012) (xy 285.878014 -393.77239) (xy 284.98038 -393.77239) (xy 284.98038 -395.046454)
			(xy 287.18205 -395.046454) (xy 287.186121 -394.990832) (xy 287.198247 -394.936395) (xy 287.21817 -394.884304)
			(xy 287.245466 -394.835669) (xy 287.279552 -394.791526) (xy 287.319701 -394.752817) (xy 287.365059 -394.720366)
			(xy 287.414659 -394.694865) (xy 287.467443 -394.676858) (xy 287.522286 -394.666728) (xy 287.57802 -394.664691)
			(xy 287.633457 -394.670791) (xy 287.687414 -394.684897) (xy 287.738743 -394.706709) (xy 287.786349 -394.735763)
			(xy 287.829217 -394.771438) (xy 287.866434 -394.812975) (xy 287.897207 -394.859488) (xy 287.920879 -394.909985)
			(xy 287.936947 -394.963392) (xy 287.945067 -395.018568) (xy 287.945576 -395.046454) (xy 287.945067 -395.07434)
			(xy 287.936947 -395.129516) (xy 287.920879 -395.182923) (xy 287.897207 -395.23342) (xy 287.866434 -395.279933)
			(xy 287.829217 -395.32147) (xy 287.786349 -395.357145) (xy 287.738743 -395.386199) (xy 287.687414 -395.408011)
			(xy 287.633457 -395.422117) (xy 287.57802 -395.428217) (xy 287.522286 -395.42618) (xy 287.467443 -395.41605)
			(xy 287.414659 -395.398043) (xy 287.365059 -395.372542) (xy 287.319701 -395.340091) (xy 287.279552 -395.301382)
			(xy 287.245466 -395.257239) (xy 287.21817 -395.208604) (xy 287.198247 -395.156513) (xy 287.186121 -395.102076)
			(xy 287.18205 -395.046454) (xy 284.98038 -395.046454) (xy 284.98038 -395.769057) (xy 288.471858 -395.769057)
			(xy 288.471858 -395.705103) (xy 288.479873 -395.641653) (xy 288.495778 -395.579708) (xy 288.519321 -395.520246)
			(xy 288.550131 -395.464202) (xy 288.587723 -395.412462) (xy 288.631502 -395.365842) (xy 288.68078 -395.325076)
			(xy 288.734778 -395.290808) (xy 288.792645 -395.263577) (xy 288.853469 -395.243814) (xy 288.91629 -395.231831)
			(xy 288.980118 -395.227815) (xy 289.043946 -395.231831) (xy 289.106767 -395.243814) (xy 289.167591 -395.263577)
			(xy 289.225458 -395.290808) (xy 289.279456 -395.325076) (xy 289.328734 -395.365842) (xy 289.372513 -395.412462)
			(xy 289.410105 -395.464202) (xy 289.440915 -395.520246) (xy 289.464458 -395.579708) (xy 289.480363 -395.641653)
			(xy 289.488378 -395.705103) (xy 289.48888 -395.73708) (xy 289.488378 -395.769057) (xy 289.480363 -395.832507)
			(xy 289.464458 -395.894452) (xy 289.460191 -395.905228) (xy 301.298862 -395.905228) (xy 301.302933 -395.849606)
			(xy 301.315059 -395.795169) (xy 301.334982 -395.743078) (xy 301.362278 -395.694443) (xy 301.396364 -395.6503)
			(xy 301.436513 -395.611591) (xy 301.481871 -395.57914) (xy 301.531471 -395.553639) (xy 301.584255 -395.535632)
			(xy 301.639098 -395.525502) (xy 301.694832 -395.523465) (xy 301.750269 -395.529565) (xy 301.804226 -395.543671)
			(xy 301.855555 -395.565483) (xy 301.903161 -395.594537) (xy 301.946029 -395.630212) (xy 301.983246 -395.671749)
			(xy 302.014019 -395.718262) (xy 302.037691 -395.768759) (xy 302.053759 -395.822166) (xy 302.061879 -395.877342)
			(xy 302.062388 -395.905228) (xy 302.061879 -395.933114) (xy 302.053759 -395.98829) (xy 302.037691 -396.041697)
			(xy 302.014019 -396.092194) (xy 301.983246 -396.138707) (xy 301.946029 -396.180244) (xy 301.903161 -396.215919)
			(xy 301.855555 -396.244973) (xy 301.804226 -396.266785) (xy 301.750269 -396.280891) (xy 301.694832 -396.286991)
			(xy 301.639098 -396.284954) (xy 301.584255 -396.274824) (xy 301.531471 -396.256817) (xy 301.481871 -396.231316)
			(xy 301.436513 -396.198865) (xy 301.396364 -396.160156) (xy 301.362278 -396.116013) (xy 301.334982 -396.067378)
			(xy 301.315059 -396.015287) (xy 301.302933 -395.96085) (xy 301.298862 -395.905228) (xy 289.460191 -395.905228)
			(xy 289.440915 -395.953914) (xy 289.410105 -396.009958) (xy 289.372513 -396.061698) (xy 289.328734 -396.108318)
			(xy 289.279456 -396.149084) (xy 289.225458 -396.183352) (xy 289.167591 -396.210583) (xy 289.106767 -396.230346)
			(xy 289.043946 -396.242329) (xy 288.980118 -396.246345) (xy 288.91629 -396.242329) (xy 288.853469 -396.230346)
			(xy 288.792645 -396.210583) (xy 288.734778 -396.183352) (xy 288.68078 -396.149084) (xy 288.631502 -396.108318)
			(xy 288.587723 -396.061698) (xy 288.550131 -396.009958) (xy 288.519321 -395.953914) (xy 288.495778 -395.894452)
			(xy 288.479873 -395.832507) (xy 288.471858 -395.769057) (xy 284.98038 -395.769057) (xy 284.98038 -397.048228)
			(xy 301.298862 -397.048228) (xy 301.302933 -396.992606) (xy 301.315059 -396.938169) (xy 301.334982 -396.886078)
			(xy 301.362278 -396.837443) (xy 301.396364 -396.7933) (xy 301.436513 -396.754591) (xy 301.481871 -396.72214)
			(xy 301.531471 -396.696639) (xy 301.584255 -396.678632) (xy 301.639098 -396.668502) (xy 301.694832 -396.666465)
			(xy 301.750269 -396.672565) (xy 301.804226 -396.686671) (xy 301.855555 -396.708483) (xy 301.903161 -396.737537)
			(xy 301.946029 -396.773212) (xy 301.983246 -396.814749) (xy 302.014019 -396.861262) (xy 302.037691 -396.911759)
			(xy 302.053759 -396.965166) (xy 302.061879 -397.020342) (xy 302.062388 -397.048228) (xy 302.061879 -397.076114)
			(xy 302.053759 -397.13129) (xy 302.037691 -397.184697) (xy 302.014019 -397.235194) (xy 301.983246 -397.281707)
			(xy 301.946029 -397.323244) (xy 301.903161 -397.358919) (xy 301.855555 -397.387973) (xy 301.804226 -397.409785)
			(xy 301.750269 -397.423891) (xy 301.694832 -397.429991) (xy 301.639098 -397.427954) (xy 301.584255 -397.417824)
			(xy 301.531471 -397.399817) (xy 301.481871 -397.374316) (xy 301.436513 -397.341865) (xy 301.396364 -397.303156)
			(xy 301.362278 -397.259013) (xy 301.334982 -397.210378) (xy 301.315059 -397.158287) (xy 301.302933 -397.10385)
			(xy 301.298862 -397.048228) (xy 284.98038 -397.048228) (xy 284.98038 -398.80032) (xy 300.428152 -398.80032)
			(xy 300.428638 -398.773069) (xy 300.436394 -398.719121) (xy 300.451749 -398.666826) (xy 300.474391 -398.617249)
			(xy 300.503857 -398.571399) (xy 300.539548 -398.530208) (xy 300.580739 -398.494517) (xy 300.626589 -398.465051)
			(xy 300.676166 -398.442409) (xy 300.728461 -398.427054) (xy 300.782409 -398.419298) (xy 300.836911 -398.419298)
			(xy 300.890859 -398.427054) (xy 300.943154 -398.442409) (xy 300.992731 -398.465051) (xy 301.038581 -398.494517)
			(xy 301.079772 -398.530208) (xy 301.115463 -398.571399) (xy 301.144929 -398.617249) (xy 301.167571 -398.666826)
			(xy 301.182926 -398.719121) (xy 301.190682 -398.773069) (xy 301.191168 -398.80032) (xy 301.190737 -398.826961)
			(xy 301.183308 -398.879723) (xy 301.168611 -398.930939) (xy 301.146932 -398.979612) (xy 301.118692 -399.024796)
			(xy 301.084442 -399.065612) (xy 301.044846 -399.101266) (xy 301.02302 -399.11655) (xy 301.011299 -399.124942)
			(xy 300.992832 -399.147067) (xy 300.981281 -399.173469) (xy 300.977564 -399.202047) (xy 300.981978 -399.230526)
			(xy 300.994171 -399.256639) (xy 301.013172 -399.278306) (xy 301.025052 -399.286476) (xy 301.047839 -399.301586)
			(xy 301.089266 -399.337268) (xy 301.125173 -399.378501) (xy 301.154822 -399.424439) (xy 301.177606 -399.47414)
			(xy 301.193058 -399.526587) (xy 301.200861 -399.580702) (xy 301.201328 -399.60804) (xy 301.200842 -399.635291)
			(xy 301.193086 -399.689239) (xy 301.177731 -399.741534) (xy 301.155089 -399.791111) (xy 301.125623 -399.836961)
			(xy 301.089932 -399.878152) (xy 301.048741 -399.913843) (xy 301.002891 -399.943309) (xy 300.953314 -399.965951)
			(xy 300.901019 -399.981306) (xy 300.847071 -399.989062) (xy 300.792569 -399.989062) (xy 300.738621 -399.981306)
			(xy 300.686326 -399.965951) (xy 300.636749 -399.943309) (xy 300.590899 -399.913843) (xy 300.549708 -399.878152)
			(xy 300.514017 -399.836961) (xy 300.484551 -399.791111) (xy 300.461909 -399.741534) (xy 300.446554 -399.689239)
			(xy 300.438798 -399.635291) (xy 300.438312 -399.60804) (xy 300.438798 -399.581401) (xy 300.446218 -399.528641)
			(xy 300.460906 -399.477427) (xy 300.482577 -399.428755) (xy 300.510807 -399.38357) (xy 300.54505 -399.342753)
			(xy 300.584638 -399.307096) (xy 300.60646 -399.29181) (xy 300.618124 -399.283345) (xy 300.636592 -399.261237)
			(xy 300.648149 -399.234851) (xy 300.651874 -399.206286) (xy 300.647471 -399.177818) (xy 300.63529 -399.151714)
			(xy 300.616302 -399.130052) (xy 300.604428 -399.121884) (xy 300.581618 -399.106807) (xy 300.540192 -399.071119)
			(xy 300.504288 -399.02988) (xy 300.474642 -398.983937) (xy 300.451862 -398.93423) (xy 300.436414 -398.881779)
			(xy 300.428616 -398.827659) (xy 300.428152 -398.80032) (xy 284.98038 -398.80032) (xy 284.98038 -399.9835)
			(xy 289.606441 -399.9835) (xy 289.610455 -399.919698) (xy 289.622434 -399.856902) (xy 289.642189 -399.796103)
			(xy 289.669408 -399.73826) (xy 289.703662 -399.684283) (xy 289.744411 -399.635026) (xy 289.791013 -399.591264)
			(xy 289.842731 -399.553688) (xy 289.898752 -399.52289) (xy 289.958191 -399.499357) (xy 290.02011 -399.483458)
			(xy 290.083534 -399.475446) (xy 290.115498 -399.474944) (xy 290.147265 -399.475449) (xy 290.210306 -399.483357)
			(xy 290.271872 -399.49905) (xy 290.331006 -399.522285) (xy 290.386788 -399.552699) (xy 290.438351 -399.589821)
			(xy 290.461954 -399.611088) (xy 290.469217 -399.617272) (xy 290.486967 -399.624223) (xy 290.506029 -399.624223)
			(xy 290.523779 -399.617272) (xy 290.531042 -399.611088) (xy 290.554606 -399.589771) (xy 290.606161 -399.552623)
			(xy 290.661946 -399.522195) (xy 290.721091 -399.498962) (xy 290.782671 -399.483285) (xy 290.845725 -399.47541)
			(xy 290.877498 -399.474944) (xy 290.909457 -399.475521) (xy 290.972872 -399.483532) (xy 291.034783 -399.499427)
			(xy 291.094213 -399.522957) (xy 291.150226 -399.55375) (xy 291.201937 -399.591321) (xy 291.248532 -399.635076)
			(xy 291.289276 -399.684326) (xy 291.323525 -399.738295) (xy 291.350741 -399.79613) (xy 291.370493 -399.856921)
			(xy 291.38247 -399.919707) (xy 291.386484 -399.9835) (xy 292.146441 -399.9835) (xy 292.150455 -399.919698)
			(xy 292.162434 -399.856902) (xy 292.182189 -399.796103) (xy 292.209408 -399.73826) (xy 292.243662 -399.684283)
			(xy 292.284411 -399.635026) (xy 292.331013 -399.591264) (xy 292.382731 -399.553688) (xy 292.438752 -399.52289)
			(xy 292.498191 -399.499357) (xy 292.56011 -399.483458) (xy 292.623534 -399.475446) (xy 292.655498 -399.474944)
			(xy 292.687265 -399.475449) (xy 292.750306 -399.483357) (xy 292.811872 -399.49905) (xy 292.871006 -399.522285)
			(xy 292.926788 -399.552699) (xy 292.978351 -399.589821) (xy 293.001954 -399.611088) (xy 293.009217 -399.617272)
			(xy 293.026967 -399.624223) (xy 293.046029 -399.624223) (xy 293.063779 -399.617272) (xy 293.071042 -399.611088)
			(xy 293.094606 -399.589771) (xy 293.146161 -399.552623) (xy 293.201946 -399.522195) (xy 293.261091 -399.498962)
			(xy 293.322671 -399.483285) (xy 293.385725 -399.47541) (xy 293.417498 -399.474944) (xy 293.449457 -399.475521)
			(xy 293.512872 -399.483532) (xy 293.574783 -399.499427) (xy 293.634213 -399.522957) (xy 293.690226 -399.55375)
			(xy 293.741937 -399.591321) (xy 293.788532 -399.635076) (xy 293.829276 -399.684326) (xy 293.863525 -399.738295)
			(xy 293.890741 -399.79613) (xy 293.910493 -399.856921) (xy 293.92247 -399.919707) (xy 293.926484 -399.9835)
			(xy 294.53602 -399.9835) (xy 294.540035 -399.919693) (xy 294.552015 -399.856892) (xy 294.571773 -399.796089)
			(xy 294.598995 -399.738241) (xy 294.633253 -399.684261) (xy 294.674007 -399.635001) (xy 294.720613 -399.591237)
			(xy 294.772338 -399.55366) (xy 294.828364 -399.522862) (xy 294.887809 -399.499329) (xy 294.949734 -399.483433)
			(xy 295.013163 -399.475423) (xy 295.04513 -399.474944) (xy 295.076898 -399.475429) (xy 295.13994 -399.483341)
			(xy 295.201506 -399.499038) (xy 295.26064 -399.522277) (xy 295.316422 -399.552695) (xy 295.367984 -399.589819)
			(xy 295.391586 -399.611088) (xy 295.398849 -399.617272) (xy 295.416599 -399.624223) (xy 295.435661 -399.624223)
			(xy 295.453411 -399.617272) (xy 295.460674 -399.611088) (xy 295.484266 -399.589803) (xy 295.535815 -399.552653)
			(xy 295.591594 -399.52222) (xy 295.650733 -399.49898) (xy 295.712309 -399.483297) (xy 295.775359 -399.475414)
			(xy 295.80713 -399.474944) (xy 295.839087 -399.475544) (xy 295.902496 -399.483558) (xy 295.964401 -399.499455)
			(xy 296.023825 -399.522986) (xy 296.079832 -399.553779) (xy 296.131538 -399.591348) (xy 296.178128 -399.635102)
			(xy 296.218866 -399.684349) (xy 296.253112 -399.738314) (xy 296.280324 -399.796145) (xy 296.300074 -399.856931)
			(xy 296.312049 -399.919712) (xy 296.316063 -399.9835) (xy 297.07602 -399.9835) (xy 297.080035 -399.919693)
			(xy 297.092015 -399.856892) (xy 297.111773 -399.796089) (xy 297.138995 -399.738241) (xy 297.173253 -399.684261)
			(xy 297.214007 -399.635001) (xy 297.260613 -399.591237) (xy 297.312338 -399.55366) (xy 297.368364 -399.522862)
			(xy 297.427809 -399.499329) (xy 297.489734 -399.483433) (xy 297.553163 -399.475423) (xy 297.58513 -399.474944)
			(xy 297.616898 -399.475429) (xy 297.67994 -399.483341) (xy 297.741506 -399.499038) (xy 297.80064 -399.522277)
			(xy 297.856422 -399.552695) (xy 297.907984 -399.589819) (xy 297.931586 -399.611088) (xy 297.938849 -399.617272)
			(xy 297.956599 -399.624223) (xy 297.975661 -399.624223) (xy 297.993411 -399.617272) (xy 298.000674 -399.611088)
			(xy 298.024266 -399.589803) (xy 298.075815 -399.552653) (xy 298.131594 -399.52222) (xy 298.190733 -399.49898)
			(xy 298.252309 -399.483297) (xy 298.315359 -399.475414) (xy 298.34713 -399.474944) (xy 298.379087 -399.475544)
			(xy 298.442496 -399.483558) (xy 298.504401 -399.499455) (xy 298.563825 -399.522986) (xy 298.619832 -399.553779)
			(xy 298.671538 -399.591348) (xy 298.718128 -399.635102) (xy 298.758866 -399.684349) (xy 298.793112 -399.738314)
			(xy 298.820324 -399.796145) (xy 298.840074 -399.856931) (xy 298.852049 -399.919712) (xy 298.856063 -399.9835)
			(xy 298.852049 -400.047288) (xy 298.840074 -400.110069) (xy 298.820324 -400.170855) (xy 298.793112 -400.228686)
			(xy 298.758866 -400.282651) (xy 298.718128 -400.331898) (xy 298.671538 -400.375652) (xy 298.619832 -400.413221)
			(xy 298.563825 -400.444014) (xy 298.504401 -400.467545) (xy 298.442496 -400.483442) (xy 298.379087 -400.491456)
			(xy 298.34713 -400.49196) (xy 298.315363 -400.491437) (xy 298.252323 -400.483532) (xy 298.190757 -400.467842)
			(xy 298.131623 -400.444611) (xy 298.075841 -400.4142) (xy 298.024278 -400.377082) (xy 298.000674 -400.355816)
			(xy 297.993411 -400.349632) (xy 297.975661 -400.342681) (xy 297.956599 -400.342681) (xy 297.938849 -400.349632)
			(xy 297.931586 -400.355816) (xy 297.908011 -400.377121) (xy 297.856458 -400.414269) (xy 297.800675 -400.444699)
			(xy 297.741533 -400.467935) (xy 297.679955 -400.483614) (xy 297.616902 -400.491492) (xy 297.58513 -400.49196)
			(xy 297.553163 -400.491577) (xy 297.489734 -400.483567) (xy 297.427809 -400.467671) (xy 297.368364 -400.444138)
			(xy 297.312338 -400.41334) (xy 297.260613 -400.375763) (xy 297.214007 -400.331999) (xy 297.173253 -400.282739)
			(xy 297.138995 -400.228759) (xy 297.111773 -400.170911) (xy 297.092015 -400.110108) (xy 297.080035 -400.047307)
			(xy 297.07602 -399.9835) (xy 296.316063 -399.9835) (xy 296.312049 -400.047288) (xy 296.300074 -400.110069)
			(xy 296.280324 -400.170855) (xy 296.253112 -400.228686) (xy 296.218866 -400.282651) (xy 296.178128 -400.331898)
			(xy 296.131538 -400.375652) (xy 296.079832 -400.413221) (xy 296.023825 -400.444014) (xy 295.964401 -400.467545)
			(xy 295.902496 -400.483442) (xy 295.839087 -400.491456) (xy 295.80713 -400.49196) (xy 295.775363 -400.491437)
			(xy 295.712323 -400.483532) (xy 295.650757 -400.467842) (xy 295.591623 -400.444611) (xy 295.535841 -400.4142)
			(xy 295.484278 -400.377082) (xy 295.460674 -400.355816) (xy 295.453411 -400.349632) (xy 295.435661 -400.342681)
			(xy 295.416599 -400.342681) (xy 295.398849 -400.349632) (xy 295.391586 -400.355816) (xy 295.368011 -400.377121)
			(xy 295.316458 -400.414269) (xy 295.260675 -400.444699) (xy 295.201533 -400.467935) (xy 295.139955 -400.483614)
			(xy 295.076902 -400.491492) (xy 295.04513 -400.49196) (xy 295.013163 -400.491577) (xy 294.949734 -400.483567)
			(xy 294.887809 -400.467671) (xy 294.828364 -400.444138) (xy 294.772338 -400.41334) (xy 294.720613 -400.375763)
			(xy 294.674007 -400.331999) (xy 294.633253 -400.282739) (xy 294.598995 -400.228759) (xy 294.571773 -400.170911)
			(xy 294.552015 -400.110108) (xy 294.540035 -400.047307) (xy 294.53602 -399.9835) (xy 293.926484 -399.9835)
			(xy 293.92247 -400.047293) (xy 293.910493 -400.110079) (xy 293.890741 -400.17087) (xy 293.863525 -400.228705)
			(xy 293.829276 -400.282674) (xy 293.788532 -400.331924) (xy 293.741937 -400.375679) (xy 293.690226 -400.41325)
			(xy 293.634213 -400.444043) (xy 293.574783 -400.467573) (xy 293.512872 -400.483468) (xy 293.449457 -400.491479)
			(xy 293.417498 -400.49196) (xy 293.385731 -400.491456) (xy 293.32269 -400.483548) (xy 293.261124 -400.467854)
			(xy 293.20199 -400.444619) (xy 293.146208 -400.414205) (xy 293.094645 -400.377084) (xy 293.071042 -400.355816)
			(xy 293.063779 -400.349632) (xy 293.046029 -400.342681) (xy 293.026967 -400.342681) (xy 293.009217 -400.349632)
			(xy 293.001954 -400.355816) (xy 292.978351 -400.377088) (xy 292.926804 -400.41424) (xy 292.871027 -400.444674)
			(xy 292.811891 -400.467916) (xy 292.750317 -400.483602) (xy 292.687268 -400.491488) (xy 292.655498 -400.49196)
			(xy 292.623534 -400.491554) (xy 292.56011 -400.483542) (xy 292.498191 -400.467643) (xy 292.438752 -400.44411)
			(xy 292.382731 -400.413312) (xy 292.331013 -400.375736) (xy 292.284411 -400.331974) (xy 292.243662 -400.282717)
			(xy 292.209408 -400.22874) (xy 292.182189 -400.170897) (xy 292.162434 -400.110098) (xy 292.150455 -400.047302)
			(xy 292.146441 -399.9835) (xy 291.386484 -399.9835) (xy 291.38247 -400.047293) (xy 291.370493 -400.110079)
			(xy 291.350741 -400.17087) (xy 291.323525 -400.228705) (xy 291.289276 -400.282674) (xy 291.248532 -400.331924)
			(xy 291.201937 -400.375679) (xy 291.150226 -400.41325) (xy 291.094213 -400.444043) (xy 291.034783 -400.467573)
			(xy 290.972872 -400.483468) (xy 290.909457 -400.491479) (xy 290.877498 -400.49196) (xy 290.845731 -400.491456)
			(xy 290.78269 -400.483548) (xy 290.721124 -400.467854) (xy 290.66199 -400.444619) (xy 290.606208 -400.414205)
			(xy 290.554645 -400.377084) (xy 290.531042 -400.355816) (xy 290.523779 -400.349632) (xy 290.506029 -400.342681)
			(xy 290.486967 -400.342681) (xy 290.469217 -400.349632) (xy 290.461954 -400.355816) (xy 290.438351 -400.377088)
			(xy 290.386804 -400.41424) (xy 290.331027 -400.444674) (xy 290.271891 -400.467916) (xy 290.210317 -400.483602)
			(xy 290.147268 -400.491488) (xy 290.115498 -400.49196) (xy 290.083534 -400.491554) (xy 290.02011 -400.483542)
			(xy 289.958191 -400.467643) (xy 289.898752 -400.44411) (xy 289.842731 -400.413312) (xy 289.791013 -400.375736)
			(xy 289.744411 -400.331974) (xy 289.703662 -400.282717) (xy 289.669408 -400.22874) (xy 289.642189 -400.170897)
			(xy 289.622434 -400.110098) (xy 289.610455 -400.047302) (xy 289.606441 -399.9835) (xy 284.98038 -399.9835)
			(xy 284.98038 -402.0155) (xy 287.066441 -402.0155) (xy 287.070455 -401.951698) (xy 287.082434 -401.888902)
			(xy 287.102189 -401.828103) (xy 287.129408 -401.77026) (xy 287.163662 -401.716283) (xy 287.204411 -401.667026)
			(xy 287.251013 -401.623264) (xy 287.302731 -401.585688) (xy 287.358752 -401.55489) (xy 287.418191 -401.531357)
			(xy 287.48011 -401.515458) (xy 287.543534 -401.507446) (xy 287.575498 -401.506944) (xy 287.607265 -401.507449)
			(xy 287.670306 -401.515357) (xy 287.731872 -401.53105) (xy 287.791006 -401.554285) (xy 287.846788 -401.584699)
			(xy 287.898351 -401.621821) (xy 287.921954 -401.643088) (xy 287.929217 -401.649272) (xy 287.946967 -401.656223)
			(xy 287.966029 -401.656223) (xy 287.983779 -401.649272) (xy 287.991042 -401.643088) (xy 288.014606 -401.621771)
			(xy 288.066161 -401.584623) (xy 288.121946 -401.554195) (xy 288.181091 -401.530962) (xy 288.242671 -401.515285)
			(xy 288.305725 -401.50741) (xy 288.337498 -401.506944) (xy 288.369457 -401.507521) (xy 288.432872 -401.515532)
			(xy 288.494783 -401.531427) (xy 288.554213 -401.554957) (xy 288.610226 -401.58575) (xy 288.661937 -401.623321)
			(xy 288.708532 -401.667076) (xy 288.749276 -401.716326) (xy 288.783525 -401.770295) (xy 288.810741 -401.82813)
			(xy 288.830493 -401.888921) (xy 288.84247 -401.951707) (xy 288.846484 -402.0155) (xy 289.606441 -402.0155)
			(xy 289.610455 -401.951698) (xy 289.622434 -401.888902) (xy 289.642189 -401.828103) (xy 289.669408 -401.77026)
			(xy 289.703662 -401.716283) (xy 289.744411 -401.667026) (xy 289.791013 -401.623264) (xy 289.842731 -401.585688)
			(xy 289.898752 -401.55489) (xy 289.958191 -401.531357) (xy 290.02011 -401.515458) (xy 290.083534 -401.507446)
			(xy 290.115498 -401.506944) (xy 290.147265 -401.507449) (xy 290.210306 -401.515357) (xy 290.271872 -401.53105)
			(xy 290.331006 -401.554285) (xy 290.386788 -401.584699) (xy 290.438351 -401.621821) (xy 290.461954 -401.643088)
			(xy 290.469217 -401.649272) (xy 290.486967 -401.656223) (xy 290.506029 -401.656223) (xy 290.523779 -401.649272)
			(xy 290.531042 -401.643088) (xy 290.554606 -401.621771) (xy 290.606161 -401.584623) (xy 290.661946 -401.554195)
			(xy 290.721091 -401.530962) (xy 290.782671 -401.515285) (xy 290.845725 -401.50741) (xy 290.877498 -401.506944)
			(xy 290.909457 -401.507521) (xy 290.972872 -401.515532) (xy 291.034783 -401.531427) (xy 291.094213 -401.554957)
			(xy 291.150226 -401.58575) (xy 291.201937 -401.623321) (xy 291.248532 -401.667076) (xy 291.289276 -401.716326)
			(xy 291.323525 -401.770295) (xy 291.350741 -401.82813) (xy 291.370493 -401.888921) (xy 291.38247 -401.951707)
			(xy 291.386484 -402.0155) (xy 292.146441 -402.0155) (xy 292.150455 -401.951698) (xy 292.162434 -401.888902)
			(xy 292.182189 -401.828103) (xy 292.209408 -401.77026) (xy 292.243662 -401.716283) (xy 292.284411 -401.667026)
			(xy 292.331013 -401.623264) (xy 292.382731 -401.585688) (xy 292.438752 -401.55489) (xy 292.498191 -401.531357)
			(xy 292.56011 -401.515458) (xy 292.623534 -401.507446) (xy 292.655498 -401.506944) (xy 292.687265 -401.507449)
			(xy 292.750306 -401.515357) (xy 292.811872 -401.53105) (xy 292.871006 -401.554285) (xy 292.926788 -401.584699)
			(xy 292.978351 -401.621821) (xy 293.001954 -401.643088) (xy 293.009217 -401.649272) (xy 293.026967 -401.656223)
			(xy 293.046029 -401.656223) (xy 293.063779 -401.649272) (xy 293.071042 -401.643088) (xy 293.094606 -401.621771)
			(xy 293.146161 -401.584623) (xy 293.201946 -401.554195) (xy 293.261091 -401.530962) (xy 293.322671 -401.515285)
			(xy 293.385725 -401.50741) (xy 293.417498 -401.506944) (xy 293.449457 -401.507521) (xy 293.512872 -401.515532)
			(xy 293.574783 -401.531427) (xy 293.634213 -401.554957) (xy 293.690226 -401.58575) (xy 293.741937 -401.623321)
			(xy 293.788532 -401.667076) (xy 293.829276 -401.716326) (xy 293.863525 -401.770295) (xy 293.890741 -401.82813)
			(xy 293.910493 -401.888921) (xy 293.92247 -401.951707) (xy 293.926484 -402.0155) (xy 294.53602 -402.0155)
			(xy 294.540035 -401.951693) (xy 294.552015 -401.888892) (xy 294.571773 -401.828089) (xy 294.598995 -401.770241)
			(xy 294.633253 -401.716261) (xy 294.674007 -401.667001) (xy 294.720613 -401.623237) (xy 294.772338 -401.58566)
			(xy 294.828364 -401.554862) (xy 294.887809 -401.531329) (xy 294.949734 -401.515433) (xy 295.013163 -401.507423)
			(xy 295.04513 -401.506944) (xy 295.076898 -401.507429) (xy 295.13994 -401.515341) (xy 295.201506 -401.531038)
			(xy 295.26064 -401.554277) (xy 295.316422 -401.584695) (xy 295.367984 -401.621819) (xy 295.391586 -401.643088)
			(xy 295.398849 -401.649272) (xy 295.416599 -401.656223) (xy 295.435661 -401.656223) (xy 295.453411 -401.649272)
			(xy 295.460674 -401.643088) (xy 295.484266 -401.621803) (xy 295.535815 -401.584653) (xy 295.591594 -401.55422)
			(xy 295.650733 -401.53098) (xy 295.712309 -401.515297) (xy 295.775359 -401.507414) (xy 295.80713 -401.506944)
			(xy 295.839087 -401.507544) (xy 295.902496 -401.515558) (xy 295.964401 -401.531455) (xy 296.023825 -401.554986)
			(xy 296.079832 -401.585779) (xy 296.131538 -401.623348) (xy 296.178128 -401.667102) (xy 296.218866 -401.716349)
			(xy 296.253112 -401.770314) (xy 296.280324 -401.828145) (xy 296.300074 -401.888931) (xy 296.312049 -401.951712)
			(xy 296.316063 -402.0155) (xy 297.07602 -402.0155) (xy 297.080035 -401.951693) (xy 297.092015 -401.888892)
			(xy 297.111773 -401.828089) (xy 297.138995 -401.770241) (xy 297.173253 -401.716261) (xy 297.214007 -401.667001)
			(xy 297.260613 -401.623237) (xy 297.312338 -401.58566) (xy 297.368364 -401.554862) (xy 297.427809 -401.531329)
			(xy 297.489734 -401.515433) (xy 297.553163 -401.507423) (xy 297.58513 -401.506944) (xy 297.616898 -401.507429)
			(xy 297.67994 -401.515341) (xy 297.741506 -401.531038) (xy 297.80064 -401.554277) (xy 297.856422 -401.584695)
			(xy 297.907984 -401.621819) (xy 297.931586 -401.643088) (xy 297.938849 -401.649272) (xy 297.956599 -401.656223)
			(xy 297.975661 -401.656223) (xy 297.993411 -401.649272) (xy 298.000674 -401.643088) (xy 298.024266 -401.621803)
			(xy 298.075815 -401.584653) (xy 298.131594 -401.55422) (xy 298.190733 -401.53098) (xy 298.252309 -401.515297)
			(xy 298.315359 -401.507414) (xy 298.34713 -401.506944) (xy 298.379087 -401.507544) (xy 298.442496 -401.515558)
			(xy 298.504401 -401.531455) (xy 298.563825 -401.554986) (xy 298.619832 -401.585779) (xy 298.671538 -401.623348)
			(xy 298.718128 -401.667102) (xy 298.758866 -401.716349) (xy 298.793112 -401.770314) (xy 298.820324 -401.828145)
			(xy 298.840074 -401.888931) (xy 298.852049 -401.951712) (xy 298.856063 -402.0155) (xy 298.852049 -402.079288)
			(xy 298.840074 -402.142069) (xy 298.820324 -402.202855) (xy 298.793112 -402.260686) (xy 298.758866 -402.314651)
			(xy 298.718128 -402.363898) (xy 298.671538 -402.407652) (xy 298.619832 -402.445221) (xy 298.563825 -402.476014)
			(xy 298.504401 -402.499545) (xy 298.442496 -402.515442) (xy 298.379087 -402.523456) (xy 298.34713 -402.52396)
			(xy 298.315363 -402.523437) (xy 298.252323 -402.515532) (xy 298.190757 -402.499842) (xy 298.131623 -402.476611)
			(xy 298.075841 -402.4462) (xy 298.024278 -402.409082) (xy 298.000674 -402.387816) (xy 297.993411 -402.381632)
			(xy 297.975661 -402.374681) (xy 297.956599 -402.374681) (xy 297.938849 -402.381632) (xy 297.931586 -402.387816)
			(xy 297.908011 -402.409121) (xy 297.856458 -402.446269) (xy 297.800675 -402.476699) (xy 297.741533 -402.499935)
			(xy 297.679955 -402.515614) (xy 297.616902 -402.523492) (xy 297.58513 -402.52396) (xy 297.553163 -402.523577)
			(xy 297.489734 -402.515567) (xy 297.427809 -402.499671) (xy 297.368364 -402.476138) (xy 297.312338 -402.44534)
			(xy 297.260613 -402.407763) (xy 297.214007 -402.363999) (xy 297.173253 -402.314739) (xy 297.138995 -402.260759)
			(xy 297.111773 -402.202911) (xy 297.092015 -402.142108) (xy 297.080035 -402.079307) (xy 297.07602 -402.0155)
			(xy 296.316063 -402.0155) (xy 296.312049 -402.079288) (xy 296.300074 -402.142069) (xy 296.280324 -402.202855)
			(xy 296.253112 -402.260686) (xy 296.218866 -402.314651) (xy 296.178128 -402.363898) (xy 296.131538 -402.407652)
			(xy 296.079832 -402.445221) (xy 296.023825 -402.476014) (xy 295.964401 -402.499545) (xy 295.902496 -402.515442)
			(xy 295.839087 -402.523456) (xy 295.80713 -402.52396) (xy 295.775363 -402.523437) (xy 295.712323 -402.515532)
			(xy 295.650757 -402.499842) (xy 295.591623 -402.476611) (xy 295.535841 -402.4462) (xy 295.484278 -402.409082)
			(xy 295.460674 -402.387816) (xy 295.453411 -402.381632) (xy 295.435661 -402.374681) (xy 295.416599 -402.374681)
			(xy 295.398849 -402.381632) (xy 295.391586 -402.387816) (xy 295.368011 -402.409121) (xy 295.316458 -402.446269)
			(xy 295.260675 -402.476699) (xy 295.201533 -402.499935) (xy 295.139955 -402.515614) (xy 295.076902 -402.523492)
			(xy 295.04513 -402.52396) (xy 295.013163 -402.523577) (xy 294.949734 -402.515567) (xy 294.887809 -402.499671)
			(xy 294.828364 -402.476138) (xy 294.772338 -402.44534) (xy 294.720613 -402.407763) (xy 294.674007 -402.363999)
			(xy 294.633253 -402.314739) (xy 294.598995 -402.260759) (xy 294.571773 -402.202911) (xy 294.552015 -402.142108)
			(xy 294.540035 -402.079307) (xy 294.53602 -402.0155) (xy 293.926484 -402.0155) (xy 293.92247 -402.079293)
			(xy 293.910493 -402.142079) (xy 293.890741 -402.20287) (xy 293.863525 -402.260705) (xy 293.829276 -402.314674)
			(xy 293.788532 -402.363924) (xy 293.741937 -402.407679) (xy 293.690226 -402.44525) (xy 293.634213 -402.476043)
			(xy 293.574783 -402.499573) (xy 293.512872 -402.515468) (xy 293.449457 -402.523479) (xy 293.417498 -402.52396)
			(xy 293.385731 -402.523456) (xy 293.32269 -402.515548) (xy 293.261124 -402.499854) (xy 293.20199 -402.476619)
			(xy 293.146208 -402.446205) (xy 293.094645 -402.409084) (xy 293.071042 -402.387816) (xy 293.063779 -402.381632)
			(xy 293.046029 -402.374681) (xy 293.026967 -402.374681) (xy 293.009217 -402.381632) (xy 293.001954 -402.387816)
			(xy 292.978351 -402.409088) (xy 292.926804 -402.44624) (xy 292.871027 -402.476674) (xy 292.811891 -402.499916)
			(xy 292.750317 -402.515602) (xy 292.687268 -402.523488) (xy 292.655498 -402.52396) (xy 292.623534 -402.523554)
			(xy 292.56011 -402.515542) (xy 292.498191 -402.499643) (xy 292.438752 -402.47611) (xy 292.382731 -402.445312)
			(xy 292.331013 -402.407736) (xy 292.284411 -402.363974) (xy 292.243662 -402.314717) (xy 292.209408 -402.26074)
			(xy 292.182189 -402.202897) (xy 292.162434 -402.142098) (xy 292.150455 -402.079302) (xy 292.146441 -402.0155)
			(xy 291.386484 -402.0155) (xy 291.38247 -402.079293) (xy 291.370493 -402.142079) (xy 291.350741 -402.20287)
			(xy 291.323525 -402.260705) (xy 291.289276 -402.314674) (xy 291.248532 -402.363924) (xy 291.201937 -402.407679)
			(xy 291.150226 -402.44525) (xy 291.094213 -402.476043) (xy 291.034783 -402.499573) (xy 290.972872 -402.515468)
			(xy 290.909457 -402.523479) (xy 290.877498 -402.52396) (xy 290.845731 -402.523456) (xy 290.78269 -402.515548)
			(xy 290.721124 -402.499854) (xy 290.66199 -402.476619) (xy 290.606208 -402.446205) (xy 290.554645 -402.409084)
			(xy 290.531042 -402.387816) (xy 290.523779 -402.381632) (xy 290.506029 -402.374681) (xy 290.486967 -402.374681)
			(xy 290.469217 -402.381632) (xy 290.461954 -402.387816) (xy 290.438351 -402.409088) (xy 290.386804 -402.44624)
			(xy 290.331027 -402.476674) (xy 290.271891 -402.499916) (xy 290.210317 -402.515602) (xy 290.147268 -402.523488)
			(xy 290.115498 -402.52396) (xy 290.083534 -402.523554) (xy 290.02011 -402.515542) (xy 289.958191 -402.499643)
			(xy 289.898752 -402.47611) (xy 289.842731 -402.445312) (xy 289.791013 -402.407736) (xy 289.744411 -402.363974)
			(xy 289.703662 -402.314717) (xy 289.669408 -402.26074) (xy 289.642189 -402.202897) (xy 289.622434 -402.142098)
			(xy 289.610455 -402.079302) (xy 289.606441 -402.0155) (xy 288.846484 -402.0155) (xy 288.84247 -402.079293)
			(xy 288.830493 -402.142079) (xy 288.810741 -402.20287) (xy 288.783525 -402.260705) (xy 288.749276 -402.314674)
			(xy 288.708532 -402.363924) (xy 288.661937 -402.407679) (xy 288.610226 -402.44525) (xy 288.554213 -402.476043)
			(xy 288.494783 -402.499573) (xy 288.432872 -402.515468) (xy 288.369457 -402.523479) (xy 288.337498 -402.52396)
			(xy 288.305731 -402.523456) (xy 288.24269 -402.515548) (xy 288.181124 -402.499854) (xy 288.12199 -402.476619)
			(xy 288.066208 -402.446205) (xy 288.014645 -402.409084) (xy 287.991042 -402.387816) (xy 287.983779 -402.381632)
			(xy 287.966029 -402.374681) (xy 287.946967 -402.374681) (xy 287.929217 -402.381632) (xy 287.921954 -402.387816)
			(xy 287.898351 -402.409088) (xy 287.846804 -402.44624) (xy 287.791027 -402.476674) (xy 287.731891 -402.499916)
			(xy 287.670317 -402.515602) (xy 287.607268 -402.523488) (xy 287.575498 -402.52396) (xy 287.543534 -402.523554)
			(xy 287.48011 -402.515542) (xy 287.418191 -402.499643) (xy 287.358752 -402.47611) (xy 287.302731 -402.445312)
			(xy 287.251013 -402.407736) (xy 287.204411 -402.363974) (xy 287.163662 -402.314717) (xy 287.129408 -402.26074)
			(xy 287.102189 -402.202897) (xy 287.082434 -402.142098) (xy 287.070455 -402.079302) (xy 287.066441 -402.0155)
			(xy 284.98038 -402.0155) (xy 284.98038 -404.0475) (xy 287.066441 -404.0475) (xy 287.070455 -403.983698)
			(xy 287.082434 -403.920902) (xy 287.102189 -403.860103) (xy 287.129408 -403.80226) (xy 287.163662 -403.748283)
			(xy 287.204411 -403.699026) (xy 287.251013 -403.655264) (xy 287.302731 -403.617688) (xy 287.358752 -403.58689)
			(xy 287.418191 -403.563357) (xy 287.48011 -403.547458) (xy 287.543534 -403.539446) (xy 287.575498 -403.538944)
			(xy 287.607265 -403.539449) (xy 287.670306 -403.547357) (xy 287.731872 -403.56305) (xy 287.791006 -403.586285)
			(xy 287.846788 -403.616699) (xy 287.898351 -403.653821) (xy 287.921954 -403.675088) (xy 287.929217 -403.681272)
			(xy 287.946967 -403.688223) (xy 287.966029 -403.688223) (xy 287.983779 -403.681272) (xy 287.991042 -403.675088)
			(xy 288.014606 -403.653771) (xy 288.066161 -403.616623) (xy 288.121946 -403.586195) (xy 288.181091 -403.562962)
			(xy 288.242671 -403.547285) (xy 288.305725 -403.53941) (xy 288.337498 -403.538944) (xy 288.369457 -403.539521)
			(xy 288.432872 -403.547532) (xy 288.494783 -403.563427) (xy 288.554213 -403.586957) (xy 288.610226 -403.61775)
			(xy 288.661937 -403.655321) (xy 288.708532 -403.699076) (xy 288.749276 -403.748326) (xy 288.783525 -403.802295)
			(xy 288.810741 -403.86013) (xy 288.830493 -403.920921) (xy 288.84247 -403.983707) (xy 288.846484 -404.0475)
			(xy 289.606441 -404.0475) (xy 289.610455 -403.983698) (xy 289.622434 -403.920902) (xy 289.642189 -403.860103)
			(xy 289.669408 -403.80226) (xy 289.703662 -403.748283) (xy 289.744411 -403.699026) (xy 289.791013 -403.655264)
			(xy 289.842731 -403.617688) (xy 289.898752 -403.58689) (xy 289.958191 -403.563357) (xy 290.02011 -403.547458)
			(xy 290.083534 -403.539446) (xy 290.115498 -403.538944) (xy 290.147265 -403.539449) (xy 290.210306 -403.547357)
			(xy 290.271872 -403.56305) (xy 290.331006 -403.586285) (xy 290.386788 -403.616699) (xy 290.438351 -403.653821)
			(xy 290.461954 -403.675088) (xy 290.469217 -403.681272) (xy 290.486967 -403.688223) (xy 290.506029 -403.688223)
			(xy 290.523779 -403.681272) (xy 290.531042 -403.675088) (xy 290.554606 -403.653771) (xy 290.606161 -403.616623)
			(xy 290.661946 -403.586195) (xy 290.721091 -403.562962) (xy 290.782671 -403.547285) (xy 290.845725 -403.53941)
			(xy 290.877498 -403.538944) (xy 290.909457 -403.539521) (xy 290.972872 -403.547532) (xy 291.034783 -403.563427)
			(xy 291.094213 -403.586957) (xy 291.150226 -403.61775) (xy 291.201937 -403.655321) (xy 291.248532 -403.699076)
			(xy 291.289276 -403.748326) (xy 291.323525 -403.802295) (xy 291.350741 -403.86013) (xy 291.370493 -403.920921)
			(xy 291.38247 -403.983707) (xy 291.386484 -404.0475) (xy 292.146441 -404.0475) (xy 292.150455 -403.983698)
			(xy 292.162434 -403.920902) (xy 292.182189 -403.860103) (xy 292.209408 -403.80226) (xy 292.243662 -403.748283)
			(xy 292.284411 -403.699026) (xy 292.331013 -403.655264) (xy 292.382731 -403.617688) (xy 292.438752 -403.58689)
			(xy 292.498191 -403.563357) (xy 292.56011 -403.547458) (xy 292.623534 -403.539446) (xy 292.655498 -403.538944)
			(xy 292.687265 -403.539449) (xy 292.750306 -403.547357) (xy 292.811872 -403.56305) (xy 292.871006 -403.586285)
			(xy 292.926788 -403.616699) (xy 292.978351 -403.653821) (xy 293.001954 -403.675088) (xy 293.009217 -403.681272)
			(xy 293.026967 -403.688223) (xy 293.046029 -403.688223) (xy 293.063779 -403.681272) (xy 293.071042 -403.675088)
			(xy 293.094606 -403.653771) (xy 293.146161 -403.616623) (xy 293.201946 -403.586195) (xy 293.261091 -403.562962)
			(xy 293.322671 -403.547285) (xy 293.385725 -403.53941) (xy 293.417498 -403.538944) (xy 293.449457 -403.539521)
			(xy 293.512872 -403.547532) (xy 293.574783 -403.563427) (xy 293.634213 -403.586957) (xy 293.690226 -403.61775)
			(xy 293.741937 -403.655321) (xy 293.788532 -403.699076) (xy 293.829276 -403.748326) (xy 293.863525 -403.802295)
			(xy 293.890741 -403.86013) (xy 293.910493 -403.920921) (xy 293.92247 -403.983707) (xy 293.926484 -404.0475)
			(xy 294.53602 -404.0475) (xy 294.540035 -403.983693) (xy 294.552015 -403.920892) (xy 294.571773 -403.860089)
			(xy 294.598995 -403.802241) (xy 294.633253 -403.748261) (xy 294.674007 -403.699001) (xy 294.720613 -403.655237)
			(xy 294.772338 -403.61766) (xy 294.828364 -403.586862) (xy 294.887809 -403.563329) (xy 294.949734 -403.547433)
			(xy 295.013163 -403.539423) (xy 295.04513 -403.538944) (xy 295.076898 -403.539429) (xy 295.13994 -403.547341)
			(xy 295.201506 -403.563038) (xy 295.26064 -403.586277) (xy 295.316422 -403.616695) (xy 295.367984 -403.653819)
			(xy 295.391586 -403.675088) (xy 295.398849 -403.681272) (xy 295.416599 -403.688223) (xy 295.435661 -403.688223)
			(xy 295.453411 -403.681272) (xy 295.460674 -403.675088) (xy 295.484266 -403.653803) (xy 295.535815 -403.616653)
			(xy 295.591594 -403.58622) (xy 295.650733 -403.56298) (xy 295.712309 -403.547297) (xy 295.775359 -403.539414)
			(xy 295.80713 -403.538944) (xy 295.839087 -403.539544) (xy 295.902496 -403.547558) (xy 295.964401 -403.563455)
			(xy 296.023825 -403.586986) (xy 296.079832 -403.617779) (xy 296.131538 -403.655348) (xy 296.178128 -403.699102)
			(xy 296.218866 -403.748349) (xy 296.253112 -403.802314) (xy 296.280324 -403.860145) (xy 296.300074 -403.920931)
			(xy 296.312049 -403.983712) (xy 296.316063 -404.0475) (xy 297.07602 -404.0475) (xy 297.080035 -403.983693)
			(xy 297.092015 -403.920892) (xy 297.111773 -403.860089) (xy 297.138995 -403.802241) (xy 297.173253 -403.748261)
			(xy 297.214007 -403.699001) (xy 297.260613 -403.655237) (xy 297.312338 -403.61766) (xy 297.368364 -403.586862)
			(xy 297.427809 -403.563329) (xy 297.489734 -403.547433) (xy 297.553163 -403.539423) (xy 297.58513 -403.538944)
			(xy 297.616898 -403.539429) (xy 297.67994 -403.547341) (xy 297.741506 -403.563038) (xy 297.80064 -403.586277)
			(xy 297.856422 -403.616695) (xy 297.907984 -403.653819) (xy 297.931586 -403.675088) (xy 297.938849 -403.681272)
			(xy 297.956599 -403.688223) (xy 297.975661 -403.688223) (xy 297.993411 -403.681272) (xy 298.000674 -403.675088)
			(xy 298.024266 -403.653803) (xy 298.075815 -403.616653) (xy 298.131594 -403.58622) (xy 298.190733 -403.56298)
			(xy 298.252309 -403.547297) (xy 298.315359 -403.539414) (xy 298.34713 -403.538944) (xy 298.379087 -403.539544)
			(xy 298.442496 -403.547558) (xy 298.504401 -403.563455) (xy 298.563825 -403.586986) (xy 298.619832 -403.617779)
			(xy 298.671538 -403.655348) (xy 298.718128 -403.699102) (xy 298.758866 -403.748349) (xy 298.793112 -403.802314)
			(xy 298.820324 -403.860145) (xy 298.840074 -403.920931) (xy 298.852049 -403.983712) (xy 298.856063 -404.0475)
			(xy 298.852049 -404.111288) (xy 298.840074 -404.174069) (xy 298.820324 -404.234855) (xy 298.793112 -404.292686)
			(xy 298.758866 -404.346651) (xy 298.718128 -404.395898) (xy 298.671538 -404.439652) (xy 298.619832 -404.477221)
			(xy 298.563825 -404.508014) (xy 298.504401 -404.531545) (xy 298.442496 -404.547442) (xy 298.379087 -404.555456)
			(xy 298.34713 -404.55596) (xy 298.315363 -404.555437) (xy 298.252323 -404.547532) (xy 298.190757 -404.531842)
			(xy 298.131623 -404.508611) (xy 298.075841 -404.4782) (xy 298.024278 -404.441082) (xy 298.000674 -404.419816)
			(xy 297.993411 -404.413632) (xy 297.975661 -404.406681) (xy 297.956599 -404.406681) (xy 297.938849 -404.413632)
			(xy 297.931586 -404.419816) (xy 297.908011 -404.441121) (xy 297.856458 -404.478269) (xy 297.800675 -404.508699)
			(xy 297.741533 -404.531935) (xy 297.679955 -404.547614) (xy 297.616902 -404.555492) (xy 297.58513 -404.55596)
			(xy 297.553163 -404.555577) (xy 297.489734 -404.547567) (xy 297.427809 -404.531671) (xy 297.368364 -404.508138)
			(xy 297.312338 -404.47734) (xy 297.260613 -404.439763) (xy 297.214007 -404.395999) (xy 297.173253 -404.346739)
			(xy 297.138995 -404.292759) (xy 297.111773 -404.234911) (xy 297.092015 -404.174108) (xy 297.080035 -404.111307)
			(xy 297.07602 -404.0475) (xy 296.316063 -404.0475) (xy 296.312049 -404.111288) (xy 296.300074 -404.174069)
			(xy 296.280324 -404.234855) (xy 296.253112 -404.292686) (xy 296.218866 -404.346651) (xy 296.178128 -404.395898)
			(xy 296.131538 -404.439652) (xy 296.079832 -404.477221) (xy 296.023825 -404.508014) (xy 295.964401 -404.531545)
			(xy 295.902496 -404.547442) (xy 295.839087 -404.555456) (xy 295.80713 -404.55596) (xy 295.775363 -404.555437)
			(xy 295.712323 -404.547532) (xy 295.650757 -404.531842) (xy 295.591623 -404.508611) (xy 295.535841 -404.4782)
			(xy 295.484278 -404.441082) (xy 295.460674 -404.419816) (xy 295.453411 -404.413632) (xy 295.435661 -404.406681)
			(xy 295.416599 -404.406681) (xy 295.398849 -404.413632) (xy 295.391586 -404.419816) (xy 295.368011 -404.441121)
			(xy 295.316458 -404.478269) (xy 295.260675 -404.508699) (xy 295.201533 -404.531935) (xy 295.139955 -404.547614)
			(xy 295.076902 -404.555492) (xy 295.04513 -404.55596) (xy 295.013163 -404.555577) (xy 294.949734 -404.547567)
			(xy 294.887809 -404.531671) (xy 294.828364 -404.508138) (xy 294.772338 -404.47734) (xy 294.720613 -404.439763)
			(xy 294.674007 -404.395999) (xy 294.633253 -404.346739) (xy 294.598995 -404.292759) (xy 294.571773 -404.234911)
			(xy 294.552015 -404.174108) (xy 294.540035 -404.111307) (xy 294.53602 -404.0475) (xy 293.926484 -404.0475)
			(xy 293.92247 -404.111293) (xy 293.910493 -404.174079) (xy 293.890741 -404.23487) (xy 293.863525 -404.292705)
			(xy 293.829276 -404.346674) (xy 293.788532 -404.395924) (xy 293.741937 -404.439679) (xy 293.690226 -404.47725)
			(xy 293.634213 -404.508043) (xy 293.574783 -404.531573) (xy 293.512872 -404.547468) (xy 293.449457 -404.555479)
			(xy 293.417498 -404.55596) (xy 293.385731 -404.555456) (xy 293.32269 -404.547548) (xy 293.261124 -404.531854)
			(xy 293.20199 -404.508619) (xy 293.146208 -404.478205) (xy 293.094645 -404.441084) (xy 293.071042 -404.419816)
			(xy 293.063779 -404.413632) (xy 293.046029 -404.406681) (xy 293.026967 -404.406681) (xy 293.009217 -404.413632)
			(xy 293.001954 -404.419816) (xy 292.978351 -404.441088) (xy 292.926804 -404.47824) (xy 292.871027 -404.508674)
			(xy 292.811891 -404.531916) (xy 292.750317 -404.547602) (xy 292.687268 -404.555488) (xy 292.655498 -404.55596)
			(xy 292.623534 -404.555554) (xy 292.56011 -404.547542) (xy 292.498191 -404.531643) (xy 292.438752 -404.50811)
			(xy 292.382731 -404.477312) (xy 292.331013 -404.439736) (xy 292.284411 -404.395974) (xy 292.243662 -404.346717)
			(xy 292.209408 -404.29274) (xy 292.182189 -404.234897) (xy 292.162434 -404.174098) (xy 292.150455 -404.111302)
			(xy 292.146441 -404.0475) (xy 291.386484 -404.0475) (xy 291.38247 -404.111293) (xy 291.370493 -404.174079)
			(xy 291.350741 -404.23487) (xy 291.323525 -404.292705) (xy 291.289276 -404.346674) (xy 291.248532 -404.395924)
			(xy 291.201937 -404.439679) (xy 291.150226 -404.47725) (xy 291.094213 -404.508043) (xy 291.034783 -404.531573)
			(xy 290.972872 -404.547468) (xy 290.909457 -404.555479) (xy 290.877498 -404.55596) (xy 290.845731 -404.555456)
			(xy 290.78269 -404.547548) (xy 290.721124 -404.531854) (xy 290.66199 -404.508619) (xy 290.606208 -404.478205)
			(xy 290.554645 -404.441084) (xy 290.531042 -404.419816) (xy 290.523779 -404.413632) (xy 290.506029 -404.406681)
			(xy 290.486967 -404.406681) (xy 290.469217 -404.413632) (xy 290.461954 -404.419816) (xy 290.438351 -404.441088)
			(xy 290.386804 -404.47824) (xy 290.331027 -404.508674) (xy 290.271891 -404.531916) (xy 290.210317 -404.547602)
			(xy 290.147268 -404.555488) (xy 290.115498 -404.55596) (xy 290.083534 -404.555554) (xy 290.02011 -404.547542)
			(xy 289.958191 -404.531643) (xy 289.898752 -404.50811) (xy 289.842731 -404.477312) (xy 289.791013 -404.439736)
			(xy 289.744411 -404.395974) (xy 289.703662 -404.346717) (xy 289.669408 -404.29274) (xy 289.642189 -404.234897)
			(xy 289.622434 -404.174098) (xy 289.610455 -404.111302) (xy 289.606441 -404.0475) (xy 288.846484 -404.0475)
			(xy 288.84247 -404.111293) (xy 288.830493 -404.174079) (xy 288.810741 -404.23487) (xy 288.783525 -404.292705)
			(xy 288.749276 -404.346674) (xy 288.708532 -404.395924) (xy 288.661937 -404.439679) (xy 288.610226 -404.47725)
			(xy 288.554213 -404.508043) (xy 288.494783 -404.531573) (xy 288.432872 -404.547468) (xy 288.369457 -404.555479)
			(xy 288.337498 -404.55596) (xy 288.305731 -404.555456) (xy 288.24269 -404.547548) (xy 288.181124 -404.531854)
			(xy 288.12199 -404.508619) (xy 288.066208 -404.478205) (xy 288.014645 -404.441084) (xy 287.991042 -404.419816)
			(xy 287.983779 -404.413632) (xy 287.966029 -404.406681) (xy 287.946967 -404.406681) (xy 287.929217 -404.413632)
			(xy 287.921954 -404.419816) (xy 287.898351 -404.441088) (xy 287.846804 -404.47824) (xy 287.791027 -404.508674)
			(xy 287.731891 -404.531916) (xy 287.670317 -404.547602) (xy 287.607268 -404.555488) (xy 287.575498 -404.55596)
			(xy 287.543534 -404.555554) (xy 287.48011 -404.547542) (xy 287.418191 -404.531643) (xy 287.358752 -404.50811)
			(xy 287.302731 -404.477312) (xy 287.251013 -404.439736) (xy 287.204411 -404.395974) (xy 287.163662 -404.346717)
			(xy 287.129408 -404.29274) (xy 287.102189 -404.234897) (xy 287.082434 -404.174098) (xy 287.070455 -404.111302)
			(xy 287.066441 -404.0475) (xy 284.98038 -404.0475) (xy 284.98038 -405.65832) (xy 300.181772 -405.65832)
			(xy 300.182203 -405.632922) (xy 300.188941 -405.582575) (xy 300.202301 -405.533567) (xy 300.222045 -405.486765)
			(xy 300.247826 -405.442997) (xy 300.279187 -405.403038) (xy 300.297088 -405.385016) (xy 300.307889 -405.373792)
			(xy 300.322646 -405.346376) (xy 300.328447 -405.315786) (xy 300.32475 -405.284871) (xy 300.311899 -405.256511)
			(xy 300.301914 -405.244554) (xy 300.283736 -405.223451) (xy 300.25301 -405.176998) (xy 300.229364 -405.126572)
			(xy 300.2133 -405.073244) (xy 300.20516 -405.018147) (xy 300.204632 -404.9903) (xy 300.205073 -404.963524)
			(xy 300.21258 -404.910501) (xy 300.227433 -404.859049) (xy 300.249339 -404.810183) (xy 300.277868 -404.764862)
			(xy 300.312457 -404.723979) (xy 300.33214 -404.70582) (xy 300.342388 -404.696115) (xy 300.357483 -404.672275)
			(xy 300.365476 -404.645213) (xy 300.365756 -404.616998) (xy 300.358303 -404.589783) (xy 300.343686 -404.565647)
			(xy 300.333664 -404.555706) (xy 300.314881 -404.537574) (xy 300.281899 -404.497105) (xy 300.254741 -404.452518)
			(xy 300.233914 -404.404646) (xy 300.219807 -404.354381) (xy 300.212683 -404.302663) (xy 300.212252 -404.27656)
			(xy 300.212738 -404.249309) (xy 300.220494 -404.195361) (xy 300.235849 -404.143066) (xy 300.258491 -404.093489)
			(xy 300.287957 -404.047639) (xy 300.323648 -404.006448) (xy 300.364839 -403.970757) (xy 300.410689 -403.941291)
			(xy 300.460266 -403.918649) (xy 300.512561 -403.903294) (xy 300.566509 -403.895538) (xy 300.621011 -403.895538)
			(xy 300.674959 -403.903294) (xy 300.727254 -403.918649) (xy 300.776831 -403.941291) (xy 300.822681 -403.970757)
			(xy 300.863872 -404.006448) (xy 300.899563 -404.047639) (xy 300.929029 -404.093489) (xy 300.951671 -404.143066)
			(xy 300.967026 -404.195361) (xy 300.974782 -404.249309) (xy 300.975268 -404.27656) (xy 300.9748 -404.303335)
			(xy 300.967298 -404.356357) (xy 300.952451 -404.407808) (xy 300.93055 -404.456675) (xy 300.902026 -404.501996)
			(xy 300.867441 -404.542881) (xy 300.84776 -404.56104) (xy 300.837552 -404.570784) (xy 300.822455 -404.594613)
			(xy 300.814458 -404.621664) (xy 300.81417 -404.649872) (xy 300.821613 -404.677081) (xy 300.83622 -404.701213)
			(xy 300.846236 -404.711154) (xy 300.865048 -404.729257) (xy 300.898027 -404.769733) (xy 300.925181 -404.814325)
			(xy 300.946003 -404.862203) (xy 300.960104 -404.912473) (xy 300.967221 -404.964195) (xy 300.967648 -404.9903)
			(xy 300.967254 -405.0157) (xy 300.960512 -405.066049) (xy 300.947147 -405.115059) (xy 300.927395 -405.161861)
			(xy 300.901607 -405.205628) (xy 300.870237 -405.245584) (xy 300.852332 -405.263604) (xy 300.841511 -405.274811)
			(xy 300.826752 -405.302232) (xy 300.820954 -405.332828) (xy 300.824657 -405.363748) (xy 300.837517 -405.392109)
			(xy 300.847506 -405.404066) (xy 300.865697 -405.425158) (xy 300.89642 -405.471614) (xy 300.920064 -405.522043)
			(xy 300.936125 -405.575374) (xy 300.944262 -405.630472) (xy 300.944788 -405.65832) (xy 300.944298 -405.686325)
			(xy 300.936128 -405.741737) (xy 300.919952 -405.79536) (xy 300.896116 -405.846046) (xy 300.881034 -405.869648)
			(xy 300.873148 -405.882528) (xy 300.864464 -405.911433) (xy 300.864621 -405.941613) (xy 300.873604 -405.970426)
			(xy 300.890627 -405.995348) (xy 300.914199 -406.014197) (xy 300.928024 -406.02027) (xy 300.954253 -406.031236)
			(xy 301.003364 -406.059873) (xy 301.047679 -406.095484) (xy 301.086216 -406.13728) (xy 301.11812 -406.184334)
			(xy 301.142685 -406.235604) (xy 301.159365 -406.289952) (xy 301.16779 -406.346175) (xy 301.168308 -406.3746)
			(xy 301.167899 -406.400917) (xy 301.160669 -406.453053) (xy 301.146348 -406.503702) (xy 301.125205 -406.551904)
			(xy 301.097642 -406.596745) (xy 301.064181 -406.637375) (xy 301.045118 -406.655524) (xy 301.035096 -406.665335)
			(xy 301.020396 -406.689208) (xy 301.012757 -406.716182) (xy 301.012757 -406.744218) (xy 301.020396 -406.771192)
			(xy 301.035096 -406.795065) (xy 301.045118 -406.804876) (xy 301.06417 -406.823039) (xy 301.097654 -406.863651)
			(xy 301.12523 -406.908485) (xy 301.146374 -406.956688) (xy 301.160683 -407.007341) (xy 301.167886 -407.059482)
			(xy 301.168308 -407.0858) (xy 301.167822 -407.113051) (xy 301.160066 -407.166999) (xy 301.144711 -407.219294)
			(xy 301.122069 -407.268871) (xy 301.092603 -407.314721) (xy 301.056912 -407.355912) (xy 301.015721 -407.391603)
			(xy 300.969871 -407.421069) (xy 300.920294 -407.443711) (xy 300.867999 -407.459066) (xy 300.814051 -407.466822)
			(xy 300.759549 -407.466822) (xy 300.705601 -407.459066) (xy 300.653306 -407.443711) (xy 300.603729 -407.421069)
			(xy 300.557879 -407.391603) (xy 300.516688 -407.355912) (xy 300.480997 -407.314721) (xy 300.451531 -407.268871)
			(xy 300.428889 -407.219294) (xy 300.413534 -407.166999) (xy 300.405778 -407.113051) (xy 300.405292 -407.0858)
			(xy 300.405701 -407.059483) (xy 300.412931 -407.007347) (xy 300.427252 -406.956698) (xy 300.448395 -406.908496)
			(xy 300.475958 -406.863655) (xy 300.509419 -406.823025) (xy 300.528482 -406.804876) (xy 300.538504 -406.795065)
			(xy 300.553204 -406.771192) (xy 300.560843 -406.744218) (xy 300.560843 -406.716182) (xy 300.553204 -406.689208)
			(xy 300.538504 -406.665335) (xy 300.528482 -406.655524) (xy 300.50943 -406.637361) (xy 300.475946 -406.596749)
			(xy 300.44837 -406.551915) (xy 300.427226 -406.503712) (xy 300.412917 -406.453059) (xy 300.405714 -406.400918)
			(xy 300.405292 -406.3746) (xy 300.405795 -406.346595) (xy 300.413961 -406.291184) (xy 300.430134 -406.237561)
			(xy 300.453966 -406.186875) (xy 300.469046 -406.163272) (xy 300.477036 -406.150451) (xy 300.48571 -406.121524)
			(xy 300.485538 -406.091324) (xy 300.476535 -406.062498) (xy 300.459489 -406.037569) (xy 300.435893 -406.01872)
			(xy 300.422056 -406.01265) (xy 300.39583 -406.001678) (xy 300.34672 -405.97304) (xy 300.302406 -405.93743)
			(xy 300.26387 -405.895634) (xy 300.231966 -405.848581) (xy 300.207401 -405.797313) (xy 300.190719 -405.742966)
			(xy 300.182291 -405.686745) (xy 300.181772 -405.65832) (xy 284.98038 -405.65832) (xy 284.98038 -407.05786)
			(xy 291.814502 -407.05786) (xy 291.818573 -407.002238) (xy 291.830699 -406.947801) (xy 291.850622 -406.89571)
			(xy 291.877918 -406.847075) (xy 291.912004 -406.802932) (xy 291.952153 -406.764223) (xy 291.997511 -406.731772)
			(xy 292.047111 -406.706271) (xy 292.099895 -406.688264) (xy 292.154738 -406.678134) (xy 292.210472 -406.676097)
			(xy 292.265909 -406.682197) (xy 292.319866 -406.696303) (xy 292.371195 -406.718115) (xy 292.418801 -406.747169)
			(xy 292.453044 -406.775666) (xy 295.040048 -406.775666) (xy 295.044119 -406.720044) (xy 295.056245 -406.665607)
			(xy 295.076168 -406.613516) (xy 295.103464 -406.564881) (xy 295.13755 -406.520738) (xy 295.177699 -406.482029)
			(xy 295.223057 -406.449578) (xy 295.272657 -406.424077) (xy 295.325441 -406.40607) (xy 295.380284 -406.39594)
			(xy 295.436018 -406.393903) (xy 295.491455 -406.400003) (xy 295.545412 -406.414109) (xy 295.596741 -406.435921)
			(xy 295.644347 -406.464975) (xy 295.687215 -406.50065) (xy 295.724432 -406.542187) (xy 295.755205 -406.5887)
			(xy 295.778877 -406.639197) (xy 295.790972 -406.6794) (xy 298.865542 -406.6794) (xy 298.869613 -406.623778)
			(xy 298.881739 -406.569341) (xy 298.901662 -406.51725) (xy 298.928958 -406.468615) (xy 298.963044 -406.424472)
			(xy 299.003193 -406.385763) (xy 299.048551 -406.353312) (xy 299.098151 -406.327811) (xy 299.150935 -406.309804)
			(xy 299.205778 -406.299674) (xy 299.261512 -406.297637) (xy 299.316949 -406.303737) (xy 299.370906 -406.317843)
			(xy 299.422235 -406.339655) (xy 299.469841 -406.368709) (xy 299.512709 -406.404384) (xy 299.549926 -406.445921)
			(xy 299.580699 -406.492434) (xy 299.604371 -406.542931) (xy 299.620439 -406.596338) (xy 299.628559 -406.651514)
			(xy 299.629068 -406.6794) (xy 299.628559 -406.707286) (xy 299.620439 -406.762462) (xy 299.604371 -406.815869)
			(xy 299.580699 -406.866366) (xy 299.549926 -406.912879) (xy 299.512709 -406.954416) (xy 299.469841 -406.990091)
			(xy 299.422235 -407.019145) (xy 299.370906 -407.040957) (xy 299.316949 -407.055063) (xy 299.261512 -407.061163)
			(xy 299.205778 -407.059126) (xy 299.150935 -407.048996) (xy 299.098151 -407.030989) (xy 299.048551 -407.005488)
			(xy 299.003193 -406.973037) (xy 298.963044 -406.934328) (xy 298.928958 -406.890185) (xy 298.901662 -406.84155)
			(xy 298.881739 -406.789459) (xy 298.869613 -406.735022) (xy 298.865542 -406.6794) (xy 295.790972 -406.6794)
			(xy 295.794945 -406.692604) (xy 295.803065 -406.74778) (xy 295.803574 -406.775666) (xy 295.803065 -406.803552)
			(xy 295.794945 -406.858728) (xy 295.778877 -406.912135) (xy 295.755205 -406.962632) (xy 295.724432 -407.009145)
			(xy 295.687215 -407.050682) (xy 295.644347 -407.086357) (xy 295.596741 -407.115411) (xy 295.545412 -407.137223)
			(xy 295.491455 -407.151329) (xy 295.436018 -407.157429) (xy 295.380284 -407.155392) (xy 295.325441 -407.145262)
			(xy 295.272657 -407.127255) (xy 295.223057 -407.101754) (xy 295.177699 -407.069303) (xy 295.13755 -407.030594)
			(xy 295.103464 -406.986451) (xy 295.076168 -406.937816) (xy 295.056245 -406.885725) (xy 295.044119 -406.831288)
			(xy 295.040048 -406.775666) (xy 292.453044 -406.775666) (xy 292.461669 -406.782844) (xy 292.498886 -406.824381)
			(xy 292.529659 -406.870894) (xy 292.553331 -406.921391) (xy 292.569399 -406.974798) (xy 292.577519 -407.029974)
			(xy 292.578028 -407.05786) (xy 292.577519 -407.085746) (xy 292.569399 -407.140922) (xy 292.553331 -407.194329)
			(xy 292.529659 -407.244826) (xy 292.498886 -407.291339) (xy 292.461669 -407.332876) (xy 292.418801 -407.368551)
			(xy 292.371195 -407.397605) (xy 292.319866 -407.419417) (xy 292.265909 -407.433523) (xy 292.210472 -407.439623)
			(xy 292.154738 -407.437586) (xy 292.099895 -407.427456) (xy 292.047111 -407.409449) (xy 291.997511 -407.383948)
			(xy 291.952153 -407.351497) (xy 291.912004 -407.312788) (xy 291.877918 -407.268645) (xy 291.850622 -407.22001)
			(xy 291.830699 -407.167919) (xy 291.818573 -407.113482) (xy 291.814502 -407.05786) (xy 284.98038 -407.05786)
			(xy 284.98038 -407.49982) (xy 289.368482 -407.49982) (xy 289.372553 -407.444198) (xy 289.384679 -407.389761)
			(xy 289.404602 -407.33767) (xy 289.431898 -407.289035) (xy 289.465984 -407.244892) (xy 289.506133 -407.206183)
			(xy 289.551491 -407.173732) (xy 289.601091 -407.148231) (xy 289.653875 -407.130224) (xy 289.708718 -407.120094)
			(xy 289.764452 -407.118057) (xy 289.819889 -407.124157) (xy 289.873846 -407.138263) (xy 289.925175 -407.160075)
			(xy 289.972781 -407.189129) (xy 290.015649 -407.224804) (xy 290.052866 -407.266341) (xy 290.083639 -407.312854)
			(xy 290.107311 -407.363351) (xy 290.123379 -407.416758) (xy 290.128127 -407.44902) (xy 296.33926 -407.44902)
			(xy 296.339746 -407.421769) (xy 296.347502 -407.367821) (xy 296.362857 -407.315526) (xy 296.385499 -407.265949)
			(xy 296.414965 -407.220099) (xy 296.450656 -407.178908) (xy 296.491847 -407.143217) (xy 296.537697 -407.113751)
			(xy 296.587274 -407.091109) (xy 296.639569 -407.075754) (xy 296.693517 -407.067998) (xy 296.748019 -407.067998)
			(xy 296.801967 -407.075754) (xy 296.854262 -407.091109) (xy 296.903839 -407.113751) (xy 296.949689 -407.143217)
			(xy 296.99088 -407.178908) (xy 297.026571 -407.220099) (xy 297.056037 -407.265949) (xy 297.078679 -407.315526)
			(xy 297.094034 -407.367821) (xy 297.10179 -407.421769) (xy 297.102276 -407.44902) (xy 297.101502 -407.483304)
			(xy 297.089227 -407.550766) (xy 297.077892 -407.583132) (xy 297.073446 -407.596471) (xy 297.071168 -407.624483)
			(xy 297.076591 -407.652059) (xy 297.089307 -407.677122) (xy 297.108357 -407.697784) (xy 297.132308 -407.712488)
			(xy 297.14571 -407.716736) (xy 297.172086 -407.724593) (xy 297.22241 -407.746873) (xy 297.269008 -407.776158)
			(xy 297.31091 -407.811839) (xy 297.347246 -407.853174) (xy 297.377261 -407.899304) (xy 297.400331 -407.949271)
			(xy 297.415977 -408.002036) (xy 297.42385 -408.056334) (xy 300.481236 -408.056334) (xy 300.485307 -408.000712)
			(xy 300.497433 -407.946275) (xy 300.517356 -407.894184) (xy 300.544652 -407.845549) (xy 300.578738 -407.801406)
			(xy 300.618887 -407.762697) (xy 300.664245 -407.730246) (xy 300.713845 -407.704745) (xy 300.766629 -407.686738)
			(xy 300.821472 -407.676608) (xy 300.877206 -407.674571) (xy 300.932643 -407.680671) (xy 300.9866 -407.694777)
			(xy 301.037929 -407.716589) (xy 301.085535 -407.745643) (xy 301.128403 -407.781318) (xy 301.16562 -407.822855)
			(xy 301.196393 -407.869368) (xy 301.220065 -407.919865) (xy 301.236133 -407.973272) (xy 301.244253 -408.028448)
			(xy 301.244762 -408.056334) (xy 301.244253 -408.08422) (xy 301.236133 -408.139396) (xy 301.220065 -408.192803)
			(xy 301.196393 -408.2433) (xy 301.16562 -408.289813) (xy 301.128403 -408.33135) (xy 301.085535 -408.367025)
			(xy 301.037929 -408.396079) (xy 300.9866 -408.417891) (xy 300.932643 -408.431997) (xy 300.877206 -408.438097)
			(xy 300.821472 -408.43606) (xy 300.766629 -408.42593) (xy 300.713845 -408.407923) (xy 300.664245 -408.382422)
			(xy 300.618887 -408.349971) (xy 300.578738 -408.311262) (xy 300.544652 -408.267119) (xy 300.517356 -408.218484)
			(xy 300.497433 -408.166393) (xy 300.485307 -408.111956) (xy 300.481236 -408.056334) (xy 297.42385 -408.056334)
			(xy 297.423874 -408.056502) (xy 297.424348 -408.08402) (xy 297.423862 -408.111271) (xy 297.416106 -408.165219)
			(xy 297.400751 -408.217514) (xy 297.378109 -408.267091) (xy 297.348643 -408.312941) (xy 297.312952 -408.354132)
			(xy 297.271761 -408.389823) (xy 297.225911 -408.419289) (xy 297.176334 -408.441931) (xy 297.124039 -408.457286)
			(xy 297.070091 -408.465042) (xy 297.015589 -408.465042) (xy 296.961641 -408.457286) (xy 296.909346 -408.441931)
			(xy 296.859769 -408.419289) (xy 296.813919 -408.389823) (xy 296.772728 -408.354132) (xy 296.737037 -408.312941)
			(xy 296.707571 -408.267091) (xy 296.684929 -408.217514) (xy 296.669574 -408.165219) (xy 296.661818 -408.111271)
			(xy 296.661332 -408.08402) (xy 296.662116 -408.049736) (xy 296.674384 -407.982274) (xy 296.685716 -407.949908)
			(xy 296.690179 -407.936571) (xy 296.69247 -407.908553) (xy 296.687051 -407.88097) (xy 296.674331 -407.855901)
			(xy 296.65527 -407.835239) (xy 296.631306 -407.820544) (xy 296.617898 -407.816304) (xy 296.591535 -407.808406)
			(xy 296.541213 -407.78613) (xy 296.494617 -407.75685) (xy 296.452715 -407.721174) (xy 296.416378 -407.679844)
			(xy 296.386361 -407.633719) (xy 296.363288 -407.583758) (xy 296.347638 -407.530998) (xy 296.339737 -407.476536)
			(xy 296.33926 -407.44902) (xy 290.128127 -407.44902) (xy 290.131499 -407.471934) (xy 290.132008 -407.49982)
			(xy 290.131499 -407.527706) (xy 290.123379 -407.582882) (xy 290.107311 -407.636289) (xy 290.083639 -407.686786)
			(xy 290.052866 -407.733299) (xy 290.015649 -407.774836) (xy 289.972781 -407.810511) (xy 289.925175 -407.839565)
			(xy 289.873846 -407.861377) (xy 289.819889 -407.875483) (xy 289.764452 -407.881583) (xy 289.708718 -407.879546)
			(xy 289.653875 -407.869416) (xy 289.601091 -407.851409) (xy 289.551491 -407.825908) (xy 289.506133 -407.793457)
			(xy 289.465984 -407.754748) (xy 289.431898 -407.710605) (xy 289.404602 -407.66197) (xy 289.384679 -407.609879)
			(xy 289.372553 -407.555442) (xy 289.368482 -407.49982) (xy 284.98038 -407.49982) (xy 284.98038 -408.1526)
			(xy 284.42158 -408.7114) (xy 298.893482 -408.7114) (xy 298.897553 -408.655778) (xy 298.909679 -408.601341)
			(xy 298.929602 -408.54925) (xy 298.956898 -408.500615) (xy 298.990984 -408.456472) (xy 299.031133 -408.417763)
			(xy 299.076491 -408.385312) (xy 299.126091 -408.359811) (xy 299.178875 -408.341804) (xy 299.233718 -408.331674)
			(xy 299.289452 -408.329637) (xy 299.344889 -408.335737) (xy 299.398846 -408.349843) (xy 299.450175 -408.371655)
			(xy 299.497781 -408.400709) (xy 299.540649 -408.436384) (xy 299.577866 -408.477921) (xy 299.608639 -408.524434)
			(xy 299.632311 -408.574931) (xy 299.648379 -408.628338) (xy 299.656499 -408.683514) (xy 299.657008 -408.7114)
			(xy 299.656499 -408.739286) (xy 299.648379 -408.794462) (xy 299.632311 -408.847869) (xy 299.608639 -408.898366)
			(xy 299.577866 -408.944879) (xy 299.540649 -408.986416) (xy 299.497781 -409.022091) (xy 299.450175 -409.051145)
			(xy 299.398846 -409.072957) (xy 299.344889 -409.087063) (xy 299.289452 -409.093163) (xy 299.233718 -409.091126)
			(xy 299.178875 -409.080996) (xy 299.126091 -409.062989) (xy 299.076491 -409.037488) (xy 299.031133 -409.005037)
			(xy 298.990984 -408.966328) (xy 298.956898 -408.922185) (xy 298.929602 -408.87355) (xy 298.909679 -408.821459)
			(xy 298.897553 -408.767022) (xy 298.893482 -408.7114) (xy 284.42158 -408.7114) (xy 283.77896 -409.35402)
			(xy 296.660822 -409.35402) (xy 296.664893 -409.298398) (xy 296.677019 -409.243961) (xy 296.696942 -409.19187)
			(xy 296.724238 -409.143235) (xy 296.758324 -409.099092) (xy 296.798473 -409.060383) (xy 296.843831 -409.027932)
			(xy 296.893431 -409.002431) (xy 296.946215 -408.984424) (xy 297.001058 -408.974294) (xy 297.056792 -408.972257)
			(xy 297.112229 -408.978357) (xy 297.166186 -408.992463) (xy 297.217515 -409.014275) (xy 297.265121 -409.043329)
			(xy 297.307989 -409.079004) (xy 297.345206 -409.120541) (xy 297.375979 -409.167054) (xy 297.399651 -409.217551)
			(xy 297.415719 -409.270958) (xy 297.423839 -409.326134) (xy 297.424348 -409.35402) (xy 297.423839 -409.381906)
			(xy 297.415719 -409.437082) (xy 297.399651 -409.490489) (xy 297.375979 -409.540986) (xy 297.345206 -409.587499)
			(xy 297.307989 -409.629036) (xy 297.265121 -409.664711) (xy 297.217515 -409.693765) (xy 297.166186 -409.715577)
			(xy 297.112229 -409.729683) (xy 297.056792 -409.735783) (xy 297.001058 -409.733746) (xy 296.946215 -409.723616)
			(xy 296.893431 -409.705609) (xy 296.843831 -409.680108) (xy 296.798473 -409.647657) (xy 296.758324 -409.608948)
			(xy 296.724238 -409.564805) (xy 296.696942 -409.51617) (xy 296.677019 -409.464079) (xy 296.664893 -409.409642)
			(xy 296.660822 -409.35402) (xy 283.77896 -409.35402) (xy 283.460444 -409.672536) (xy 283.450014 -409.683759)
			(xy 283.435816 -409.710895) (xy 283.43029 -409.741017) (xy 283.433932 -409.771425) (xy 283.446414 -409.799391)
			(xy 283.466617 -409.822407) (xy 283.492729 -409.838409) (xy 283.507434 -409.842716) (xy 283.534498 -409.850088)
			(xy 283.586264 -409.871683) (xy 283.634311 -409.900626) (xy 283.677601 -409.936292) (xy 283.715202 -409.977913)
			(xy 283.746304 -410.024592) (xy 283.770234 -410.075321) (xy 283.786478 -410.129008) (xy 283.794686 -410.184495)
			(xy 283.795216 -410.21254) (xy 284.21787 -410.21254) (xy 284.221941 -410.156918) (xy 284.234067 -410.102481)
			(xy 284.25399 -410.05039) (xy 284.281286 -410.001755) (xy 284.315372 -409.957612) (xy 284.355521 -409.918903)
			(xy 284.400879 -409.886452) (xy 284.450479 -409.860951) (xy 284.503263 -409.842944) (xy 284.558106 -409.832814)
			(xy 284.61384 -409.830777) (xy 284.669277 -409.836877) (xy 284.723234 -409.850983) (xy 284.774563 -409.872795)
			(xy 284.822169 -409.901849) (xy 284.865037 -409.937524) (xy 284.902254 -409.979061) (xy 284.933027 -410.025574)
			(xy 284.956699 -410.076071) (xy 284.972767 -410.129478) (xy 284.980887 -410.184654) (xy 284.981396 -410.21254)
			(xy 284.980887 -410.240426) (xy 284.972767 -410.295602) (xy 284.956699 -410.349009) (xy 284.933027 -410.399506)
			(xy 284.902254 -410.446019) (xy 284.865037 -410.487556) (xy 284.822169 -410.523231) (xy 284.774563 -410.552285)
			(xy 284.723234 -410.574097) (xy 284.687726 -410.58338) (xy 292.467282 -410.58338) (xy 292.471353 -410.527758)
			(xy 292.483479 -410.473321) (xy 292.503402 -410.42123) (xy 292.530698 -410.372595) (xy 292.564784 -410.328452)
			(xy 292.604933 -410.289743) (xy 292.650291 -410.257292) (xy 292.699891 -410.231791) (xy 292.752675 -410.213784)
			(xy 292.807518 -410.203654) (xy 292.863252 -410.201617) (xy 292.918689 -410.207717) (xy 292.972646 -410.221823)
			(xy 293.023975 -410.243635) (xy 293.071581 -410.272689) (xy 293.114449 -410.308364) (xy 293.151666 -410.349901)
			(xy 293.182439 -410.396414) (xy 293.206111 -410.446911) (xy 293.222179 -410.500318) (xy 293.230299 -410.555494)
			(xy 293.230808 -410.58338) (xy 293.230299 -410.611266) (xy 293.222179 -410.666442) (xy 293.206111 -410.719849)
			(xy 293.182439 -410.770346) (xy 293.151666 -410.816859) (xy 293.114449 -410.858396) (xy 293.071581 -410.894071)
			(xy 293.056679 -410.903166) (xy 295.769282 -410.903166) (xy 295.773353 -410.847544) (xy 295.785479 -410.793107)
			(xy 295.805402 -410.741016) (xy 295.832698 -410.692381) (xy 295.866784 -410.648238) (xy 295.906933 -410.609529)
			(xy 295.952291 -410.577078) (xy 296.001891 -410.551577) (xy 296.054675 -410.53357) (xy 296.109518 -410.52344)
			(xy 296.165252 -410.521403) (xy 296.220689 -410.527503) (xy 296.274646 -410.541609) (xy 296.325975 -410.563421)
			(xy 296.373581 -410.592475) (xy 296.411486 -410.62402) (xy 296.660822 -410.62402) (xy 296.664893 -410.568398)
			(xy 296.677019 -410.513961) (xy 296.696942 -410.46187) (xy 296.724238 -410.413235) (xy 296.758324 -410.369092)
			(xy 296.798473 -410.330383) (xy 296.843831 -410.297932) (xy 296.893431 -410.272431) (xy 296.946215 -410.254424)
			(xy 297.001058 -410.244294) (xy 297.056792 -410.242257) (xy 297.112229 -410.248357) (xy 297.166186 -410.262463)
			(xy 297.217515 -410.284275) (xy 297.265121 -410.313329) (xy 297.307989 -410.349004) (xy 297.326819 -410.37002)
			(xy 297.953682 -410.37002) (xy 297.957753 -410.314398) (xy 297.969879 -410.259961) (xy 297.989802 -410.20787)
			(xy 298.017098 -410.159235) (xy 298.051184 -410.115092) (xy 298.091333 -410.076383) (xy 298.136691 -410.043932)
			(xy 298.186291 -410.018431) (xy 298.239075 -410.000424) (xy 298.293918 -409.990294) (xy 298.349652 -409.988257)
			(xy 298.405089 -409.994357) (xy 298.459046 -410.008463) (xy 298.510375 -410.030275) (xy 298.557981 -410.059329)
			(xy 298.600849 -410.095004) (xy 298.638066 -410.136541) (xy 298.668839 -410.183054) (xy 298.692511 -410.233551)
			(xy 298.708579 -410.286958) (xy 298.716699 -410.342134) (xy 298.717208 -410.37002) (xy 298.716699 -410.397906)
			(xy 298.708579 -410.453082) (xy 298.692511 -410.506489) (xy 298.668839 -410.556986) (xy 298.638066 -410.603499)
			(xy 298.600849 -410.645036) (xy 298.557981 -410.680711) (xy 298.510375 -410.709765) (xy 298.459046 -410.731577)
			(xy 298.405089 -410.745683) (xy 298.349652 -410.751783) (xy 298.293918 -410.749746) (xy 298.239075 -410.739616)
			(xy 298.186291 -410.721609) (xy 298.136691 -410.696108) (xy 298.091333 -410.663657) (xy 298.051184 -410.624948)
			(xy 298.017098 -410.580805) (xy 297.989802 -410.53217) (xy 297.969879 -410.480079) (xy 297.957753 -410.425642)
			(xy 297.953682 -410.37002) (xy 297.326819 -410.37002) (xy 297.345206 -410.390541) (xy 297.375979 -410.437054)
			(xy 297.399651 -410.487551) (xy 297.415719 -410.540958) (xy 297.423839 -410.596134) (xy 297.424348 -410.62402)
			(xy 297.423839 -410.651906) (xy 297.415719 -410.707082) (xy 297.399651 -410.760489) (xy 297.375979 -410.810986)
			(xy 297.345206 -410.857499) (xy 297.307989 -410.899036) (xy 297.265121 -410.934711) (xy 297.217515 -410.963765)
			(xy 297.166186 -410.985577) (xy 297.112229 -410.999683) (xy 297.056792 -411.005783) (xy 297.001058 -411.003746)
			(xy 296.946215 -410.993616) (xy 296.893431 -410.975609) (xy 296.843831 -410.950108) (xy 296.798473 -410.917657)
			(xy 296.758324 -410.878948) (xy 296.724238 -410.834805) (xy 296.696942 -410.78617) (xy 296.677019 -410.734079)
			(xy 296.664893 -410.679642) (xy 296.660822 -410.62402) (xy 296.411486 -410.62402) (xy 296.416449 -410.62815)
			(xy 296.453666 -410.669687) (xy 296.484439 -410.7162) (xy 296.508111 -410.766697) (xy 296.524179 -410.820104)
			(xy 296.532299 -410.87528) (xy 296.532808 -410.903166) (xy 296.532299 -410.931052) (xy 296.524179 -410.986228)
			(xy 296.508111 -411.039635) (xy 296.484439 -411.090132) (xy 296.453666 -411.136645) (xy 296.416449 -411.178182)
			(xy 296.385238 -411.204156) (xy 299.965362 -411.204156) (xy 299.969433 -411.148534) (xy 299.981559 -411.094097)
			(xy 300.001482 -411.042006) (xy 300.028778 -410.993371) (xy 300.062864 -410.949228) (xy 300.103013 -410.910519)
			(xy 300.148371 -410.878068) (xy 300.197971 -410.852567) (xy 300.250755 -410.83456) (xy 300.305598 -410.82443)
			(xy 300.361332 -410.822393) (xy 300.416769 -410.828493) (xy 300.470726 -410.842599) (xy 300.522055 -410.864411)
			(xy 300.569661 -410.893465) (xy 300.612529 -410.92914) (xy 300.649746 -410.970677) (xy 300.680519 -411.01719)
			(xy 300.704191 -411.067687) (xy 300.720259 -411.121094) (xy 300.728379 -411.17627) (xy 300.728888 -411.204156)
			(xy 300.728379 -411.232042) (xy 300.720259 -411.287218) (xy 300.704191 -411.340625) (xy 300.680519 -411.391122)
			(xy 300.649746 -411.437635) (xy 300.630677 -411.458918) (xy 355.548182 -411.458918) (xy 355.552253 -411.403296)
			(xy 355.564379 -411.348859) (xy 355.584302 -411.296768) (xy 355.611598 -411.248133) (xy 355.645684 -411.20399)
			(xy 355.685833 -411.165281) (xy 355.731191 -411.13283) (xy 355.780791 -411.107329) (xy 355.833575 -411.089322)
			(xy 355.888418 -411.079192) (xy 355.944152 -411.077155) (xy 355.999589 -411.083255) (xy 356.053546 -411.097361)
			(xy 356.104875 -411.119173) (xy 356.152481 -411.148227) (xy 356.195349 -411.183902) (xy 356.232566 -411.225439)
			(xy 356.263339 -411.271952) (xy 356.287011 -411.322449) (xy 356.303079 -411.375856) (xy 356.311199 -411.431032)
			(xy 356.311708 -411.458918) (xy 356.311199 -411.486804) (xy 356.303079 -411.54198) (xy 356.298801 -411.5562)
			(xy 365.835182 -411.5562) (xy 365.839253 -411.500578) (xy 365.851379 -411.446141) (xy 365.871302 -411.39405)
			(xy 365.898598 -411.345415) (xy 365.932684 -411.301272) (xy 365.972833 -411.262563) (xy 366.018191 -411.230112)
			(xy 366.067791 -411.204611) (xy 366.120575 -411.186604) (xy 366.175418 -411.176474) (xy 366.231152 -411.174437)
			(xy 366.286589 -411.180537) (xy 366.340546 -411.194643) (xy 366.391875 -411.216455) (xy 366.439481 -411.245509)
			(xy 366.482349 -411.281184) (xy 366.519566 -411.322721) (xy 366.550339 -411.369234) (xy 366.574011 -411.419731)
			(xy 366.590079 -411.473138) (xy 366.598199 -411.528314) (xy 366.598708 -411.5562) (xy 366.598199 -411.584086)
			(xy 366.590079 -411.639262) (xy 366.574011 -411.692669) (xy 366.550339 -411.743166) (xy 366.519566 -411.789679)
			(xy 366.482349 -411.831216) (xy 366.439481 -411.866891) (xy 366.391875 -411.895945) (xy 366.340546 -411.917757)
			(xy 366.286589 -411.931863) (xy 366.231152 -411.937963) (xy 366.175418 -411.935926) (xy 366.120575 -411.925796)
			(xy 366.067791 -411.907789) (xy 366.018191 -411.882288) (xy 365.972833 -411.849837) (xy 365.932684 -411.811128)
			(xy 365.898598 -411.766985) (xy 365.871302 -411.71835) (xy 365.851379 -411.666259) (xy 365.839253 -411.611822)
			(xy 365.835182 -411.5562) (xy 356.298801 -411.5562) (xy 356.287011 -411.595387) (xy 356.263339 -411.645884)
			(xy 356.232566 -411.692397) (xy 356.195349 -411.733934) (xy 356.152481 -411.769609) (xy 356.104875 -411.798663)
			(xy 356.053546 -411.820475) (xy 355.999589 -411.834581) (xy 355.944152 -411.840681) (xy 355.888418 -411.838644)
			(xy 355.833575 -411.828514) (xy 355.780791 -411.810507) (xy 355.731191 -411.785006) (xy 355.685833 -411.752555)
			(xy 355.645684 -411.713846) (xy 355.611598 -411.669703) (xy 355.584302 -411.621068) (xy 355.564379 -411.568977)
			(xy 355.552253 -411.51454) (xy 355.548182 -411.458918) (xy 300.630677 -411.458918) (xy 300.612529 -411.479172)
			(xy 300.569661 -411.514847) (xy 300.522055 -411.543901) (xy 300.470726 -411.565713) (xy 300.416769 -411.579819)
			(xy 300.361332 -411.585919) (xy 300.305598 -411.583882) (xy 300.250755 -411.573752) (xy 300.197971 -411.555745)
			(xy 300.148371 -411.530244) (xy 300.103013 -411.497793) (xy 300.062864 -411.459084) (xy 300.028778 -411.414941)
			(xy 300.001482 -411.366306) (xy 299.981559 -411.314215) (xy 299.969433 -411.259778) (xy 299.965362 -411.204156)
			(xy 296.385238 -411.204156) (xy 296.373581 -411.213857) (xy 296.325975 -411.242911) (xy 296.274646 -411.264723)
			(xy 296.220689 -411.278829) (xy 296.165252 -411.284929) (xy 296.109518 -411.282892) (xy 296.054675 -411.272762)
			(xy 296.001891 -411.254755) (xy 295.952291 -411.229254) (xy 295.906933 -411.196803) (xy 295.866784 -411.158094)
			(xy 295.832698 -411.113951) (xy 295.805402 -411.065316) (xy 295.785479 -411.013225) (xy 295.773353 -410.958788)
			(xy 295.769282 -410.903166) (xy 293.056679 -410.903166) (xy 293.023975 -410.923125) (xy 292.972646 -410.944937)
			(xy 292.918689 -410.959043) (xy 292.863252 -410.965143) (xy 292.807518 -410.963106) (xy 292.752675 -410.952976)
			(xy 292.699891 -410.934969) (xy 292.650291 -410.909468) (xy 292.604933 -410.877017) (xy 292.564784 -410.838308)
			(xy 292.530698 -410.794165) (xy 292.503402 -410.74553) (xy 292.483479 -410.693439) (xy 292.471353 -410.639002)
			(xy 292.467282 -410.58338) (xy 284.687726 -410.58338) (xy 284.669277 -410.588203) (xy 284.61384 -410.594303)
			(xy 284.558106 -410.592266) (xy 284.503263 -410.582136) (xy 284.450479 -410.564129) (xy 284.400879 -410.538628)
			(xy 284.355521 -410.506177) (xy 284.315372 -410.467468) (xy 284.281286 -410.423325) (xy 284.25399 -410.37469)
			(xy 284.234067 -410.322599) (xy 284.221941 -410.268162) (xy 284.21787 -410.21254) (xy 283.795216 -410.21254)
			(xy 283.794727 -410.23979) (xy 283.786966 -410.293733) (xy 283.771608 -410.346024) (xy 283.748965 -410.395597)
			(xy 283.719497 -410.441442) (xy 283.683806 -410.482629) (xy 283.642617 -410.518317) (xy 283.596768 -410.54778)
			(xy 283.547194 -410.570419) (xy 283.494902 -410.585773) (xy 283.440958 -410.59353) (xy 283.413708 -410.594048)
			(xy 283.401034 -410.59396) (xy 283.37574 -410.592304) (xy 283.363162 -410.590746) (xy 283.348789 -410.589346)
			(xy 283.320255 -410.593707) (xy 283.294081 -410.605874) (xy 283.272354 -410.624878) (xy 283.25681 -410.6492)
			(xy 283.24869 -410.676899) (xy 283.2481 -410.69133) (xy 283.2481 -411.2895) (xy 293.757602 -411.2895)
			(xy 293.761673 -411.233878) (xy 293.773799 -411.179441) (xy 293.793722 -411.12735) (xy 293.821018 -411.078715)
			(xy 293.855104 -411.034572) (xy 293.895253 -410.995863) (xy 293.940611 -410.963412) (xy 293.990211 -410.937911)
			(xy 294.042995 -410.919904) (xy 294.097838 -410.909774) (xy 294.153572 -410.907737) (xy 294.209009 -410.913837)
			(xy 294.262966 -410.927943) (xy 294.314295 -410.949755) (xy 294.361901 -410.978809) (xy 294.404769 -411.014484)
			(xy 294.441986 -411.056021) (xy 294.472759 -411.102534) (xy 294.496431 -411.153031) (xy 294.512499 -411.206438)
			(xy 294.520619 -411.261614) (xy 294.521128 -411.2895) (xy 294.520619 -411.317386) (xy 294.512499 -411.372562)
			(xy 294.496431 -411.425969) (xy 294.472759 -411.476466) (xy 294.441986 -411.522979) (xy 294.404769 -411.564516)
			(xy 294.361901 -411.600191) (xy 294.314295 -411.629245) (xy 294.306871 -411.6324) (xy 295.266362 -411.6324)
			(xy 295.270433 -411.576778) (xy 295.282559 -411.522341) (xy 295.302482 -411.47025) (xy 295.329778 -411.421615)
			(xy 295.363864 -411.377472) (xy 295.404013 -411.338763) (xy 295.449371 -411.306312) (xy 295.498971 -411.280811)
			(xy 295.551755 -411.262804) (xy 295.606598 -411.252674) (xy 295.662332 -411.250637) (xy 295.717769 -411.256737)
			(xy 295.771726 -411.270843) (xy 295.823055 -411.292655) (xy 295.870661 -411.321709) (xy 295.913529 -411.357384)
			(xy 295.950746 -411.398921) (xy 295.981519 -411.445434) (xy 296.005191 -411.495931) (xy 296.021259 -411.549338)
			(xy 296.029379 -411.604514) (xy 296.029888 -411.6324) (xy 296.029379 -411.660286) (xy 296.021259 -411.715462)
			(xy 296.005191 -411.768869) (xy 295.981519 -411.819366) (xy 295.950746 -411.865879) (xy 295.913529 -411.907416)
			(xy 295.870661 -411.943091) (xy 295.823055 -411.972145) (xy 295.771726 -411.993957) (xy 295.717769 -412.008063)
			(xy 295.662332 -412.014163) (xy 295.606598 -412.012126) (xy 295.551755 -412.001996) (xy 295.498971 -411.983989)
			(xy 295.449371 -411.958488) (xy 295.404013 -411.926037) (xy 295.363864 -411.887328) (xy 295.329778 -411.843185)
			(xy 295.302482 -411.79455) (xy 295.282559 -411.742459) (xy 295.270433 -411.688022) (xy 295.266362 -411.6324)
			(xy 294.306871 -411.6324) (xy 294.262966 -411.651057) (xy 294.209009 -411.665163) (xy 294.153572 -411.671263)
			(xy 294.097838 -411.669226) (xy 294.042995 -411.659096) (xy 293.990211 -411.641089) (xy 293.940611 -411.615588)
			(xy 293.895253 -411.583137) (xy 293.855104 -411.544428) (xy 293.821018 -411.500285) (xy 293.793722 -411.45165)
			(xy 293.773799 -411.399559) (xy 293.761673 -411.345122) (xy 293.757602 -411.2895) (xy 283.2481 -411.2895)
			(xy 283.2481 -411.696154) (xy 289.02355 -411.696154) (xy 289.027621 -411.640532) (xy 289.039747 -411.586095)
			(xy 289.05967 -411.534004) (xy 289.086966 -411.485369) (xy 289.121052 -411.441226) (xy 289.161201 -411.402517)
			(xy 289.206559 -411.370066) (xy 289.256159 -411.344565) (xy 289.308943 -411.326558) (xy 289.363786 -411.316428)
			(xy 289.41952 -411.314391) (xy 289.474957 -411.320491) (xy 289.528914 -411.334597) (xy 289.580243 -411.356409)
			(xy 289.627849 -411.385463) (xy 289.670717 -411.421138) (xy 289.707934 -411.462675) (xy 289.738707 -411.509188)
			(xy 289.762379 -411.559685) (xy 289.778447 -411.613092) (xy 289.786567 -411.668268) (xy 289.787076 -411.696154)
			(xy 289.786567 -411.72404) (xy 289.778447 -411.779216) (xy 289.762379 -411.832623) (xy 289.738707 -411.88312)
			(xy 289.707934 -411.929633) (xy 289.670717 -411.97117) (xy 289.627849 -412.006845) (xy 289.580243 -412.035899)
			(xy 289.528914 -412.057711) (xy 289.474957 -412.071817) (xy 289.41952 -412.077917) (xy 289.363786 -412.07588)
			(xy 289.308943 -412.06575) (xy 289.256159 -412.047743) (xy 289.206559 -412.022242) (xy 289.161201 -411.989791)
			(xy 289.121052 -411.951082) (xy 289.086966 -411.906939) (xy 289.05967 -411.858304) (xy 289.039747 -411.806213)
			(xy 289.027621 -411.751776) (xy 289.02355 -411.696154) (xy 283.2481 -411.696154) (xy 283.2481 -412.24708)
			(xy 297.440602 -412.24708) (xy 297.444673 -412.191458) (xy 297.456799 -412.137021) (xy 297.476722 -412.08493)
			(xy 297.504018 -412.036295) (xy 297.538104 -411.992152) (xy 297.578253 -411.953443) (xy 297.623611 -411.920992)
			(xy 297.673211 -411.895491) (xy 297.725995 -411.877484) (xy 297.780838 -411.867354) (xy 297.836572 -411.865317)
			(xy 297.892009 -411.871417) (xy 297.945966 -411.885523) (xy 297.997295 -411.907335) (xy 298.044901 -411.936389)
			(xy 298.087769 -411.972064) (xy 298.124986 -412.013601) (xy 298.155759 -412.060114) (xy 298.179431 -412.110611)
			(xy 298.195499 -412.164018) (xy 298.203619 -412.219194) (xy 298.204128 -412.24708) (xy 298.203619 -412.274966)
			(xy 298.195499 -412.330142) (xy 298.179431 -412.383549) (xy 298.155759 -412.434046) (xy 298.124986 -412.480559)
			(xy 298.087769 -412.522096) (xy 298.044901 -412.557771) (xy 297.997295 -412.586825) (xy 297.945966 -412.608637)
			(xy 297.892009 -412.622743) (xy 297.836572 -412.628843) (xy 297.780838 -412.626806) (xy 297.725995 -412.616676)
			(xy 297.673211 -412.598669) (xy 297.623611 -412.573168) (xy 297.578253 -412.540717) (xy 297.538104 -412.502008)
			(xy 297.504018 -412.457865) (xy 297.476722 -412.40923) (xy 297.456799 -412.357139) (xy 297.444673 -412.302702)
			(xy 297.440602 -412.24708) (xy 283.2481 -412.24708) (xy 283.2481 -412.86684) (xy 283.38221 -412.86684)
			(xy 283.386281 -412.811218) (xy 283.398407 -412.756781) (xy 283.41833 -412.70469) (xy 283.445626 -412.656055)
			(xy 283.479712 -412.611912) (xy 283.519861 -412.573203) (xy 283.565219 -412.540752) (xy 283.614819 -412.515251)
			(xy 283.667603 -412.497244) (xy 283.722446 -412.487114) (xy 283.77818 -412.485077) (xy 283.833617 -412.491177)
			(xy 283.887574 -412.505283) (xy 283.938903 -412.527095) (xy 283.986509 -412.556149) (xy 284.029377 -412.591824)
			(xy 284.066594 -412.633361) (xy 284.097367 -412.679874) (xy 284.121039 -412.730371) (xy 284.137107 -412.783778)
			(xy 284.145227 -412.838954) (xy 284.145736 -412.86684) (xy 284.145227 -412.894726) (xy 284.137107 -412.949902)
			(xy 284.1232 -412.996126) (xy 287.05251 -412.996126) (xy 287.056581 -412.940504) (xy 287.068707 -412.886067)
			(xy 287.08863 -412.833976) (xy 287.115926 -412.785341) (xy 287.150012 -412.741198) (xy 287.190161 -412.702489)
			(xy 287.235519 -412.670038) (xy 287.285119 -412.644537) (xy 287.337903 -412.62653) (xy 287.392746 -412.6164)
			(xy 287.44848 -412.614363) (xy 287.503917 -412.620463) (xy 287.557874 -412.634569) (xy 287.609203 -412.656381)
			(xy 287.621097 -412.66364) (xy 300.615602 -412.66364) (xy 300.619673 -412.608018) (xy 300.631799 -412.553581)
			(xy 300.651722 -412.50149) (xy 300.679018 -412.452855) (xy 300.713104 -412.408712) (xy 300.753253 -412.370003)
			(xy 300.798611 -412.337552) (xy 300.848211 -412.312051) (xy 300.900995 -412.294044) (xy 300.955838 -412.283914)
			(xy 301.011572 -412.281877) (xy 301.067009 -412.287977) (xy 301.120966 -412.302083) (xy 301.172295 -412.323895)
			(xy 301.200837 -412.341314) (xy 362.647482 -412.341314) (xy 362.651553 -412.285692) (xy 362.663679 -412.231255)
			(xy 362.683602 -412.179164) (xy 362.710898 -412.130529) (xy 362.744984 -412.086386) (xy 362.785133 -412.047677)
			(xy 362.830491 -412.015226) (xy 362.880091 -411.989725) (xy 362.932875 -411.971718) (xy 362.987718 -411.961588)
			(xy 363.043452 -411.959551) (xy 363.098889 -411.965651) (xy 363.152846 -411.979757) (xy 363.204175 -412.001569)
			(xy 363.251781 -412.030623) (xy 363.294649 -412.066298) (xy 363.331866 -412.107835) (xy 363.362639 -412.154348)
			(xy 363.386311 -412.204845) (xy 363.402379 -412.258252) (xy 363.410499 -412.313428) (xy 363.411008 -412.341314)
			(xy 363.410499 -412.3692) (xy 363.402379 -412.424376) (xy 363.386311 -412.477783) (xy 363.362639 -412.52828)
			(xy 363.331866 -412.574793) (xy 363.294649 -412.61633) (xy 363.251781 -412.652005) (xy 363.204175 -412.681059)
			(xy 363.152846 -412.702871) (xy 363.098889 -412.716977) (xy 363.043452 -412.723077) (xy 362.987718 -412.72104)
			(xy 362.932875 -412.71091) (xy 362.880091 -412.692903) (xy 362.830491 -412.667402) (xy 362.785133 -412.634951)
			(xy 362.744984 -412.596242) (xy 362.710898 -412.552099) (xy 362.683602 -412.503464) (xy 362.663679 -412.451373)
			(xy 362.651553 -412.396936) (xy 362.647482 -412.341314) (xy 301.200837 -412.341314) (xy 301.219901 -412.352949)
			(xy 301.262769 -412.388624) (xy 301.299986 -412.430161) (xy 301.330759 -412.476674) (xy 301.354431 -412.527171)
			(xy 301.370499 -412.580578) (xy 301.378619 -412.635754) (xy 301.379128 -412.66364) (xy 301.378619 -412.691526)
			(xy 301.370499 -412.746702) (xy 301.354431 -412.800109) (xy 301.330759 -412.850606) (xy 301.299986 -412.897119)
			(xy 301.262769 -412.938656) (xy 301.219901 -412.974331) (xy 301.172295 -413.003385) (xy 301.120966 -413.025197)
			(xy 301.067009 -413.039303) (xy 301.011572 -413.045403) (xy 300.955838 -413.043366) (xy 300.900995 -413.033236)
			(xy 300.848211 -413.015229) (xy 300.798611 -412.989728) (xy 300.753253 -412.957277) (xy 300.713104 -412.918568)
			(xy 300.679018 -412.874425) (xy 300.651722 -412.82579) (xy 300.631799 -412.773699) (xy 300.619673 -412.719262)
			(xy 300.615602 -412.66364) (xy 287.621097 -412.66364) (xy 287.656809 -412.685435) (xy 287.699677 -412.72111)
			(xy 287.736894 -412.762647) (xy 287.767667 -412.80916) (xy 287.791339 -412.859657) (xy 287.807407 -412.913064)
			(xy 287.815527 -412.96824) (xy 287.816036 -412.996126) (xy 287.815527 -413.024012) (xy 287.807407 -413.079188)
			(xy 287.791339 -413.132595) (xy 287.767667 -413.183092) (xy 287.736894 -413.229605) (xy 287.699677 -413.271142)
			(xy 287.656809 -413.306817) (xy 287.609203 -413.335871) (xy 287.557874 -413.357683) (xy 287.503917 -413.371789)
			(xy 287.44848 -413.377889) (xy 287.392746 -413.375852) (xy 287.337903 -413.365722) (xy 287.285119 -413.347715)
			(xy 287.235519 -413.322214) (xy 287.190161 -413.289763) (xy 287.150012 -413.251054) (xy 287.115926 -413.206911)
			(xy 287.08863 -413.158276) (xy 287.068707 -413.106185) (xy 287.056581 -413.051748) (xy 287.05251 -412.996126)
			(xy 284.1232 -412.996126) (xy 284.121039 -413.003309) (xy 284.097367 -413.053806) (xy 284.066594 -413.100319)
			(xy 284.029377 -413.141856) (xy 283.986509 -413.177531) (xy 283.938903 -413.206585) (xy 283.887574 -413.228397)
			(xy 283.833617 -413.242503) (xy 283.77818 -413.248603) (xy 283.722446 -413.246566) (xy 283.667603 -413.236436)
			(xy 283.614819 -413.218429) (xy 283.565219 -413.192928) (xy 283.519861 -413.160477) (xy 283.479712 -413.121768)
			(xy 283.445626 -413.077625) (xy 283.41833 -413.02899) (xy 283.398407 -412.976899) (xy 283.386281 -412.922462)
			(xy 283.38221 -412.86684) (xy 283.2481 -412.86684) (xy 283.2481 -413.63519) (xy 285.97174 -413.63519)
			(xy 285.975811 -413.579568) (xy 285.987937 -413.525131) (xy 286.00786 -413.47304) (xy 286.035156 -413.424405)
			(xy 286.069242 -413.380262) (xy 286.109391 -413.341553) (xy 286.154749 -413.309102) (xy 286.204349 -413.283601)
			(xy 286.257133 -413.265594) (xy 286.311976 -413.255464) (xy 286.36771 -413.253427) (xy 286.423147 -413.259527)
			(xy 286.477104 -413.273633) (xy 286.528433 -413.295445) (xy 286.576039 -413.324499) (xy 286.618907 -413.360174)
			(xy 286.656124 -413.401711) (xy 286.686897 -413.448224) (xy 286.710569 -413.498721) (xy 286.726637 -413.552128)
			(xy 286.734757 -413.607304) (xy 286.735266 -413.63519) (xy 286.734757 -413.663076) (xy 286.726637 -413.718252)
			(xy 286.725263 -413.72282) (xy 295.484802 -413.72282) (xy 295.488873 -413.667198) (xy 295.500999 -413.612761)
			(xy 295.520922 -413.56067) (xy 295.548218 -413.512035) (xy 295.582304 -413.467892) (xy 295.622453 -413.429183)
			(xy 295.667811 -413.396732) (xy 295.717411 -413.371231) (xy 295.770195 -413.353224) (xy 295.825038 -413.343094)
			(xy 295.880772 -413.341057) (xy 295.936209 -413.347157) (xy 295.990166 -413.361263) (xy 296.041495 -413.383075)
			(xy 296.048811 -413.38754) (xy 298.550582 -413.38754) (xy 298.554653 -413.331918) (xy 298.566779 -413.277481)
			(xy 298.586702 -413.22539) (xy 298.613998 -413.176755) (xy 298.648084 -413.132612) (xy 298.688233 -413.093903)
			(xy 298.733591 -413.061452) (xy 298.783191 -413.035951) (xy 298.835975 -413.017944) (xy 298.890818 -413.007814)
			(xy 298.946552 -413.005777) (xy 299.001989 -413.011877) (xy 299.055946 -413.025983) (xy 299.107275 -413.047795)
			(xy 299.154881 -413.076849) (xy 299.197749 -413.112524) (xy 299.234966 -413.154061) (xy 299.265739 -413.200574)
			(xy 299.289411 -413.251071) (xy 299.305479 -413.304478) (xy 299.313599 -413.359654) (xy 299.314108 -413.38754)
			(xy 299.313599 -413.415426) (xy 299.306863 -413.4612) (xy 304.265582 -413.4612) (xy 304.269653 -413.405578)
			(xy 304.281779 -413.351141) (xy 304.301702 -413.29905) (xy 304.328998 -413.250415) (xy 304.363084 -413.206272)
			(xy 304.403233 -413.167563) (xy 304.448591 -413.135112) (xy 304.498191 -413.109611) (xy 304.550975 -413.091604)
			(xy 304.605818 -413.081474) (xy 304.661552 -413.079437) (xy 304.716989 -413.085537) (xy 304.756812 -413.095948)
			(xy 355.217982 -413.095948) (xy 355.222053 -413.040326) (xy 355.234179 -412.985889) (xy 355.254102 -412.933798)
			(xy 355.281398 -412.885163) (xy 355.315484 -412.84102) (xy 355.355633 -412.802311) (xy 355.400991 -412.76986)
			(xy 355.450591 -412.744359) (xy 355.503375 -412.726352) (xy 355.558218 -412.716222) (xy 355.613952 -412.714185)
			(xy 355.669389 -412.720285) (xy 355.723346 -412.734391) (xy 355.774675 -412.756203) (xy 355.822281 -412.785257)
			(xy 355.865149 -412.820932) (xy 355.902366 -412.862469) (xy 355.933139 -412.908982) (xy 355.956811 -412.959479)
			(xy 355.972879 -413.012886) (xy 355.980999 -413.068062) (xy 355.981508 -413.095948) (xy 355.980999 -413.123834)
			(xy 355.972879 -413.17901) (xy 355.956811 -413.232417) (xy 355.933139 -413.282914) (xy 355.902366 -413.329427)
			(xy 355.865149 -413.370964) (xy 355.822281 -413.406639) (xy 355.774675 -413.435693) (xy 355.723346 -413.457505)
			(xy 355.669389 -413.471611) (xy 355.613952 -413.477711) (xy 355.558218 -413.475674) (xy 355.503375 -413.465544)
			(xy 355.450591 -413.447537) (xy 355.400991 -413.422036) (xy 355.355633 -413.389585) (xy 355.315484 -413.350876)
			(xy 355.281398 -413.306733) (xy 355.254102 -413.258098) (xy 355.234179 -413.206007) (xy 355.222053 -413.15157)
			(xy 355.217982 -413.095948) (xy 304.756812 -413.095948) (xy 304.770946 -413.099643) (xy 304.822275 -413.121455)
			(xy 304.869881 -413.150509) (xy 304.912749 -413.186184) (xy 304.949966 -413.227721) (xy 304.980739 -413.274234)
			(xy 305.004411 -413.324731) (xy 305.020479 -413.378138) (xy 305.028599 -413.433314) (xy 305.029108 -413.4612)
			(xy 305.028599 -413.489086) (xy 305.025601 -413.50946) (xy 368.319302 -413.50946) (xy 368.323373 -413.453838)
			(xy 368.335499 -413.399401) (xy 368.355422 -413.34731) (xy 368.382718 -413.298675) (xy 368.416804 -413.254532)
			(xy 368.456953 -413.215823) (xy 368.502311 -413.183372) (xy 368.551911 -413.157871) (xy 368.604695 -413.139864)
			(xy 368.659538 -413.129734) (xy 368.715272 -413.127697) (xy 368.770709 -413.133797) (xy 368.824666 -413.147903)
			(xy 368.875995 -413.169715) (xy 368.923601 -413.198769) (xy 368.966469 -413.234444) (xy 369.003686 -413.275981)
			(xy 369.034459 -413.322494) (xy 369.058131 -413.372991) (xy 369.074199 -413.426398) (xy 369.082319 -413.481574)
			(xy 369.082828 -413.50946) (xy 369.082319 -413.537346) (xy 369.074199 -413.592522) (xy 369.058131 -413.645929)
			(xy 369.034459 -413.696426) (xy 369.003686 -413.742939) (xy 368.966469 -413.784476) (xy 368.923601 -413.820151)
			(xy 368.875995 -413.849205) (xy 368.824666 -413.871017) (xy 368.770709 -413.885123) (xy 368.715272 -413.891223)
			(xy 368.659538 -413.889186) (xy 368.604695 -413.879056) (xy 368.551911 -413.861049) (xy 368.502311 -413.835548)
			(xy 368.456953 -413.803097) (xy 368.416804 -413.764388) (xy 368.382718 -413.720245) (xy 368.355422 -413.67161)
			(xy 368.335499 -413.619519) (xy 368.323373 -413.565082) (xy 368.319302 -413.50946) (xy 305.025601 -413.50946)
			(xy 305.020479 -413.544262) (xy 305.004411 -413.597669) (xy 304.980739 -413.648166) (xy 304.949966 -413.694679)
			(xy 304.912749 -413.736216) (xy 304.869881 -413.771891) (xy 304.822275 -413.800945) (xy 304.770946 -413.822757)
			(xy 304.716989 -413.836863) (xy 304.661552 -413.842963) (xy 304.605818 -413.840926) (xy 304.550975 -413.830796)
			(xy 304.498191 -413.812789) (xy 304.448591 -413.787288) (xy 304.403233 -413.754837) (xy 304.363084 -413.716128)
			(xy 304.328998 -413.671985) (xy 304.301702 -413.62335) (xy 304.281779 -413.571259) (xy 304.269653 -413.516822)
			(xy 304.265582 -413.4612) (xy 299.306863 -413.4612) (xy 299.305479 -413.470602) (xy 299.289411 -413.524009)
			(xy 299.265739 -413.574506) (xy 299.234966 -413.621019) (xy 299.197749 -413.662556) (xy 299.154881 -413.698231)
			(xy 299.107275 -413.727285) (xy 299.055946 -413.749097) (xy 299.001989 -413.763203) (xy 298.946552 -413.769303)
			(xy 298.890818 -413.767266) (xy 298.835975 -413.757136) (xy 298.783191 -413.739129) (xy 298.733591 -413.713628)
			(xy 298.688233 -413.681177) (xy 298.648084 -413.642468) (xy 298.613998 -413.598325) (xy 298.586702 -413.54969)
			(xy 298.566779 -413.497599) (xy 298.554653 -413.443162) (xy 298.550582 -413.38754) (xy 296.048811 -413.38754)
			(xy 296.089101 -413.412129) (xy 296.131969 -413.447804) (xy 296.169186 -413.489341) (xy 296.199959 -413.535854)
			(xy 296.223631 -413.586351) (xy 296.239699 -413.639758) (xy 296.247819 -413.694934) (xy 296.248328 -413.72282)
			(xy 296.247819 -413.750706) (xy 296.239699 -413.805882) (xy 296.223631 -413.859289) (xy 296.199959 -413.909786)
			(xy 296.169186 -413.956299) (xy 296.131969 -413.997836) (xy 296.089101 -414.033511) (xy 296.041495 -414.062565)
			(xy 295.990166 -414.084377) (xy 295.936209 -414.098483) (xy 295.880772 -414.104583) (xy 295.825038 -414.102546)
			(xy 295.770195 -414.092416) (xy 295.717411 -414.074409) (xy 295.667811 -414.048908) (xy 295.622453 -414.016457)
			(xy 295.582304 -413.977748) (xy 295.548218 -413.933605) (xy 295.520922 -413.88497) (xy 295.500999 -413.832879)
			(xy 295.488873 -413.778442) (xy 295.484802 -413.72282) (xy 286.725263 -413.72282) (xy 286.710569 -413.771659)
			(xy 286.686897 -413.822156) (xy 286.656124 -413.868669) (xy 286.618907 -413.910206) (xy 286.576039 -413.945881)
			(xy 286.528433 -413.974935) (xy 286.477104 -413.996747) (xy 286.423147 -414.010853) (xy 286.36771 -414.016953)
			(xy 286.311976 -414.014916) (xy 286.257133 -414.004786) (xy 286.204349 -413.986779) (xy 286.154749 -413.961278)
			(xy 286.109391 -413.928827) (xy 286.069242 -413.890118) (xy 286.035156 -413.845975) (xy 286.00786 -413.79734)
			(xy 285.987937 -413.745249) (xy 285.975811 -413.690812) (xy 285.97174 -413.63519) (xy 283.2481 -413.63519)
			(xy 283.2481 -414.111948) (xy 355.217982 -414.111948) (xy 355.222053 -414.056326) (xy 355.234179 -414.001889)
			(xy 355.254102 -413.949798) (xy 355.281398 -413.901163) (xy 355.315484 -413.85702) (xy 355.355633 -413.818311)
			(xy 355.400991 -413.78586) (xy 355.450591 -413.760359) (xy 355.503375 -413.742352) (xy 355.558218 -413.732222)
			(xy 355.613952 -413.730185) (xy 355.669389 -413.736285) (xy 355.723346 -413.750391) (xy 355.774675 -413.772203)
			(xy 355.822281 -413.801257) (xy 355.865149 -413.836932) (xy 355.902366 -413.878469) (xy 355.933139 -413.924982)
			(xy 355.956811 -413.975479) (xy 355.972879 -414.028886) (xy 355.980999 -414.084062) (xy 355.981508 -414.111948)
			(xy 355.980999 -414.139834) (xy 355.972879 -414.19501) (xy 355.956811 -414.248417) (xy 355.944818 -414.274)
			(xy 360.112562 -414.274) (xy 360.116633 -414.218378) (xy 360.128759 -414.163941) (xy 360.148682 -414.11185)
			(xy 360.175978 -414.063215) (xy 360.210064 -414.019072) (xy 360.250213 -413.980363) (xy 360.295571 -413.947912)
			(xy 360.345171 -413.922411) (xy 360.397955 -413.904404) (xy 360.452798 -413.894274) (xy 360.508532 -413.892237)
			(xy 360.563969 -413.898337) (xy 360.617926 -413.912443) (xy 360.669255 -413.934255) (xy 360.716861 -413.963309)
			(xy 360.759729 -413.998984) (xy 360.796946 -414.040521) (xy 360.827719 -414.087034) (xy 360.851391 -414.137531)
			(xy 360.867459 -414.190938) (xy 360.875579 -414.246114) (xy 360.876088 -414.274) (xy 360.875579 -414.301886)
			(xy 360.867459 -414.357062) (xy 360.851391 -414.410469) (xy 360.827719 -414.460966) (xy 360.796946 -414.507479)
			(xy 360.759729 -414.549016) (xy 360.716861 -414.584691) (xy 360.669255 -414.613745) (xy 360.617926 -414.635557)
			(xy 360.563969 -414.649663) (xy 360.508532 -414.655763) (xy 360.452798 -414.653726) (xy 360.397955 -414.643596)
			(xy 360.345171 -414.625589) (xy 360.295571 -414.600088) (xy 360.250213 -414.567637) (xy 360.210064 -414.528928)
			(xy 360.175978 -414.484785) (xy 360.148682 -414.43615) (xy 360.128759 -414.384059) (xy 360.116633 -414.329622)
			(xy 360.112562 -414.274) (xy 355.944818 -414.274) (xy 355.933139 -414.298914) (xy 355.902366 -414.345427)
			(xy 355.865149 -414.386964) (xy 355.822281 -414.422639) (xy 355.774675 -414.451693) (xy 355.723346 -414.473505)
			(xy 355.669389 -414.487611) (xy 355.613952 -414.493711) (xy 355.558218 -414.491674) (xy 355.503375 -414.481544)
			(xy 355.450591 -414.463537) (xy 355.400991 -414.438036) (xy 355.355633 -414.405585) (xy 355.315484 -414.366876)
			(xy 355.281398 -414.322733) (xy 355.254102 -414.274098) (xy 355.234179 -414.222007) (xy 355.222053 -414.16757)
			(xy 355.217982 -414.111948) (xy 283.2481 -414.111948) (xy 283.2481 -414.125664) (xy 283.264449 -414.14623)
			(xy 283.291941 -414.191) (xy 283.313029 -414.239119) (xy 283.327314 -414.289676) (xy 283.334525 -414.341716)
			(xy 283.334528 -414.394253) (xy 283.32732 -414.446293) (xy 283.313039 -414.496852) (xy 283.291955 -414.544973)
			(xy 283.264467 -414.589745) (xy 283.2481 -414.610296) (xy 283.2481 -415.00552) (xy 292.462202 -415.00552)
			(xy 292.466273 -414.949898) (xy 292.478399 -414.895461) (xy 292.498322 -414.84337) (xy 292.525618 -414.794735)
			(xy 292.559704 -414.750592) (xy 292.599853 -414.711883) (xy 292.645211 -414.679432) (xy 292.694811 -414.653931)
			(xy 292.747595 -414.635924) (xy 292.802438 -414.625794) (xy 292.858172 -414.623757) (xy 292.913609 -414.629857)
			(xy 292.967566 -414.643963) (xy 293.018895 -414.665775) (xy 293.066501 -414.694829) (xy 293.109369 -414.730504)
			(xy 293.146586 -414.772041) (xy 293.154855 -414.78454) (xy 300.615602 -414.78454) (xy 300.619673 -414.728918)
			(xy 300.631799 -414.674481) (xy 300.651722 -414.62239) (xy 300.679018 -414.573755) (xy 300.713104 -414.529612)
			(xy 300.753253 -414.490903) (xy 300.798611 -414.458452) (xy 300.848211 -414.432951) (xy 300.900995 -414.414944)
			(xy 300.955838 -414.404814) (xy 301.011572 -414.402777) (xy 301.067009 -414.408877) (xy 301.120966 -414.422983)
			(xy 301.172295 -414.444795) (xy 301.219901 -414.473849) (xy 301.262769 -414.509524) (xy 301.299986 -414.551061)
			(xy 301.330759 -414.597574) (xy 301.354431 -414.648071) (xy 301.370499 -414.701478) (xy 301.378619 -414.756654)
			(xy 301.379128 -414.78454) (xy 301.378619 -414.812426) (xy 301.370499 -414.867602) (xy 301.354431 -414.921009)
			(xy 301.330759 -414.971506) (xy 301.32338 -414.98266) (xy 304.824382 -414.98266) (xy 304.828453 -414.927038)
			(xy 304.840579 -414.872601) (xy 304.860502 -414.82051) (xy 304.887798 -414.771875) (xy 304.921884 -414.727732)
			(xy 304.962033 -414.689023) (xy 305.007391 -414.656572) (xy 305.056991 -414.631071) (xy 305.109775 -414.613064)
			(xy 305.164618 -414.602934) (xy 305.220352 -414.600897) (xy 305.275789 -414.606997) (xy 305.329746 -414.621103)
			(xy 305.381075 -414.642915) (xy 305.428681 -414.671969) (xy 305.471549 -414.707644) (xy 305.508766 -414.749181)
			(xy 305.539539 -414.795694) (xy 305.563211 -414.846191) (xy 305.579279 -414.899598) (xy 305.587399 -414.954774)
			(xy 305.587825 -414.978088) (xy 361.763562 -414.978088) (xy 361.767633 -414.922466) (xy 361.779759 -414.868029)
			(xy 361.799682 -414.815938) (xy 361.826978 -414.767303) (xy 361.861064 -414.72316) (xy 361.901213 -414.684451)
			(xy 361.946571 -414.652) (xy 361.996171 -414.626499) (xy 362.048955 -414.608492) (xy 362.103798 -414.598362)
			(xy 362.159532 -414.596325) (xy 362.214969 -414.602425) (xy 362.268926 -414.616531) (xy 362.320255 -414.638343)
			(xy 362.367861 -414.667397) (xy 362.410729 -414.703072) (xy 362.447946 -414.744609) (xy 362.455879 -414.7566)
			(xy 365.835182 -414.7566) (xy 365.839253 -414.700978) (xy 365.851379 -414.646541) (xy 365.871302 -414.59445)
			(xy 365.898598 -414.545815) (xy 365.932684 -414.501672) (xy 365.972833 -414.462963) (xy 366.018191 -414.430512)
			(xy 366.067791 -414.405011) (xy 366.120575 -414.387004) (xy 366.175418 -414.376874) (xy 366.231152 -414.374837)
			(xy 366.286589 -414.380937) (xy 366.340546 -414.395043) (xy 366.391875 -414.416855) (xy 366.439481 -414.445909)
			(xy 366.482349 -414.481584) (xy 366.519566 -414.523121) (xy 366.550339 -414.569634) (xy 366.574011 -414.620131)
			(xy 366.590079 -414.673538) (xy 366.598199 -414.728714) (xy 366.598708 -414.7566) (xy 366.598199 -414.784486)
			(xy 366.590079 -414.839662) (xy 366.574011 -414.893069) (xy 366.550339 -414.943566) (xy 366.519566 -414.990079)
			(xy 366.509372 -415.001456) (xy 375.045986 -415.001456) (xy 375.046472 -414.974205) (xy 375.054228 -414.920257)
			(xy 375.069583 -414.867962) (xy 375.092225 -414.818385) (xy 375.121691 -414.772535) (xy 375.157382 -414.731344)
			(xy 375.198573 -414.695653) (xy 375.244423 -414.666187) (xy 375.294 -414.643545) (xy 375.346295 -414.62819)
			(xy 375.400243 -414.620434) (xy 375.454745 -414.620434) (xy 375.508693 -414.62819) (xy 375.560988 -414.643545)
			(xy 375.610565 -414.666187) (xy 375.656415 -414.695653) (xy 375.697606 -414.731344) (xy 375.733297 -414.772535)
			(xy 375.762763 -414.818385) (xy 375.785405 -414.867962) (xy 375.80076 -414.920257) (xy 375.808516 -414.974205)
			(xy 375.809002 -415.001456) (xy 375.808486 -415.030194) (xy 375.799876 -415.08702) (xy 375.782842 -415.141913)
			(xy 375.757772 -415.193632) (xy 375.72523 -415.241007) (xy 375.685954 -415.282969) (xy 375.663714 -415.301176)
			(xy 375.652984 -415.310179) (xy 375.636495 -415.332806) (xy 375.626779 -415.359064) (xy 375.624568 -415.386974)
			(xy 375.630028 -415.414434) (xy 375.642748 -415.439376) (xy 375.661769 -415.45992) (xy 375.68566 -415.474519)
			(xy 375.69902 -415.478722) (xy 375.725377 -415.486597) (xy 375.775653 -415.508919) (xy 375.822202 -415.53823)
			(xy 375.864058 -415.573923) (xy 375.900355 -415.615258) (xy 375.930338 -415.661377) (xy 375.953387 -415.711324)
			(xy 375.969023 -415.764063) (xy 375.976923 -415.818502) (xy 375.977404 -415.846006) (xy 375.976918 -415.873257)
			(xy 375.969162 -415.927205) (xy 375.953807 -415.9795) (xy 375.931165 -416.029077) (xy 375.901699 -416.074927)
			(xy 375.866008 -416.116118) (xy 375.824817 -416.151809) (xy 375.778967 -416.181275) (xy 375.72939 -416.203917)
			(xy 375.677095 -416.219272) (xy 375.623147 -416.227028) (xy 375.568645 -416.227028) (xy 375.514697 -416.219272)
			(xy 375.462402 -416.203917) (xy 375.412825 -416.181275) (xy 375.366975 -416.151809) (xy 375.325784 -416.116118)
			(xy 375.290093 -416.074927) (xy 375.260627 -416.029077) (xy 375.237985 -415.9795) (xy 375.22263 -415.927205)
			(xy 375.214874 -415.873257) (xy 375.214388 -415.846006) (xy 375.214881 -415.817268) (xy 375.223497 -415.76044)
			(xy 375.240535 -415.705547) (xy 375.26561 -415.653828) (xy 375.298155 -415.606453) (xy 375.337435 -415.564493)
			(xy 375.359676 -415.546286) (xy 375.370451 -415.537333) (xy 375.386942 -415.514695) (xy 375.396657 -415.488427)
			(xy 375.398865 -415.460506) (xy 375.393398 -415.433037) (xy 375.38067 -415.408089) (xy 375.361637 -415.387542)
			(xy 375.337736 -415.372943) (xy 375.32437 -415.36874) (xy 375.29802 -415.360842) (xy 375.24774 -415.338529)
			(xy 375.201187 -415.309224) (xy 375.159328 -415.273535) (xy 375.123029 -415.232203) (xy 375.093044 -415.186086)
			(xy 375.069995 -415.136139) (xy 375.05436 -415.083399) (xy 375.046464 -415.02896) (xy 375.045986 -415.001456)
			(xy 366.509372 -415.001456) (xy 366.482349 -415.031616) (xy 366.439481 -415.067291) (xy 366.391875 -415.096345)
			(xy 366.340546 -415.118157) (xy 366.286589 -415.132263) (xy 366.231152 -415.138363) (xy 366.175418 -415.136326)
			(xy 366.120575 -415.126196) (xy 366.067791 -415.108189) (xy 366.018191 -415.082688) (xy 365.972833 -415.050237)
			(xy 365.932684 -415.011528) (xy 365.898598 -414.967385) (xy 365.871302 -414.91875) (xy 365.851379 -414.866659)
			(xy 365.839253 -414.812222) (xy 365.835182 -414.7566) (xy 362.455879 -414.7566) (xy 362.478719 -414.791122)
			(xy 362.502391 -414.841619) (xy 362.518459 -414.895026) (xy 362.526579 -414.950202) (xy 362.527088 -414.978088)
			(xy 362.526579 -415.005974) (xy 362.518459 -415.06115) (xy 362.502391 -415.114557) (xy 362.478719 -415.165054)
			(xy 362.447946 -415.211567) (xy 362.410729 -415.253104) (xy 362.367861 -415.288779) (xy 362.320255 -415.317833)
			(xy 362.268926 -415.339645) (xy 362.214969 -415.353751) (xy 362.159532 -415.359851) (xy 362.103798 -415.357814)
			(xy 362.048955 -415.347684) (xy 361.996171 -415.329677) (xy 361.946571 -415.304176) (xy 361.901213 -415.271725)
			(xy 361.861064 -415.233016) (xy 361.826978 -415.188873) (xy 361.799682 -415.140238) (xy 361.779759 -415.088147)
			(xy 361.767633 -415.03371) (xy 361.763562 -414.978088) (xy 305.587825 -414.978088) (xy 305.587908 -414.98266)
			(xy 305.587399 -415.010546) (xy 305.579279 -415.065722) (xy 305.563211 -415.119129) (xy 305.539539 -415.169626)
			(xy 305.508766 -415.216139) (xy 305.471549 -415.257676) (xy 305.428681 -415.293351) (xy 305.381075 -415.322405)
			(xy 305.329746 -415.344217) (xy 305.275789 -415.358323) (xy 305.220352 -415.364423) (xy 305.164618 -415.362386)
			(xy 305.109775 -415.352256) (xy 305.056991 -415.334249) (xy 305.007391 -415.308748) (xy 304.962033 -415.276297)
			(xy 304.921884 -415.237588) (xy 304.887798 -415.193445) (xy 304.860502 -415.14481) (xy 304.840579 -415.092719)
			(xy 304.828453 -415.038282) (xy 304.824382 -414.98266) (xy 301.32338 -414.98266) (xy 301.299986 -415.018019)
			(xy 301.262769 -415.059556) (xy 301.219901 -415.095231) (xy 301.172295 -415.124285) (xy 301.120966 -415.146097)
			(xy 301.067009 -415.160203) (xy 301.011572 -415.166303) (xy 300.955838 -415.164266) (xy 300.900995 -415.154136)
			(xy 300.848211 -415.136129) (xy 300.798611 -415.110628) (xy 300.753253 -415.078177) (xy 300.713104 -415.039468)
			(xy 300.679018 -414.995325) (xy 300.651722 -414.94669) (xy 300.631799 -414.894599) (xy 300.619673 -414.840162)
			(xy 300.615602 -414.78454) (xy 293.154855 -414.78454) (xy 293.177359 -414.818554) (xy 293.201031 -414.869051)
			(xy 293.217099 -414.922458) (xy 293.225219 -414.977634) (xy 293.225728 -415.00552) (xy 293.225219 -415.033406)
			(xy 293.217099 -415.088582) (xy 293.201031 -415.141989) (xy 293.177359 -415.192486) (xy 293.146586 -415.238999)
			(xy 293.109369 -415.280536) (xy 293.066501 -415.316211) (xy 293.018895 -415.345265) (xy 292.967566 -415.367077)
			(xy 292.913609 -415.381183) (xy 292.858172 -415.387283) (xy 292.802438 -415.385246) (xy 292.747595 -415.375116)
			(xy 292.694811 -415.357109) (xy 292.645211 -415.331608) (xy 292.599853 -415.299157) (xy 292.559704 -415.260448)
			(xy 292.525618 -415.216305) (xy 292.498322 -415.16767) (xy 292.478399 -415.115579) (xy 292.466273 -415.061142)
			(xy 292.462202 -415.00552) (xy 283.2481 -415.00552) (xy 283.2481 -415.033206) (xy 283.476954 -415.26206)
			(xy 291.5666 -415.26206) (xy 292.86454 -416.56) (xy 300.861982 -416.56) (xy 300.866053 -416.504378)
			(xy 300.878179 -416.449941) (xy 300.898102 -416.39785) (xy 300.925398 -416.349215) (xy 300.959484 -416.305072)
			(xy 300.999633 -416.266363) (xy 301.044991 -416.233912) (xy 301.094591 -416.208411) (xy 301.147375 -416.190404)
			(xy 301.202218 -416.180274) (xy 301.257952 -416.178237) (xy 301.313389 -416.184337) (xy 301.367346 -416.198443)
			(xy 301.418675 -416.220255) (xy 301.466281 -416.249309) (xy 301.492283 -416.270948) (xy 357.884982 -416.270948)
			(xy 357.889053 -416.215326) (xy 357.901179 -416.160889) (xy 357.921102 -416.108798) (xy 357.948398 -416.060163)
			(xy 357.982484 -416.01602) (xy 358.022633 -415.977311) (xy 358.067991 -415.94486) (xy 358.117591 -415.919359)
			(xy 358.170375 -415.901352) (xy 358.225218 -415.891222) (xy 358.280952 -415.889185) (xy 358.336389 -415.895285)
			(xy 358.390346 -415.909391) (xy 358.441675 -415.931203) (xy 358.489281 -415.960257) (xy 358.532149 -415.995932)
			(xy 358.569366 -416.037469) (xy 358.600139 -416.083982) (xy 358.623811 -416.134479) (xy 358.639879 -416.187886)
			(xy 358.647999 -416.243062) (xy 358.648508 -416.270948) (xy 358.647999 -416.298834) (xy 358.639879 -416.35401)
			(xy 358.623811 -416.407417) (xy 358.600139 -416.457914) (xy 358.569366 -416.504427) (xy 358.532149 -416.545964)
			(xy 358.489281 -416.581639) (xy 358.441675 -416.610693) (xy 358.390346 -416.632505) (xy 358.336389 -416.646611)
			(xy 358.280952 -416.652711) (xy 358.225218 -416.650674) (xy 358.170375 -416.640544) (xy 358.117591 -416.622537)
			(xy 358.067991 -416.597036) (xy 358.022633 -416.564585) (xy 357.982484 -416.525876) (xy 357.948398 -416.481733)
			(xy 357.921102 -416.433098) (xy 357.901179 -416.381007) (xy 357.889053 -416.32657) (xy 357.884982 -416.270948)
			(xy 301.492283 -416.270948) (xy 301.509149 -416.284984) (xy 301.546366 -416.326521) (xy 301.577139 -416.373034)
			(xy 301.600811 -416.423531) (xy 301.616879 -416.476938) (xy 301.624999 -416.532114) (xy 301.625508 -416.56)
			(xy 301.624999 -416.587886) (xy 301.616879 -416.643062) (xy 301.600811 -416.696469) (xy 301.577139 -416.746966)
			(xy 301.546366 -416.793479) (xy 301.509149 -416.835016) (xy 301.466281 -416.870691) (xy 301.418675 -416.899745)
			(xy 301.381364 -416.9156) (xy 351.814382 -416.9156) (xy 351.818453 -416.859978) (xy 351.830579 -416.805541)
			(xy 351.850502 -416.75345) (xy 351.877798 -416.704815) (xy 351.911884 -416.660672) (xy 351.952033 -416.621963)
			(xy 351.997391 -416.589512) (xy 352.046991 -416.564011) (xy 352.099775 -416.546004) (xy 352.154618 -416.535874)
			(xy 352.210352 -416.533837) (xy 352.265789 -416.539937) (xy 352.319746 -416.554043) (xy 352.371075 -416.575855)
			(xy 352.418681 -416.604909) (xy 352.461549 -416.640584) (xy 352.498766 -416.682121) (xy 352.529539 -416.728634)
			(xy 352.553211 -416.779131) (xy 352.569279 -416.832538) (xy 352.577399 -416.887714) (xy 352.577908 -416.9156)
			(xy 352.577399 -416.943486) (xy 352.569279 -416.998662) (xy 352.553211 -417.052069) (xy 352.529539 -417.102566)
			(xy 352.517574 -417.120651) (xy 354.431578 -417.120651) (xy 354.431578 -417.066149) (xy 354.439334 -417.012201)
			(xy 354.454689 -416.959906) (xy 354.477331 -416.910329) (xy 354.506797 -416.864479) (xy 354.542488 -416.823288)
			(xy 354.583679 -416.787597) (xy 354.629529 -416.758131) (xy 354.679106 -416.735489) (xy 354.731401 -416.720134)
			(xy 354.785349 -416.712378) (xy 354.8126 -416.711892) (xy 354.841007 -416.712388) (xy 354.89719 -416.720834)
			(xy 354.951502 -416.737508) (xy 355.002745 -416.762044) (xy 355.049789 -416.7939) (xy 355.091594 -416.832373)
			(xy 355.127239 -416.876614) (xy 355.142038 -416.900868) (xy 355.149371 -416.912726) (xy 355.169412 -416.932103)
			(xy 355.193946 -416.945338) (xy 355.221145 -416.951444) (xy 355.248982 -416.949966) (xy 355.275381 -416.941014)
			(xy 355.298376 -416.925255) (xy 355.307646 -416.914838) (xy 355.32586 -416.89387) (xy 355.367341 -416.856936)
			(xy 355.413738 -416.826407) (xy 355.464071 -416.802927) (xy 355.517276 -416.786992) (xy 355.57223 -416.77894)
			(xy 355.6 -416.77844) (xy 355.627255 -416.77883) (xy 355.681209 -416.786587) (xy 355.733511 -416.801944)
			(xy 355.783094 -416.824588) (xy 355.783218 -416.824668) (xy 358.578402 -416.824668) (xy 358.582473 -416.769046)
			(xy 358.594599 -416.714609) (xy 358.614522 -416.662518) (xy 358.641818 -416.613883) (xy 358.675904 -416.56974)
			(xy 358.716053 -416.531031) (xy 358.761411 -416.49858) (xy 358.811011 -416.473079) (xy 358.863795 -416.455072)
			(xy 358.918638 -416.444942) (xy 358.974372 -416.442905) (xy 359.029809 -416.449005) (xy 359.083766 -416.463111)
			(xy 359.135095 -416.484923) (xy 359.182701 -416.513977) (xy 359.225569 -416.549652) (xy 359.262786 -416.591189)
			(xy 359.293559 -416.637702) (xy 359.317231 -416.688199) (xy 359.333299 -416.741606) (xy 359.341419 -416.796782)
			(xy 359.341928 -416.824668) (xy 359.341419 -416.852554) (xy 359.333299 -416.90773) (xy 359.317231 -416.961137)
			(xy 359.293559 -417.011634) (xy 359.262786 -417.058147) (xy 359.225569 -417.099684) (xy 359.182701 -417.135359)
			(xy 359.135095 -417.164413) (xy 359.083766 -417.186225) (xy 359.029809 -417.200331) (xy 358.974372 -417.206431)
			(xy 358.918638 -417.204394) (xy 358.863795 -417.194264) (xy 358.811011 -417.176257) (xy 358.761411 -417.150756)
			(xy 358.716053 -417.118305) (xy 358.675904 -417.079596) (xy 358.641818 -417.035453) (xy 358.614522 -416.986818)
			(xy 358.594599 -416.934727) (xy 358.582473 -416.88029) (xy 358.578402 -416.824668) (xy 355.783218 -416.824668)
			(xy 355.82895 -416.854058) (xy 355.870146 -416.889754) (xy 355.905842 -416.93095) (xy 355.935312 -416.976806)
			(xy 355.957956 -417.026389) (xy 355.973313 -417.078691) (xy 355.98107 -417.132645) (xy 355.98107 -417.187155)
			(xy 355.973313 -417.241109) (xy 355.957956 -417.293411) (xy 355.935312 -417.342994) (xy 355.905842 -417.38885)
			(xy 355.870146 -417.430046) (xy 355.82895 -417.465742) (xy 355.783094 -417.495212) (xy 355.733511 -417.517856)
			(xy 355.681209 -417.533213) (xy 355.627255 -417.54097) (xy 355.6 -417.541456) (xy 355.571594 -417.540936)
			(xy 355.515413 -417.532492) (xy 355.461103 -417.51582) (xy 355.409861 -417.491287) (xy 355.362817 -417.459435)
			(xy 355.321011 -417.420967) (xy 355.285363 -417.376731) (xy 355.270562 -417.35248) (xy 355.263226 -417.340622)
			(xy 355.24319 -417.321237) (xy 355.218656 -417.307996) (xy 355.191455 -417.301888) (xy 355.163616 -417.303367)
			(xy 355.137215 -417.312323) (xy 355.114222 -417.328089) (xy 355.104954 -417.33851) (xy 355.086728 -417.359467)
			(xy 355.045251 -417.396404) (xy 354.998857 -417.426936) (xy 354.948526 -417.450418) (xy 354.895322 -417.466354)
			(xy 354.84037 -417.474407) (xy 354.8126 -417.474908) (xy 354.785349 -417.474422) (xy 354.731401 -417.466666)
			(xy 354.679106 -417.451311) (xy 354.629529 -417.428669) (xy 354.583679 -417.399203) (xy 354.542488 -417.363512)
			(xy 354.506797 -417.322321) (xy 354.477331 -417.276471) (xy 354.454689 -417.226894) (xy 354.439334 -417.174599)
			(xy 354.431578 -417.120651) (xy 352.517574 -417.120651) (xy 352.498766 -417.149079) (xy 352.461549 -417.190616)
			(xy 352.418681 -417.226291) (xy 352.371075 -417.255345) (xy 352.319746 -417.277157) (xy 352.265789 -417.291263)
			(xy 352.210352 -417.297363) (xy 352.154618 -417.295326) (xy 352.099775 -417.285196) (xy 352.046991 -417.267189)
			(xy 351.997391 -417.241688) (xy 351.952033 -417.209237) (xy 351.911884 -417.170528) (xy 351.877798 -417.126385)
			(xy 351.850502 -417.07775) (xy 351.830579 -417.025659) (xy 351.818453 -416.971222) (xy 351.814382 -416.9156)
			(xy 301.381364 -416.9156) (xy 301.367346 -416.921557) (xy 301.313389 -416.935663) (xy 301.257952 -416.941763)
			(xy 301.202218 -416.939726) (xy 301.147375 -416.929596) (xy 301.094591 -416.911589) (xy 301.044991 -416.886088)
			(xy 300.999633 -416.853637) (xy 300.959484 -416.814928) (xy 300.925398 -416.770785) (xy 300.898102 -416.72215)
			(xy 300.878179 -416.670059) (xy 300.866053 -416.615622) (xy 300.861982 -416.56) (xy 292.86454 -416.56)
			(xy 293.52494 -417.2204) (xy 293.832532 -417.2204) (xy 293.836603 -417.164778) (xy 293.848729 -417.110341)
			(xy 293.868652 -417.05825) (xy 293.895948 -417.009615) (xy 293.930034 -416.965472) (xy 293.970183 -416.926763)
			(xy 294.015541 -416.894312) (xy 294.065141 -416.868811) (xy 294.117925 -416.850804) (xy 294.172768 -416.840674)
			(xy 294.228502 -416.838637) (xy 294.283939 -416.844737) (xy 294.337896 -416.858843) (xy 294.389225 -416.880655)
			(xy 294.436831 -416.909709) (xy 294.479699 -416.945384) (xy 294.516916 -416.986921) (xy 294.547689 -417.033434)
			(xy 294.571361 -417.083931) (xy 294.587429 -417.137338) (xy 294.595549 -417.192514) (xy 294.596058 -417.2204)
			(xy 296.626532 -417.2204) (xy 296.630603 -417.164778) (xy 296.642729 -417.110341) (xy 296.662652 -417.05825)
			(xy 296.689948 -417.009615) (xy 296.724034 -416.965472) (xy 296.764183 -416.926763) (xy 296.809541 -416.894312)
			(xy 296.859141 -416.868811) (xy 296.911925 -416.850804) (xy 296.966768 -416.840674) (xy 297.022502 -416.838637)
			(xy 297.077939 -416.844737) (xy 297.131896 -416.858843) (xy 297.183225 -416.880655) (xy 297.230831 -416.909709)
			(xy 297.273699 -416.945384) (xy 297.310916 -416.986921) (xy 297.341689 -417.033434) (xy 297.365361 -417.083931)
			(xy 297.381429 -417.137338) (xy 297.389549 -417.192514) (xy 297.390058 -417.2204) (xy 299.420532 -417.2204)
			(xy 299.424603 -417.164778) (xy 299.436729 -417.110341) (xy 299.456652 -417.05825) (xy 299.483948 -417.009615)
			(xy 299.518034 -416.965472) (xy 299.558183 -416.926763) (xy 299.603541 -416.894312) (xy 299.653141 -416.868811)
			(xy 299.705925 -416.850804) (xy 299.760768 -416.840674) (xy 299.816502 -416.838637) (xy 299.871939 -416.844737)
			(xy 299.925896 -416.858843) (xy 299.977225 -416.880655) (xy 300.024831 -416.909709) (xy 300.067699 -416.945384)
			(xy 300.104916 -416.986921) (xy 300.135689 -417.033434) (xy 300.159361 -417.083931) (xy 300.175429 -417.137338)
			(xy 300.183549 -417.192514) (xy 300.184058 -417.2204) (xy 300.183549 -417.248286) (xy 300.176065 -417.29914)
			(xy 302.105312 -417.29914) (xy 302.109383 -417.243518) (xy 302.121509 -417.189081) (xy 302.141432 -417.13699)
			(xy 302.168728 -417.088355) (xy 302.202814 -417.044212) (xy 302.242963 -417.005503) (xy 302.288321 -416.973052)
			(xy 302.337921 -416.947551) (xy 302.390705 -416.929544) (xy 302.445548 -416.919414) (xy 302.501282 -416.917377)
			(xy 302.556719 -416.923477) (xy 302.610676 -416.937583) (xy 302.662005 -416.959395) (xy 302.709611 -416.988449)
			(xy 302.752479 -417.024124) (xy 302.789696 -417.065661) (xy 302.820469 -417.112174) (xy 302.844141 -417.162671)
			(xy 302.860209 -417.216078) (xy 302.868329 -417.271254) (xy 302.868838 -417.29914) (xy 302.868329 -417.327026)
			(xy 302.860209 -417.382202) (xy 302.844141 -417.435609) (xy 302.820469 -417.486106) (xy 302.789696 -417.532619)
			(xy 302.752479 -417.574156) (xy 302.709611 -417.609831) (xy 302.662005 -417.638885) (xy 302.610676 -417.660697)
			(xy 302.556719 -417.674803) (xy 302.501282 -417.680903) (xy 302.445548 -417.678866) (xy 302.390705 -417.668736)
			(xy 302.337921 -417.650729) (xy 302.288321 -417.625228) (xy 302.242963 -417.592777) (xy 302.202814 -417.554068)
			(xy 302.168728 -417.509925) (xy 302.141432 -417.46129) (xy 302.121509 -417.409199) (xy 302.109383 -417.354762)
			(xy 302.105312 -417.29914) (xy 300.176065 -417.29914) (xy 300.175429 -417.303462) (xy 300.159361 -417.356869)
			(xy 300.135689 -417.407366) (xy 300.104916 -417.453879) (xy 300.067699 -417.495416) (xy 300.024831 -417.531091)
			(xy 299.977225 -417.560145) (xy 299.925896 -417.581957) (xy 299.871939 -417.596063) (xy 299.816502 -417.602163)
			(xy 299.760768 -417.600126) (xy 299.705925 -417.589996) (xy 299.653141 -417.571989) (xy 299.603541 -417.546488)
			(xy 299.558183 -417.514037) (xy 299.518034 -417.475328) (xy 299.483948 -417.431185) (xy 299.456652 -417.38255)
			(xy 299.436729 -417.330459) (xy 299.424603 -417.276022) (xy 299.420532 -417.2204) (xy 297.390058 -417.2204)
			(xy 297.389549 -417.248286) (xy 297.381429 -417.303462) (xy 297.365361 -417.356869) (xy 297.341689 -417.407366)
			(xy 297.310916 -417.453879) (xy 297.273699 -417.495416) (xy 297.230831 -417.531091) (xy 297.183225 -417.560145)
			(xy 297.131896 -417.581957) (xy 297.077939 -417.596063) (xy 297.022502 -417.602163) (xy 296.966768 -417.600126)
			(xy 296.911925 -417.589996) (xy 296.859141 -417.571989) (xy 296.809541 -417.546488) (xy 296.764183 -417.514037)
			(xy 296.724034 -417.475328) (xy 296.689948 -417.431185) (xy 296.662652 -417.38255) (xy 296.642729 -417.330459)
			(xy 296.630603 -417.276022) (xy 296.626532 -417.2204) (xy 294.596058 -417.2204) (xy 294.595549 -417.248286)
			(xy 294.587429 -417.303462) (xy 294.571361 -417.356869) (xy 294.547689 -417.407366) (xy 294.516916 -417.453879)
			(xy 294.479699 -417.495416) (xy 294.436831 -417.531091) (xy 294.389225 -417.560145) (xy 294.337896 -417.581957)
			(xy 294.283939 -417.596063) (xy 294.228502 -417.602163) (xy 294.172768 -417.600126) (xy 294.117925 -417.589996)
			(xy 294.065141 -417.571989) (xy 294.015541 -417.546488) (xy 293.970183 -417.514037) (xy 293.930034 -417.475328)
			(xy 293.895948 -417.431185) (xy 293.868652 -417.38255) (xy 293.848729 -417.330459) (xy 293.836603 -417.276022)
			(xy 293.832532 -417.2204) (xy 293.52494 -417.2204) (xy 293.92118 -417.61664) (xy 293.92118 -417.990528)
			(xy 294.240202 -417.990528) (xy 294.244273 -417.934906) (xy 294.256399 -417.880469) (xy 294.276322 -417.828378)
			(xy 294.303618 -417.779743) (xy 294.337704 -417.7356) (xy 294.377853 -417.696891) (xy 294.423211 -417.66444)
			(xy 294.472811 -417.638939) (xy 294.525595 -417.620932) (xy 294.580438 -417.610802) (xy 294.636172 -417.608765)
			(xy 294.691609 -417.614865) (xy 294.745566 -417.628971) (xy 294.796895 -417.650783) (xy 294.844501 -417.679837)
			(xy 294.887369 -417.715512) (xy 294.924586 -417.757049) (xy 294.955359 -417.803562) (xy 294.979031 -417.854059)
			(xy 294.995099 -417.907466) (xy 295.003219 -417.962642) (xy 295.003728 -417.990528) (xy 295.484802 -417.990528)
			(xy 295.488873 -417.934906) (xy 295.500999 -417.880469) (xy 295.520922 -417.828378) (xy 295.548218 -417.779743)
			(xy 295.582304 -417.7356) (xy 295.622453 -417.696891) (xy 295.667811 -417.66444) (xy 295.717411 -417.638939)
			(xy 295.770195 -417.620932) (xy 295.825038 -417.610802) (xy 295.880772 -417.608765) (xy 295.936209 -417.614865)
			(xy 295.990166 -417.628971) (xy 296.041495 -417.650783) (xy 296.089101 -417.679837) (xy 296.131969 -417.715512)
			(xy 296.169186 -417.757049) (xy 296.199959 -417.803562) (xy 296.223631 -417.854059) (xy 296.239699 -417.907466)
			(xy 296.247819 -417.962642) (xy 296.248328 -417.990528) (xy 297.034202 -417.990528) (xy 297.038273 -417.934906)
			(xy 297.050399 -417.880469) (xy 297.070322 -417.828378) (xy 297.097618 -417.779743) (xy 297.131704 -417.7356)
			(xy 297.171853 -417.696891) (xy 297.217211 -417.66444) (xy 297.266811 -417.638939) (xy 297.319595 -417.620932)
			(xy 297.374438 -417.610802) (xy 297.430172 -417.608765) (xy 297.485609 -417.614865) (xy 297.539566 -417.628971)
			(xy 297.590895 -417.650783) (xy 297.638501 -417.679837) (xy 297.681369 -417.715512) (xy 297.718586 -417.757049)
			(xy 297.749359 -417.803562) (xy 297.773031 -417.854059) (xy 297.789099 -417.907466) (xy 297.797219 -417.962642)
			(xy 297.797728 -417.990528) (xy 298.278802 -417.990528) (xy 298.282873 -417.934906) (xy 298.294999 -417.880469)
			(xy 298.314922 -417.828378) (xy 298.342218 -417.779743) (xy 298.376304 -417.7356) (xy 298.416453 -417.696891)
			(xy 298.461811 -417.66444) (xy 298.511411 -417.638939) (xy 298.564195 -417.620932) (xy 298.619038 -417.610802)
			(xy 298.674772 -417.608765) (xy 298.730209 -417.614865) (xy 298.784166 -417.628971) (xy 298.835495 -417.650783)
			(xy 298.883101 -417.679837) (xy 298.925969 -417.715512) (xy 298.963186 -417.757049) (xy 298.993959 -417.803562)
			(xy 299.017631 -417.854059) (xy 299.033699 -417.907466) (xy 299.041819 -417.962642) (xy 299.042328 -417.990528)
			(xy 299.828202 -417.990528) (xy 299.832273 -417.934906) (xy 299.844399 -417.880469) (xy 299.864322 -417.828378)
			(xy 299.891618 -417.779743) (xy 299.925704 -417.7356) (xy 299.965853 -417.696891) (xy 300.011211 -417.66444)
			(xy 300.060811 -417.638939) (xy 300.113595 -417.620932) (xy 300.168438 -417.610802) (xy 300.224172 -417.608765)
			(xy 300.279609 -417.614865) (xy 300.333566 -417.628971) (xy 300.384895 -417.650783) (xy 300.432501 -417.679837)
			(xy 300.475369 -417.715512) (xy 300.512586 -417.757049) (xy 300.543359 -417.803562) (xy 300.567031 -417.854059)
			(xy 300.583099 -417.907466) (xy 300.591219 -417.962642) (xy 300.591728 -417.990528) (xy 301.072802 -417.990528)
			(xy 301.076873 -417.934906) (xy 301.088999 -417.880469) (xy 301.108922 -417.828378) (xy 301.136218 -417.779743)
			(xy 301.170304 -417.7356) (xy 301.210453 -417.696891) (xy 301.255811 -417.66444) (xy 301.305411 -417.638939)
			(xy 301.358195 -417.620932) (xy 301.413038 -417.610802) (xy 301.468772 -417.608765) (xy 301.524209 -417.614865)
			(xy 301.578166 -417.628971) (xy 301.629495 -417.650783) (xy 301.677101 -417.679837) (xy 301.719969 -417.715512)
			(xy 301.757186 -417.757049) (xy 301.787959 -417.803562) (xy 301.811631 -417.854059) (xy 301.827699 -417.907466)
			(xy 301.835819 -417.962642) (xy 301.836328 -417.990528) (xy 301.835819 -418.018414) (xy 301.828335 -418.069268)
			(xy 302.512982 -418.069268) (xy 302.517053 -418.013646) (xy 302.529179 -417.959209) (xy 302.549102 -417.907118)
			(xy 302.576398 -417.858483) (xy 302.610484 -417.81434) (xy 302.650633 -417.775631) (xy 302.695991 -417.74318)
			(xy 302.745591 -417.717679) (xy 302.798375 -417.699672) (xy 302.853218 -417.689542) (xy 302.908952 -417.687505)
			(xy 302.964389 -417.693605) (xy 303.018346 -417.707711) (xy 303.069675 -417.729523) (xy 303.117281 -417.758577)
			(xy 303.160149 -417.794252) (xy 303.197366 -417.835789) (xy 303.228139 -417.882302) (xy 303.251811 -417.932799)
			(xy 303.267879 -417.986206) (xy 303.275999 -418.041382) (xy 303.276508 -418.069268) (xy 303.757582 -418.069268)
			(xy 303.761653 -418.013646) (xy 303.773779 -417.959209) (xy 303.793702 -417.907118) (xy 303.820998 -417.858483)
			(xy 303.855084 -417.81434) (xy 303.895233 -417.775631) (xy 303.940591 -417.74318) (xy 303.990191 -417.717679)
			(xy 304.042975 -417.699672) (xy 304.097818 -417.689542) (xy 304.153552 -417.687505) (xy 304.208989 -417.693605)
			(xy 304.262946 -417.707711) (xy 304.314275 -417.729523) (xy 304.361881 -417.758577) (xy 304.404749 -417.794252)
			(xy 304.441966 -417.835789) (xy 304.472739 -417.882302) (xy 304.496411 -417.932799) (xy 304.512479 -417.986206)
			(xy 304.515657 -418.0078) (xy 351.712782 -418.0078) (xy 351.716853 -417.952178) (xy 351.728979 -417.897741)
			(xy 351.748902 -417.84565) (xy 351.776198 -417.797015) (xy 351.810284 -417.752872) (xy 351.850433 -417.714163)
			(xy 351.895791 -417.681712) (xy 351.945391 -417.656211) (xy 351.998175 -417.638204) (xy 352.053018 -417.628074)
			(xy 352.108752 -417.626037) (xy 352.164189 -417.632137) (xy 352.218146 -417.646243) (xy 352.269475 -417.668055)
			(xy 352.317081 -417.697109) (xy 352.359949 -417.732784) (xy 352.397166 -417.774321) (xy 352.427939 -417.820834)
			(xy 352.451611 -417.871331) (xy 352.467679 -417.924738) (xy 352.475799 -417.979914) (xy 352.476308 -418.0078)
			(xy 352.475799 -418.035686) (xy 352.467679 -418.090862) (xy 352.451611 -418.144269) (xy 352.427939 -418.194766)
			(xy 352.397166 -418.241279) (xy 352.359949 -418.282816) (xy 352.317081 -418.318491) (xy 352.269475 -418.347545)
			(xy 352.218146 -418.369357) (xy 352.164189 -418.383463) (xy 352.108752 -418.389563) (xy 352.053018 -418.387526)
			(xy 351.998175 -418.377396) (xy 351.945391 -418.359389) (xy 351.895791 -418.333888) (xy 351.850433 -418.301437)
			(xy 351.810284 -418.262728) (xy 351.776198 -418.218585) (xy 351.748902 -418.16995) (xy 351.728979 -418.117859)
			(xy 351.716853 -418.063422) (xy 351.712782 -418.0078) (xy 304.515657 -418.0078) (xy 304.520599 -418.041382)
			(xy 304.521108 -418.069268) (xy 304.520599 -418.097154) (xy 304.512479 -418.15233) (xy 304.496411 -418.205737)
			(xy 304.472739 -418.256234) (xy 304.441966 -418.302747) (xy 304.404749 -418.344284) (xy 304.361881 -418.379959)
			(xy 304.314275 -418.409013) (xy 304.262946 -418.430825) (xy 304.208989 -418.444931) (xy 304.153552 -418.451031)
			(xy 304.097818 -418.448994) (xy 304.042975 -418.438864) (xy 303.990191 -418.420857) (xy 303.940591 -418.395356)
			(xy 303.895233 -418.362905) (xy 303.855084 -418.324196) (xy 303.820998 -418.280053) (xy 303.793702 -418.231418)
			(xy 303.773779 -418.179327) (xy 303.761653 -418.12489) (xy 303.757582 -418.069268) (xy 303.276508 -418.069268)
			(xy 303.275999 -418.097154) (xy 303.267879 -418.15233) (xy 303.251811 -418.205737) (xy 303.228139 -418.256234)
			(xy 303.197366 -418.302747) (xy 303.160149 -418.344284) (xy 303.117281 -418.379959) (xy 303.069675 -418.409013)
			(xy 303.018346 -418.430825) (xy 302.964389 -418.444931) (xy 302.908952 -418.451031) (xy 302.853218 -418.448994)
			(xy 302.798375 -418.438864) (xy 302.745591 -418.420857) (xy 302.695991 -418.395356) (xy 302.650633 -418.362905)
			(xy 302.610484 -418.324196) (xy 302.576398 -418.280053) (xy 302.549102 -418.231418) (xy 302.529179 -418.179327)
			(xy 302.517053 -418.12489) (xy 302.512982 -418.069268) (xy 301.828335 -418.069268) (xy 301.827699 -418.07359)
			(xy 301.811631 -418.126997) (xy 301.787959 -418.177494) (xy 301.757186 -418.224007) (xy 301.719969 -418.265544)
			(xy 301.677101 -418.301219) (xy 301.629495 -418.330273) (xy 301.578166 -418.352085) (xy 301.524209 -418.366191)
			(xy 301.468772 -418.372291) (xy 301.413038 -418.370254) (xy 301.358195 -418.360124) (xy 301.305411 -418.342117)
			(xy 301.255811 -418.316616) (xy 301.210453 -418.284165) (xy 301.170304 -418.245456) (xy 301.136218 -418.201313)
			(xy 301.108922 -418.152678) (xy 301.088999 -418.100587) (xy 301.076873 -418.04615) (xy 301.072802 -417.990528)
			(xy 300.591728 -417.990528) (xy 300.591219 -418.018414) (xy 300.583099 -418.07359) (xy 300.567031 -418.126997)
			(xy 300.543359 -418.177494) (xy 300.512586 -418.224007) (xy 300.475369 -418.265544) (xy 300.432501 -418.301219)
			(xy 300.384895 -418.330273) (xy 300.333566 -418.352085) (xy 300.279609 -418.366191) (xy 300.224172 -418.372291)
			(xy 300.168438 -418.370254) (xy 300.113595 -418.360124) (xy 300.060811 -418.342117) (xy 300.011211 -418.316616)
			(xy 299.965853 -418.284165) (xy 299.925704 -418.245456) (xy 299.891618 -418.201313) (xy 299.864322 -418.152678)
			(xy 299.844399 -418.100587) (xy 299.832273 -418.04615) (xy 299.828202 -417.990528) (xy 299.042328 -417.990528)
			(xy 299.041819 -418.018414) (xy 299.033699 -418.07359) (xy 299.017631 -418.126997) (xy 298.993959 -418.177494)
			(xy 298.963186 -418.224007) (xy 298.925969 -418.265544) (xy 298.883101 -418.301219) (xy 298.835495 -418.330273)
			(xy 298.784166 -418.352085) (xy 298.730209 -418.366191) (xy 298.674772 -418.372291) (xy 298.619038 -418.370254)
			(xy 298.564195 -418.360124) (xy 298.511411 -418.342117) (xy 298.461811 -418.316616) (xy 298.416453 -418.284165)
			(xy 298.376304 -418.245456) (xy 298.342218 -418.201313) (xy 298.314922 -418.152678) (xy 298.294999 -418.100587)
			(xy 298.282873 -418.04615) (xy 298.278802 -417.990528) (xy 297.797728 -417.990528) (xy 297.797219 -418.018414)
			(xy 297.789099 -418.07359) (xy 297.773031 -418.126997) (xy 297.749359 -418.177494) (xy 297.718586 -418.224007)
			(xy 297.681369 -418.265544) (xy 297.638501 -418.301219) (xy 297.590895 -418.330273) (xy 297.539566 -418.352085)
			(xy 297.485609 -418.366191) (xy 297.430172 -418.372291) (xy 297.374438 -418.370254) (xy 297.319595 -418.360124)
			(xy 297.266811 -418.342117) (xy 297.217211 -418.316616) (xy 297.171853 -418.284165) (xy 297.131704 -418.245456)
			(xy 297.097618 -418.201313) (xy 297.070322 -418.152678) (xy 297.050399 -418.100587) (xy 297.038273 -418.04615)
			(xy 297.034202 -417.990528) (xy 296.248328 -417.990528) (xy 296.247819 -418.018414) (xy 296.239699 -418.07359)
			(xy 296.223631 -418.126997) (xy 296.199959 -418.177494) (xy 296.169186 -418.224007) (xy 296.131969 -418.265544)
			(xy 296.089101 -418.301219) (xy 296.041495 -418.330273) (xy 295.990166 -418.352085) (xy 295.936209 -418.366191)
			(xy 295.880772 -418.372291) (xy 295.825038 -418.370254) (xy 295.770195 -418.360124) (xy 295.717411 -418.342117)
			(xy 295.667811 -418.316616) (xy 295.622453 -418.284165) (xy 295.582304 -418.245456) (xy 295.548218 -418.201313)
			(xy 295.520922 -418.152678) (xy 295.500999 -418.100587) (xy 295.488873 -418.04615) (xy 295.484802 -417.990528)
			(xy 295.003728 -417.990528) (xy 295.003219 -418.018414) (xy 294.995099 -418.07359) (xy 294.979031 -418.126997)
			(xy 294.955359 -418.177494) (xy 294.924586 -418.224007) (xy 294.887369 -418.265544) (xy 294.844501 -418.301219)
			(xy 294.796895 -418.330273) (xy 294.745566 -418.352085) (xy 294.691609 -418.366191) (xy 294.636172 -418.372291)
			(xy 294.580438 -418.370254) (xy 294.525595 -418.360124) (xy 294.472811 -418.342117) (xy 294.423211 -418.316616)
			(xy 294.377853 -418.284165) (xy 294.337704 -418.245456) (xy 294.303618 -418.201313) (xy 294.276322 -418.152678)
			(xy 294.256399 -418.100587) (xy 294.244273 -418.04615) (xy 294.240202 -417.990528) (xy 293.92118 -417.990528)
			(xy 293.92118 -419.064948) (xy 366.031524 -419.064948) (xy 366.035595 -419.009326) (xy 366.047721 -418.954889)
			(xy 366.067644 -418.902798) (xy 366.09494 -418.854163) (xy 366.129026 -418.81002) (xy 366.169175 -418.771311)
			(xy 366.214533 -418.73886) (xy 366.264133 -418.713359) (xy 366.316917 -418.695352) (xy 366.37176 -418.685222)
			(xy 366.427494 -418.683185) (xy 366.482931 -418.689285) (xy 366.536888 -418.703391) (xy 366.588217 -418.725203)
			(xy 366.635823 -418.754257) (xy 366.678691 -418.789932) (xy 366.715908 -418.831469) (xy 366.746681 -418.877982)
			(xy 366.770353 -418.928479) (xy 366.786421 -418.981886) (xy 366.794541 -419.037062) (xy 366.79505 -419.064948)
			(xy 366.794541 -419.092834) (xy 366.786421 -419.14801) (xy 366.770353 -419.201417) (xy 366.746681 -419.251914)
			(xy 366.715908 -419.298427) (xy 366.678691 -419.339964) (xy 366.635823 -419.375639) (xy 366.588217 -419.404693)
			(xy 366.536888 -419.426505) (xy 366.482931 -419.440611) (xy 366.427494 -419.446711) (xy 366.37176 -419.444674)
			(xy 366.316917 -419.434544) (xy 366.264133 -419.416537) (xy 366.214533 -419.391036) (xy 366.169175 -419.358585)
			(xy 366.129026 -419.319876) (xy 366.09494 -419.275733) (xy 366.067644 -419.227098) (xy 366.047721 -419.175007)
			(xy 366.035595 -419.12057) (xy 366.031524 -419.064948) (xy 293.92118 -419.064948) (xy 293.92118 -419.73627)
			(xy 294.863264 -419.73627) (xy 294.867335 -419.680648) (xy 294.879461 -419.626211) (xy 294.899384 -419.57412)
			(xy 294.92668 -419.525485) (xy 294.960766 -419.481342) (xy 295.000915 -419.442633) (xy 295.046273 -419.410182)
			(xy 295.095873 -419.384681) (xy 295.148657 -419.366674) (xy 295.2035 -419.356544) (xy 295.259234 -419.354507)
			(xy 295.314671 -419.360607) (xy 295.368628 -419.374713) (xy 295.419957 -419.396525) (xy 295.467563 -419.425579)
			(xy 295.510431 -419.461254) (xy 295.547648 -419.502791) (xy 295.578421 -419.549304) (xy 295.602093 -419.599801)
			(xy 295.618161 -419.653208) (xy 295.626281 -419.708384) (xy 295.62679 -419.73627) (xy 297.657264 -419.73627)
			(xy 297.661335 -419.680648) (xy 297.673461 -419.626211) (xy 297.693384 -419.57412) (xy 297.72068 -419.525485)
			(xy 297.754766 -419.481342) (xy 297.794915 -419.442633) (xy 297.840273 -419.410182) (xy 297.889873 -419.384681)
			(xy 297.942657 -419.366674) (xy 297.9975 -419.356544) (xy 298.053234 -419.354507) (xy 298.108671 -419.360607)
			(xy 298.162628 -419.374713) (xy 298.213957 -419.396525) (xy 298.261563 -419.425579) (xy 298.304431 -419.461254)
			(xy 298.341648 -419.502791) (xy 298.372421 -419.549304) (xy 298.396093 -419.599801) (xy 298.412161 -419.653208)
			(xy 298.420281 -419.708384) (xy 298.42079 -419.73627) (xy 300.451264 -419.73627) (xy 300.455335 -419.680648)
			(xy 300.467461 -419.626211) (xy 300.487384 -419.57412) (xy 300.51468 -419.525485) (xy 300.548766 -419.481342)
			(xy 300.588915 -419.442633) (xy 300.634273 -419.410182) (xy 300.683873 -419.384681) (xy 300.736657 -419.366674)
			(xy 300.7915 -419.356544) (xy 300.847234 -419.354507) (xy 300.902671 -419.360607) (xy 300.956628 -419.374713)
			(xy 301.007957 -419.396525) (xy 301.055563 -419.425579) (xy 301.098431 -419.461254) (xy 301.135648 -419.502791)
			(xy 301.166421 -419.549304) (xy 301.190093 -419.599801) (xy 301.206161 -419.653208) (xy 301.214281 -419.708384)
			(xy 301.21479 -419.73627) (xy 301.214281 -419.764156) (xy 301.206161 -419.819332) (xy 301.200202 -419.83914)
			(xy 305.896262 -419.83914) (xy 305.900333 -419.783518) (xy 305.912459 -419.729081) (xy 305.932382 -419.67699)
			(xy 305.959678 -419.628355) (xy 305.993764 -419.584212) (xy 306.033913 -419.545503) (xy 306.079271 -419.513052)
			(xy 306.128871 -419.487551) (xy 306.181655 -419.469544) (xy 306.236498 -419.459414) (xy 306.292232 -419.457377)
			(xy 306.347669 -419.463477) (xy 306.401626 -419.477583) (xy 306.452955 -419.499395) (xy 306.500561 -419.528449)
			(xy 306.543429 -419.564124) (xy 306.580646 -419.605661) (xy 306.611419 -419.652174) (xy 306.635091 -419.702671)
			(xy 306.651159 -419.756078) (xy 306.659279 -419.811254) (xy 306.659788 -419.83914) (xy 306.659279 -419.867026)
			(xy 306.651159 -419.922202) (xy 306.635091 -419.975609) (xy 306.611419 -420.026106) (xy 306.580646 -420.072619)
			(xy 306.543429 -420.114156) (xy 306.500561 -420.149831) (xy 306.452955 -420.178885) (xy 306.401626 -420.200697)
			(xy 306.347669 -420.214803) (xy 306.292232 -420.220903) (xy 306.236498 -420.218866) (xy 306.181655 -420.208736)
			(xy 306.128871 -420.190729) (xy 306.079271 -420.165228) (xy 306.033913 -420.132777) (xy 305.993764 -420.094068)
			(xy 305.959678 -420.049925) (xy 305.932382 -420.00129) (xy 305.912459 -419.949199) (xy 305.900333 -419.894762)
			(xy 305.896262 -419.83914) (xy 301.200202 -419.83914) (xy 301.190093 -419.872739) (xy 301.166421 -419.923236)
			(xy 301.135648 -419.969749) (xy 301.098431 -420.011286) (xy 301.055563 -420.046961) (xy 301.007957 -420.076015)
			(xy 300.956628 -420.097827) (xy 300.902671 -420.111933) (xy 300.847234 -420.118033) (xy 300.7915 -420.115996)
			(xy 300.736657 -420.105866) (xy 300.683873 -420.087859) (xy 300.634273 -420.062358) (xy 300.588915 -420.029907)
			(xy 300.548766 -419.991198) (xy 300.51468 -419.947055) (xy 300.487384 -419.89842) (xy 300.467461 -419.846329)
			(xy 300.455335 -419.791892) (xy 300.451264 -419.73627) (xy 298.42079 -419.73627) (xy 298.420281 -419.764156)
			(xy 298.412161 -419.819332) (xy 298.396093 -419.872739) (xy 298.372421 -419.923236) (xy 298.341648 -419.969749)
			(xy 298.304431 -420.011286) (xy 298.261563 -420.046961) (xy 298.213957 -420.076015) (xy 298.162628 -420.097827)
			(xy 298.108671 -420.111933) (xy 298.053234 -420.118033) (xy 297.9975 -420.115996) (xy 297.942657 -420.105866)
			(xy 297.889873 -420.087859) (xy 297.840273 -420.062358) (xy 297.794915 -420.029907) (xy 297.754766 -419.991198)
			(xy 297.72068 -419.947055) (xy 297.693384 -419.89842) (xy 297.673461 -419.846329) (xy 297.661335 -419.791892)
			(xy 297.657264 -419.73627) (xy 295.62679 -419.73627) (xy 295.626281 -419.764156) (xy 295.618161 -419.819332)
			(xy 295.602093 -419.872739) (xy 295.578421 -419.923236) (xy 295.547648 -419.969749) (xy 295.510431 -420.011286)
			(xy 295.467563 -420.046961) (xy 295.419957 -420.076015) (xy 295.368628 -420.097827) (xy 295.314671 -420.111933)
			(xy 295.259234 -420.118033) (xy 295.2035 -420.115996) (xy 295.148657 -420.105866) (xy 295.095873 -420.087859)
			(xy 295.046273 -420.062358) (xy 295.000915 -420.029907) (xy 294.960766 -419.991198) (xy 294.92668 -419.947055)
			(xy 294.899384 -419.89842) (xy 294.879461 -419.846329) (xy 294.867335 -419.791892) (xy 294.863264 -419.73627)
			(xy 293.92118 -419.73627) (xy 293.92118 -421.23741) (xy 307.07406 -421.23741) (xy 307.078131 -421.181788)
			(xy 307.090257 -421.127351) (xy 307.11018 -421.07526) (xy 307.137476 -421.026625) (xy 307.171562 -420.982482)
			(xy 307.211711 -420.943773) (xy 307.257069 -420.911322) (xy 307.306669 -420.885821) (xy 307.359453 -420.867814)
			(xy 307.414296 -420.857684) (xy 307.47003 -420.855647) (xy 307.525467 -420.861747) (xy 307.579424 -420.875853)
			(xy 307.630753 -420.897665) (xy 307.678359 -420.926719) (xy 307.721227 -420.962394) (xy 307.758444 -421.003931)
			(xy 307.789217 -421.050444) (xy 307.812889 -421.100941) (xy 307.828957 -421.154348) (xy 307.837077 -421.209524)
			(xy 307.837586 -421.23741) (xy 307.837077 -421.265296) (xy 307.828957 -421.320472) (xy 307.812889 -421.373879)
			(xy 307.789217 -421.424376) (xy 307.758444 -421.470889) (xy 307.721227 -421.512426) (xy 307.678359 -421.548101)
			(xy 307.630753 -421.577155) (xy 307.579424 -421.598967) (xy 307.525467 -421.613073) (xy 307.47003 -421.619173)
			(xy 307.414296 -421.617136) (xy 307.359453 -421.607006) (xy 307.306669 -421.588999) (xy 307.257069 -421.563498)
			(xy 307.211711 -421.531047) (xy 307.171562 -421.492338) (xy 307.137476 -421.448195) (xy 307.11018 -421.39956)
			(xy 307.090257 -421.347469) (xy 307.078131 -421.293032) (xy 307.07406 -421.23741) (xy 293.92118 -421.23741)
			(xy 293.92118 -423.954448) (xy 294.667684 -423.954448) (xy 294.671755 -423.898826) (xy 294.683881 -423.844389)
			(xy 294.703804 -423.792298) (xy 294.7311 -423.743663) (xy 294.765186 -423.69952) (xy 294.805335 -423.660811)
			(xy 294.850693 -423.62836) (xy 294.900293 -423.602859) (xy 294.953077 -423.584852) (xy 295.00792 -423.574722)
			(xy 295.063654 -423.572685) (xy 295.119091 -423.578785) (xy 295.173048 -423.592891) (xy 295.224377 -423.614703)
			(xy 295.271983 -423.643757) (xy 295.314851 -423.679432) (xy 295.352068 -423.720969) (xy 295.382841 -423.767482)
			(xy 295.406513 -423.817979) (xy 295.422581 -423.871386) (xy 295.430701 -423.926562) (xy 295.43121 -423.954448)
			(xy 297.461684 -423.954448) (xy 297.465755 -423.898826) (xy 297.477881 -423.844389) (xy 297.497804 -423.792298)
			(xy 297.5251 -423.743663) (xy 297.559186 -423.69952) (xy 297.599335 -423.660811) (xy 297.644693 -423.62836)
			(xy 297.694293 -423.602859) (xy 297.747077 -423.584852) (xy 297.80192 -423.574722) (xy 297.857654 -423.572685)
			(xy 297.913091 -423.578785) (xy 297.967048 -423.592891) (xy 298.018377 -423.614703) (xy 298.065983 -423.643757)
			(xy 298.108851 -423.679432) (xy 298.146068 -423.720969) (xy 298.176841 -423.767482) (xy 298.200513 -423.817979)
			(xy 298.216581 -423.871386) (xy 298.224701 -423.926562) (xy 298.22521 -423.954448) (xy 300.255684 -423.954448)
			(xy 300.259755 -423.898826) (xy 300.271881 -423.844389) (xy 300.291804 -423.792298) (xy 300.3191 -423.743663)
			(xy 300.353186 -423.69952) (xy 300.393335 -423.660811) (xy 300.438693 -423.62836) (xy 300.488293 -423.602859)
			(xy 300.541077 -423.584852) (xy 300.59592 -423.574722) (xy 300.651654 -423.572685) (xy 300.707091 -423.578785)
			(xy 300.761048 -423.592891) (xy 300.812377 -423.614703) (xy 300.859983 -423.643757) (xy 300.902851 -423.679432)
			(xy 300.940068 -423.720969) (xy 300.970841 -423.767482) (xy 300.994513 -423.817979) (xy 301.010581 -423.871386)
			(xy 301.018701 -423.926562) (xy 301.01921 -423.954448) (xy 301.018701 -423.982334) (xy 301.011217 -424.033188)
			(xy 302.940464 -424.033188) (xy 302.944535 -423.977566) (xy 302.956661 -423.923129) (xy 302.976584 -423.871038)
			(xy 303.00388 -423.822403) (xy 303.037966 -423.77826) (xy 303.078115 -423.739551) (xy 303.123473 -423.7071)
			(xy 303.173073 -423.681599) (xy 303.225857 -423.663592) (xy 303.2807 -423.653462) (xy 303.336434 -423.651425)
			(xy 303.391871 -423.657525) (xy 303.445828 -423.671631) (xy 303.497157 -423.693443) (xy 303.544763 -423.722497)
			(xy 303.587631 -423.758172) (xy 303.624848 -423.799709) (xy 303.655621 -423.846222) (xy 303.679293 -423.896719)
			(xy 303.695361 -423.950126) (xy 303.703481 -424.005302) (xy 303.70399 -424.033188) (xy 303.703481 -424.061074)
			(xy 303.695361 -424.11625) (xy 303.679293 -424.169657) (xy 303.655621 -424.220154) (xy 303.624848 -424.266667)
			(xy 303.587631 -424.308204) (xy 303.544763 -424.343879) (xy 303.497157 -424.372933) (xy 303.445828 -424.394745)
			(xy 303.391871 -424.408851) (xy 303.336434 -424.414951) (xy 303.2807 -424.412914) (xy 303.225857 -424.402784)
			(xy 303.173073 -424.384777) (xy 303.123473 -424.359276) (xy 303.078115 -424.326825) (xy 303.037966 -424.288116)
			(xy 303.00388 -424.243973) (xy 302.976584 -424.195338) (xy 302.956661 -424.143247) (xy 302.944535 -424.08881)
			(xy 302.940464 -424.033188) (xy 301.011217 -424.033188) (xy 301.010581 -424.03751) (xy 300.994513 -424.090917)
			(xy 300.970841 -424.141414) (xy 300.940068 -424.187927) (xy 300.902851 -424.229464) (xy 300.859983 -424.265139)
			(xy 300.812377 -424.294193) (xy 300.761048 -424.316005) (xy 300.707091 -424.330111) (xy 300.651654 -424.336211)
			(xy 300.59592 -424.334174) (xy 300.541077 -424.324044) (xy 300.488293 -424.306037) (xy 300.438693 -424.280536)
			(xy 300.393335 -424.248085) (xy 300.353186 -424.209376) (xy 300.3191 -424.165233) (xy 300.291804 -424.116598)
			(xy 300.271881 -424.064507) (xy 300.259755 -424.01007) (xy 300.255684 -423.954448) (xy 298.22521 -423.954448)
			(xy 298.224701 -423.982334) (xy 298.216581 -424.03751) (xy 298.200513 -424.090917) (xy 298.176841 -424.141414)
			(xy 298.146068 -424.187927) (xy 298.108851 -424.229464) (xy 298.065983 -424.265139) (xy 298.018377 -424.294193)
			(xy 297.967048 -424.316005) (xy 297.913091 -424.330111) (xy 297.857654 -424.336211) (xy 297.80192 -424.334174)
			(xy 297.747077 -424.324044) (xy 297.694293 -424.306037) (xy 297.644693 -424.280536) (xy 297.599335 -424.248085)
			(xy 297.559186 -424.209376) (xy 297.5251 -424.165233) (xy 297.497804 -424.116598) (xy 297.477881 -424.064507)
			(xy 297.465755 -424.01007) (xy 297.461684 -423.954448) (xy 295.43121 -423.954448) (xy 295.430701 -423.982334)
			(xy 295.422581 -424.03751) (xy 295.406513 -424.090917) (xy 295.382841 -424.141414) (xy 295.352068 -424.187927)
			(xy 295.314851 -424.229464) (xy 295.271983 -424.265139) (xy 295.224377 -424.294193) (xy 295.173048 -424.316005)
			(xy 295.119091 -424.330111) (xy 295.063654 -424.336211) (xy 295.00792 -424.334174) (xy 294.953077 -424.324044)
			(xy 294.900293 -424.306037) (xy 294.850693 -424.280536) (xy 294.805335 -424.248085) (xy 294.765186 -424.209376)
			(xy 294.7311 -424.165233) (xy 294.703804 -424.116598) (xy 294.683881 -424.064507) (xy 294.671755 -424.01007)
			(xy 294.667684 -423.954448) (xy 293.92118 -423.954448) (xy 293.92118 -425.831) (xy 307.968902 -425.831)
			(xy 307.972973 -425.775378) (xy 307.985099 -425.720941) (xy 308.005022 -425.66885) (xy 308.032318 -425.620215)
			(xy 308.066404 -425.576072) (xy 308.106553 -425.537363) (xy 308.151911 -425.504912) (xy 308.201511 -425.479411)
			(xy 308.254295 -425.461404) (xy 308.309138 -425.451274) (xy 308.364872 -425.449237) (xy 308.420309 -425.455337)
			(xy 308.474266 -425.469443) (xy 308.525595 -425.491255) (xy 308.573201 -425.520309) (xy 308.616069 -425.555984)
			(xy 308.653286 -425.597521) (xy 308.684059 -425.644034) (xy 308.707731 -425.694531) (xy 308.723799 -425.747938)
			(xy 308.731919 -425.803114) (xy 308.732428 -425.831) (xy 308.731919 -425.858886) (xy 308.723799 -425.914062)
			(xy 308.707731 -425.967469) (xy 308.684059 -426.017966) (xy 308.653286 -426.064479) (xy 308.616069 -426.106016)
			(xy 308.573201 -426.141691) (xy 308.525595 -426.170745) (xy 308.474266 -426.192557) (xy 308.420309 -426.206663)
			(xy 308.364872 -426.212763) (xy 308.309138 -426.210726) (xy 308.254295 -426.200596) (xy 308.201511 -426.182589)
			(xy 308.151911 -426.157088) (xy 308.106553 -426.124637) (xy 308.066404 -426.085928) (xy 308.032318 -426.041785)
			(xy 308.005022 -425.99315) (xy 307.985099 -425.941059) (xy 307.972973 -425.886622) (xy 307.968902 -425.831)
			(xy 293.92118 -425.831) (xy 293.92118 -426.39996) (xy 294.15105 -426.62983) (xy 294.163496 -426.633386)
			(xy 294.189474 -426.641534) (xy 294.238989 -426.664171) (xy 294.284784 -426.693617) (xy 294.325927 -426.729273)
			(xy 294.361583 -426.770416) (xy 294.391029 -426.816211) (xy 294.413666 -426.865726) (xy 294.421814 -426.891704)
			(xy 294.42537 -426.90415) (xy 294.690038 -427.168818) (xy 304.699922 -427.168818) (xy 304.703993 -427.113196)
			(xy 304.716119 -427.058759) (xy 304.736042 -427.006668) (xy 304.763338 -426.958033) (xy 304.797424 -426.91389)
			(xy 304.837573 -426.875181) (xy 304.882931 -426.84273) (xy 304.932531 -426.817229) (xy 304.985315 -426.799222)
			(xy 305.040158 -426.789092) (xy 305.095892 -426.787055) (xy 305.151329 -426.793155) (xy 305.205286 -426.807261)
			(xy 305.256615 -426.829073) (xy 305.304221 -426.858127) (xy 305.347089 -426.893802) (xy 305.384306 -426.935339)
			(xy 305.415079 -426.981852) (xy 305.438751 -427.032349) (xy 305.454819 -427.085756) (xy 305.462939 -427.140932)
			(xy 305.463448 -427.168818) (xy 305.462939 -427.196704) (xy 305.454819 -427.25188) (xy 305.438751 -427.305287)
			(xy 305.415079 -427.355784) (xy 305.384306 -427.402297) (xy 305.347089 -427.443834) (xy 305.304221 -427.479509)
			(xy 305.256615 -427.508563) (xy 305.205286 -427.530375) (xy 305.151329 -427.544481) (xy 305.095892 -427.550581)
			(xy 305.040158 -427.548544) (xy 304.985315 -427.538414) (xy 304.932531 -427.520407) (xy 304.882931 -427.494906)
			(xy 304.837573 -427.462455) (xy 304.797424 -427.423746) (xy 304.763338 -427.379603) (xy 304.736042 -427.330968)
			(xy 304.716119 -427.278877) (xy 304.703993 -427.22444) (xy 304.699922 -427.168818) (xy 294.690038 -427.168818)
			(xy 294.9702 -427.44898) (xy 299.1993 -427.44898) (xy 299.91304 -428.16272) (xy 306.241702 -428.16272)
			(xy 306.245773 -428.107098) (xy 306.257899 -428.052661) (xy 306.277822 -428.00057) (xy 306.305118 -427.951935)
			(xy 306.339204 -427.907792) (xy 306.379353 -427.869083) (xy 306.424711 -427.836632) (xy 306.474311 -427.811131)
			(xy 306.527095 -427.793124) (xy 306.581938 -427.782994) (xy 306.637672 -427.780957) (xy 306.693109 -427.787057)
			(xy 306.747066 -427.801163) (xy 306.798395 -427.822975) (xy 306.846001 -427.852029) (xy 306.865288 -427.86808)
			(xy 308.789322 -427.86808) (xy 308.793393 -427.812458) (xy 308.805519 -427.758021) (xy 308.825442 -427.70593)
			(xy 308.852738 -427.657295) (xy 308.886824 -427.613152) (xy 308.926973 -427.574443) (xy 308.972331 -427.541992)
			(xy 309.021931 -427.516491) (xy 309.074715 -427.498484) (xy 309.129558 -427.488354) (xy 309.185292 -427.486317)
			(xy 309.240729 -427.492417) (xy 309.294686 -427.506523) (xy 309.346015 -427.528335) (xy 309.393621 -427.557389)
			(xy 309.436489 -427.593064) (xy 309.473706 -427.634601) (xy 309.504479 -427.681114) (xy 309.528151 -427.731611)
			(xy 309.544219 -427.785018) (xy 309.552339 -427.840194) (xy 309.552848 -427.86808) (xy 309.552339 -427.895966)
			(xy 309.544219 -427.951142) (xy 309.528151 -428.004549) (xy 309.504479 -428.055046) (xy 309.473706 -428.101559)
			(xy 309.436489 -428.143096) (xy 309.393621 -428.178771) (xy 309.346015 -428.207825) (xy 309.294686 -428.229637)
			(xy 309.240729 -428.243743) (xy 309.185292 -428.249843) (xy 309.129558 -428.247806) (xy 309.074715 -428.237676)
			(xy 309.021931 -428.219669) (xy 308.972331 -428.194168) (xy 308.926973 -428.161717) (xy 308.886824 -428.123008)
			(xy 308.852738 -428.078865) (xy 308.825442 -428.03023) (xy 308.805519 -427.978139) (xy 308.793393 -427.923702)
			(xy 308.789322 -427.86808) (xy 306.865288 -427.86808) (xy 306.888869 -427.887704) (xy 306.926086 -427.929241)
			(xy 306.956859 -427.975754) (xy 306.980531 -428.026251) (xy 306.996599 -428.079658) (xy 307.004719 -428.134834)
			(xy 307.005228 -428.16272) (xy 307.004719 -428.190606) (xy 306.996599 -428.245782) (xy 306.980531 -428.299189)
			(xy 306.956859 -428.349686) (xy 306.926086 -428.396199) (xy 306.888869 -428.437736) (xy 306.846001 -428.473411)
			(xy 306.798395 -428.502465) (xy 306.747066 -428.524277) (xy 306.693109 -428.538383) (xy 306.637672 -428.544483)
			(xy 306.581938 -428.542446) (xy 306.527095 -428.532316) (xy 306.474311 -428.514309) (xy 306.424711 -428.488808)
			(xy 306.379353 -428.456357) (xy 306.339204 -428.417648) (xy 306.305118 -428.373505) (xy 306.277822 -428.32487)
			(xy 306.257899 -428.272779) (xy 306.245773 -428.218342) (xy 306.241702 -428.16272) (xy 299.91304 -428.16272)
			(xy 300.60138 -428.85106) (xy 302.064672 -428.85106) (xy 302.068743 -428.795438) (xy 302.080869 -428.741001)
			(xy 302.100792 -428.68891) (xy 302.128088 -428.640275) (xy 302.162174 -428.596132) (xy 302.202323 -428.557423)
			(xy 302.247681 -428.524972) (xy 302.297281 -428.499471) (xy 302.350065 -428.481464) (xy 302.404908 -428.471334)
			(xy 302.460642 -428.469297) (xy 302.516079 -428.475397) (xy 302.570036 -428.489503) (xy 302.621365 -428.511315)
			(xy 302.668971 -428.540369) (xy 302.711839 -428.576044) (xy 302.749056 -428.617581) (xy 302.779829 -428.664094)
			(xy 302.803501 -428.714591) (xy 302.819569 -428.767998) (xy 302.827689 -428.823174) (xy 302.828198 -428.85106)
			(xy 302.827989 -428.86249) (xy 304.800252 -428.86249) (xy 304.804323 -428.806868) (xy 304.816449 -428.752431)
			(xy 304.836372 -428.70034) (xy 304.863668 -428.651705) (xy 304.897754 -428.607562) (xy 304.937903 -428.568853)
			(xy 304.983261 -428.536402) (xy 305.032861 -428.510901) (xy 305.085645 -428.492894) (xy 305.140488 -428.482764)
			(xy 305.196222 -428.480727) (xy 305.251659 -428.486827) (xy 305.305616 -428.500933) (xy 305.356945 -428.522745)
			(xy 305.404551 -428.551799) (xy 305.447419 -428.587474) (xy 305.484636 -428.629011) (xy 305.515409 -428.675524)
			(xy 305.539081 -428.726021) (xy 305.555149 -428.779428) (xy 305.563269 -428.834604) (xy 305.563778 -428.86249)
			(xy 305.563269 -428.890376) (xy 305.557467 -428.9298) (xy 307.543452 -428.9298) (xy 307.547523 -428.874178)
			(xy 307.559649 -428.819741) (xy 307.579572 -428.76765) (xy 307.606868 -428.719015) (xy 307.640954 -428.674872)
			(xy 307.681103 -428.636163) (xy 307.726461 -428.603712) (xy 307.776061 -428.578211) (xy 307.828845 -428.560204)
			(xy 307.883688 -428.550074) (xy 307.939422 -428.548037) (xy 307.994859 -428.554137) (xy 308.048816 -428.568243)
			(xy 308.100145 -428.590055) (xy 308.147751 -428.619109) (xy 308.190619 -428.654784) (xy 308.227836 -428.696321)
			(xy 308.258609 -428.742834) (xy 308.282281 -428.793331) (xy 308.298349 -428.846738) (xy 308.306469 -428.901914)
			(xy 308.306978 -428.9298) (xy 308.306469 -428.957686) (xy 308.298349 -429.012862) (xy 308.282281 -429.066269)
			(xy 308.258609 -429.116766) (xy 308.227836 -429.163279) (xy 308.190619 -429.204816) (xy 308.147751 -429.240491)
			(xy 308.100145 -429.269545) (xy 308.048816 -429.291357) (xy 307.994859 -429.305463) (xy 307.939422 -429.311563)
			(xy 307.883688 -429.309526) (xy 307.828845 -429.299396) (xy 307.776061 -429.281389) (xy 307.726461 -429.255888)
			(xy 307.681103 -429.223437) (xy 307.640954 -429.184728) (xy 307.606868 -429.140585) (xy 307.579572 -429.09195)
			(xy 307.559649 -429.039859) (xy 307.547523 -428.985422) (xy 307.543452 -428.9298) (xy 305.557467 -428.9298)
			(xy 305.555149 -428.945552) (xy 305.539081 -428.998959) (xy 305.515409 -429.049456) (xy 305.484636 -429.095969)
			(xy 305.447419 -429.137506) (xy 305.404551 -429.173181) (xy 305.356945 -429.202235) (xy 305.305616 -429.224047)
			(xy 305.251659 -429.238153) (xy 305.196222 -429.244253) (xy 305.140488 -429.242216) (xy 305.085645 -429.232086)
			(xy 305.032861 -429.214079) (xy 304.983261 -429.188578) (xy 304.937903 -429.156127) (xy 304.897754 -429.117418)
			(xy 304.863668 -429.073275) (xy 304.836372 -429.02464) (xy 304.816449 -428.972549) (xy 304.804323 -428.918112)
			(xy 304.800252 -428.86249) (xy 302.827989 -428.86249) (xy 302.827689 -428.878946) (xy 302.819569 -428.934122)
			(xy 302.803501 -428.987529) (xy 302.779829 -429.038026) (xy 302.749056 -429.084539) (xy 302.711839 -429.126076)
			(xy 302.668971 -429.161751) (xy 302.621365 -429.190805) (xy 302.570036 -429.212617) (xy 302.516079 -429.226723)
			(xy 302.460642 -429.232823) (xy 302.404908 -429.230786) (xy 302.350065 -429.220656) (xy 302.297281 -429.202649)
			(xy 302.247681 -429.177148) (xy 302.202323 -429.144697) (xy 302.162174 -429.105988) (xy 302.128088 -429.061845)
			(xy 302.100792 -429.01321) (xy 302.080869 -428.961119) (xy 302.068743 -428.906682) (xy 302.064672 -428.85106)
			(xy 300.60138 -428.85106) (xy 301.371508 -429.621188) (xy 302.472342 -429.621188) (xy 302.476413 -429.565566)
			(xy 302.488539 -429.511129) (xy 302.508462 -429.459038) (xy 302.535758 -429.410403) (xy 302.569844 -429.36626)
			(xy 302.609993 -429.327551) (xy 302.655351 -429.2951) (xy 302.704951 -429.269599) (xy 302.757735 -429.251592)
			(xy 302.812578 -429.241462) (xy 302.868312 -429.239425) (xy 302.923749 -429.245525) (xy 302.977706 -429.259631)
			(xy 303.029035 -429.281443) (xy 303.076641 -429.310497) (xy 303.119509 -429.346172) (xy 303.156726 -429.387709)
			(xy 303.187499 -429.434222) (xy 303.211171 -429.484719) (xy 303.227239 -429.538126) (xy 303.235359 -429.593302)
			(xy 303.235868 -429.621188) (xy 303.716942 -429.621188) (xy 303.721013 -429.565566) (xy 303.733139 -429.511129)
			(xy 303.753062 -429.459038) (xy 303.780358 -429.410403) (xy 303.814444 -429.36626) (xy 303.854593 -429.327551)
			(xy 303.899951 -429.2951) (xy 303.949551 -429.269599) (xy 304.002335 -429.251592) (xy 304.057178 -429.241462)
			(xy 304.112912 -429.239425) (xy 304.168349 -429.245525) (xy 304.222306 -429.259631) (xy 304.273635 -429.281443)
			(xy 304.321241 -429.310497) (xy 304.364109 -429.346172) (xy 304.401326 -429.387709) (xy 304.432099 -429.434222)
			(xy 304.455771 -429.484719) (xy 304.471839 -429.538126) (xy 304.479959 -429.593302) (xy 304.480468 -429.621188)
			(xy 304.480259 -429.632618) (xy 305.207922 -429.632618) (xy 305.211993 -429.576996) (xy 305.224119 -429.522559)
			(xy 305.244042 -429.470468) (xy 305.271338 -429.421833) (xy 305.305424 -429.37769) (xy 305.345573 -429.338981)
			(xy 305.390931 -429.30653) (xy 305.440531 -429.281029) (xy 305.493315 -429.263022) (xy 305.548158 -429.252892)
			(xy 305.603892 -429.250855) (xy 305.659329 -429.256955) (xy 305.713286 -429.271061) (xy 305.764615 -429.292873)
			(xy 305.812221 -429.321927) (xy 305.855089 -429.357602) (xy 305.892306 -429.399139) (xy 305.923079 -429.445652)
			(xy 305.946751 -429.496149) (xy 305.962819 -429.549556) (xy 305.970939 -429.604732) (xy 305.971448 -429.632618)
			(xy 306.452522 -429.632618) (xy 306.456593 -429.576996) (xy 306.468719 -429.522559) (xy 306.488642 -429.470468)
			(xy 306.515938 -429.421833) (xy 306.550024 -429.37769) (xy 306.590173 -429.338981) (xy 306.635531 -429.30653)
			(xy 306.685131 -429.281029) (xy 306.737915 -429.263022) (xy 306.792758 -429.252892) (xy 306.848492 -429.250855)
			(xy 306.903929 -429.256955) (xy 306.957886 -429.271061) (xy 307.009215 -429.292873) (xy 307.056821 -429.321927)
			(xy 307.099689 -429.357602) (xy 307.136906 -429.399139) (xy 307.167679 -429.445652) (xy 307.191351 -429.496149)
			(xy 307.207419 -429.549556) (xy 307.215539 -429.604732) (xy 307.216048 -429.632618) (xy 307.215539 -429.660504)
			(xy 307.209737 -429.699928) (xy 307.951122 -429.699928) (xy 307.955193 -429.644306) (xy 307.967319 -429.589869)
			(xy 307.987242 -429.537778) (xy 308.014538 -429.489143) (xy 308.048624 -429.445) (xy 308.088773 -429.406291)
			(xy 308.134131 -429.37384) (xy 308.183731 -429.348339) (xy 308.236515 -429.330332) (xy 308.291358 -429.320202)
			(xy 308.347092 -429.318165) (xy 308.402529 -429.324265) (xy 308.456486 -429.338371) (xy 308.507815 -429.360183)
			(xy 308.555421 -429.389237) (xy 308.598289 -429.424912) (xy 308.635506 -429.466449) (xy 308.666279 -429.512962)
			(xy 308.689951 -429.563459) (xy 308.706019 -429.616866) (xy 308.714139 -429.672042) (xy 308.714648 -429.699928)
			(xy 309.195722 -429.699928) (xy 309.199793 -429.644306) (xy 309.211919 -429.589869) (xy 309.231842 -429.537778)
			(xy 309.259138 -429.489143) (xy 309.293224 -429.445) (xy 309.333373 -429.406291) (xy 309.378731 -429.37384)
			(xy 309.428331 -429.348339) (xy 309.481115 -429.330332) (xy 309.535958 -429.320202) (xy 309.591692 -429.318165)
			(xy 309.647129 -429.324265) (xy 309.701086 -429.338371) (xy 309.752415 -429.360183) (xy 309.800021 -429.389237)
			(xy 309.842889 -429.424912) (xy 309.880106 -429.466449) (xy 309.910879 -429.512962) (xy 309.934551 -429.563459)
			(xy 309.950619 -429.616866) (xy 309.958739 -429.672042) (xy 309.959248 -429.699928) (xy 309.958739 -429.727814)
			(xy 309.950619 -429.78299) (xy 309.934551 -429.836397) (xy 309.910879 -429.886894) (xy 309.880106 -429.933407)
			(xy 309.842889 -429.974944) (xy 309.800021 -430.010619) (xy 309.752415 -430.039673) (xy 309.701086 -430.061485)
			(xy 309.647129 -430.075591) (xy 309.591692 -430.081691) (xy 309.535958 -430.079654) (xy 309.481115 -430.069524)
			(xy 309.428331 -430.051517) (xy 309.378731 -430.026016) (xy 309.333373 -429.993565) (xy 309.293224 -429.954856)
			(xy 309.259138 -429.910713) (xy 309.231842 -429.862078) (xy 309.211919 -429.809987) (xy 309.199793 -429.75555)
			(xy 309.195722 -429.699928) (xy 308.714648 -429.699928) (xy 308.714139 -429.727814) (xy 308.706019 -429.78299)
			(xy 308.689951 -429.836397) (xy 308.666279 -429.886894) (xy 308.635506 -429.933407) (xy 308.598289 -429.974944)
			(xy 308.555421 -430.010619) (xy 308.507815 -430.039673) (xy 308.456486 -430.061485) (xy 308.402529 -430.075591)
			(xy 308.347092 -430.081691) (xy 308.291358 -430.079654) (xy 308.236515 -430.069524) (xy 308.183731 -430.051517)
			(xy 308.134131 -430.026016) (xy 308.088773 -429.993565) (xy 308.048624 -429.954856) (xy 308.014538 -429.910713)
			(xy 307.987242 -429.862078) (xy 307.967319 -429.809987) (xy 307.955193 -429.75555) (xy 307.951122 -429.699928)
			(xy 307.209737 -429.699928) (xy 307.207419 -429.71568) (xy 307.191351 -429.769087) (xy 307.167679 -429.819584)
			(xy 307.136906 -429.866097) (xy 307.099689 -429.907634) (xy 307.056821 -429.943309) (xy 307.009215 -429.972363)
			(xy 306.957886 -429.994175) (xy 306.903929 -430.008281) (xy 306.848492 -430.014381) (xy 306.792758 -430.012344)
			(xy 306.737915 -430.002214) (xy 306.685131 -429.984207) (xy 306.635531 -429.958706) (xy 306.590173 -429.926255)
			(xy 306.550024 -429.887546) (xy 306.515938 -429.843403) (xy 306.488642 -429.794768) (xy 306.468719 -429.742677)
			(xy 306.456593 -429.68824) (xy 306.452522 -429.632618) (xy 305.971448 -429.632618) (xy 305.970939 -429.660504)
			(xy 305.962819 -429.71568) (xy 305.946751 -429.769087) (xy 305.923079 -429.819584) (xy 305.892306 -429.866097)
			(xy 305.855089 -429.907634) (xy 305.812221 -429.943309) (xy 305.764615 -429.972363) (xy 305.713286 -429.994175)
			(xy 305.659329 -430.008281) (xy 305.603892 -430.014381) (xy 305.548158 -430.012344) (xy 305.493315 -430.002214)
			(xy 305.440531 -429.984207) (xy 305.390931 -429.958706) (xy 305.345573 -429.926255) (xy 305.305424 -429.887546)
			(xy 305.271338 -429.843403) (xy 305.244042 -429.794768) (xy 305.224119 -429.742677) (xy 305.211993 -429.68824)
			(xy 305.207922 -429.632618) (xy 304.480259 -429.632618) (xy 304.479959 -429.649074) (xy 304.471839 -429.70425)
			(xy 304.455771 -429.757657) (xy 304.432099 -429.808154) (xy 304.401326 -429.854667) (xy 304.364109 -429.896204)
			(xy 304.321241 -429.931879) (xy 304.273635 -429.960933) (xy 304.222306 -429.982745) (xy 304.168349 -429.996851)
			(xy 304.112912 -430.002951) (xy 304.057178 -430.000914) (xy 304.002335 -429.990784) (xy 303.949551 -429.972777)
			(xy 303.899951 -429.947276) (xy 303.854593 -429.914825) (xy 303.814444 -429.876116) (xy 303.780358 -429.831973)
			(xy 303.753062 -429.783338) (xy 303.733139 -429.731247) (xy 303.721013 -429.67681) (xy 303.716942 -429.621188)
			(xy 303.235868 -429.621188) (xy 303.235359 -429.649074) (xy 303.227239 -429.70425) (xy 303.211171 -429.757657)
			(xy 303.187499 -429.808154) (xy 303.156726 -429.854667) (xy 303.119509 -429.896204) (xy 303.076641 -429.931879)
			(xy 303.029035 -429.960933) (xy 302.977706 -429.982745) (xy 302.923749 -429.996851) (xy 302.868312 -430.002951)
			(xy 302.812578 -430.000914) (xy 302.757735 -429.990784) (xy 302.704951 -429.972777) (xy 302.655351 -429.947276)
			(xy 302.609993 -429.914825) (xy 302.569844 -429.876116) (xy 302.535758 -429.831973) (xy 302.508462 -429.783338)
			(xy 302.488539 -429.731247) (xy 302.476413 -429.67681) (xy 302.472342 -429.621188) (xy 301.371508 -429.621188)
			(xy 302.13808 -430.38776) (xy 302.13808 -431.36693) (xy 303.095404 -431.36693) (xy 303.099475 -431.311308)
			(xy 303.111601 -431.256871) (xy 303.131524 -431.20478) (xy 303.15882 -431.156145) (xy 303.192906 -431.112002)
			(xy 303.233055 -431.073293) (xy 303.278413 -431.040842) (xy 303.328013 -431.015341) (xy 303.380797 -430.997334)
			(xy 303.43564 -430.987204) (xy 303.491374 -430.985167) (xy 303.546811 -430.991267) (xy 303.600768 -431.005373)
			(xy 303.652097 -431.027185) (xy 303.699703 -431.056239) (xy 303.742571 -431.091914) (xy 303.779788 -431.133451)
			(xy 303.810561 -431.179964) (xy 303.834233 -431.230461) (xy 303.850301 -431.283868) (xy 303.858421 -431.339044)
			(xy 303.85893 -431.36693) (xy 303.858721 -431.37836) (xy 305.830984 -431.37836) (xy 305.835055 -431.322738)
			(xy 305.847181 -431.268301) (xy 305.867104 -431.21621) (xy 305.8944 -431.167575) (xy 305.928486 -431.123432)
			(xy 305.968635 -431.084723) (xy 306.013993 -431.052272) (xy 306.063593 -431.026771) (xy 306.116377 -431.008764)
			(xy 306.17122 -430.998634) (xy 306.226954 -430.996597) (xy 306.282391 -431.002697) (xy 306.336348 -431.016803)
			(xy 306.387677 -431.038615) (xy 306.435283 -431.067669) (xy 306.478151 -431.103344) (xy 306.515368 -431.144881)
			(xy 306.546141 -431.191394) (xy 306.569813 -431.241891) (xy 306.585881 -431.295298) (xy 306.594001 -431.350474)
			(xy 306.59451 -431.37836) (xy 306.594001 -431.406246) (xy 306.588199 -431.44567) (xy 308.574184 -431.44567)
			(xy 308.578255 -431.390048) (xy 308.590381 -431.335611) (xy 308.610304 -431.28352) (xy 308.6376 -431.234885)
			(xy 308.671686 -431.190742) (xy 308.711835 -431.152033) (xy 308.757193 -431.119582) (xy 308.806793 -431.094081)
			(xy 308.859577 -431.076074) (xy 308.91442 -431.065944) (xy 308.970154 -431.063907) (xy 309.025591 -431.070007)
			(xy 309.079548 -431.084113) (xy 309.130877 -431.105925) (xy 309.178483 -431.134979) (xy 309.221351 -431.170654)
			(xy 309.258568 -431.212191) (xy 309.289341 -431.258704) (xy 309.313013 -431.309201) (xy 309.329081 -431.362608)
			(xy 309.337201 -431.417784) (xy 309.33771 -431.44567) (xy 309.337201 -431.473556) (xy 309.329081 -431.528732)
			(xy 309.313013 -431.582139) (xy 309.289341 -431.632636) (xy 309.258568 -431.679149) (xy 309.221351 -431.720686)
			(xy 309.178483 -431.756361) (xy 309.130877 -431.785415) (xy 309.079548 -431.807227) (xy 309.025591 -431.821333)
			(xy 308.970154 -431.827433) (xy 308.91442 -431.825396) (xy 308.859577 -431.815266) (xy 308.806793 -431.797259)
			(xy 308.757193 -431.771758) (xy 308.711835 -431.739307) (xy 308.671686 -431.700598) (xy 308.6376 -431.656455)
			(xy 308.610304 -431.60782) (xy 308.590381 -431.555729) (xy 308.578255 -431.501292) (xy 308.574184 -431.44567)
			(xy 306.588199 -431.44567) (xy 306.585881 -431.461422) (xy 306.569813 -431.514829) (xy 306.546141 -431.565326)
			(xy 306.515368 -431.611839) (xy 306.478151 -431.653376) (xy 306.435283 -431.689051) (xy 306.387677 -431.718105)
			(xy 306.336348 -431.739917) (xy 306.282391 -431.754023) (xy 306.226954 -431.760123) (xy 306.17122 -431.758086)
			(xy 306.116377 -431.747956) (xy 306.063593 -431.729949) (xy 306.013993 -431.704448) (xy 305.968635 -431.671997)
			(xy 305.928486 -431.633288) (xy 305.8944 -431.589145) (xy 305.867104 -431.54051) (xy 305.847181 -431.488419)
			(xy 305.835055 -431.433982) (xy 305.830984 -431.37836) (xy 303.858721 -431.37836) (xy 303.858421 -431.394816)
			(xy 303.850301 -431.449992) (xy 303.834233 -431.503399) (xy 303.810561 -431.553896) (xy 303.779788 -431.600409)
			(xy 303.742571 -431.641946) (xy 303.699703 -431.677621) (xy 303.652097 -431.706675) (xy 303.600768 -431.728487)
			(xy 303.546811 -431.742593) (xy 303.491374 -431.748693) (xy 303.43564 -431.746656) (xy 303.380797 -431.736526)
			(xy 303.328013 -431.718519) (xy 303.278413 -431.693018) (xy 303.233055 -431.660567) (xy 303.192906 -431.621858)
			(xy 303.15882 -431.577715) (xy 303.131524 -431.52908) (xy 303.111601 -431.476989) (xy 303.099475 -431.422552)
			(xy 303.095404 -431.36693) (xy 302.13808 -431.36693) (xy 302.13808 -435.585108) (xy 302.899824 -435.585108)
			(xy 302.903895 -435.529486) (xy 302.916021 -435.475049) (xy 302.935944 -435.422958) (xy 302.96324 -435.374323)
			(xy 302.997326 -435.33018) (xy 303.037475 -435.291471) (xy 303.082833 -435.25902) (xy 303.132433 -435.233519)
			(xy 303.185217 -435.215512) (xy 303.24006 -435.205382) (xy 303.295794 -435.203345) (xy 303.351231 -435.209445)
			(xy 303.405188 -435.223551) (xy 303.456517 -435.245363) (xy 303.504123 -435.274417) (xy 303.546991 -435.310092)
			(xy 303.584208 -435.351629) (xy 303.614981 -435.398142) (xy 303.638653 -435.448639) (xy 303.654721 -435.502046)
			(xy 303.662841 -435.557222) (xy 303.66335 -435.585108) (xy 303.663141 -435.596538) (xy 305.635404 -435.596538)
			(xy 305.639475 -435.540916) (xy 305.651601 -435.486479) (xy 305.671524 -435.434388) (xy 305.69882 -435.385753)
			(xy 305.732906 -435.34161) (xy 305.773055 -435.302901) (xy 305.818413 -435.27045) (xy 305.868013 -435.244949)
			(xy 305.920797 -435.226942) (xy 305.97564 -435.216812) (xy 306.031374 -435.214775) (xy 306.086811 -435.220875)
			(xy 306.140768 -435.234981) (xy 306.192097 -435.256793) (xy 306.239703 -435.285847) (xy 306.282571 -435.321522)
			(xy 306.319788 -435.363059) (xy 306.350561 -435.409572) (xy 306.374233 -435.460069) (xy 306.390301 -435.513476)
			(xy 306.398421 -435.568652) (xy 306.39893 -435.596538) (xy 306.398421 -435.624424) (xy 306.392619 -435.663848)
			(xy 308.378604 -435.663848) (xy 308.382675 -435.608226) (xy 308.394801 -435.553789) (xy 308.414724 -435.501698)
			(xy 308.44202 -435.453063) (xy 308.476106 -435.40892) (xy 308.516255 -435.370211) (xy 308.561613 -435.33776)
			(xy 308.611213 -435.312259) (xy 308.663997 -435.294252) (xy 308.71884 -435.284122) (xy 308.774574 -435.282085)
			(xy 308.830011 -435.288185) (xy 308.883968 -435.302291) (xy 308.935297 -435.324103) (xy 308.982903 -435.353157)
			(xy 309.025771 -435.388832) (xy 309.062988 -435.430369) (xy 309.093761 -435.476882) (xy 309.117433 -435.527379)
			(xy 309.133501 -435.580786) (xy 309.141621 -435.635962) (xy 309.14213 -435.663848) (xy 309.141621 -435.691734)
			(xy 309.133501 -435.74691) (xy 309.117433 -435.800317) (xy 309.093761 -435.850814) (xy 309.062988 -435.897327)
			(xy 309.025771 -435.938864) (xy 308.982903 -435.974539) (xy 308.935297 -436.003593) (xy 308.883968 -436.025405)
			(xy 308.830011 -436.039511) (xy 308.774574 -436.045611) (xy 308.71884 -436.043574) (xy 308.663997 -436.033444)
			(xy 308.611213 -436.015437) (xy 308.561613 -435.989936) (xy 308.516255 -435.957485) (xy 308.476106 -435.918776)
			(xy 308.44202 -435.874633) (xy 308.414724 -435.825998) (xy 308.394801 -435.773907) (xy 308.382675 -435.71947)
			(xy 308.378604 -435.663848) (xy 306.392619 -435.663848) (xy 306.390301 -435.6796) (xy 306.374233 -435.733007)
			(xy 306.350561 -435.783504) (xy 306.319788 -435.830017) (xy 306.282571 -435.871554) (xy 306.239703 -435.907229)
			(xy 306.192097 -435.936283) (xy 306.140768 -435.958095) (xy 306.086811 -435.972201) (xy 306.031374 -435.978301)
			(xy 305.97564 -435.976264) (xy 305.920797 -435.966134) (xy 305.868013 -435.948127) (xy 305.818413 -435.922626)
			(xy 305.773055 -435.890175) (xy 305.732906 -435.851466) (xy 305.69882 -435.807323) (xy 305.671524 -435.758688)
			(xy 305.651601 -435.706597) (xy 305.639475 -435.65216) (xy 305.635404 -435.596538) (xy 303.663141 -435.596538)
			(xy 303.662841 -435.612994) (xy 303.654721 -435.66817) (xy 303.638653 -435.721577) (xy 303.614981 -435.772074)
			(xy 303.584208 -435.818587) (xy 303.546991 -435.860124) (xy 303.504123 -435.895799) (xy 303.456517 -435.924853)
			(xy 303.405188 -435.946665) (xy 303.351231 -435.960771) (xy 303.295794 -435.966871) (xy 303.24006 -435.964834)
			(xy 303.185217 -435.954704) (xy 303.132433 -435.936697) (xy 303.082833 -435.911196) (xy 303.037475 -435.878745)
			(xy 302.997326 -435.840036) (xy 302.96324 -435.795893) (xy 302.935944 -435.747258) (xy 302.916021 -435.695167)
			(xy 302.903895 -435.64073) (xy 302.899824 -435.585108) (xy 302.13808 -435.585108) (xy 302.13808 -438.92724)
			(xy 303.26584 -440.055) (xy 309.59044 -440.055)
		)
		(stroke
			(width 0)
			(type solid)
		)
		(fill yes)
		(layer "In15.Cu")
		(net "P3V3_AUX")
	)
	(gr_poly
		(pts
			(xy 341.7062 -273.120866) (xy 341.737033 -273.109755) (xy 341.801451 -273.097735) (xy 341.834216 -273.09699)
			(xy 341.866979 -273.097758) (xy 341.931396 -273.10977) (xy 341.962232 -273.120866) (xy 341.970868 -273.124168)
			(xy 342.63711 -273.124168) (xy 342.645746 -273.120866) (xy 342.676579 -273.109759) (xy 342.740998 -273.097747)
			(xy 342.773762 -273.09699) (xy 342.806524 -273.097762) (xy 342.870938 -273.109782) (xy 342.901778 -273.120866)
			(xy 342.910414 -273.124168) (xy 343.577164 -273.124168) (xy 343.5858 -273.120866) (xy 343.616633 -273.109755)
			(xy 343.681051 -273.097735) (xy 343.713816 -273.09699) (xy 343.746579 -273.097758) (xy 343.810996 -273.10977)
			(xy 343.841832 -273.120866) (xy 343.850468 -273.124168) (xy 344.516964 -273.124168) (xy 344.5256 -273.120866)
			(xy 344.556433 -273.109755) (xy 344.620851 -273.097735) (xy 344.653616 -273.09699) (xy 344.686379 -273.097758)
			(xy 344.750796 -273.10977) (xy 344.781632 -273.120866) (xy 344.790268 -273.124168) (xy 345.456764 -273.124168)
			(xy 345.4654 -273.120866) (xy 345.496233 -273.109755) (xy 345.560651 -273.097735) (xy 345.593416 -273.09699)
			(xy 345.626179 -273.097758) (xy 345.690596 -273.10977) (xy 345.721432 -273.120866) (xy 345.730068 -273.124168)
			(xy 346.396564 -273.124168) (xy 346.4052 -273.120866) (xy 346.436033 -273.109755) (xy 346.500451 -273.097735)
			(xy 346.533216 -273.09699) (xy 346.565979 -273.097758) (xy 346.630396 -273.10977) (xy 346.661232 -273.120866)
			(xy 346.669868 -273.124168) (xy 347.336364 -273.124168) (xy 347.345 -273.120866) (xy 347.375833 -273.109755)
			(xy 347.440251 -273.097735) (xy 347.473016 -273.09699) (xy 347.505779 -273.097758) (xy 347.570196 -273.10977)
			(xy 347.601032 -273.120866) (xy 347.609668 -273.124168) (xy 348.276164 -273.124168) (xy 348.2848 -273.120866)
			(xy 348.315633 -273.109755) (xy 348.380051 -273.097735) (xy 348.412816 -273.09699) (xy 348.445579 -273.097758)
			(xy 348.509996 -273.10977) (xy 348.540832 -273.120866) (xy 348.549468 -273.124168) (xy 349.21571 -273.124168)
			(xy 349.224346 -273.120866) (xy 349.255179 -273.109759) (xy 349.319598 -273.097747) (xy 349.352362 -273.09699)
			(xy 349.385124 -273.097762) (xy 349.449538 -273.109782) (xy 349.480378 -273.120866) (xy 349.489014 -273.124168)
			(xy 350.155764 -273.124168) (xy 350.1644 -273.120866) (xy 350.195233 -273.109755) (xy 350.259651 -273.097735)
			(xy 350.292416 -273.09699) (xy 350.325179 -273.097758) (xy 350.389596 -273.10977) (xy 350.420432 -273.120866)
			(xy 350.429068 -273.124168) (xy 351.09531 -273.124168) (xy 351.103946 -273.120866) (xy 351.134779 -273.109759)
			(xy 351.199198 -273.097747) (xy 351.231962 -273.09699) (xy 351.264724 -273.097762) (xy 351.329138 -273.109782)
			(xy 351.359978 -273.120866) (xy 351.368614 -273.124168) (xy 352.035364 -273.124168) (xy 352.044 -273.120866)
			(xy 352.074833 -273.109755) (xy 352.139251 -273.097735) (xy 352.172016 -273.09699) (xy 352.204779 -273.097758)
			(xy 352.269196 -273.10977) (xy 352.300032 -273.120866) (xy 352.308668 -273.124168) (xy 353.914964 -273.124168)
			(xy 353.9236 -273.120866) (xy 353.954433 -273.109755) (xy 354.018851 -273.097735) (xy 354.051616 -273.09699)
			(xy 354.084379 -273.097758) (xy 354.148796 -273.10977) (xy 354.179632 -273.120866) (xy 354.188268 -273.124168)
			(xy 354.854764 -273.124168) (xy 354.8634 -273.120866) (xy 354.894233 -273.109755) (xy 354.958651 -273.097735)
			(xy 354.991416 -273.09699) (xy 355.024179 -273.097758) (xy 355.088596 -273.10977) (xy 355.119432 -273.120866)
			(xy 355.128068 -273.124168) (xy 355.74732 -273.124168) (xy 356.078028 -272.79346) (xy 356.066852 -272.762726)
			(xy 356.056551 -272.73291) (xy 356.045443 -272.67082) (xy 356.044754 -272.639282) (xy 356.045223 -272.61335)
			(xy 356.052748 -272.562036) (xy 356.067636 -272.512355) (xy 356.089573 -272.465359) (xy 356.118095 -272.422043)
			(xy 356.152597 -272.383321) (xy 356.192352 -272.350013) (xy 356.236517 -272.322823) (xy 356.260146 -272.31213)
			(xy 356.29088 -272.298922) (xy 356.29088 -272.203164) (xy 356.290428 -272.189371) (xy 356.28305 -272.16279)
			(xy 356.268816 -272.13916) (xy 356.248768 -272.12021) (xy 356.224374 -272.107329) (xy 356.19742 -272.101459)
			(xy 356.169879 -272.103029) (xy 356.143766 -272.111925) (xy 356.13213 -272.119344) (xy 356.109825 -272.133954)
			(xy 356.061792 -272.157101) (xy 356.010848 -272.172839) (xy 355.958129 -272.180817) (xy 355.93147 -272.18132)
			(xy 355.931216 -272.18132) (xy 355.904563 -272.180848) (xy 355.851853 -272.172905) (xy 355.800915 -272.157195)
			(xy 355.752887 -272.134068) (xy 355.708843 -272.104041) (xy 355.669767 -272.067785) (xy 355.63653 -272.02611)
			(xy 355.609877 -271.979946) (xy 355.590402 -271.930326) (xy 355.57854 -271.878357) (xy 355.574556 -271.8252)
			(xy 355.57854 -271.772043) (xy 355.590402 -271.720074) (xy 355.609877 -271.670454) (xy 355.63653 -271.62429)
			(xy 355.669767 -271.582615) (xy 355.708843 -271.546359) (xy 355.752887 -271.516332) (xy 355.800915 -271.493205)
			(xy 355.851853 -271.477495) (xy 355.904563 -271.469552) (xy 355.931216 -271.469104) (xy 355.93147 -271.469104)
			(xy 355.958135 -271.469571) (xy 356.010868 -271.477515) (xy 356.061825 -271.493245) (xy 356.109861 -271.516408)
			(xy 356.13213 -271.53108) (xy 356.143779 -271.538457) (xy 356.169883 -271.547306) (xy 356.197403 -271.548848)
			(xy 356.224331 -271.54297) (xy 356.248706 -271.530102) (xy 356.268748 -271.511181) (xy 356.282997 -271.487587)
			(xy 356.290414 -271.461041) (xy 356.29088 -271.44726) (xy 356.29088 -271.351756) (xy 356.260146 -271.338548)
			(xy 356.23651 -271.32787) (xy 356.192345 -271.300678) (xy 356.152591 -271.267368) (xy 356.118089 -271.228645)
			(xy 356.089569 -271.185326) (xy 356.067634 -271.138329) (xy 356.052748 -271.088646) (xy 356.045225 -271.037331)
			(xy 356.045225 -270.985466) (xy 356.052748 -270.93415) (xy 356.067635 -270.884469) (xy 356.089571 -270.837471)
			(xy 356.118091 -270.794153) (xy 356.152593 -270.755429) (xy 356.192347 -270.72212) (xy 356.236513 -270.694929)
			(xy 356.260146 -270.684244) (xy 356.29088 -270.671036) (xy 356.29088 -270.575532) (xy 356.290437 -270.561732)
			(xy 356.283069 -270.535134) (xy 356.268838 -270.511487) (xy 356.248786 -270.492523) (xy 356.224382 -270.479632)
			(xy 356.197415 -270.473758) (xy 356.16986 -270.475333) (xy 356.143738 -270.48424) (xy 356.13213 -270.491712)
			(xy 356.109825 -270.506323) (xy 356.061793 -270.529473) (xy 356.010849 -270.545212) (xy 355.95813 -270.553191)
			(xy 355.93147 -270.553688) (xy 355.931216 -270.553688) (xy 355.904566 -270.553216) (xy 355.85186 -270.545274)
			(xy 355.800926 -270.529565) (xy 355.752903 -270.50644) (xy 355.708863 -270.476416) (xy 355.66979 -270.440163)
			(xy 355.636557 -270.398492) (xy 355.609906 -270.352332) (xy 355.590432 -270.302716) (xy 355.578571 -270.250752)
			(xy 355.574588 -270.1976) (xy 355.578571 -270.144448) (xy 355.590432 -270.092484) (xy 355.609906 -270.042868)
			(xy 355.636557 -269.996708) (xy 355.66979 -269.955037) (xy 355.708863 -269.918784) (xy 355.752903 -269.88876)
			(xy 355.800926 -269.865635) (xy 355.85186 -269.849926) (xy 355.904566 -269.841984) (xy 355.931216 -269.841472)
			(xy 355.93147 -269.841472) (xy 355.958134 -269.841939) (xy 356.010867 -269.849885) (xy 356.061822 -269.865617)
			(xy 356.109856 -269.888784) (xy 356.13213 -269.903448) (xy 356.143778 -269.910827) (xy 356.16988 -269.919679)
			(xy 356.197398 -269.921222) (xy 356.224326 -269.915344) (xy 356.248698 -269.902474) (xy 356.268738 -269.883551)
			(xy 356.282982 -269.859955) (xy 356.290391 -269.833408) (xy 356.29088 -269.819628) (xy 356.29088 -269.72387)
			(xy 356.260146 -269.710662) (xy 356.236509 -269.699984) (xy 356.192342 -269.672792) (xy 356.152586 -269.639482)
			(xy 356.118082 -269.600757) (xy 356.089561 -269.557437) (xy 356.067624 -269.510438) (xy 356.052736 -269.460755)
			(xy 356.045213 -269.409437) (xy 356.045212 -269.357571) (xy 356.052734 -269.306253) (xy 356.067621 -269.256569)
			(xy 356.089557 -269.20957) (xy 356.118078 -269.166249) (xy 356.15258 -269.127524) (xy 356.192335 -269.094213)
			(xy 356.236502 -269.06702) (xy 356.260146 -269.056358) (xy 356.29088 -269.04315) (xy 356.29088 -268.947646)
			(xy 356.290426 -268.933855) (xy 356.283045 -268.907278) (xy 356.26881 -268.883653) (xy 356.248763 -268.864707)
			(xy 356.224372 -268.851828) (xy 356.197421 -268.845959) (xy 356.169884 -268.847528) (xy 356.143774 -268.856422)
			(xy 356.13213 -268.863826) (xy 356.109825 -268.878437) (xy 356.061792 -268.901585) (xy 356.010849 -268.917324)
			(xy 355.958129 -268.925303) (xy 355.93147 -268.925802) (xy 355.931216 -268.925802) (xy 355.904565 -268.92533)
			(xy 355.851857 -268.917388) (xy 355.800921 -268.901678) (xy 355.752896 -268.878553) (xy 355.708854 -268.848527)
			(xy 355.66978 -268.812273) (xy 355.636545 -268.7706) (xy 355.609893 -268.724438) (xy 355.590419 -268.67482)
			(xy 355.578557 -268.622854) (xy 355.574574 -268.5697) (xy 355.578557 -268.516546) (xy 355.590419 -268.46458)
			(xy 355.609893 -268.414962) (xy 355.636545 -268.3688) (xy 355.66978 -268.327127) (xy 355.708854 -268.290873)
			(xy 355.752896 -268.260847) (xy 355.800921 -268.237722) (xy 355.851857 -268.222012) (xy 355.904565 -268.21407)
			(xy 355.931216 -268.213586) (xy 355.93147 -268.213586) (xy 355.958134 -268.214053) (xy 356.010867 -268.221999)
			(xy 356.061822 -268.237732) (xy 356.109855 -268.260899) (xy 356.13213 -268.275562) (xy 356.143779 -268.28294)
			(xy 356.169881 -268.291791) (xy 356.1974 -268.293333) (xy 356.224328 -268.287456) (xy 356.248702 -268.274586)
			(xy 356.268742 -268.255664) (xy 356.282988 -268.232069) (xy 356.290401 -268.205522) (xy 356.29088 -268.191742)
			(xy 356.29088 -268.096238) (xy 356.260146 -268.08303) (xy 356.236511 -268.072352) (xy 356.192349 -268.045161)
			(xy 356.152598 -268.011852) (xy 356.118098 -267.973129) (xy 356.08958 -267.929812) (xy 356.067647 -267.882816)
			(xy 356.052762 -267.833136) (xy 356.045241 -267.781822) (xy 356.045242 -267.72996) (xy 356.052766 -267.678647)
			(xy 356.067653 -267.628968) (xy 356.089589 -267.581973) (xy 356.118109 -267.538657) (xy 356.15261 -267.499936)
			(xy 356.192363 -267.466629) (xy 356.236527 -267.43944) (xy 356.260146 -267.428726) (xy 356.29088 -267.415518)
			(xy 356.29088 -267.31976) (xy 356.290428 -267.305967) (xy 356.283049 -267.279387) (xy 356.268815 -267.255758)
			(xy 356.248767 -267.23681) (xy 356.224374 -267.223929) (xy 356.19742 -267.218059) (xy 356.16988 -267.219629)
			(xy 356.143768 -267.228525) (xy 356.13213 -267.23594) (xy 356.109825 -267.25055) (xy 356.061792 -267.273698)
			(xy 356.010848 -267.289436) (xy 355.958129 -267.297414) (xy 355.93147 -267.297916) (xy 355.931216 -267.297916)
			(xy 355.904563 -267.297444) (xy 355.851854 -267.289501) (xy 355.800916 -267.273791) (xy 355.752889 -267.250665)
			(xy 355.708846 -267.220638) (xy 355.66977 -267.184382) (xy 355.636534 -267.142708) (xy 355.60988 -267.096544)
			(xy 355.590405 -267.046924) (xy 355.578544 -266.994956) (xy 355.57456 -266.9418) (xy 355.578544 -266.888644)
			(xy 355.590405 -266.836676) (xy 355.60988 -266.787056) (xy 355.636534 -266.740892) (xy 355.66977 -266.699218)
			(xy 355.708846 -266.662962) (xy 355.752889 -266.632935) (xy 355.800916 -266.609809) (xy 355.851854 -266.594099)
			(xy 355.904563 -266.586156) (xy 355.931216 -266.5857) (xy 355.93147 -266.5857) (xy 355.958135 -266.586167)
			(xy 356.010869 -266.594111) (xy 356.061825 -266.609841) (xy 356.109861 -266.633004) (xy 356.13213 -266.647676)
			(xy 356.143779 -266.655054) (xy 356.169883 -266.663903) (xy 356.197402 -266.665445) (xy 356.224331 -266.659567)
			(xy 356.248705 -266.646698) (xy 356.268747 -266.627777) (xy 356.282995 -266.604183) (xy 356.290411 -266.577637)
			(xy 356.29088 -266.563856) (xy 356.29088 -266.468606) (xy 356.260146 -266.455398) (xy 356.236506 -266.444719)
			(xy 356.192334 -266.417527) (xy 356.152573 -266.384215) (xy 356.118065 -266.345488) (xy 356.089539 -266.302166)
			(xy 356.067598 -266.255163) (xy 356.052707 -266.205476) (xy 356.045181 -266.154154) (xy 356.045178 -266.102283)
			(xy 356.052699 -266.05096) (xy 356.067585 -266.001271) (xy 356.089521 -265.954266) (xy 356.118043 -265.910941)
			(xy 356.152547 -265.87221) (xy 356.192305 -265.838894) (xy 356.236474 -265.811697) (xy 356.260146 -265.801094)
			(xy 356.29088 -265.787886) (xy 356.29088 -264.919968) (xy 355.59492 -264.224008) (xy 352.124772 -264.224008)
			(xy 352.110494 -264.22448) (xy 352.083053 -264.232374) (xy 352.058874 -264.247565) (xy 352.039853 -264.268862)
			(xy 352.027479 -264.294597) (xy 352.022723 -264.322753) (xy 352.025956 -264.351124) (xy 352.031046 -264.36447)
			(xy 352.039561 -264.386102) (xy 352.051545 -264.43102) (xy 352.057584 -264.477115) (xy 352.05797 -264.50036)
			(xy 352.057472 -264.527009) (xy 352.049529 -264.579713) (xy 352.033819 -264.630643) (xy 352.010693 -264.678664)
			(xy 351.980669 -264.722701) (xy 351.944417 -264.761772) (xy 351.902746 -264.795003) (xy 351.856588 -264.821652)
			(xy 351.806974 -264.841124) (xy 351.755012 -264.852984) (xy 351.701862 -264.856968) (xy 351.648712 -264.852984)
			(xy 351.59675 -264.841124) (xy 351.547136 -264.821652) (xy 351.500978 -264.795003) (xy 351.459307 -264.761772)
			(xy 351.423055 -264.722701) (xy 351.393031 -264.678664) (xy 351.369905 -264.630643) (xy 351.354195 -264.579713)
			(xy 351.346252 -264.527009) (xy 351.345754 -264.50036) (xy 351.346132 -264.477116) (xy 351.352181 -264.431022)
			(xy 351.364171 -264.386105) (xy 351.372678 -264.36447) (xy 351.377693 -264.351107) (xy 351.38089 -264.322757)
			(xy 351.37612 -264.294629) (xy 351.363756 -264.268918) (xy 351.344762 -264.247629) (xy 351.320621 -264.232426)
			(xy 351.293216 -264.224493) (xy 351.278952 -264.224008) (xy 351.184972 -264.224008) (xy 351.170694 -264.22448)
			(xy 351.143253 -264.232374) (xy 351.119074 -264.247565) (xy 351.100053 -264.268862) (xy 351.087679 -264.294597)
			(xy 351.082923 -264.322753) (xy 351.086156 -264.351124) (xy 351.091246 -264.36447) (xy 351.099761 -264.386102)
			(xy 351.111745 -264.43102) (xy 351.117784 -264.477115) (xy 351.11817 -264.50036) (xy 351.117672 -264.527009)
			(xy 351.109729 -264.579713) (xy 351.094019 -264.630643) (xy 351.070893 -264.678664) (xy 351.040869 -264.722701)
			(xy 351.004617 -264.761772) (xy 350.962946 -264.795003) (xy 350.916788 -264.821652) (xy 350.867174 -264.841124)
			(xy 350.815212 -264.852984) (xy 350.762062 -264.856968) (xy 350.708912 -264.852984) (xy 350.65695 -264.841124)
			(xy 350.607336 -264.821652) (xy 350.561178 -264.795003) (xy 350.519507 -264.761772) (xy 350.483255 -264.722701)
			(xy 350.453231 -264.678664) (xy 350.430105 -264.630643) (xy 350.414395 -264.579713) (xy 350.406452 -264.527009)
			(xy 350.405954 -264.50036) (xy 350.406469 -264.472849) (xy 350.414937 -264.418482) (xy 350.431666 -264.366065)
			(xy 350.456258 -264.316844) (xy 350.488127 -264.27199) (xy 350.526515 -264.232572) (xy 350.548194 -264.215626)
			(xy 350.559508 -264.206496) (xy 350.576907 -264.183222) (xy 350.587051 -264.155991) (xy 350.589119 -264.127006)
			(xy 350.582944 -264.09861) (xy 350.569026 -264.073102) (xy 350.559116 -264.062464) (xy 350.484948 -263.988296)
			(xy 350.452182 -264.004806) (xy 350.427257 -264.016738) (xy 350.374638 -264.033608) (xy 350.320045 -264.042147)
			(xy 350.292416 -264.042652) (xy 350.264431 -264.042104) (xy 350.209149 -264.033352) (xy 350.155917 -264.016059)
			(xy 350.106045 -263.990652) (xy 350.060762 -263.957757) (xy 350.021182 -263.918184) (xy 349.988279 -263.872906)
			(xy 349.962864 -263.823038) (xy 349.945563 -263.769809) (xy 349.9368 -263.714529) (xy 349.936308 -263.686544)
			(xy 349.936833 -263.658917) (xy 349.945374 -263.604327) (xy 349.962242 -263.551711) (xy 349.974154 -263.526778)
			(xy 349.990664 -263.494012) (xy 349.400114 -262.903462) (xy 349.39023 -262.894218) (xy 349.366719 -262.880835)
			(xy 349.340518 -262.874095) (xy 349.313467 -262.874471) (xy 349.287465 -262.881937) (xy 349.264334 -262.895968)
			(xy 349.2457 -262.91558) (xy 349.232868 -262.939397) (xy 349.229426 -262.952484) (xy 349.222963 -262.978293)
			(xy 349.203421 -263.027777) (xy 349.176736 -263.073803) (xy 349.1435 -263.115347) (xy 349.104454 -263.151485)
			(xy 349.060467 -263.181412) (xy 349.012518 -263.204463) (xy 348.961672 -263.220125) (xy 348.909063 -263.228048)
			(xy 348.882462 -263.228582) (xy 348.854482 -263.22803) (xy 348.799211 -263.21927) (xy 348.74599 -263.201972)
			(xy 348.696131 -263.176562) (xy 348.650861 -263.143664) (xy 348.611294 -263.10409) (xy 348.578405 -263.058814)
			(xy 348.553003 -263.008951) (xy 348.535715 -262.955727) (xy 348.526965 -262.900455) (xy 348.526354 -262.872474)
			(xy 348.526844 -262.845867) (xy 348.534753 -262.793244) (xy 348.550406 -262.742384) (xy 348.573454 -262.694421)
			(xy 348.603384 -262.650422) (xy 348.639529 -262.611367) (xy 348.681084 -262.578128) (xy 348.727124 -262.551443)
			(xy 348.776622 -262.531907) (xy 348.802452 -262.52551) (xy 348.815548 -262.522061) (xy 348.839403 -262.509265)
			(xy 348.859051 -262.490642) (xy 348.873106 -262.467505) (xy 348.880578 -262.441486) (xy 348.88094 -262.414417)
			(xy 348.874166 -262.388207) (xy 348.860735 -262.364703) (xy 348.851474 -262.354822) (xy 348.807786 -262.311134)
			(xy 348.79808 -262.302035) (xy 348.775058 -262.288722) (xy 348.749379 -262.281807) (xy 348.722785 -262.281759)
			(xy 348.697081 -262.288582) (xy 348.674011 -262.301812) (xy 348.664276 -262.31088) (xy 348.644103 -262.330206)
			(xy 348.59886 -262.362972) (xy 348.54906 -262.388279) (xy 348.495922 -262.405509) (xy 348.440747 -262.414241)
			(xy 348.412816 -262.414766) (xy 348.384831 -262.414247) (xy 348.32955 -262.405493) (xy 348.276319 -262.388198)
			(xy 348.22645 -262.362788) (xy 348.18117 -262.329888) (xy 348.141595 -262.29031) (xy 348.108699 -262.245028)
			(xy 348.083292 -262.195157) (xy 348.066001 -262.141925) (xy 348.057251 -262.086643) (xy 348.056708 -262.058658)
			(xy 348.057248 -262.030726) (xy 348.06596 -261.975546) (xy 348.083179 -261.922403) (xy 348.108484 -261.8726)
			(xy 348.141253 -261.827357) (xy 348.160594 -261.807198) (xy 348.169656 -261.797461) (xy 348.182883 -261.774395)
			(xy 348.189701 -261.748695) (xy 348.189648 -261.722105) (xy 348.182729 -261.696432) (xy 348.169411 -261.673419)
			(xy 348.16034 -261.663688) (xy 348.07398 -261.577328) (xy 348.04477 -261.585964) (xy 348.019821 -261.592946)
			(xy 347.968565 -261.600475) (xy 347.942662 -261.60095) (xy 347.91468 -261.600398) (xy 347.859405 -261.591639)
			(xy 347.80618 -261.574341) (xy 347.756316 -261.548932) (xy 347.71104 -261.516036) (xy 347.671467 -261.476463)
			(xy 347.63857 -261.431187) (xy 347.61316 -261.381324) (xy 347.595862 -261.328099) (xy 347.587102 -261.272824)
			(xy 347.586554 -261.244842) (xy 347.587015 -261.218937) (xy 347.594533 -261.167677) (xy 347.60154 -261.142734)
			(xy 347.610176 -261.113524) (xy 347.4085 -260.911848) (xy 347.4085 -260.78307) (xy 347.372178 -260.772402)
			(xy 347.346523 -260.764295) (xy 347.297817 -260.741439) (xy 347.253101 -260.71152) (xy 347.213393 -260.675217)
			(xy 347.179595 -260.633355) (xy 347.152476 -260.586888) (xy 347.132653 -260.53687) (xy 347.120577 -260.484441)
			(xy 347.116521 -260.430792) (xy 347.120579 -260.377143) (xy 347.132658 -260.324714) (xy 347.152483 -260.274698)
			(xy 347.179604 -260.228232) (xy 347.213404 -260.186372) (xy 347.253114 -260.15007) (xy 347.297831 -260.120153)
			(xy 347.346538 -260.0973) (xy 347.372178 -260.089142) (xy 347.4085 -260.078474) (xy 347.4085 -259.959094)
			(xy 347.408021 -259.944471) (xy 347.399735 -259.916424) (xy 347.383842 -259.891874) (xy 347.361646 -259.872831)
			(xy 347.334964 -259.860856) (xy 347.305984 -259.85693) (xy 347.277078 -259.861375) (xy 347.250615 -259.873827)
			(xy 347.239336 -259.883148) (xy 347.219691 -259.899998) (xy 347.176442 -259.928425) (xy 347.129532 -259.950287)
			(xy 347.079949 -259.965121) (xy 347.028739 -259.972615) (xy 347.002862 -259.973064) (xy 346.976218 -259.972563)
			(xy 346.923525 -259.964616) (xy 346.872606 -259.948905) (xy 346.824597 -259.92578) (xy 346.78057 -259.895759)
			(xy 346.741508 -259.859511) (xy 346.708286 -259.817847) (xy 346.681643 -259.771697) (xy 346.662176 -259.722092)
			(xy 346.650319 -259.670139) (xy 346.646337 -259.617) (xy 346.650319 -259.563861) (xy 346.662176 -259.511908)
			(xy 346.681643 -259.462303) (xy 346.708286 -259.416153) (xy 346.741509 -259.374489) (xy 346.78057 -259.338241)
			(xy 346.824597 -259.30822) (xy 346.872606 -259.285095) (xy 346.923525 -259.269384) (xy 346.976218 -259.261437)
			(xy 347.002862 -259.260848) (xy 347.028737 -259.261317) (xy 347.07994 -259.26882) (xy 347.129517 -259.283658)
			(xy 347.176423 -259.305519) (xy 347.219669 -259.333942) (xy 347.239336 -259.350764) (xy 347.25058 -259.360136)
			(xy 347.277051 -259.372604) (xy 347.305971 -259.377058) (xy 347.334967 -259.373131) (xy 347.36166 -259.361146)
			(xy 347.383861 -259.342087) (xy 347.399749 -259.317516) (xy 347.408021 -259.289449) (xy 347.4085 -259.274818)
			(xy 347.4085 -259.155438) (xy 347.372178 -259.14477) (xy 347.346518 -259.136663) (xy 347.297801 -259.113806)
			(xy 347.253076 -259.083883) (xy 347.213358 -259.047576) (xy 347.179552 -259.005708) (xy 347.152426 -258.959234)
			(xy 347.132596 -258.909208) (xy 347.120514 -258.85677) (xy 347.116455 -258.803111) (xy 347.120511 -258.749452)
			(xy 347.132589 -258.697013) (xy 347.152416 -258.646987) (xy 347.179539 -258.60051) (xy 347.213343 -258.558641)
			(xy 347.253058 -258.522331) (xy 347.297781 -258.492405) (xy 347.346496 -258.469545) (xy 347.372178 -258.46151)
			(xy 347.4085 -258.450842) (xy 347.4085 -258.331462) (xy 347.408031 -258.316853) (xy 347.399772 -258.288829)
			(xy 347.383912 -258.264292) (xy 347.36175 -258.245253) (xy 347.335103 -258.233272) (xy 347.306154 -258.22933)
			(xy 347.277274 -258.233751) (xy 347.250829 -258.246172) (xy 347.23959 -258.255516) (xy 347.219947 -258.27231)
			(xy 347.176724 -258.300638) (xy 347.129862 -258.322425) (xy 347.080344 -258.337212) (xy 347.029209 -258.344689)
			(xy 347.00337 -258.345178) (xy 347.003116 -258.345178) (xy 346.976466 -258.344706) (xy 346.923762 -258.336764)
			(xy 346.87283 -258.321056) (xy 346.824808 -258.297932) (xy 346.780769 -258.267908) (xy 346.741697 -258.231657)
			(xy 346.708465 -258.189986) (xy 346.681815 -258.143828) (xy 346.662342 -258.094213) (xy 346.650481 -258.04225)
			(xy 346.646498 -257.9891) (xy 346.650481 -257.93595) (xy 346.662342 -257.883987) (xy 346.681815 -257.834372)
			(xy 346.708465 -257.788214) (xy 346.741697 -257.746543) (xy 346.780769 -257.710292) (xy 346.824808 -257.680268)
			(xy 346.87283 -257.657144) (xy 346.923762 -257.641436) (xy 346.976466 -257.633494) (xy 347.003116 -257.632962)
			(xy 347.00337 -257.632962) (xy 347.029211 -257.633422) (xy 347.080352 -257.640892) (xy 347.129874 -257.65568)
			(xy 347.176736 -257.677475) (xy 347.219954 -257.705818) (xy 347.23959 -257.722624) (xy 347.250832 -257.731943)
			(xy 347.277268 -257.744319) (xy 347.306126 -257.74871) (xy 347.335047 -257.744757) (xy 347.361667 -257.732784)
			(xy 347.383813 -257.713768) (xy 347.399674 -257.689263) (xy 347.407953 -257.661272) (xy 347.4085 -257.646678)
			(xy 347.4085 -257.527552) (xy 347.372178 -257.516884) (xy 347.346497 -257.508805) (xy 347.297735 -257.485993)
			(xy 347.252962 -257.456101) (xy 347.213199 -257.41981) (xy 347.179351 -257.377947) (xy 347.152191 -257.331466)
			(xy 347.132337 -257.281426) (xy 347.120241 -257.228968) (xy 347.11618 -257.175287) (xy 347.120245 -257.121606)
			(xy 347.132345 -257.069149) (xy 347.152202 -257.019111) (xy 347.179366 -256.972632) (xy 347.213216 -256.930771)
			(xy 347.252982 -256.894483) (xy 347.297757 -256.864594) (xy 347.346521 -256.841786) (xy 347.372178 -256.833624)
			(xy 347.4085 -256.822956) (xy 347.4085 -256.703576) (xy 347.408019 -256.688955) (xy 347.39973 -256.660913)
			(xy 347.383837 -256.636367) (xy 347.361642 -256.617328) (xy 347.334963 -256.605356) (xy 347.305986 -256.60143)
			(xy 347.277084 -256.605873) (xy 347.250624 -256.618321) (xy 347.239336 -256.62763) (xy 347.219691 -256.64448)
			(xy 347.176443 -256.67291) (xy 347.129533 -256.694772) (xy 347.079949 -256.709607) (xy 347.02874 -256.717101)
			(xy 347.002862 -256.717546) (xy 346.976212 -256.717046) (xy 346.923507 -256.709096) (xy 346.872576 -256.693381)
			(xy 346.824555 -256.670251) (xy 346.780518 -256.640223) (xy 346.741448 -256.603967) (xy 346.708217 -256.562294)
			(xy 346.681569 -256.516133) (xy 346.662097 -256.466516) (xy 346.650237 -256.414552) (xy 346.646254 -256.3614)
			(xy 346.650237 -256.308248) (xy 346.662097 -256.256284) (xy 346.681569 -256.206667) (xy 346.708217 -256.160506)
			(xy 346.741448 -256.118833) (xy 346.780518 -256.082577) (xy 346.824555 -256.052549) (xy 346.872576 -256.029419)
			(xy 346.923507 -256.013704) (xy 346.976212 -256.005754) (xy 347.002862 -256.00533) (xy 347.028737 -256.005799)
			(xy 347.079941 -256.013301) (xy 347.129518 -256.028139) (xy 347.176425 -256.049999) (xy 347.219672 -256.078421)
			(xy 347.239336 -256.095246) (xy 347.250585 -256.104613) (xy 347.277061 -256.117072) (xy 347.305982 -256.12152)
			(xy 347.334979 -256.117592) (xy 347.361674 -256.105611) (xy 347.383882 -256.086557) (xy 347.399782 -256.061993)
			(xy 347.408071 -256.033931) (xy 347.4085 -256.0193) (xy 347.4085 -255.89992) (xy 347.372178 -255.889252)
			(xy 347.346519 -255.881145) (xy 347.297805 -255.858289) (xy 347.253082 -255.828367) (xy 347.213367 -255.79206)
			(xy 347.179563 -255.750194) (xy 347.152439 -255.703721) (xy 347.132611 -255.653698) (xy 347.120531 -255.601262)
			(xy 347.116473 -255.547606) (xy 347.120529 -255.49395) (xy 347.132607 -255.441514) (xy 347.152433 -255.39149)
			(xy 347.179556 -255.345016) (xy 347.213359 -255.303149) (xy 347.253072 -255.266841) (xy 347.297794 -255.236918)
			(xy 347.346507 -255.214059) (xy 347.372178 -255.205992) (xy 347.4085 -255.195324) (xy 347.4085 -255.07569)
			(xy 347.408021 -255.061068) (xy 347.399734 -255.033022) (xy 347.383841 -255.008472) (xy 347.361645 -254.98943)
			(xy 347.334964 -254.977456) (xy 347.305984 -254.97353) (xy 347.277079 -254.977975) (xy 347.250617 -254.990425)
			(xy 347.239336 -254.999744) (xy 347.219691 -255.016594) (xy 347.176443 -255.045022) (xy 347.129532 -255.066884)
			(xy 347.079949 -255.081718) (xy 347.028739 -255.089212) (xy 347.002862 -255.08966) (xy 346.976218 -255.089159)
			(xy 346.923526 -255.081212) (xy 346.872607 -255.065501) (xy 346.824599 -255.042376) (xy 346.780572 -255.012355)
			(xy 346.741511 -254.976108) (xy 346.708289 -254.934445) (xy 346.681647 -254.888295) (xy 346.66218 -254.838691)
			(xy 346.650323 -254.786739) (xy 346.646341 -254.7336) (xy 346.650323 -254.680461) (xy 346.66218 -254.628509)
			(xy 346.681647 -254.578905) (xy 346.708289 -254.532755) (xy 346.741511 -254.491092) (xy 346.780572 -254.454844)
			(xy 346.824599 -254.424824) (xy 346.872607 -254.401699) (xy 346.923526 -254.385988) (xy 346.976218 -254.378041)
			(xy 347.002862 -254.377444) (xy 347.028737 -254.377913) (xy 347.07994 -254.385416) (xy 347.129518 -254.400254)
			(xy 347.176424 -254.422115) (xy 347.21967 -254.450537) (xy 347.239336 -254.46736) (xy 347.25058 -254.476732)
			(xy 347.277051 -254.489201) (xy 347.30597 -254.493655) (xy 347.334966 -254.489728) (xy 347.361659 -254.477743)
			(xy 347.38386 -254.458683) (xy 347.399748 -254.434112) (xy 347.408018 -254.406045) (xy 347.4085 -254.391414)
			(xy 347.4085 -254.272034) (xy 347.372178 -254.261366) (xy 347.346518 -254.253259) (xy 347.297802 -254.230402)
			(xy 347.253077 -254.20048) (xy 347.21336 -254.164172) (xy 347.179554 -254.122305) (xy 347.152429 -254.075831)
			(xy 347.132599 -254.025806) (xy 347.120518 -253.973368) (xy 347.116459 -253.91971) (xy 347.120515 -253.866052)
			(xy 347.132593 -253.813613) (xy 347.15242 -253.763587) (xy 347.179543 -253.717112) (xy 347.213346 -253.675243)
			(xy 347.253061 -253.638933) (xy 347.297784 -253.609008) (xy 347.346499 -253.586148) (xy 347.372178 -253.578106)
			(xy 347.4085 -253.567438) (xy 347.4085 -249.213116) (xy 347.358462 -249.162316) (xy 347.332034 -249.161498)
			(xy 347.279846 -249.153015) (xy 347.229486 -249.13691) (xy 347.182061 -249.113537) (xy 347.138611 -249.083409)
			(xy 347.100094 -249.047189) (xy 347.067355 -249.005672) (xy 347.041113 -248.959771) (xy 347.021946 -248.910495)
			(xy 347.010275 -248.858927) (xy 347.006356 -248.8062) (xy 347.010275 -248.753473) (xy 347.021946 -248.701905)
			(xy 347.041113 -248.652629) (xy 347.067355 -248.606728) (xy 347.100094 -248.565211) (xy 347.138611 -248.528991)
			(xy 347.18206 -248.498863) (xy 347.229486 -248.47549) (xy 347.279846 -248.459385) (xy 347.332034 -248.450902)
			(xy 347.358462 -248.4501) (xy 347.4085 -248.3993) (xy 347.4085 -247.58523) (xy 347.358462 -247.53443)
			(xy 347.332033 -247.533612) (xy 347.279843 -247.525129) (xy 347.229481 -247.509023) (xy 347.182054 -247.485649)
			(xy 347.138603 -247.45552) (xy 347.100084 -247.419299) (xy 347.067343 -247.37778) (xy 347.041101 -247.331878)
			(xy 347.021933 -247.2826) (xy 347.010261 -247.231029) (xy 347.006342 -247.1783) (xy 347.010261 -247.125571)
			(xy 347.021933 -247.074001) (xy 347.0411 -247.024723) (xy 347.067343 -246.97882) (xy 347.100084 -246.937302)
			(xy 347.138602 -246.90108) (xy 347.182053 -246.870951) (xy 347.229481 -246.847577) (xy 347.279843 -246.831471)
			(xy 347.332032 -246.822989) (xy 347.358462 -246.822214) (xy 347.4085 -246.771414) (xy 347.4085 -245.957598)
			(xy 347.358462 -245.906798) (xy 347.332035 -245.90598) (xy 347.27985 -245.897498) (xy 347.229493 -245.881394)
			(xy 347.182069 -245.858022) (xy 347.138623 -245.827895) (xy 347.100107 -245.791677) (xy 347.06737 -245.750162)
			(xy 347.041129 -245.704263) (xy 347.021963 -245.65499) (xy 347.010293 -245.603424) (xy 347.006374 -245.5507)
			(xy 347.010293 -245.497975) (xy 347.021963 -245.44641) (xy 347.04113 -245.397136) (xy 347.06737 -245.351238)
			(xy 347.100107 -245.309723) (xy 347.138623 -245.273505) (xy 347.18207 -245.243378) (xy 347.229493 -245.220006)
			(xy 347.279851 -245.203902) (xy 347.332036 -245.19542) (xy 347.358462 -245.194582) (xy 347.4085 -245.143782)
			(xy 347.4085 -244.329712) (xy 347.358462 -244.278912) (xy 347.332034 -244.278094) (xy 347.279847 -244.269611)
			(xy 347.229488 -244.253507) (xy 347.182063 -244.230134) (xy 347.138614 -244.200006) (xy 347.100097 -244.163786)
			(xy 347.067358 -244.12227) (xy 347.041117 -244.07637) (xy 347.02195 -244.027094) (xy 347.010279 -243.975527)
			(xy 347.00636 -243.9228) (xy 347.010279 -243.870074) (xy 347.02195 -243.818506) (xy 347.041117 -243.76923)
			(xy 347.067358 -243.72333) (xy 347.100097 -243.681814) (xy 347.138614 -243.645594) (xy 347.182062 -243.615466)
			(xy 347.229488 -243.592093) (xy 347.279847 -243.575989) (xy 347.332034 -243.567506) (xy 347.358462 -243.566696)
			(xy 347.4085 -243.515896) (xy 347.4085 -242.701826) (xy 347.358462 -242.651026) (xy 347.332033 -242.650208)
			(xy 347.279844 -242.641725) (xy 347.229483 -242.62562) (xy 347.182056 -242.602246) (xy 347.138605 -242.572117)
			(xy 347.100087 -242.535896) (xy 347.067347 -242.494378) (xy 347.041104 -242.448476) (xy 347.021937 -242.399198)
			(xy 347.010265 -242.347629) (xy 347.006346 -242.2949) (xy 347.010265 -242.242172) (xy 347.021937 -242.190602)
			(xy 347.041104 -242.141325) (xy 347.067346 -242.095422) (xy 347.100086 -242.053904) (xy 347.138605 -242.017683)
			(xy 347.182055 -241.987554) (xy 347.229482 -241.964181) (xy 347.279844 -241.948075) (xy 347.332033 -241.939593)
			(xy 347.358462 -241.93881) (xy 347.4085 -241.88801) (xy 347.4085 -241.074194) (xy 347.358462 -241.023394)
			(xy 347.332036 -241.022576) (xy 347.279851 -241.014094) (xy 347.229494 -240.99799) (xy 347.182071 -240.974618)
			(xy 347.138625 -240.944492) (xy 347.10011 -240.908274) (xy 347.067373 -240.86676) (xy 347.041133 -240.820862)
			(xy 347.021967 -240.771589) (xy 347.010296 -240.720024) (xy 347.006378 -240.6673) (xy 347.010297 -240.614576)
			(xy 347.021967 -240.563011) (xy 347.041133 -240.513738) (xy 347.067373 -240.46784) (xy 347.10011 -240.426326)
			(xy 347.138625 -240.390108) (xy 347.182072 -240.359982) (xy 347.229495 -240.33661) (xy 347.279852 -240.320506)
			(xy 347.332036 -240.312024) (xy 347.358462 -240.311178) (xy 347.4085 -240.260378) (xy 347.4085 -239.494568)
			(xy 347.457268 -239.4458) (xy 347.405452 -239.39373) (xy 347.382846 -239.395) (xy 347.363034 -239.395508)
			(xy 347.336381 -239.395037) (xy 347.28367 -239.387097) (xy 347.232732 -239.371389) (xy 347.184704 -239.348264)
			(xy 347.140659 -239.318238) (xy 347.101581 -239.281983) (xy 347.068344 -239.240309) (xy 347.04169 -239.194146)
			(xy 347.022214 -239.144525) (xy 347.010352 -239.092556) (xy 347.006368 -239.0394) (xy 347.010352 -238.986244)
			(xy 347.022214 -238.934275) (xy 347.04169 -238.884654) (xy 347.068344 -238.838491) (xy 347.101581 -238.796817)
			(xy 347.140659 -238.760562) (xy 347.184704 -238.730536) (xy 347.232732 -238.707411) (xy 347.28367 -238.691703)
			(xy 347.336381 -238.683763) (xy 347.363034 -238.683292) (xy 347.390147 -238.683802) (xy 347.443747 -238.692027)
			(xy 347.495481 -238.70828) (xy 347.544153 -238.732187) (xy 347.58864 -238.763195) (xy 347.627913 -238.800588)
			(xy 347.661064 -238.843501) (xy 347.687328 -238.890943) (xy 347.706098 -238.941818) (xy 347.71203 -238.96828)
			(xy 347.715192 -238.981616) (xy 347.727592 -239.006048) (xy 347.746048 -239.026296) (xy 347.769229 -239.0409)
			(xy 347.795462 -239.048804) (xy 347.822853 -239.049439) (xy 347.849424 -239.042759) (xy 347.873257 -239.029246)
			(xy 347.883226 -239.019842) (xy 347.95968 -238.943388) (xy 347.96349 -238.931704) (xy 347.972603 -238.904817)
			(xy 347.998146 -238.854121) (xy 348.03141 -238.808121) (xy 348.071554 -238.767983) (xy 348.117558 -238.734724)
			(xy 348.168257 -238.709187) (xy 348.195138 -238.700056) (xy 348.206822 -238.696246) (xy 348.476316 -238.426752)
			(xy 348.458536 -238.393478) (xy 348.445279 -238.367498) (xy 348.426488 -238.312285) (xy 348.416958 -238.254745)
			(xy 348.416372 -238.225584) (xy 348.416922 -238.197601) (xy 348.425679 -238.142325) (xy 348.442975 -238.089099)
			(xy 348.468383 -238.039233) (xy 348.501279 -237.993956) (xy 348.540853 -237.954382) (xy 348.58613 -237.921485)
			(xy 348.635995 -237.896076) (xy 348.689221 -237.87878) (xy 348.744497 -237.870022) (xy 348.77248 -237.869476)
			(xy 348.80164 -237.87008) (xy 348.859176 -237.879615) (xy 348.914394 -237.898384) (xy 348.940374 -237.91164)
			(xy 348.973648 -237.92942) (xy 349.047816 -237.855252) (xy 349.057888 -237.844502) (xy 349.071925 -237.818616)
			(xy 349.077991 -237.789801) (xy 349.075579 -237.760454) (xy 349.064892 -237.733015) (xy 349.046818 -237.709768)
			(xy 349.035116 -237.70082) (xy 349.012532 -237.683982) (xy 348.972482 -237.644373) (xy 348.939173 -237.598948)
			(xy 348.913438 -237.548842) (xy 348.895921 -237.495306) (xy 348.887058 -237.439679) (xy 348.886526 -237.411514)
			(xy 348.887046 -237.383529) (xy 348.8958 -237.328248) (xy 348.913095 -237.275017) (xy 348.938505 -237.225147)
			(xy 348.971404 -237.179867) (xy 349.010982 -237.140291) (xy 349.056264 -237.107394) (xy 349.106135 -237.081987)
			(xy 349.159367 -237.064695) (xy 349.214649 -237.055944) (xy 349.242634 -237.055406) (xy 349.270797 -237.055944)
			(xy 349.326419 -237.064819) (xy 349.37995 -237.082342) (xy 349.430054 -237.108076) (xy 349.47548 -237.141379)
			(xy 349.515095 -237.18142) (xy 349.53194 -237.203996) (xy 349.540917 -237.215669) (xy 349.564174 -237.233712)
			(xy 349.591606 -237.244385) (xy 349.620941 -237.246806) (xy 349.649752 -237.240774) (xy 349.675652 -237.226789)
			(xy 349.686372 -237.216696) (xy 349.77578 -237.127288) (xy 349.785903 -237.116396) (xy 349.799928 -237.090192)
			(xy 349.805816 -237.061059) (xy 349.803071 -237.031465) (xy 349.791923 -237.003913) (xy 349.773316 -236.980736)
			(xy 349.748826 -236.963895) (xy 349.720525 -236.954816) (xy 349.705676 -236.95406) (xy 349.678032 -236.953029)
			(xy 349.623548 -236.943474) (xy 349.571198 -236.925607) (xy 349.52224 -236.899858) (xy 349.477855 -236.866847)
			(xy 349.439109 -236.827368) (xy 349.406935 -236.782371) (xy 349.382108 -236.73294) (xy 349.365225 -236.680264)
			(xy 349.356693 -236.62561) (xy 349.356172 -236.597952) (xy 349.356725 -236.569971) (xy 349.365485 -236.514698)
			(xy 349.382784 -236.461476) (xy 349.408194 -236.411615) (xy 349.441091 -236.366343) (xy 349.480664 -236.326773)
			(xy 349.525939 -236.29388) (xy 349.575802 -236.268473) (xy 349.629026 -236.251179) (xy 349.684299 -236.242422)
			(xy 349.71228 -236.241844) (xy 349.739934 -236.242372) (xy 349.794574 -236.250932) (xy 349.847236 -236.267833)
			(xy 349.896653 -236.292669) (xy 349.941639 -236.324844) (xy 349.981111 -236.363584) (xy 350.014123 -236.407959)
			(xy 350.03988 -236.456902) (xy 350.057764 -236.509238) (xy 350.067346 -236.563709) (xy 350.068388 -236.591348)
			(xy 350.069159 -236.606204) (xy 350.078214 -236.634524) (xy 350.095045 -236.659035) (xy 350.118224 -236.677657)
			(xy 350.145785 -236.688812) (xy 350.175392 -236.691553) (xy 350.204533 -236.685647) (xy 350.230737 -236.671596)
			(xy 350.241616 -236.661452) (xy 350.46539 -236.437678) (xy 350.465898 -236.417358) (xy 350.467075 -236.38982)
			(xy 350.476874 -236.33558) (xy 350.494916 -236.283499) (xy 350.520768 -236.234821) (xy 350.553814 -236.190708)
			(xy 350.593264 -236.152216) (xy 350.638175 -236.120264) (xy 350.687474 -236.095615) (xy 350.739983 -236.078859)
			(xy 350.794447 -236.070396) (xy 350.822006 -236.069886) (xy 350.849202 -236.070394) (xy 350.902963 -236.078656)
			(xy 350.954841 -236.095002) (xy 351.003628 -236.11905) (xy 351.048187 -236.150242) (xy 351.087482 -236.187851)
			(xy 351.120597 -236.231) (xy 351.146762 -236.278686) (xy 351.156524 -236.304074) (xy 351.168716 -236.337348)
			(xy 354.994718 -236.337348) (xy 355.008605 -236.336887) (xy 355.035356 -236.329418) (xy 355.059102 -236.315012)
			(xy 355.078082 -236.294735) (xy 355.09089 -236.270091) (xy 355.096578 -236.242906) (xy 355.094723 -236.215194)
			(xy 355.090476 -236.201966) (xy 355.081133 -236.173466) (xy 355.07104 -236.11435) (xy 355.07041 -236.084364)
			(xy 355.07041 -236.083856) (xy 355.070858 -236.058153) (xy 355.078241 -236.00728) (xy 355.092864 -235.957998)
			(xy 355.11442 -235.911331) (xy 355.128068 -235.889546) (xy 355.135494 -235.87731) (xy 355.143894 -235.849961)
			(xy 355.144364 -235.821355) (xy 355.136867 -235.793745) (xy 355.121994 -235.769305) (xy 355.111812 -235.759244)
			(xy 355.094051 -235.74232) (xy 355.062877 -235.704437) (xy 355.037198 -235.662635) (xy 355.017498 -235.617704)
			(xy 355.004151 -235.570494) (xy 354.997408 -235.5219) (xy 354.997004 -235.49737) (xy 354.997555 -235.469389)
			(xy 355.006314 -235.414116) (xy 355.023611 -235.360894) (xy 355.049021 -235.311032) (xy 355.081918 -235.26576)
			(xy 355.121492 -235.226191) (xy 355.166768 -235.193299) (xy 355.216633 -235.167895) (xy 355.269857 -235.150604)
			(xy 355.325131 -235.141852) (xy 355.353112 -235.141262) (xy 355.353366 -235.141262) (xy 355.380668 -235.14175)
			(xy 355.434633 -235.150075) (xy 355.486691 -235.166552) (xy 355.535619 -235.190791) (xy 355.580268 -235.222225)
			(xy 355.600254 -235.24083) (xy 355.611876 -235.251227) (xy 355.63981 -235.265051) (xy 355.670612 -235.269807)
			(xy 355.701414 -235.265051) (xy 355.729348 -235.251227) (xy 355.74097 -235.24083) (xy 355.761004 -235.222285)
			(xy 355.805659 -235.190886) (xy 355.854578 -235.166661) (xy 355.906619 -235.150177) (xy 355.960564 -235.141818)
			(xy 355.987858 -235.141262) (xy 355.988112 -235.141262) (xy 356.016095 -235.141812) (xy 356.071373 -235.150568)
			(xy 356.1246 -235.167863) (xy 356.174467 -235.193272) (xy 356.219745 -235.226167) (xy 356.259321 -235.265741)
			(xy 356.292219 -235.311018) (xy 356.31763 -235.360883) (xy 356.334928 -235.41411) (xy 356.343687 -235.469387)
			(xy 356.34422 -235.49737) (xy 356.343771 -235.523073) (xy 356.336384 -235.573944) (xy 356.32176 -235.623225)
			(xy 356.300202 -235.669891) (xy 356.286562 -235.69168) (xy 356.279123 -235.703917) (xy 356.270701 -235.731274)
			(xy 356.270214 -235.759894) (xy 356.277702 -235.787521) (xy 356.291693 -235.810531) (xy 357.345224 -235.810531)
			(xy 357.345224 -235.757233) (xy 357.353167 -235.704529) (xy 357.368877 -235.653599) (xy 357.392003 -235.605578)
			(xy 357.422027 -235.561541) (xy 357.458279 -235.52247) (xy 357.49995 -235.489239) (xy 357.546108 -235.46259)
			(xy 357.595722 -235.443118) (xy 357.647684 -235.431258) (xy 357.700834 -235.427275) (xy 357.753984 -235.431258)
			(xy 357.805946 -235.443118) (xy 357.85556 -235.46259) (xy 357.901718 -235.489239) (xy 357.943389 -235.52247)
			(xy 357.979641 -235.561541) (xy 358.009665 -235.605578) (xy 358.032791 -235.653599) (xy 358.048501 -235.704529)
			(xy 358.056444 -235.757233) (xy 358.056942 -235.783882) (xy 358.056444 -235.810531) (xy 358.285024 -235.810531)
			(xy 358.285024 -235.757233) (xy 358.292967 -235.704529) (xy 358.308677 -235.653599) (xy 358.331803 -235.605578)
			(xy 358.361827 -235.561541) (xy 358.398079 -235.52247) (xy 358.43975 -235.489239) (xy 358.485908 -235.46259)
			(xy 358.535522 -235.443118) (xy 358.587484 -235.431258) (xy 358.640634 -235.427275) (xy 358.693784 -235.431258)
			(xy 358.745746 -235.443118) (xy 358.79536 -235.46259) (xy 358.841518 -235.489239) (xy 358.883189 -235.52247)
			(xy 358.919441 -235.561541) (xy 358.949465 -235.605578) (xy 358.972591 -235.653599) (xy 358.988301 -235.704529)
			(xy 358.996244 -235.757233) (xy 358.996742 -235.783882) (xy 358.996244 -235.810531) (xy 359.224824 -235.810531)
			(xy 359.224824 -235.757233) (xy 359.232767 -235.704529) (xy 359.248477 -235.653599) (xy 359.271603 -235.605578)
			(xy 359.301627 -235.561541) (xy 359.337879 -235.52247) (xy 359.37955 -235.489239) (xy 359.425708 -235.46259)
			(xy 359.475322 -235.443118) (xy 359.527284 -235.431258) (xy 359.580434 -235.427275) (xy 359.633584 -235.431258)
			(xy 359.685546 -235.443118) (xy 359.73516 -235.46259) (xy 359.781318 -235.489239) (xy 359.822989 -235.52247)
			(xy 359.859241 -235.561541) (xy 359.889265 -235.605578) (xy 359.912391 -235.653599) (xy 359.928101 -235.704529)
			(xy 359.936044 -235.757233) (xy 359.936542 -235.783882) (xy 359.936044 -235.810531) (xy 360.164624 -235.810531)
			(xy 360.164624 -235.757233) (xy 360.172567 -235.704529) (xy 360.188277 -235.653599) (xy 360.211403 -235.605578)
			(xy 360.241427 -235.561541) (xy 360.277679 -235.52247) (xy 360.31935 -235.489239) (xy 360.365508 -235.46259)
			(xy 360.415122 -235.443118) (xy 360.467084 -235.431258) (xy 360.520234 -235.427275) (xy 360.573384 -235.431258)
			(xy 360.625346 -235.443118) (xy 360.67496 -235.46259) (xy 360.721118 -235.489239) (xy 360.762789 -235.52247)
			(xy 360.799041 -235.561541) (xy 360.829065 -235.605578) (xy 360.852191 -235.653599) (xy 360.867901 -235.704529)
			(xy 360.875844 -235.757233) (xy 360.876342 -235.783882) (xy 360.875844 -235.810531) (xy 361.104424 -235.810531)
			(xy 361.104424 -235.757233) (xy 361.112367 -235.704529) (xy 361.128077 -235.653599) (xy 361.151203 -235.605578)
			(xy 361.181227 -235.561541) (xy 361.217479 -235.52247) (xy 361.25915 -235.489239) (xy 361.305308 -235.46259)
			(xy 361.354922 -235.443118) (xy 361.406884 -235.431258) (xy 361.460034 -235.427275) (xy 361.513184 -235.431258)
			(xy 361.565146 -235.443118) (xy 361.61476 -235.46259) (xy 361.660918 -235.489239) (xy 361.702589 -235.52247)
			(xy 361.738841 -235.561541) (xy 361.768865 -235.605578) (xy 361.791991 -235.653599) (xy 361.807701 -235.704529)
			(xy 361.815644 -235.757233) (xy 361.816142 -235.783882) (xy 361.815644 -235.810531) (xy 362.044224 -235.810531)
			(xy 362.044224 -235.757233) (xy 362.052167 -235.704529) (xy 362.067877 -235.653599) (xy 362.091003 -235.605578)
			(xy 362.121027 -235.561541) (xy 362.157279 -235.52247) (xy 362.19895 -235.489239) (xy 362.245108 -235.46259)
			(xy 362.294722 -235.443118) (xy 362.346684 -235.431258) (xy 362.399834 -235.427275) (xy 362.452984 -235.431258)
			(xy 362.504946 -235.443118) (xy 362.55456 -235.46259) (xy 362.600718 -235.489239) (xy 362.642389 -235.52247)
			(xy 362.678641 -235.561541) (xy 362.708665 -235.605578) (xy 362.731791 -235.653599) (xy 362.747501 -235.704529)
			(xy 362.755444 -235.757233) (xy 362.755942 -235.783882) (xy 362.755444 -235.810531) (xy 369.562624 -235.810531)
			(xy 369.562624 -235.757233) (xy 369.570567 -235.704529) (xy 369.586277 -235.653599) (xy 369.609403 -235.605578)
			(xy 369.639427 -235.561541) (xy 369.675679 -235.52247) (xy 369.71735 -235.489239) (xy 369.763508 -235.46259)
			(xy 369.813122 -235.443118) (xy 369.865084 -235.431258) (xy 369.918234 -235.427275) (xy 369.971384 -235.431258)
			(xy 370.023346 -235.443118) (xy 370.07296 -235.46259) (xy 370.119118 -235.489239) (xy 370.160789 -235.52247)
			(xy 370.197041 -235.561541) (xy 370.227065 -235.605578) (xy 370.250191 -235.653599) (xy 370.265901 -235.704529)
			(xy 370.273844 -235.757233) (xy 370.274342 -235.783882) (xy 370.273844 -235.810531) (xy 370.502424 -235.810531)
			(xy 370.502424 -235.757233) (xy 370.510367 -235.704529) (xy 370.526077 -235.653599) (xy 370.549203 -235.605578)
			(xy 370.579227 -235.561541) (xy 370.615479 -235.52247) (xy 370.65715 -235.489239) (xy 370.703308 -235.46259)
			(xy 370.752922 -235.443118) (xy 370.804884 -235.431258) (xy 370.858034 -235.427275) (xy 370.911184 -235.431258)
			(xy 370.963146 -235.443118) (xy 371.01276 -235.46259) (xy 371.058918 -235.489239) (xy 371.100589 -235.52247)
			(xy 371.136841 -235.561541) (xy 371.166865 -235.605578) (xy 371.189991 -235.653599) (xy 371.205701 -235.704529)
			(xy 371.213644 -235.757233) (xy 371.214142 -235.783882) (xy 371.213644 -235.810531) (xy 371.442224 -235.810531)
			(xy 371.442224 -235.757233) (xy 371.450167 -235.704529) (xy 371.465877 -235.653599) (xy 371.489003 -235.605578)
			(xy 371.519027 -235.561541) (xy 371.555279 -235.52247) (xy 371.59695 -235.489239) (xy 371.643108 -235.46259)
			(xy 371.692722 -235.443118) (xy 371.744684 -235.431258) (xy 371.797834 -235.427275) (xy 371.850984 -235.431258)
			(xy 371.902946 -235.443118) (xy 371.95256 -235.46259) (xy 371.998718 -235.489239) (xy 372.040389 -235.52247)
			(xy 372.076641 -235.561541) (xy 372.106665 -235.605578) (xy 372.129791 -235.653599) (xy 372.145501 -235.704529)
			(xy 372.153444 -235.757233) (xy 372.153942 -235.783882) (xy 372.153444 -235.810531) (xy 372.382024 -235.810531)
			(xy 372.382024 -235.757233) (xy 372.389967 -235.704529) (xy 372.405677 -235.653599) (xy 372.428803 -235.605578)
			(xy 372.458827 -235.561541) (xy 372.495079 -235.52247) (xy 372.53675 -235.489239) (xy 372.582908 -235.46259)
			(xy 372.632522 -235.443118) (xy 372.684484 -235.431258) (xy 372.737634 -235.427275) (xy 372.790784 -235.431258)
			(xy 372.842746 -235.443118) (xy 372.89236 -235.46259) (xy 372.938518 -235.489239) (xy 372.980189 -235.52247)
			(xy 373.016441 -235.561541) (xy 373.046465 -235.605578) (xy 373.069591 -235.653599) (xy 373.085301 -235.704529)
			(xy 373.093244 -235.757233) (xy 373.093742 -235.783882) (xy 373.093244 -235.810531) (xy 373.32157 -235.810531)
			(xy 373.32157 -235.757233) (xy 373.329513 -235.704529) (xy 373.345223 -235.653599) (xy 373.368349 -235.605578)
			(xy 373.398373 -235.561541) (xy 373.434625 -235.52247) (xy 373.476296 -235.489239) (xy 373.522454 -235.46259)
			(xy 373.572068 -235.443118) (xy 373.62403 -235.431258) (xy 373.67718 -235.427275) (xy 373.73033 -235.431258)
			(xy 373.782292 -235.443118) (xy 373.831906 -235.46259) (xy 373.878064 -235.489239) (xy 373.919735 -235.52247)
			(xy 373.955987 -235.561541) (xy 373.986011 -235.605578) (xy 374.009137 -235.653599) (xy 374.024847 -235.704529)
			(xy 374.03279 -235.757233) (xy 374.033288 -235.783882) (xy 374.03279 -235.810531) (xy 374.261624 -235.810531)
			(xy 374.261624 -235.757233) (xy 374.269567 -235.704529) (xy 374.285277 -235.653599) (xy 374.308403 -235.605578)
			(xy 374.338427 -235.561541) (xy 374.374679 -235.52247) (xy 374.41635 -235.489239) (xy 374.462508 -235.46259)
			(xy 374.512122 -235.443118) (xy 374.564084 -235.431258) (xy 374.617234 -235.427275) (xy 374.670384 -235.431258)
			(xy 374.722346 -235.443118) (xy 374.77196 -235.46259) (xy 374.818118 -235.489239) (xy 374.859789 -235.52247)
			(xy 374.896041 -235.561541) (xy 374.926065 -235.605578) (xy 374.949191 -235.653599) (xy 374.964901 -235.704529)
			(xy 374.972844 -235.757233) (xy 374.973342 -235.783882) (xy 374.972844 -235.810531) (xy 375.201424 -235.810531)
			(xy 375.201424 -235.757233) (xy 375.209367 -235.704529) (xy 375.225077 -235.653599) (xy 375.248203 -235.605578)
			(xy 375.278227 -235.561541) (xy 375.314479 -235.52247) (xy 375.35615 -235.489239) (xy 375.402308 -235.46259)
			(xy 375.451922 -235.443118) (xy 375.503884 -235.431258) (xy 375.557034 -235.427275) (xy 375.610184 -235.431258)
			(xy 375.662146 -235.443118) (xy 375.71176 -235.46259) (xy 375.757918 -235.489239) (xy 375.799589 -235.52247)
			(xy 375.835841 -235.561541) (xy 375.865865 -235.605578) (xy 375.888991 -235.653599) (xy 375.904701 -235.704529)
			(xy 375.912644 -235.757233) (xy 375.913142 -235.783882) (xy 375.912644 -235.810531) (xy 376.141224 -235.810531)
			(xy 376.141224 -235.757233) (xy 376.149167 -235.704529) (xy 376.164877 -235.653599) (xy 376.188003 -235.605578)
			(xy 376.218027 -235.561541) (xy 376.254279 -235.52247) (xy 376.29595 -235.489239) (xy 376.342108 -235.46259)
			(xy 376.391722 -235.443118) (xy 376.443684 -235.431258) (xy 376.496834 -235.427275) (xy 376.549984 -235.431258)
			(xy 376.601946 -235.443118) (xy 376.65156 -235.46259) (xy 376.697718 -235.489239) (xy 376.739389 -235.52247)
			(xy 376.775641 -235.561541) (xy 376.805665 -235.605578) (xy 376.828791 -235.653599) (xy 376.844501 -235.704529)
			(xy 376.852444 -235.757233) (xy 376.852942 -235.783882) (xy 376.852444 -235.810531) (xy 377.081024 -235.810531)
			(xy 377.081024 -235.757233) (xy 377.088967 -235.704529) (xy 377.104677 -235.653599) (xy 377.127803 -235.605578)
			(xy 377.157827 -235.561541) (xy 377.194079 -235.52247) (xy 377.23575 -235.489239) (xy 377.281908 -235.46259)
			(xy 377.331522 -235.443118) (xy 377.383484 -235.431258) (xy 377.436634 -235.427275) (xy 377.489784 -235.431258)
			(xy 377.541746 -235.443118) (xy 377.59136 -235.46259) (xy 377.637518 -235.489239) (xy 377.679189 -235.52247)
			(xy 377.715441 -235.561541) (xy 377.745465 -235.605578) (xy 377.768591 -235.653599) (xy 377.784301 -235.704529)
			(xy 377.792244 -235.757233) (xy 377.792742 -235.783882) (xy 377.792244 -235.810531) (xy 378.020824 -235.810531)
			(xy 378.020824 -235.757233) (xy 378.028767 -235.704529) (xy 378.044477 -235.653599) (xy 378.067603 -235.605578)
			(xy 378.097627 -235.561541) (xy 378.133879 -235.52247) (xy 378.17555 -235.489239) (xy 378.221708 -235.46259)
			(xy 378.271322 -235.443118) (xy 378.323284 -235.431258) (xy 378.376434 -235.427275) (xy 378.429584 -235.431258)
			(xy 378.481546 -235.443118) (xy 378.53116 -235.46259) (xy 378.577318 -235.489239) (xy 378.618989 -235.52247)
			(xy 378.655241 -235.561541) (xy 378.685265 -235.605578) (xy 378.708391 -235.653599) (xy 378.724101 -235.704529)
			(xy 378.732044 -235.757233) (xy 378.732542 -235.783882) (xy 378.732044 -235.810531) (xy 378.960624 -235.810531)
			(xy 378.960624 -235.757233) (xy 378.968567 -235.704529) (xy 378.984277 -235.653599) (xy 379.007403 -235.605578)
			(xy 379.037427 -235.561541) (xy 379.073679 -235.52247) (xy 379.11535 -235.489239) (xy 379.161508 -235.46259)
			(xy 379.211122 -235.443118) (xy 379.263084 -235.431258) (xy 379.316234 -235.427275) (xy 379.369384 -235.431258)
			(xy 379.421346 -235.443118) (xy 379.47096 -235.46259) (xy 379.517118 -235.489239) (xy 379.558789 -235.52247)
			(xy 379.595041 -235.561541) (xy 379.625065 -235.605578) (xy 379.648191 -235.653599) (xy 379.663901 -235.704529)
			(xy 379.671844 -235.757233) (xy 379.672342 -235.783882) (xy 379.671844 -235.810531) (xy 379.90017 -235.810531)
			(xy 379.90017 -235.757233) (xy 379.908113 -235.704529) (xy 379.923823 -235.653599) (xy 379.946949 -235.605578)
			(xy 379.976973 -235.561541) (xy 380.013225 -235.52247) (xy 380.054896 -235.489239) (xy 380.101054 -235.46259)
			(xy 380.150668 -235.443118) (xy 380.20263 -235.431258) (xy 380.25578 -235.427275) (xy 380.30893 -235.431258)
			(xy 380.360892 -235.443118) (xy 380.410506 -235.46259) (xy 380.456664 -235.489239) (xy 380.498335 -235.52247)
			(xy 380.534587 -235.561541) (xy 380.564611 -235.605578) (xy 380.587737 -235.653599) (xy 380.603447 -235.704529)
			(xy 380.61139 -235.757233) (xy 380.611888 -235.783882) (xy 380.61139 -235.810531) (xy 380.840224 -235.810531)
			(xy 380.840224 -235.757233) (xy 380.848167 -235.704529) (xy 380.863877 -235.653599) (xy 380.887003 -235.605578)
			(xy 380.917027 -235.561541) (xy 380.953279 -235.52247) (xy 380.99495 -235.489239) (xy 381.041108 -235.46259)
			(xy 381.090722 -235.443118) (xy 381.142684 -235.431258) (xy 381.195834 -235.427275) (xy 381.248984 -235.431258)
			(xy 381.300946 -235.443118) (xy 381.35056 -235.46259) (xy 381.396718 -235.489239) (xy 381.438389 -235.52247)
			(xy 381.474641 -235.561541) (xy 381.504665 -235.605578) (xy 381.527791 -235.653599) (xy 381.543501 -235.704529)
			(xy 381.551444 -235.757233) (xy 381.551942 -235.783882) (xy 381.551444 -235.810531) (xy 381.543501 -235.863235)
			(xy 381.527791 -235.914165) (xy 381.504665 -235.962186) (xy 381.474641 -236.006223) (xy 381.438389 -236.045294)
			(xy 381.396718 -236.078525) (xy 381.35056 -236.105174) (xy 381.300946 -236.124646) (xy 381.248984 -236.136506)
			(xy 381.195834 -236.14049) (xy 381.142684 -236.136506) (xy 381.090722 -236.124646) (xy 381.041108 -236.105174)
			(xy 380.99495 -236.078525) (xy 380.953279 -236.045294) (xy 380.917027 -236.006223) (xy 380.887003 -235.962186)
			(xy 380.863877 -235.914165) (xy 380.848167 -235.863235) (xy 380.840224 -235.810531) (xy 380.61139 -235.810531)
			(xy 380.603447 -235.863235) (xy 380.587737 -235.914165) (xy 380.564611 -235.962186) (xy 380.534587 -236.006223)
			(xy 380.498335 -236.045294) (xy 380.456664 -236.078525) (xy 380.410506 -236.105174) (xy 380.360892 -236.124646)
			(xy 380.30893 -236.136506) (xy 380.25578 -236.14049) (xy 380.20263 -236.136506) (xy 380.150668 -236.124646)
			(xy 380.101054 -236.105174) (xy 380.054896 -236.078525) (xy 380.013225 -236.045294) (xy 379.976973 -236.006223)
			(xy 379.946949 -235.962186) (xy 379.923823 -235.914165) (xy 379.908113 -235.863235) (xy 379.90017 -235.810531)
			(xy 379.671844 -235.810531) (xy 379.663901 -235.863235) (xy 379.648191 -235.914165) (xy 379.625065 -235.962186)
			(xy 379.595041 -236.006223) (xy 379.558789 -236.045294) (xy 379.517118 -236.078525) (xy 379.47096 -236.105174)
			(xy 379.421346 -236.124646) (xy 379.369384 -236.136506) (xy 379.316234 -236.14049) (xy 379.263084 -236.136506)
			(xy 379.211122 -236.124646) (xy 379.161508 -236.105174) (xy 379.11535 -236.078525) (xy 379.073679 -236.045294)
			(xy 379.037427 -236.006223) (xy 379.007403 -235.962186) (xy 378.984277 -235.914165) (xy 378.968567 -235.863235)
			(xy 378.960624 -235.810531) (xy 378.732044 -235.810531) (xy 378.724101 -235.863235) (xy 378.708391 -235.914165)
			(xy 378.685265 -235.962186) (xy 378.655241 -236.006223) (xy 378.618989 -236.045294) (xy 378.577318 -236.078525)
			(xy 378.53116 -236.105174) (xy 378.481546 -236.124646) (xy 378.429584 -236.136506) (xy 378.376434 -236.14049)
			(xy 378.323284 -236.136506) (xy 378.271322 -236.124646) (xy 378.221708 -236.105174) (xy 378.17555 -236.078525)
			(xy 378.133879 -236.045294) (xy 378.097627 -236.006223) (xy 378.067603 -235.962186) (xy 378.044477 -235.914165)
			(xy 378.028767 -235.863235) (xy 378.020824 -235.810531) (xy 377.792244 -235.810531) (xy 377.784301 -235.863235)
			(xy 377.768591 -235.914165) (xy 377.745465 -235.962186) (xy 377.715441 -236.006223) (xy 377.679189 -236.045294)
			(xy 377.637518 -236.078525) (xy 377.59136 -236.105174) (xy 377.541746 -236.124646) (xy 377.489784 -236.136506)
			(xy 377.436634 -236.14049) (xy 377.383484 -236.136506) (xy 377.331522 -236.124646) (xy 377.281908 -236.105174)
			(xy 377.23575 -236.078525) (xy 377.194079 -236.045294) (xy 377.157827 -236.006223) (xy 377.127803 -235.962186)
			(xy 377.104677 -235.914165) (xy 377.088967 -235.863235) (xy 377.081024 -235.810531) (xy 376.852444 -235.810531)
			(xy 376.844501 -235.863235) (xy 376.828791 -235.914165) (xy 376.805665 -235.962186) (xy 376.775641 -236.006223)
			(xy 376.739389 -236.045294) (xy 376.697718 -236.078525) (xy 376.65156 -236.105174) (xy 376.601946 -236.124646)
			(xy 376.549984 -236.136506) (xy 376.496834 -236.14049) (xy 376.443684 -236.136506) (xy 376.391722 -236.124646)
			(xy 376.342108 -236.105174) (xy 376.29595 -236.078525) (xy 376.254279 -236.045294) (xy 376.218027 -236.006223)
			(xy 376.188003 -235.962186) (xy 376.164877 -235.914165) (xy 376.149167 -235.863235) (xy 376.141224 -235.810531)
			(xy 375.912644 -235.810531) (xy 375.904701 -235.863235) (xy 375.888991 -235.914165) (xy 375.865865 -235.962186)
			(xy 375.835841 -236.006223) (xy 375.799589 -236.045294) (xy 375.757918 -236.078525) (xy 375.71176 -236.105174)
			(xy 375.662146 -236.124646) (xy 375.610184 -236.136506) (xy 375.557034 -236.14049) (xy 375.503884 -236.136506)
			(xy 375.451922 -236.124646) (xy 375.402308 -236.105174) (xy 375.35615 -236.078525) (xy 375.314479 -236.045294)
			(xy 375.278227 -236.006223) (xy 375.248203 -235.962186) (xy 375.225077 -235.914165) (xy 375.209367 -235.863235)
			(xy 375.201424 -235.810531) (xy 374.972844 -235.810531) (xy 374.964901 -235.863235) (xy 374.949191 -235.914165)
			(xy 374.926065 -235.962186) (xy 374.896041 -236.006223) (xy 374.859789 -236.045294) (xy 374.818118 -236.078525)
			(xy 374.77196 -236.105174) (xy 374.722346 -236.124646) (xy 374.670384 -236.136506) (xy 374.617234 -236.14049)
			(xy 374.564084 -236.136506) (xy 374.512122 -236.124646) (xy 374.462508 -236.105174) (xy 374.41635 -236.078525)
			(xy 374.374679 -236.045294) (xy 374.338427 -236.006223) (xy 374.308403 -235.962186) (xy 374.285277 -235.914165)
			(xy 374.269567 -235.863235) (xy 374.261624 -235.810531) (xy 374.03279 -235.810531) (xy 374.024847 -235.863235)
			(xy 374.009137 -235.914165) (xy 373.986011 -235.962186) (xy 373.955987 -236.006223) (xy 373.919735 -236.045294)
			(xy 373.878064 -236.078525) (xy 373.831906 -236.105174) (xy 373.782292 -236.124646) (xy 373.73033 -236.136506)
			(xy 373.67718 -236.14049) (xy 373.62403 -236.136506) (xy 373.572068 -236.124646) (xy 373.522454 -236.105174)
			(xy 373.476296 -236.078525) (xy 373.434625 -236.045294) (xy 373.398373 -236.006223) (xy 373.368349 -235.962186)
			(xy 373.345223 -235.914165) (xy 373.329513 -235.863235) (xy 373.32157 -235.810531) (xy 373.093244 -235.810531)
			(xy 373.085301 -235.863235) (xy 373.069591 -235.914165) (xy 373.046465 -235.962186) (xy 373.016441 -236.006223)
			(xy 372.980189 -236.045294) (xy 372.938518 -236.078525) (xy 372.89236 -236.105174) (xy 372.842746 -236.124646)
			(xy 372.790784 -236.136506) (xy 372.737634 -236.14049) (xy 372.684484 -236.136506) (xy 372.632522 -236.124646)
			(xy 372.582908 -236.105174) (xy 372.53675 -236.078525) (xy 372.495079 -236.045294) (xy 372.458827 -236.006223)
			(xy 372.428803 -235.962186) (xy 372.405677 -235.914165) (xy 372.389967 -235.863235) (xy 372.382024 -235.810531)
			(xy 372.153444 -235.810531) (xy 372.145501 -235.863235) (xy 372.129791 -235.914165) (xy 372.106665 -235.962186)
			(xy 372.076641 -236.006223) (xy 372.040389 -236.045294) (xy 371.998718 -236.078525) (xy 371.95256 -236.105174)
			(xy 371.902946 -236.124646) (xy 371.850984 -236.136506) (xy 371.797834 -236.14049) (xy 371.744684 -236.136506)
			(xy 371.692722 -236.124646) (xy 371.643108 -236.105174) (xy 371.59695 -236.078525) (xy 371.555279 -236.045294)
			(xy 371.519027 -236.006223) (xy 371.489003 -235.962186) (xy 371.465877 -235.914165) (xy 371.450167 -235.863235)
			(xy 371.442224 -235.810531) (xy 371.213644 -235.810531) (xy 371.205701 -235.863235) (xy 371.189991 -235.914165)
			(xy 371.166865 -235.962186) (xy 371.136841 -236.006223) (xy 371.100589 -236.045294) (xy 371.058918 -236.078525)
			(xy 371.01276 -236.105174) (xy 370.963146 -236.124646) (xy 370.911184 -236.136506) (xy 370.858034 -236.14049)
			(xy 370.804884 -236.136506) (xy 370.752922 -236.124646) (xy 370.703308 -236.105174) (xy 370.65715 -236.078525)
			(xy 370.615479 -236.045294) (xy 370.579227 -236.006223) (xy 370.549203 -235.962186) (xy 370.526077 -235.914165)
			(xy 370.510367 -235.863235) (xy 370.502424 -235.810531) (xy 370.273844 -235.810531) (xy 370.265901 -235.863235)
			(xy 370.250191 -235.914165) (xy 370.227065 -235.962186) (xy 370.197041 -236.006223) (xy 370.160789 -236.045294)
			(xy 370.119118 -236.078525) (xy 370.07296 -236.105174) (xy 370.023346 -236.124646) (xy 369.971384 -236.136506)
			(xy 369.918234 -236.14049) (xy 369.865084 -236.136506) (xy 369.813122 -236.124646) (xy 369.763508 -236.105174)
			(xy 369.71735 -236.078525) (xy 369.675679 -236.045294) (xy 369.639427 -236.006223) (xy 369.609403 -235.962186)
			(xy 369.586277 -235.914165) (xy 369.570567 -235.863235) (xy 369.562624 -235.810531) (xy 362.755444 -235.810531)
			(xy 362.747501 -235.863235) (xy 362.731791 -235.914165) (xy 362.708665 -235.962186) (xy 362.678641 -236.006223)
			(xy 362.642389 -236.045294) (xy 362.600718 -236.078525) (xy 362.55456 -236.105174) (xy 362.504946 -236.124646)
			(xy 362.452984 -236.136506) (xy 362.399834 -236.14049) (xy 362.346684 -236.136506) (xy 362.294722 -236.124646)
			(xy 362.245108 -236.105174) (xy 362.19895 -236.078525) (xy 362.157279 -236.045294) (xy 362.121027 -236.006223)
			(xy 362.091003 -235.962186) (xy 362.067877 -235.914165) (xy 362.052167 -235.863235) (xy 362.044224 -235.810531)
			(xy 361.815644 -235.810531) (xy 361.807701 -235.863235) (xy 361.791991 -235.914165) (xy 361.768865 -235.962186)
			(xy 361.738841 -236.006223) (xy 361.702589 -236.045294) (xy 361.660918 -236.078525) (xy 361.61476 -236.105174)
			(xy 361.565146 -236.124646) (xy 361.513184 -236.136506) (xy 361.460034 -236.14049) (xy 361.406884 -236.136506)
			(xy 361.354922 -236.124646) (xy 361.305308 -236.105174) (xy 361.25915 -236.078525) (xy 361.217479 -236.045294)
			(xy 361.181227 -236.006223) (xy 361.151203 -235.962186) (xy 361.128077 -235.914165) (xy 361.112367 -235.863235)
			(xy 361.104424 -235.810531) (xy 360.875844 -235.810531) (xy 360.867901 -235.863235) (xy 360.852191 -235.914165)
			(xy 360.829065 -235.962186) (xy 360.799041 -236.006223) (xy 360.762789 -236.045294) (xy 360.721118 -236.078525)
			(xy 360.67496 -236.105174) (xy 360.625346 -236.124646) (xy 360.573384 -236.136506) (xy 360.520234 -236.14049)
			(xy 360.467084 -236.136506) (xy 360.415122 -236.124646) (xy 360.365508 -236.105174) (xy 360.31935 -236.078525)
			(xy 360.277679 -236.045294) (xy 360.241427 -236.006223) (xy 360.211403 -235.962186) (xy 360.188277 -235.914165)
			(xy 360.172567 -235.863235) (xy 360.164624 -235.810531) (xy 359.936044 -235.810531) (xy 359.928101 -235.863235)
			(xy 359.912391 -235.914165) (xy 359.889265 -235.962186) (xy 359.859241 -236.006223) (xy 359.822989 -236.045294)
			(xy 359.781318 -236.078525) (xy 359.73516 -236.105174) (xy 359.685546 -236.124646) (xy 359.633584 -236.136506)
			(xy 359.580434 -236.14049) (xy 359.527284 -236.136506) (xy 359.475322 -236.124646) (xy 359.425708 -236.105174)
			(xy 359.37955 -236.078525) (xy 359.337879 -236.045294) (xy 359.301627 -236.006223) (xy 359.271603 -235.962186)
			(xy 359.248477 -235.914165) (xy 359.232767 -235.863235) (xy 359.224824 -235.810531) (xy 358.996244 -235.810531)
			(xy 358.988301 -235.863235) (xy 358.972591 -235.914165) (xy 358.949465 -235.962186) (xy 358.919441 -236.006223)
			(xy 358.883189 -236.045294) (xy 358.841518 -236.078525) (xy 358.79536 -236.105174) (xy 358.745746 -236.124646)
			(xy 358.693784 -236.136506) (xy 358.640634 -236.14049) (xy 358.587484 -236.136506) (xy 358.535522 -236.124646)
			(xy 358.485908 -236.105174) (xy 358.43975 -236.078525) (xy 358.398079 -236.045294) (xy 358.361827 -236.006223)
			(xy 358.331803 -235.962186) (xy 358.308677 -235.914165) (xy 358.292967 -235.863235) (xy 358.285024 -235.810531)
			(xy 358.056444 -235.810531) (xy 358.048501 -235.863235) (xy 358.032791 -235.914165) (xy 358.009665 -235.962186)
			(xy 357.979641 -236.006223) (xy 357.943389 -236.045294) (xy 357.901718 -236.078525) (xy 357.85556 -236.105174)
			(xy 357.805946 -236.124646) (xy 357.753984 -236.136506) (xy 357.700834 -236.14049) (xy 357.647684 -236.136506)
			(xy 357.595722 -236.124646) (xy 357.546108 -236.105174) (xy 357.49995 -236.078525) (xy 357.458279 -236.045294)
			(xy 357.422027 -236.006223) (xy 357.392003 -235.962186) (xy 357.368877 -235.914165) (xy 357.353167 -235.863235)
			(xy 357.345224 -235.810531) (xy 356.291693 -235.810531) (xy 356.292573 -235.811979) (xy 356.302818 -235.821982)
			(xy 356.320581 -235.838905) (xy 356.351757 -235.876786) (xy 356.377439 -235.918588) (xy 356.39714 -235.96352)
			(xy 356.410487 -236.01073) (xy 356.417227 -236.059326) (xy 356.417626 -236.083856) (xy 356.417626 -236.084364)
			(xy 356.416985 -236.114349) (xy 356.406897 -236.173465) (xy 356.39756 -236.201966) (xy 356.393397 -236.215207)
			(xy 356.391573 -236.242892) (xy 356.39727 -236.270045) (xy 356.410069 -236.294661) (xy 356.429023 -236.314922)
			(xy 356.452732 -236.329331) (xy 356.479446 -236.336823) (xy 356.493318 -236.337348) (xy 356.98811 -236.337348)
			(xy 357.007974 -236.319494) (xy 357.052053 -236.289335) (xy 357.100144 -236.266103) (xy 357.151167 -236.250318)
			(xy 357.203976 -236.242336) (xy 357.257384 -236.242336) (xy 357.310193 -236.250318) (xy 357.361216 -236.266103)
			(xy 357.409307 -236.289335) (xy 357.453386 -236.319494) (xy 357.47325 -236.337348) (xy 357.928164 -236.337348)
			(xy 357.948028 -236.319494) (xy 357.992107 -236.289335) (xy 358.040198 -236.266103) (xy 358.091221 -236.250318)
			(xy 358.14403 -236.242336) (xy 358.197438 -236.242336) (xy 358.250247 -236.250318) (xy 358.30127 -236.266103)
			(xy 358.349361 -236.289335) (xy 358.39344 -236.319494) (xy 358.413304 -236.337348) (xy 358.86771 -236.337348)
			(xy 358.887574 -236.319494) (xy 358.931653 -236.289335) (xy 358.979744 -236.266103) (xy 359.030767 -236.250318)
			(xy 359.083576 -236.242336) (xy 359.136984 -236.242336) (xy 359.189793 -236.250318) (xy 359.240816 -236.266103)
			(xy 359.288907 -236.289335) (xy 359.332986 -236.319494) (xy 359.35285 -236.337348) (xy 359.80751 -236.337348)
			(xy 359.827374 -236.319494) (xy 359.871453 -236.289335) (xy 359.919544 -236.266103) (xy 359.970567 -236.250318)
			(xy 360.023376 -236.242336) (xy 360.076784 -236.242336) (xy 360.129593 -236.250318) (xy 360.180616 -236.266103)
			(xy 360.228707 -236.289335) (xy 360.272786 -236.319494) (xy 360.29265 -236.337348) (xy 360.74731 -236.337348)
			(xy 360.767174 -236.319494) (xy 360.811253 -236.289335) (xy 360.859344 -236.266103) (xy 360.910367 -236.250318)
			(xy 360.963176 -236.242336) (xy 361.016584 -236.242336) (xy 361.069393 -236.250318) (xy 361.120416 -236.266103)
			(xy 361.168507 -236.289335) (xy 361.212586 -236.319494) (xy 361.23245 -236.337348) (xy 361.687364 -236.337348)
			(xy 361.707228 -236.319494) (xy 361.751307 -236.289335) (xy 361.799398 -236.266103) (xy 361.850421 -236.250318)
			(xy 361.90323 -236.242336) (xy 361.956638 -236.242336) (xy 362.009447 -236.250318) (xy 362.06047 -236.266103)
			(xy 362.108561 -236.289335) (xy 362.15264 -236.319494) (xy 362.172504 -236.337348) (xy 363.008164 -236.337348)
			(xy 363.025153 -236.317597) (xy 363.06392 -236.282794) (xy 363.107346 -236.254015) (xy 363.154505 -236.231874)
			(xy 363.204387 -236.216846) (xy 363.255927 -236.20925) (xy 363.308025 -236.20925) (xy 363.359565 -236.216846)
			(xy 363.409447 -236.231874) (xy 363.451675 -236.2517) (xy 368.559618 -236.2517) (xy 368.563601 -236.198554)
			(xy 368.57546 -236.146595) (xy 368.594931 -236.096984) (xy 368.621579 -236.050829) (xy 368.654808 -236.009161)
			(xy 368.693877 -235.972912) (xy 368.737911 -235.94289) (xy 368.785929 -235.919766) (xy 368.836856 -235.904057)
			(xy 368.889556 -235.896115) (xy 368.916204 -235.895642) (xy 368.942799 -235.896074) (xy 368.995396 -235.903986)
			(xy 369.046232 -235.919633) (xy 369.094176 -235.942667) (xy 369.13816 -235.972575) (xy 369.177207 -236.008693)
			(xy 369.210447 -236.050216) (xy 369.237142 -236.096222) (xy 369.256697 -236.145686) (xy 369.263168 -236.171486)
			(xy 369.267197 -236.186575) (xy 369.283088 -236.213444) (xy 369.306362 -236.234249) (xy 369.334838 -236.24704)
			(xy 369.365849 -236.250619) (xy 369.381278 -236.248194) (xy 369.397757 -236.245241) (xy 369.431086 -236.242065)
			(xy 369.447826 -236.241844) (xy 369.448588 -236.241844) (xy 369.475236 -236.242412) (xy 369.527937 -236.250354)
			(xy 369.578866 -236.266062) (xy 369.626885 -236.289185) (xy 369.670921 -236.319207) (xy 369.709991 -236.355457)
			(xy 369.743221 -236.397125) (xy 369.76987 -236.443281) (xy 369.789341 -236.492893) (xy 369.801201 -236.544853)
			(xy 369.805184 -236.598) (xy 369.80319 -236.624601) (xy 370.03227 -236.624601) (xy 370.03227 -236.571303)
			(xy 370.040213 -236.518599) (xy 370.055923 -236.467669) (xy 370.079049 -236.419648) (xy 370.109073 -236.375611)
			(xy 370.145325 -236.33654) (xy 370.186996 -236.303309) (xy 370.233154 -236.27666) (xy 370.282768 -236.257188)
			(xy 370.33473 -236.245328) (xy 370.38788 -236.241345) (xy 370.44103 -236.245328) (xy 370.492992 -236.257188)
			(xy 370.542606 -236.27666) (xy 370.588764 -236.303309) (xy 370.630435 -236.33654) (xy 370.666687 -236.375611)
			(xy 370.696711 -236.419648) (xy 370.719837 -236.467669) (xy 370.735547 -236.518599) (xy 370.74349 -236.571303)
			(xy 370.743988 -236.597952) (xy 370.74349 -236.624601) (xy 370.97207 -236.624601) (xy 370.97207 -236.571303)
			(xy 370.980013 -236.518599) (xy 370.995723 -236.467669) (xy 371.018849 -236.419648) (xy 371.048873 -236.375611)
			(xy 371.085125 -236.33654) (xy 371.126796 -236.303309) (xy 371.172954 -236.27666) (xy 371.222568 -236.257188)
			(xy 371.27453 -236.245328) (xy 371.32768 -236.241345) (xy 371.38083 -236.245328) (xy 371.432792 -236.257188)
			(xy 371.482406 -236.27666) (xy 371.528564 -236.303309) (xy 371.570235 -236.33654) (xy 371.606487 -236.375611)
			(xy 371.636511 -236.419648) (xy 371.659637 -236.467669) (xy 371.675347 -236.518599) (xy 371.68329 -236.571303)
			(xy 371.683788 -236.597952) (xy 371.68329 -236.624601) (xy 371.91187 -236.624601) (xy 371.91187 -236.571303)
			(xy 371.919813 -236.518599) (xy 371.935523 -236.467669) (xy 371.958649 -236.419648) (xy 371.988673 -236.375611)
			(xy 372.024925 -236.33654) (xy 372.066596 -236.303309) (xy 372.112754 -236.27666) (xy 372.162368 -236.257188)
			(xy 372.21433 -236.245328) (xy 372.26748 -236.241345) (xy 372.32063 -236.245328) (xy 372.372592 -236.257188)
			(xy 372.422206 -236.27666) (xy 372.468364 -236.303309) (xy 372.510035 -236.33654) (xy 372.546287 -236.375611)
			(xy 372.576311 -236.419648) (xy 372.599437 -236.467669) (xy 372.615147 -236.518599) (xy 372.62309 -236.571303)
			(xy 372.623588 -236.597952) (xy 372.62309 -236.624601) (xy 372.85167 -236.624601) (xy 372.85167 -236.571303)
			(xy 372.859613 -236.518599) (xy 372.875323 -236.467669) (xy 372.898449 -236.419648) (xy 372.928473 -236.375611)
			(xy 372.964725 -236.33654) (xy 373.006396 -236.303309) (xy 373.052554 -236.27666) (xy 373.102168 -236.257188)
			(xy 373.15413 -236.245328) (xy 373.20728 -236.241345) (xy 373.26043 -236.245328) (xy 373.312392 -236.257188)
			(xy 373.362006 -236.27666) (xy 373.408164 -236.303309) (xy 373.449835 -236.33654) (xy 373.486087 -236.375611)
			(xy 373.516111 -236.419648) (xy 373.539237 -236.467669) (xy 373.554947 -236.518599) (xy 373.56289 -236.571303)
			(xy 373.563388 -236.597952) (xy 373.56289 -236.624601) (xy 373.79147 -236.624601) (xy 373.79147 -236.571303)
			(xy 373.799413 -236.518599) (xy 373.815123 -236.467669) (xy 373.838249 -236.419648) (xy 373.868273 -236.375611)
			(xy 373.904525 -236.33654) (xy 373.946196 -236.303309) (xy 373.992354 -236.27666) (xy 374.041968 -236.257188)
			(xy 374.09393 -236.245328) (xy 374.14708 -236.241345) (xy 374.20023 -236.245328) (xy 374.252192 -236.257188)
			(xy 374.301806 -236.27666) (xy 374.347964 -236.303309) (xy 374.389635 -236.33654) (xy 374.425887 -236.375611)
			(xy 374.455911 -236.419648) (xy 374.479037 -236.467669) (xy 374.494747 -236.518599) (xy 374.50269 -236.571303)
			(xy 374.503188 -236.597952) (xy 374.50269 -236.624601) (xy 374.73127 -236.624601) (xy 374.73127 -236.571303)
			(xy 374.739213 -236.518599) (xy 374.754923 -236.467669) (xy 374.778049 -236.419648) (xy 374.808073 -236.375611)
			(xy 374.844325 -236.33654) (xy 374.885996 -236.303309) (xy 374.932154 -236.27666) (xy 374.981768 -236.257188)
			(xy 375.03373 -236.245328) (xy 375.08688 -236.241345) (xy 375.14003 -236.245328) (xy 375.191992 -236.257188)
			(xy 375.241606 -236.27666) (xy 375.287764 -236.303309) (xy 375.329435 -236.33654) (xy 375.365687 -236.375611)
			(xy 375.395711 -236.419648) (xy 375.418837 -236.467669) (xy 375.434547 -236.518599) (xy 375.44249 -236.571303)
			(xy 375.442988 -236.597952) (xy 375.44249 -236.624601) (xy 375.67107 -236.624601) (xy 375.67107 -236.571303)
			(xy 375.679013 -236.518599) (xy 375.694723 -236.467669) (xy 375.717849 -236.419648) (xy 375.747873 -236.375611)
			(xy 375.784125 -236.33654) (xy 375.825796 -236.303309) (xy 375.871954 -236.27666) (xy 375.921568 -236.257188)
			(xy 375.97353 -236.245328) (xy 376.02668 -236.241345) (xy 376.07983 -236.245328) (xy 376.131792 -236.257188)
			(xy 376.181406 -236.27666) (xy 376.227564 -236.303309) (xy 376.269235 -236.33654) (xy 376.305487 -236.375611)
			(xy 376.335511 -236.419648) (xy 376.358637 -236.467669) (xy 376.374347 -236.518599) (xy 376.38229 -236.571303)
			(xy 376.382788 -236.597952) (xy 376.38229 -236.624601) (xy 376.611124 -236.624601) (xy 376.611124 -236.571303)
			(xy 376.619067 -236.518599) (xy 376.634777 -236.467669) (xy 376.657903 -236.419648) (xy 376.687927 -236.375611)
			(xy 376.724179 -236.33654) (xy 376.76585 -236.303309) (xy 376.812008 -236.27666) (xy 376.861622 -236.257188)
			(xy 376.913584 -236.245328) (xy 376.966734 -236.241345) (xy 377.019884 -236.245328) (xy 377.071846 -236.257188)
			(xy 377.12146 -236.27666) (xy 377.167618 -236.303309) (xy 377.209289 -236.33654) (xy 377.245541 -236.375611)
			(xy 377.275565 -236.419648) (xy 377.298691 -236.467669) (xy 377.314401 -236.518599) (xy 377.322344 -236.571303)
			(xy 377.322842 -236.597952) (xy 377.322344 -236.624601) (xy 377.55067 -236.624601) (xy 377.55067 -236.571303)
			(xy 377.558613 -236.518599) (xy 377.574323 -236.467669) (xy 377.597449 -236.419648) (xy 377.627473 -236.375611)
			(xy 377.663725 -236.33654) (xy 377.705396 -236.303309) (xy 377.751554 -236.27666) (xy 377.801168 -236.257188)
			(xy 377.85313 -236.245328) (xy 377.90628 -236.241345) (xy 377.95943 -236.245328) (xy 378.011392 -236.257188)
			(xy 378.061006 -236.27666) (xy 378.107164 -236.303309) (xy 378.148835 -236.33654) (xy 378.185087 -236.375611)
			(xy 378.215111 -236.419648) (xy 378.238237 -236.467669) (xy 378.253947 -236.518599) (xy 378.26189 -236.571303)
			(xy 378.262388 -236.597952) (xy 378.26189 -236.624601) (xy 378.49047 -236.624601) (xy 378.49047 -236.571303)
			(xy 378.498413 -236.518599) (xy 378.514123 -236.467669) (xy 378.537249 -236.419648) (xy 378.567273 -236.375611)
			(xy 378.603525 -236.33654) (xy 378.645196 -236.303309) (xy 378.691354 -236.27666) (xy 378.740968 -236.257188)
			(xy 378.79293 -236.245328) (xy 378.84608 -236.241345) (xy 378.89923 -236.245328) (xy 378.951192 -236.257188)
			(xy 379.000806 -236.27666) (xy 379.046964 -236.303309) (xy 379.088635 -236.33654) (xy 379.124887 -236.375611)
			(xy 379.154911 -236.419648) (xy 379.178037 -236.467669) (xy 379.193747 -236.518599) (xy 379.20169 -236.571303)
			(xy 379.202188 -236.597952) (xy 379.20169 -236.624601) (xy 379.43027 -236.624601) (xy 379.43027 -236.571303)
			(xy 379.438213 -236.518599) (xy 379.453923 -236.467669) (xy 379.477049 -236.419648) (xy 379.507073 -236.375611)
			(xy 379.543325 -236.33654) (xy 379.584996 -236.303309) (xy 379.631154 -236.27666) (xy 379.680768 -236.257188)
			(xy 379.73273 -236.245328) (xy 379.78588 -236.241345) (xy 379.83903 -236.245328) (xy 379.890992 -236.257188)
			(xy 379.940606 -236.27666) (xy 379.986764 -236.303309) (xy 380.028435 -236.33654) (xy 380.064687 -236.375611)
			(xy 380.094711 -236.419648) (xy 380.117837 -236.467669) (xy 380.133547 -236.518599) (xy 380.14149 -236.571303)
			(xy 380.141988 -236.597952) (xy 380.14149 -236.624601) (xy 380.37007 -236.624601) (xy 380.37007 -236.571303)
			(xy 380.378013 -236.518599) (xy 380.393723 -236.467669) (xy 380.416849 -236.419648) (xy 380.446873 -236.375611)
			(xy 380.483125 -236.33654) (xy 380.524796 -236.303309) (xy 380.570954 -236.27666) (xy 380.620568 -236.257188)
			(xy 380.67253 -236.245328) (xy 380.72568 -236.241345) (xy 380.77883 -236.245328) (xy 380.830792 -236.257188)
			(xy 380.880406 -236.27666) (xy 380.926564 -236.303309) (xy 380.968235 -236.33654) (xy 381.004487 -236.375611)
			(xy 381.034511 -236.419648) (xy 381.057637 -236.467669) (xy 381.073347 -236.518599) (xy 381.08129 -236.571303)
			(xy 381.081788 -236.597952) (xy 381.08129 -236.624601) (xy 381.073347 -236.677305) (xy 381.057637 -236.728235)
			(xy 381.034511 -236.776256) (xy 381.004487 -236.820293) (xy 380.968235 -236.859364) (xy 380.926564 -236.892595)
			(xy 380.880406 -236.919244) (xy 380.830792 -236.938716) (xy 380.77883 -236.950576) (xy 380.72568 -236.95456)
			(xy 380.67253 -236.950576) (xy 380.620568 -236.938716) (xy 380.570954 -236.919244) (xy 380.524796 -236.892595)
			(xy 380.483125 -236.859364) (xy 380.446873 -236.820293) (xy 380.416849 -236.776256) (xy 380.393723 -236.728235)
			(xy 380.378013 -236.677305) (xy 380.37007 -236.624601) (xy 380.14149 -236.624601) (xy 380.133547 -236.677305)
			(xy 380.117837 -236.728235) (xy 380.094711 -236.776256) (xy 380.064687 -236.820293) (xy 380.028435 -236.859364)
			(xy 379.986764 -236.892595) (xy 379.940606 -236.919244) (xy 379.890992 -236.938716) (xy 379.83903 -236.950576)
			(xy 379.78588 -236.95456) (xy 379.73273 -236.950576) (xy 379.680768 -236.938716) (xy 379.631154 -236.919244)
			(xy 379.584996 -236.892595) (xy 379.543325 -236.859364) (xy 379.507073 -236.820293) (xy 379.477049 -236.776256)
			(xy 379.453923 -236.728235) (xy 379.438213 -236.677305) (xy 379.43027 -236.624601) (xy 379.20169 -236.624601)
			(xy 379.193747 -236.677305) (xy 379.178037 -236.728235) (xy 379.154911 -236.776256) (xy 379.124887 -236.820293)
			(xy 379.088635 -236.859364) (xy 379.046964 -236.892595) (xy 379.000806 -236.919244) (xy 378.951192 -236.938716)
			(xy 378.89923 -236.950576) (xy 378.84608 -236.95456) (xy 378.79293 -236.950576) (xy 378.740968 -236.938716)
			(xy 378.691354 -236.919244) (xy 378.645196 -236.892595) (xy 378.603525 -236.859364) (xy 378.567273 -236.820293)
			(xy 378.537249 -236.776256) (xy 378.514123 -236.728235) (xy 378.498413 -236.677305) (xy 378.49047 -236.624601)
			(xy 378.26189 -236.624601) (xy 378.253947 -236.677305) (xy 378.238237 -236.728235) (xy 378.215111 -236.776256)
			(xy 378.185087 -236.820293) (xy 378.148835 -236.859364) (xy 378.107164 -236.892595) (xy 378.061006 -236.919244)
			(xy 378.011392 -236.938716) (xy 377.95943 -236.950576) (xy 377.90628 -236.95456) (xy 377.85313 -236.950576)
			(xy 377.801168 -236.938716) (xy 377.751554 -236.919244) (xy 377.705396 -236.892595) (xy 377.663725 -236.859364)
			(xy 377.627473 -236.820293) (xy 377.597449 -236.776256) (xy 377.574323 -236.728235) (xy 377.558613 -236.677305)
			(xy 377.55067 -236.624601) (xy 377.322344 -236.624601) (xy 377.314401 -236.677305) (xy 377.298691 -236.728235)
			(xy 377.275565 -236.776256) (xy 377.245541 -236.820293) (xy 377.209289 -236.859364) (xy 377.167618 -236.892595)
			(xy 377.12146 -236.919244) (xy 377.071846 -236.938716) (xy 377.019884 -236.950576) (xy 376.966734 -236.95456)
			(xy 376.913584 -236.950576) (xy 376.861622 -236.938716) (xy 376.812008 -236.919244) (xy 376.76585 -236.892595)
			(xy 376.724179 -236.859364) (xy 376.687927 -236.820293) (xy 376.657903 -236.776256) (xy 376.634777 -236.728235)
			(xy 376.619067 -236.677305) (xy 376.611124 -236.624601) (xy 376.38229 -236.624601) (xy 376.374347 -236.677305)
			(xy 376.358637 -236.728235) (xy 376.335511 -236.776256) (xy 376.305487 -236.820293) (xy 376.269235 -236.859364)
			(xy 376.227564 -236.892595) (xy 376.181406 -236.919244) (xy 376.131792 -236.938716) (xy 376.07983 -236.950576)
			(xy 376.02668 -236.95456) (xy 375.97353 -236.950576) (xy 375.921568 -236.938716) (xy 375.871954 -236.919244)
			(xy 375.825796 -236.892595) (xy 375.784125 -236.859364) (xy 375.747873 -236.820293) (xy 375.717849 -236.776256)
			(xy 375.694723 -236.728235) (xy 375.679013 -236.677305) (xy 375.67107 -236.624601) (xy 375.44249 -236.624601)
			(xy 375.434547 -236.677305) (xy 375.418837 -236.728235) (xy 375.395711 -236.776256) (xy 375.365687 -236.820293)
			(xy 375.329435 -236.859364) (xy 375.287764 -236.892595) (xy 375.241606 -236.919244) (xy 375.191992 -236.938716)
			(xy 375.14003 -236.950576) (xy 375.08688 -236.95456) (xy 375.03373 -236.950576) (xy 374.981768 -236.938716)
			(xy 374.932154 -236.919244) (xy 374.885996 -236.892595) (xy 374.844325 -236.859364) (xy 374.808073 -236.820293)
			(xy 374.778049 -236.776256) (xy 374.754923 -236.728235) (xy 374.739213 -236.677305) (xy 374.73127 -236.624601)
			(xy 374.50269 -236.624601) (xy 374.494747 -236.677305) (xy 374.479037 -236.728235) (xy 374.455911 -236.776256)
			(xy 374.425887 -236.820293) (xy 374.389635 -236.859364) (xy 374.347964 -236.892595) (xy 374.301806 -236.919244)
			(xy 374.252192 -236.938716) (xy 374.20023 -236.950576) (xy 374.14708 -236.95456) (xy 374.09393 -236.950576)
			(xy 374.041968 -236.938716) (xy 373.992354 -236.919244) (xy 373.946196 -236.892595) (xy 373.904525 -236.859364)
			(xy 373.868273 -236.820293) (xy 373.838249 -236.776256) (xy 373.815123 -236.728235) (xy 373.799413 -236.677305)
			(xy 373.79147 -236.624601) (xy 373.56289 -236.624601) (xy 373.554947 -236.677305) (xy 373.539237 -236.728235)
			(xy 373.516111 -236.776256) (xy 373.486087 -236.820293) (xy 373.449835 -236.859364) (xy 373.408164 -236.892595)
			(xy 373.362006 -236.919244) (xy 373.312392 -236.938716) (xy 373.26043 -236.950576) (xy 373.20728 -236.95456)
			(xy 373.15413 -236.950576) (xy 373.102168 -236.938716) (xy 373.052554 -236.919244) (xy 373.006396 -236.892595)
			(xy 372.964725 -236.859364) (xy 372.928473 -236.820293) (xy 372.898449 -236.776256) (xy 372.875323 -236.728235)
			(xy 372.859613 -236.677305) (xy 372.85167 -236.624601) (xy 372.62309 -236.624601) (xy 372.615147 -236.677305)
			(xy 372.599437 -236.728235) (xy 372.576311 -236.776256) (xy 372.546287 -236.820293) (xy 372.510035 -236.859364)
			(xy 372.468364 -236.892595) (xy 372.422206 -236.919244) (xy 372.372592 -236.938716) (xy 372.32063 -236.950576)
			(xy 372.26748 -236.95456) (xy 372.21433 -236.950576) (xy 372.162368 -236.938716) (xy 372.112754 -236.919244)
			(xy 372.066596 -236.892595) (xy 372.024925 -236.859364) (xy 371.988673 -236.820293) (xy 371.958649 -236.776256)
			(xy 371.935523 -236.728235) (xy 371.919813 -236.677305) (xy 371.91187 -236.624601) (xy 371.68329 -236.624601)
			(xy 371.675347 -236.677305) (xy 371.659637 -236.728235) (xy 371.636511 -236.776256) (xy 371.606487 -236.820293)
			(xy 371.570235 -236.859364) (xy 371.528564 -236.892595) (xy 371.482406 -236.919244) (xy 371.432792 -236.938716)
			(xy 371.38083 -236.950576) (xy 371.32768 -236.95456) (xy 371.27453 -236.950576) (xy 371.222568 -236.938716)
			(xy 371.172954 -236.919244) (xy 371.126796 -236.892595) (xy 371.085125 -236.859364) (xy 371.048873 -236.820293)
			(xy 371.018849 -236.776256) (xy 370.995723 -236.728235) (xy 370.980013 -236.677305) (xy 370.97207 -236.624601)
			(xy 370.74349 -236.624601) (xy 370.735547 -236.677305) (xy 370.719837 -236.728235) (xy 370.696711 -236.776256)
			(xy 370.666687 -236.820293) (xy 370.630435 -236.859364) (xy 370.588764 -236.892595) (xy 370.542606 -236.919244)
			(xy 370.492992 -236.938716) (xy 370.44103 -236.950576) (xy 370.38788 -236.95456) (xy 370.33473 -236.950576)
			(xy 370.282768 -236.938716) (xy 370.233154 -236.919244) (xy 370.186996 -236.892595) (xy 370.145325 -236.859364)
			(xy 370.109073 -236.820293) (xy 370.079049 -236.776256) (xy 370.055923 -236.728235) (xy 370.040213 -236.677305)
			(xy 370.03227 -236.624601) (xy 369.80319 -236.624601) (xy 369.801201 -236.651147) (xy 369.789341 -236.703107)
			(xy 369.76987 -236.752719) (xy 369.743221 -236.798875) (xy 369.709991 -236.840543) (xy 369.670921 -236.876793)
			(xy 369.626885 -236.906815) (xy 369.578866 -236.929938) (xy 369.527937 -236.945646) (xy 369.475236 -236.953588)
			(xy 369.448588 -236.95406) (xy 369.421996 -236.953543) (xy 369.369402 -236.945644) (xy 369.318568 -236.93001)
			(xy 369.270625 -236.906988) (xy 369.226641 -236.877091) (xy 369.187593 -236.840983) (xy 369.154351 -236.799468)
			(xy 369.127654 -236.75347) (xy 369.108097 -236.704013) (xy 369.101624 -236.678216) (xy 369.097602 -236.663125)
			(xy 369.08171 -236.636254) (xy 369.058435 -236.615449) (xy 369.029957 -236.602659) (xy 368.998944 -236.599082)
			(xy 368.983514 -236.601508) (xy 368.967033 -236.604448) (xy 368.933705 -236.607633) (xy 368.916966 -236.607858)
			(xy 368.916204 -236.607858) (xy 368.889556 -236.607285) (xy 368.836856 -236.599343) (xy 368.785929 -236.583634)
			(xy 368.737911 -236.56051) (xy 368.693877 -236.530488) (xy 368.654808 -236.494239) (xy 368.621579 -236.452571)
			(xy 368.594931 -236.406416) (xy 368.57546 -236.356805) (xy 368.563601 -236.304846) (xy 368.559618 -236.2517)
			(xy 363.451675 -236.2517) (xy 363.456606 -236.254015) (xy 363.500032 -236.282794) (xy 363.538799 -236.317597)
			(xy 363.555788 -236.337348) (xy 368.00028 -236.337348) (xy 368.76101 -237.098078) (xy 368.79149 -237.086648)
			(xy 368.82159 -237.076125) (xy 368.884325 -237.06476) (xy 368.916204 -237.064042) (xy 368.944188 -237.064591)
			(xy 368.999468 -237.073346) (xy 369.052698 -237.090641) (xy 369.102567 -237.116048) (xy 369.147848 -237.148944)
			(xy 369.187427 -237.188517) (xy 369.220328 -237.233794) (xy 369.245742 -237.28366) (xy 369.263043 -237.336887)
			(xy 369.271805 -237.392166) (xy 369.272312 -237.42015) (xy 369.271989 -237.438163) (xy 369.562624 -237.438163)
			(xy 369.562624 -237.384865) (xy 369.570567 -237.332161) (xy 369.586277 -237.281231) (xy 369.609403 -237.23321)
			(xy 369.639427 -237.189173) (xy 369.675679 -237.150102) (xy 369.71735 -237.116871) (xy 369.763508 -237.090222)
			(xy 369.813122 -237.07075) (xy 369.865084 -237.05889) (xy 369.918234 -237.054907) (xy 369.971384 -237.05889)
			(xy 370.023346 -237.07075) (xy 370.07296 -237.090222) (xy 370.119118 -237.116871) (xy 370.160789 -237.150102)
			(xy 370.197041 -237.189173) (xy 370.227065 -237.23321) (xy 370.250191 -237.281231) (xy 370.265901 -237.332161)
			(xy 370.273844 -237.384865) (xy 370.274342 -237.411514) (xy 370.273844 -237.438163) (xy 370.502424 -237.438163)
			(xy 370.502424 -237.384865) (xy 370.510367 -237.332161) (xy 370.526077 -237.281231) (xy 370.549203 -237.23321)
			(xy 370.579227 -237.189173) (xy 370.615479 -237.150102) (xy 370.65715 -237.116871) (xy 370.703308 -237.090222)
			(xy 370.752922 -237.07075) (xy 370.804884 -237.05889) (xy 370.858034 -237.054907) (xy 370.911184 -237.05889)
			(xy 370.963146 -237.07075) (xy 371.01276 -237.090222) (xy 371.058918 -237.116871) (xy 371.100589 -237.150102)
			(xy 371.136841 -237.189173) (xy 371.166865 -237.23321) (xy 371.189991 -237.281231) (xy 371.205701 -237.332161)
			(xy 371.213644 -237.384865) (xy 371.214142 -237.411514) (xy 371.213644 -237.438163) (xy 371.442224 -237.438163)
			(xy 371.442224 -237.384865) (xy 371.450167 -237.332161) (xy 371.465877 -237.281231) (xy 371.489003 -237.23321)
			(xy 371.519027 -237.189173) (xy 371.555279 -237.150102) (xy 371.59695 -237.116871) (xy 371.643108 -237.090222)
			(xy 371.692722 -237.07075) (xy 371.744684 -237.05889) (xy 371.797834 -237.054907) (xy 371.850984 -237.05889)
			(xy 371.902946 -237.07075) (xy 371.95256 -237.090222) (xy 371.998718 -237.116871) (xy 372.040389 -237.150102)
			(xy 372.076641 -237.189173) (xy 372.106665 -237.23321) (xy 372.129791 -237.281231) (xy 372.145501 -237.332161)
			(xy 372.153444 -237.384865) (xy 372.153942 -237.411514) (xy 372.153444 -237.438163) (xy 372.382024 -237.438163)
			(xy 372.382024 -237.384865) (xy 372.389967 -237.332161) (xy 372.405677 -237.281231) (xy 372.428803 -237.23321)
			(xy 372.458827 -237.189173) (xy 372.495079 -237.150102) (xy 372.53675 -237.116871) (xy 372.582908 -237.090222)
			(xy 372.632522 -237.07075) (xy 372.684484 -237.05889) (xy 372.737634 -237.054907) (xy 372.790784 -237.05889)
			(xy 372.842746 -237.07075) (xy 372.89236 -237.090222) (xy 372.938518 -237.116871) (xy 372.980189 -237.150102)
			(xy 373.016441 -237.189173) (xy 373.046465 -237.23321) (xy 373.069591 -237.281231) (xy 373.085301 -237.332161)
			(xy 373.093244 -237.384865) (xy 373.093742 -237.411514) (xy 373.093244 -237.438163) (xy 373.321824 -237.438163)
			(xy 373.321824 -237.384865) (xy 373.329767 -237.332161) (xy 373.345477 -237.281231) (xy 373.368603 -237.23321)
			(xy 373.398627 -237.189173) (xy 373.434879 -237.150102) (xy 373.47655 -237.116871) (xy 373.522708 -237.090222)
			(xy 373.572322 -237.07075) (xy 373.624284 -237.05889) (xy 373.677434 -237.054907) (xy 373.730584 -237.05889)
			(xy 373.782546 -237.07075) (xy 373.83216 -237.090222) (xy 373.878318 -237.116871) (xy 373.919989 -237.150102)
			(xy 373.956241 -237.189173) (xy 373.986265 -237.23321) (xy 374.009391 -237.281231) (xy 374.025101 -237.332161)
			(xy 374.033044 -237.384865) (xy 374.033542 -237.411514) (xy 374.033044 -237.438163) (xy 374.261624 -237.438163)
			(xy 374.261624 -237.384865) (xy 374.269567 -237.332161) (xy 374.285277 -237.281231) (xy 374.308403 -237.23321)
			(xy 374.338427 -237.189173) (xy 374.374679 -237.150102) (xy 374.41635 -237.116871) (xy 374.462508 -237.090222)
			(xy 374.512122 -237.07075) (xy 374.564084 -237.05889) (xy 374.617234 -237.054907) (xy 374.670384 -237.05889)
			(xy 374.722346 -237.07075) (xy 374.77196 -237.090222) (xy 374.818118 -237.116871) (xy 374.859789 -237.150102)
			(xy 374.896041 -237.189173) (xy 374.926065 -237.23321) (xy 374.949191 -237.281231) (xy 374.964901 -237.332161)
			(xy 374.972844 -237.384865) (xy 374.973342 -237.411514) (xy 374.972844 -237.438163) (xy 375.201424 -237.438163)
			(xy 375.201424 -237.384865) (xy 375.209367 -237.332161) (xy 375.225077 -237.281231) (xy 375.248203 -237.23321)
			(xy 375.278227 -237.189173) (xy 375.314479 -237.150102) (xy 375.35615 -237.116871) (xy 375.402308 -237.090222)
			(xy 375.451922 -237.07075) (xy 375.503884 -237.05889) (xy 375.557034 -237.054907) (xy 375.610184 -237.05889)
			(xy 375.662146 -237.07075) (xy 375.71176 -237.090222) (xy 375.757918 -237.116871) (xy 375.799589 -237.150102)
			(xy 375.835841 -237.189173) (xy 375.865865 -237.23321) (xy 375.888991 -237.281231) (xy 375.904701 -237.332161)
			(xy 375.912644 -237.384865) (xy 375.913142 -237.411514) (xy 375.912644 -237.438163) (xy 376.141224 -237.438163)
			(xy 376.141224 -237.384865) (xy 376.149167 -237.332161) (xy 376.164877 -237.281231) (xy 376.188003 -237.23321)
			(xy 376.218027 -237.189173) (xy 376.254279 -237.150102) (xy 376.29595 -237.116871) (xy 376.342108 -237.090222)
			(xy 376.391722 -237.07075) (xy 376.443684 -237.05889) (xy 376.496834 -237.054907) (xy 376.549984 -237.05889)
			(xy 376.601946 -237.07075) (xy 376.65156 -237.090222) (xy 376.697718 -237.116871) (xy 376.739389 -237.150102)
			(xy 376.775641 -237.189173) (xy 376.805665 -237.23321) (xy 376.828791 -237.281231) (xy 376.844501 -237.332161)
			(xy 376.852444 -237.384865) (xy 376.852942 -237.411514) (xy 376.852444 -237.438163) (xy 377.081024 -237.438163)
			(xy 377.081024 -237.384865) (xy 377.088967 -237.332161) (xy 377.104677 -237.281231) (xy 377.127803 -237.23321)
			(xy 377.157827 -237.189173) (xy 377.194079 -237.150102) (xy 377.23575 -237.116871) (xy 377.281908 -237.090222)
			(xy 377.331522 -237.07075) (xy 377.383484 -237.05889) (xy 377.436634 -237.054907) (xy 377.489784 -237.05889)
			(xy 377.541746 -237.07075) (xy 377.59136 -237.090222) (xy 377.637518 -237.116871) (xy 377.679189 -237.150102)
			(xy 377.715441 -237.189173) (xy 377.745465 -237.23321) (xy 377.768591 -237.281231) (xy 377.784301 -237.332161)
			(xy 377.792244 -237.384865) (xy 377.792742 -237.411514) (xy 377.792244 -237.438163) (xy 378.020824 -237.438163)
			(xy 378.020824 -237.384865) (xy 378.028767 -237.332161) (xy 378.044477 -237.281231) (xy 378.067603 -237.23321)
			(xy 378.097627 -237.189173) (xy 378.133879 -237.150102) (xy 378.17555 -237.116871) (xy 378.221708 -237.090222)
			(xy 378.271322 -237.07075) (xy 378.323284 -237.05889) (xy 378.376434 -237.054907) (xy 378.429584 -237.05889)
			(xy 378.481546 -237.07075) (xy 378.53116 -237.090222) (xy 378.577318 -237.116871) (xy 378.618989 -237.150102)
			(xy 378.655241 -237.189173) (xy 378.685265 -237.23321) (xy 378.708391 -237.281231) (xy 378.724101 -237.332161)
			(xy 378.732044 -237.384865) (xy 378.732542 -237.411514) (xy 378.732044 -237.438163) (xy 378.960624 -237.438163)
			(xy 378.960624 -237.384865) (xy 378.968567 -237.332161) (xy 378.984277 -237.281231) (xy 379.007403 -237.23321)
			(xy 379.037427 -237.189173) (xy 379.073679 -237.150102) (xy 379.11535 -237.116871) (xy 379.161508 -237.090222)
			(xy 379.211122 -237.07075) (xy 379.263084 -237.05889) (xy 379.316234 -237.054907) (xy 379.369384 -237.05889)
			(xy 379.421346 -237.07075) (xy 379.47096 -237.090222) (xy 379.517118 -237.116871) (xy 379.558789 -237.150102)
			(xy 379.595041 -237.189173) (xy 379.625065 -237.23321) (xy 379.648191 -237.281231) (xy 379.663901 -237.332161)
			(xy 379.671844 -237.384865) (xy 379.672342 -237.411514) (xy 379.671844 -237.438163) (xy 379.900424 -237.438163)
			(xy 379.900424 -237.384865) (xy 379.908367 -237.332161) (xy 379.924077 -237.281231) (xy 379.947203 -237.23321)
			(xy 379.977227 -237.189173) (xy 380.013479 -237.150102) (xy 380.05515 -237.116871) (xy 380.101308 -237.090222)
			(xy 380.150922 -237.07075) (xy 380.202884 -237.05889) (xy 380.256034 -237.054907) (xy 380.309184 -237.05889)
			(xy 380.361146 -237.07075) (xy 380.41076 -237.090222) (xy 380.456918 -237.116871) (xy 380.498589 -237.150102)
			(xy 380.534841 -237.189173) (xy 380.564865 -237.23321) (xy 380.587991 -237.281231) (xy 380.603701 -237.332161)
			(xy 380.611644 -237.384865) (xy 380.612142 -237.411514) (xy 380.611644 -237.438163) (xy 380.83997 -237.438163)
			(xy 380.83997 -237.384865) (xy 380.847913 -237.332161) (xy 380.863623 -237.281231) (xy 380.886749 -237.23321)
			(xy 380.916773 -237.189173) (xy 380.953025 -237.150102) (xy 380.994696 -237.116871) (xy 381.040854 -237.090222)
			(xy 381.090468 -237.07075) (xy 381.14243 -237.05889) (xy 381.19558 -237.054907) (xy 381.24873 -237.05889)
			(xy 381.300692 -237.07075) (xy 381.350306 -237.090222) (xy 381.396464 -237.116871) (xy 381.438135 -237.150102)
			(xy 381.474387 -237.189173) (xy 381.504411 -237.23321) (xy 381.527537 -237.281231) (xy 381.543247 -237.332161)
			(xy 381.55119 -237.384865) (xy 381.551688 -237.411514) (xy 381.55119 -237.438163) (xy 381.543247 -237.490867)
			(xy 381.527537 -237.541797) (xy 381.504411 -237.589818) (xy 381.474387 -237.633855) (xy 381.438135 -237.672926)
			(xy 381.396464 -237.706157) (xy 381.350306 -237.732806) (xy 381.300692 -237.752278) (xy 381.24873 -237.764138)
			(xy 381.19558 -237.768122) (xy 381.14243 -237.764138) (xy 381.090468 -237.752278) (xy 381.040854 -237.732806)
			(xy 380.994696 -237.706157) (xy 380.953025 -237.672926) (xy 380.916773 -237.633855) (xy 380.886749 -237.589818)
			(xy 380.863623 -237.541797) (xy 380.847913 -237.490867) (xy 380.83997 -237.438163) (xy 380.611644 -237.438163)
			(xy 380.603701 -237.490867) (xy 380.587991 -237.541797) (xy 380.564865 -237.589818) (xy 380.534841 -237.633855)
			(xy 380.498589 -237.672926) (xy 380.456918 -237.706157) (xy 380.41076 -237.732806) (xy 380.361146 -237.752278)
			(xy 380.309184 -237.764138) (xy 380.256034 -237.768122) (xy 380.202884 -237.764138) (xy 380.150922 -237.752278)
			(xy 380.101308 -237.732806) (xy 380.05515 -237.706157) (xy 380.013479 -237.672926) (xy 379.977227 -237.633855)
			(xy 379.947203 -237.589818) (xy 379.924077 -237.541797) (xy 379.908367 -237.490867) (xy 379.900424 -237.438163)
			(xy 379.671844 -237.438163) (xy 379.663901 -237.490867) (xy 379.648191 -237.541797) (xy 379.625065 -237.589818)
			(xy 379.595041 -237.633855) (xy 379.558789 -237.672926) (xy 379.517118 -237.706157) (xy 379.47096 -237.732806)
			(xy 379.421346 -237.752278) (xy 379.369384 -237.764138) (xy 379.316234 -237.768122) (xy 379.263084 -237.764138)
			(xy 379.211122 -237.752278) (xy 379.161508 -237.732806) (xy 379.11535 -237.706157) (xy 379.073679 -237.672926)
			(xy 379.037427 -237.633855) (xy 379.007403 -237.589818) (xy 378.984277 -237.541797) (xy 378.968567 -237.490867)
			(xy 378.960624 -237.438163) (xy 378.732044 -237.438163) (xy 378.724101 -237.490867) (xy 378.708391 -237.541797)
			(xy 378.685265 -237.589818) (xy 378.655241 -237.633855) (xy 378.618989 -237.672926) (xy 378.577318 -237.706157)
			(xy 378.53116 -237.732806) (xy 378.481546 -237.752278) (xy 378.429584 -237.764138) (xy 378.376434 -237.768122)
			(xy 378.323284 -237.764138) (xy 378.271322 -237.752278) (xy 378.221708 -237.732806) (xy 378.17555 -237.706157)
			(xy 378.133879 -237.672926) (xy 378.097627 -237.633855) (xy 378.067603 -237.589818) (xy 378.044477 -237.541797)
			(xy 378.028767 -237.490867) (xy 378.020824 -237.438163) (xy 377.792244 -237.438163) (xy 377.784301 -237.490867)
			(xy 377.768591 -237.541797) (xy 377.745465 -237.589818) (xy 377.715441 -237.633855) (xy 377.679189 -237.672926)
			(xy 377.637518 -237.706157) (xy 377.59136 -237.732806) (xy 377.541746 -237.752278) (xy 377.489784 -237.764138)
			(xy 377.436634 -237.768122) (xy 377.383484 -237.764138) (xy 377.331522 -237.752278) (xy 377.281908 -237.732806)
			(xy 377.23575 -237.706157) (xy 377.194079 -237.672926) (xy 377.157827 -237.633855) (xy 377.127803 -237.589818)
			(xy 377.104677 -237.541797) (xy 377.088967 -237.490867) (xy 377.081024 -237.438163) (xy 376.852444 -237.438163)
			(xy 376.844501 -237.490867) (xy 376.828791 -237.541797) (xy 376.805665 -237.589818) (xy 376.775641 -237.633855)
			(xy 376.739389 -237.672926) (xy 376.697718 -237.706157) (xy 376.65156 -237.732806) (xy 376.601946 -237.752278)
			(xy 376.549984 -237.764138) (xy 376.496834 -237.768122) (xy 376.443684 -237.764138) (xy 376.391722 -237.752278)
			(xy 376.342108 -237.732806) (xy 376.29595 -237.706157) (xy 376.254279 -237.672926) (xy 376.218027 -237.633855)
			(xy 376.188003 -237.589818) (xy 376.164877 -237.541797) (xy 376.149167 -237.490867) (xy 376.141224 -237.438163)
			(xy 375.912644 -237.438163) (xy 375.904701 -237.490867) (xy 375.888991 -237.541797) (xy 375.865865 -237.589818)
			(xy 375.835841 -237.633855) (xy 375.799589 -237.672926) (xy 375.757918 -237.706157) (xy 375.71176 -237.732806)
			(xy 375.662146 -237.752278) (xy 375.610184 -237.764138) (xy 375.557034 -237.768122) (xy 375.503884 -237.764138)
			(xy 375.451922 -237.752278) (xy 375.402308 -237.732806) (xy 375.35615 -237.706157) (xy 375.314479 -237.672926)
			(xy 375.278227 -237.633855) (xy 375.248203 -237.589818) (xy 375.225077 -237.541797) (xy 375.209367 -237.490867)
			(xy 375.201424 -237.438163) (xy 374.972844 -237.438163) (xy 374.964901 -237.490867) (xy 374.949191 -237.541797)
			(xy 374.926065 -237.589818) (xy 374.896041 -237.633855) (xy 374.859789 -237.672926) (xy 374.818118 -237.706157)
			(xy 374.77196 -237.732806) (xy 374.722346 -237.752278) (xy 374.670384 -237.764138) (xy 374.617234 -237.768122)
			(xy 374.564084 -237.764138) (xy 374.512122 -237.752278) (xy 374.462508 -237.732806) (xy 374.41635 -237.706157)
			(xy 374.374679 -237.672926) (xy 374.338427 -237.633855) (xy 374.308403 -237.589818) (xy 374.285277 -237.541797)
			(xy 374.269567 -237.490867) (xy 374.261624 -237.438163) (xy 374.033044 -237.438163) (xy 374.025101 -237.490867)
			(xy 374.009391 -237.541797) (xy 373.986265 -237.589818) (xy 373.956241 -237.633855) (xy 373.919989 -237.672926)
			(xy 373.878318 -237.706157) (xy 373.83216 -237.732806) (xy 373.782546 -237.752278) (xy 373.730584 -237.764138)
			(xy 373.677434 -237.768122) (xy 373.624284 -237.764138) (xy 373.572322 -237.752278) (xy 373.522708 -237.732806)
			(xy 373.47655 -237.706157) (xy 373.434879 -237.672926) (xy 373.398627 -237.633855) (xy 373.368603 -237.589818)
			(xy 373.345477 -237.541797) (xy 373.329767 -237.490867) (xy 373.321824 -237.438163) (xy 373.093244 -237.438163)
			(xy 373.085301 -237.490867) (xy 373.069591 -237.541797) (xy 373.046465 -237.589818) (xy 373.016441 -237.633855)
			(xy 372.980189 -237.672926) (xy 372.938518 -237.706157) (xy 372.89236 -237.732806) (xy 372.842746 -237.752278)
			(xy 372.790784 -237.764138) (xy 372.737634 -237.768122) (xy 372.684484 -237.764138) (xy 372.632522 -237.752278)
			(xy 372.582908 -237.732806) (xy 372.53675 -237.706157) (xy 372.495079 -237.672926) (xy 372.458827 -237.633855)
			(xy 372.428803 -237.589818) (xy 372.405677 -237.541797) (xy 372.389967 -237.490867) (xy 372.382024 -237.438163)
			(xy 372.153444 -237.438163) (xy 372.145501 -237.490867) (xy 372.129791 -237.541797) (xy 372.106665 -237.589818)
			(xy 372.076641 -237.633855) (xy 372.040389 -237.672926) (xy 371.998718 -237.706157) (xy 371.95256 -237.732806)
			(xy 371.902946 -237.752278) (xy 371.850984 -237.764138) (xy 371.797834 -237.768122) (xy 371.744684 -237.764138)
			(xy 371.692722 -237.752278) (xy 371.643108 -237.732806) (xy 371.59695 -237.706157) (xy 371.555279 -237.672926)
			(xy 371.519027 -237.633855) (xy 371.489003 -237.589818) (xy 371.465877 -237.541797) (xy 371.450167 -237.490867)
			(xy 371.442224 -237.438163) (xy 371.213644 -237.438163) (xy 371.205701 -237.490867) (xy 371.189991 -237.541797)
			(xy 371.166865 -237.589818) (xy 371.136841 -237.633855) (xy 371.100589 -237.672926) (xy 371.058918 -237.706157)
			(xy 371.01276 -237.732806) (xy 370.963146 -237.752278) (xy 370.911184 -237.764138) (xy 370.858034 -237.768122)
			(xy 370.804884 -237.764138) (xy 370.752922 -237.752278) (xy 370.703308 -237.732806) (xy 370.65715 -237.706157)
			(xy 370.615479 -237.672926) (xy 370.579227 -237.633855) (xy 370.549203 -237.589818) (xy 370.526077 -237.541797)
			(xy 370.510367 -237.490867) (xy 370.502424 -237.438163) (xy 370.273844 -237.438163) (xy 370.265901 -237.490867)
			(xy 370.250191 -237.541797) (xy 370.227065 -237.589818) (xy 370.197041 -237.633855) (xy 370.160789 -237.672926)
			(xy 370.119118 -237.706157) (xy 370.07296 -237.732806) (xy 370.023346 -237.752278) (xy 369.971384 -237.764138)
			(xy 369.918234 -237.768122) (xy 369.865084 -237.764138) (xy 369.813122 -237.752278) (xy 369.763508 -237.732806)
			(xy 369.71735 -237.706157) (xy 369.675679 -237.672926) (xy 369.639427 -237.633855) (xy 369.609403 -237.589818)
			(xy 369.586277 -237.541797) (xy 369.570567 -237.490867) (xy 369.562624 -237.438163) (xy 369.271989 -237.438163)
			(xy 369.271849 -237.445969) (xy 369.264388 -237.497066) (xy 369.249629 -237.54655) (xy 369.227882 -237.593386)
			(xy 369.199601 -237.636592) (xy 369.16538 -237.675262) (xy 369.125934 -237.708588) (xy 369.082092 -237.735871)
			(xy 369.03477 -237.75654) (xy 368.98496 -237.770161) (xy 368.959384 -237.773718) (xy 368.91468 -237.779052)
			(xy 368.91468 -238.252233) (xy 369.09247 -238.252233) (xy 369.09247 -238.198935) (xy 369.100413 -238.146231)
			(xy 369.116123 -238.095301) (xy 369.139249 -238.04728) (xy 369.169273 -238.003243) (xy 369.205525 -237.964172)
			(xy 369.247196 -237.930941) (xy 369.293354 -237.904292) (xy 369.342968 -237.88482) (xy 369.39493 -237.87296)
			(xy 369.44808 -237.868977) (xy 369.50123 -237.87296) (xy 369.553192 -237.88482) (xy 369.602806 -237.904292)
			(xy 369.648964 -237.930941) (xy 369.690635 -237.964172) (xy 369.726887 -238.003243) (xy 369.756911 -238.04728)
			(xy 369.780037 -238.095301) (xy 369.795747 -238.146231) (xy 369.80369 -238.198935) (xy 369.804188 -238.225584)
			(xy 369.80369 -238.252233) (xy 370.03227 -238.252233) (xy 370.03227 -238.198935) (xy 370.040213 -238.146231)
			(xy 370.055923 -238.095301) (xy 370.079049 -238.04728) (xy 370.109073 -238.003243) (xy 370.145325 -237.964172)
			(xy 370.186996 -237.930941) (xy 370.233154 -237.904292) (xy 370.282768 -237.88482) (xy 370.33473 -237.87296)
			(xy 370.38788 -237.868977) (xy 370.44103 -237.87296) (xy 370.492992 -237.88482) (xy 370.542606 -237.904292)
			(xy 370.588764 -237.930941) (xy 370.630435 -237.964172) (xy 370.666687 -238.003243) (xy 370.696711 -238.04728)
			(xy 370.719837 -238.095301) (xy 370.735547 -238.146231) (xy 370.74349 -238.198935) (xy 370.743988 -238.225584)
			(xy 370.74349 -238.252233) (xy 370.97207 -238.252233) (xy 370.97207 -238.198935) (xy 370.980013 -238.146231)
			(xy 370.995723 -238.095301) (xy 371.018849 -238.04728) (xy 371.048873 -238.003243) (xy 371.085125 -237.964172)
			(xy 371.126796 -237.930941) (xy 371.172954 -237.904292) (xy 371.222568 -237.88482) (xy 371.27453 -237.87296)
			(xy 371.32768 -237.868977) (xy 371.38083 -237.87296) (xy 371.432792 -237.88482) (xy 371.482406 -237.904292)
			(xy 371.528564 -237.930941) (xy 371.570235 -237.964172) (xy 371.606487 -238.003243) (xy 371.636511 -238.04728)
			(xy 371.659637 -238.095301) (xy 371.675347 -238.146231) (xy 371.68329 -238.198935) (xy 371.683788 -238.225584)
			(xy 371.68329 -238.252233) (xy 371.91187 -238.252233) (xy 371.91187 -238.198935) (xy 371.919813 -238.146231)
			(xy 371.935523 -238.095301) (xy 371.958649 -238.04728) (xy 371.988673 -238.003243) (xy 372.024925 -237.964172)
			(xy 372.066596 -237.930941) (xy 372.112754 -237.904292) (xy 372.162368 -237.88482) (xy 372.21433 -237.87296)
			(xy 372.26748 -237.868977) (xy 372.32063 -237.87296) (xy 372.372592 -237.88482) (xy 372.422206 -237.904292)
			(xy 372.468364 -237.930941) (xy 372.510035 -237.964172) (xy 372.546287 -238.003243) (xy 372.576311 -238.04728)
			(xy 372.599437 -238.095301) (xy 372.615147 -238.146231) (xy 372.62309 -238.198935) (xy 372.623588 -238.225584)
			(xy 372.62309 -238.252233) (xy 372.85167 -238.252233) (xy 372.85167 -238.198935) (xy 372.859613 -238.146231)
			(xy 372.875323 -238.095301) (xy 372.898449 -238.04728) (xy 372.928473 -238.003243) (xy 372.964725 -237.964172)
			(xy 373.006396 -237.930941) (xy 373.052554 -237.904292) (xy 373.102168 -237.88482) (xy 373.15413 -237.87296)
			(xy 373.20728 -237.868977) (xy 373.26043 -237.87296) (xy 373.312392 -237.88482) (xy 373.362006 -237.904292)
			(xy 373.408164 -237.930941) (xy 373.449835 -237.964172) (xy 373.486087 -238.003243) (xy 373.516111 -238.04728)
			(xy 373.539237 -238.095301) (xy 373.554947 -238.146231) (xy 373.56289 -238.198935) (xy 373.563388 -238.225584)
			(xy 373.56289 -238.252233) (xy 373.791724 -238.252233) (xy 373.791724 -238.198935) (xy 373.799667 -238.146231)
			(xy 373.815377 -238.095301) (xy 373.838503 -238.04728) (xy 373.868527 -238.003243) (xy 373.904779 -237.964172)
			(xy 373.94645 -237.930941) (xy 373.992608 -237.904292) (xy 374.042222 -237.88482) (xy 374.094184 -237.87296)
			(xy 374.147334 -237.868977) (xy 374.200484 -237.87296) (xy 374.252446 -237.88482) (xy 374.30206 -237.904292)
			(xy 374.348218 -237.930941) (xy 374.389889 -237.964172) (xy 374.426141 -238.003243) (xy 374.456165 -238.04728)
			(xy 374.479291 -238.095301) (xy 374.495001 -238.146231) (xy 374.502944 -238.198935) (xy 374.503442 -238.225584)
			(xy 374.502944 -238.252233) (xy 374.73127 -238.252233) (xy 374.73127 -238.198935) (xy 374.739213 -238.146231)
			(xy 374.754923 -238.095301) (xy 374.778049 -238.04728) (xy 374.808073 -238.003243) (xy 374.844325 -237.964172)
			(xy 374.885996 -237.930941) (xy 374.932154 -237.904292) (xy 374.981768 -237.88482) (xy 375.03373 -237.87296)
			(xy 375.08688 -237.868977) (xy 375.14003 -237.87296) (xy 375.191992 -237.88482) (xy 375.241606 -237.904292)
			(xy 375.287764 -237.930941) (xy 375.329435 -237.964172) (xy 375.365687 -238.003243) (xy 375.395711 -238.04728)
			(xy 375.418837 -238.095301) (xy 375.434547 -238.146231) (xy 375.44249 -238.198935) (xy 375.442988 -238.225584)
			(xy 375.44249 -238.252233) (xy 375.67107 -238.252233) (xy 375.67107 -238.198935) (xy 375.679013 -238.146231)
			(xy 375.694723 -238.095301) (xy 375.717849 -238.04728) (xy 375.747873 -238.003243) (xy 375.784125 -237.964172)
			(xy 375.825796 -237.930941) (xy 375.871954 -237.904292) (xy 375.921568 -237.88482) (xy 375.97353 -237.87296)
			(xy 376.02668 -237.868977) (xy 376.07983 -237.87296) (xy 376.131792 -237.88482) (xy 376.181406 -237.904292)
			(xy 376.227564 -237.930941) (xy 376.269235 -237.964172) (xy 376.305487 -238.003243) (xy 376.335511 -238.04728)
			(xy 376.358637 -238.095301) (xy 376.374347 -238.146231) (xy 376.38229 -238.198935) (xy 376.382788 -238.225584)
			(xy 376.38229 -238.252233) (xy 376.61087 -238.252233) (xy 376.61087 -238.198935) (xy 376.618813 -238.146231)
			(xy 376.634523 -238.095301) (xy 376.657649 -238.04728) (xy 376.687673 -238.003243) (xy 376.723925 -237.964172)
			(xy 376.765596 -237.930941) (xy 376.811754 -237.904292) (xy 376.861368 -237.88482) (xy 376.91333 -237.87296)
			(xy 376.96648 -237.868977) (xy 377.01963 -237.87296) (xy 377.071592 -237.88482) (xy 377.121206 -237.904292)
			(xy 377.167364 -237.930941) (xy 377.209035 -237.964172) (xy 377.245287 -238.003243) (xy 377.275311 -238.04728)
			(xy 377.298437 -238.095301) (xy 377.314147 -238.146231) (xy 377.32209 -238.198935) (xy 377.322588 -238.225584)
			(xy 377.32209 -238.252233) (xy 377.55067 -238.252233) (xy 377.55067 -238.198935) (xy 377.558613 -238.146231)
			(xy 377.574323 -238.095301) (xy 377.597449 -238.04728) (xy 377.627473 -238.003243) (xy 377.663725 -237.964172)
			(xy 377.705396 -237.930941) (xy 377.751554 -237.904292) (xy 377.801168 -237.88482) (xy 377.85313 -237.87296)
			(xy 377.90628 -237.868977) (xy 377.95943 -237.87296) (xy 378.011392 -237.88482) (xy 378.061006 -237.904292)
			(xy 378.107164 -237.930941) (xy 378.148835 -237.964172) (xy 378.185087 -238.003243) (xy 378.215111 -238.04728)
			(xy 378.238237 -238.095301) (xy 378.253947 -238.146231) (xy 378.26189 -238.198935) (xy 378.262388 -238.225584)
			(xy 378.26189 -238.252233) (xy 378.49047 -238.252233) (xy 378.49047 -238.198935) (xy 378.498413 -238.146231)
			(xy 378.514123 -238.095301) (xy 378.537249 -238.04728) (xy 378.567273 -238.003243) (xy 378.603525 -237.964172)
			(xy 378.645196 -237.930941) (xy 378.691354 -237.904292) (xy 378.740968 -237.88482) (xy 378.79293 -237.87296)
			(xy 378.84608 -237.868977) (xy 378.89923 -237.87296) (xy 378.951192 -237.88482) (xy 379.000806 -237.904292)
			(xy 379.046964 -237.930941) (xy 379.088635 -237.964172) (xy 379.124887 -238.003243) (xy 379.154911 -238.04728)
			(xy 379.178037 -238.095301) (xy 379.193747 -238.146231) (xy 379.20169 -238.198935) (xy 379.202188 -238.225584)
			(xy 379.20169 -238.252233) (xy 379.43027 -238.252233) (xy 379.43027 -238.198935) (xy 379.438213 -238.146231)
			(xy 379.453923 -238.095301) (xy 379.477049 -238.04728) (xy 379.507073 -238.003243) (xy 379.543325 -237.964172)
			(xy 379.584996 -237.930941) (xy 379.631154 -237.904292) (xy 379.680768 -237.88482) (xy 379.73273 -237.87296)
			(xy 379.78588 -237.868977) (xy 379.83903 -237.87296) (xy 379.890992 -237.88482) (xy 379.940606 -237.904292)
			(xy 379.986764 -237.930941) (xy 380.028435 -237.964172) (xy 380.064687 -238.003243) (xy 380.094711 -238.04728)
			(xy 380.117837 -238.095301) (xy 380.133547 -238.146231) (xy 380.14149 -238.198935) (xy 380.141988 -238.225584)
			(xy 380.14149 -238.252233) (xy 380.370324 -238.252233) (xy 380.370324 -238.198935) (xy 380.378267 -238.146231)
			(xy 380.393977 -238.095301) (xy 380.417103 -238.04728) (xy 380.447127 -238.003243) (xy 380.483379 -237.964172)
			(xy 380.52505 -237.930941) (xy 380.571208 -237.904292) (xy 380.620822 -237.88482) (xy 380.672784 -237.87296)
			(xy 380.725934 -237.868977) (xy 380.779084 -237.87296) (xy 380.831046 -237.88482) (xy 380.88066 -237.904292)
			(xy 380.926818 -237.930941) (xy 380.968489 -237.964172) (xy 381.004741 -238.003243) (xy 381.034765 -238.04728)
			(xy 381.057891 -238.095301) (xy 381.073601 -238.146231) (xy 381.081544 -238.198935) (xy 381.082042 -238.225584)
			(xy 381.081544 -238.252233) (xy 381.073601 -238.304937) (xy 381.057891 -238.355867) (xy 381.034765 -238.403888)
			(xy 381.004741 -238.447925) (xy 380.968489 -238.486996) (xy 380.926818 -238.520227) (xy 380.88066 -238.546876)
			(xy 380.831046 -238.566348) (xy 380.779084 -238.578208) (xy 380.725934 -238.582192) (xy 380.672784 -238.578208)
			(xy 380.620822 -238.566348) (xy 380.571208 -238.546876) (xy 380.52505 -238.520227) (xy 380.483379 -238.486996)
			(xy 380.447127 -238.447925) (xy 380.417103 -238.403888) (xy 380.393977 -238.355867) (xy 380.378267 -238.304937)
			(xy 380.370324 -238.252233) (xy 380.14149 -238.252233) (xy 380.133547 -238.304937) (xy 380.117837 -238.355867)
			(xy 380.094711 -238.403888) (xy 380.064687 -238.447925) (xy 380.028435 -238.486996) (xy 379.986764 -238.520227)
			(xy 379.940606 -238.546876) (xy 379.890992 -238.566348) (xy 379.83903 -238.578208) (xy 379.78588 -238.582192)
			(xy 379.73273 -238.578208) (xy 379.680768 -238.566348) (xy 379.631154 -238.546876) (xy 379.584996 -238.520227)
			(xy 379.543325 -238.486996) (xy 379.507073 -238.447925) (xy 379.477049 -238.403888) (xy 379.453923 -238.355867)
			(xy 379.438213 -238.304937) (xy 379.43027 -238.252233) (xy 379.20169 -238.252233) (xy 379.193747 -238.304937)
			(xy 379.178037 -238.355867) (xy 379.154911 -238.403888) (xy 379.124887 -238.447925) (xy 379.088635 -238.486996)
			(xy 379.046964 -238.520227) (xy 379.000806 -238.546876) (xy 378.951192 -238.566348) (xy 378.89923 -238.578208)
			(xy 378.84608 -238.582192) (xy 378.79293 -238.578208) (xy 378.740968 -238.566348) (xy 378.691354 -238.546876)
			(xy 378.645196 -238.520227) (xy 378.603525 -238.486996) (xy 378.567273 -238.447925) (xy 378.537249 -238.403888)
			(xy 378.514123 -238.355867) (xy 378.498413 -238.304937) (xy 378.49047 -238.252233) (xy 378.26189 -238.252233)
			(xy 378.253947 -238.304937) (xy 378.238237 -238.355867) (xy 378.215111 -238.403888) (xy 378.185087 -238.447925)
			(xy 378.148835 -238.486996) (xy 378.107164 -238.520227) (xy 378.061006 -238.546876) (xy 378.011392 -238.566348)
			(xy 377.95943 -238.578208) (xy 377.90628 -238.582192) (xy 377.85313 -238.578208) (xy 377.801168 -238.566348)
			(xy 377.751554 -238.546876) (xy 377.705396 -238.520227) (xy 377.663725 -238.486996) (xy 377.627473 -238.447925)
			(xy 377.597449 -238.403888) (xy 377.574323 -238.355867) (xy 377.558613 -238.304937) (xy 377.55067 -238.252233)
			(xy 377.32209 -238.252233) (xy 377.314147 -238.304937) (xy 377.298437 -238.355867) (xy 377.275311 -238.403888)
			(xy 377.245287 -238.447925) (xy 377.209035 -238.486996) (xy 377.167364 -238.520227) (xy 377.121206 -238.546876)
			(xy 377.071592 -238.566348) (xy 377.01963 -238.578208) (xy 376.96648 -238.582192) (xy 376.91333 -238.578208)
			(xy 376.861368 -238.566348) (xy 376.811754 -238.546876) (xy 376.765596 -238.520227) (xy 376.723925 -238.486996)
			(xy 376.687673 -238.447925) (xy 376.657649 -238.403888) (xy 376.634523 -238.355867) (xy 376.618813 -238.304937)
			(xy 376.61087 -238.252233) (xy 376.38229 -238.252233) (xy 376.374347 -238.304937) (xy 376.358637 -238.355867)
			(xy 376.335511 -238.403888) (xy 376.305487 -238.447925) (xy 376.269235 -238.486996) (xy 376.227564 -238.520227)
			(xy 376.181406 -238.546876) (xy 376.131792 -238.566348) (xy 376.07983 -238.578208) (xy 376.02668 -238.582192)
			(xy 375.97353 -238.578208) (xy 375.921568 -238.566348) (xy 375.871954 -238.546876) (xy 375.825796 -238.520227)
			(xy 375.784125 -238.486996) (xy 375.747873 -238.447925) (xy 375.717849 -238.403888) (xy 375.694723 -238.355867)
			(xy 375.679013 -238.304937) (xy 375.67107 -238.252233) (xy 375.44249 -238.252233) (xy 375.434547 -238.304937)
			(xy 375.418837 -238.355867) (xy 375.395711 -238.403888) (xy 375.365687 -238.447925) (xy 375.329435 -238.486996)
			(xy 375.287764 -238.520227) (xy 375.241606 -238.546876) (xy 375.191992 -238.566348) (xy 375.14003 -238.578208)
			(xy 375.08688 -238.582192) (xy 375.03373 -238.578208) (xy 374.981768 -238.566348) (xy 374.932154 -238.546876)
			(xy 374.885996 -238.520227) (xy 374.844325 -238.486996) (xy 374.808073 -238.447925) (xy 374.778049 -238.403888)
			(xy 374.754923 -238.355867) (xy 374.739213 -238.304937) (xy 374.73127 -238.252233) (xy 374.502944 -238.252233)
			(xy 374.495001 -238.304937) (xy 374.479291 -238.355867) (xy 374.456165 -238.403888) (xy 374.426141 -238.447925)
			(xy 374.389889 -238.486996) (xy 374.348218 -238.520227) (xy 374.30206 -238.546876) (xy 374.252446 -238.566348)
			(xy 374.200484 -238.578208) (xy 374.147334 -238.582192) (xy 374.094184 -238.578208) (xy 374.042222 -238.566348)
			(xy 373.992608 -238.546876) (xy 373.94645 -238.520227) (xy 373.904779 -238.486996) (xy 373.868527 -238.447925)
			(xy 373.838503 -238.403888) (xy 373.815377 -238.355867) (xy 373.799667 -238.304937) (xy 373.791724 -238.252233)
			(xy 373.56289 -238.252233) (xy 373.554947 -238.304937) (xy 373.539237 -238.355867) (xy 373.516111 -238.403888)
			(xy 373.486087 -238.447925) (xy 373.449835 -238.486996) (xy 373.408164 -238.520227) (xy 373.362006 -238.546876)
			(xy 373.312392 -238.566348) (xy 373.26043 -238.578208) (xy 373.20728 -238.582192) (xy 373.15413 -238.578208)
			(xy 373.102168 -238.566348) (xy 373.052554 -238.546876) (xy 373.006396 -238.520227) (xy 372.964725 -238.486996)
			(xy 372.928473 -238.447925) (xy 372.898449 -238.403888) (xy 372.875323 -238.355867) (xy 372.859613 -238.304937)
			(xy 372.85167 -238.252233) (xy 372.62309 -238.252233) (xy 372.615147 -238.304937) (xy 372.599437 -238.355867)
			(xy 372.576311 -238.403888) (xy 372.546287 -238.447925) (xy 372.510035 -238.486996) (xy 372.468364 -238.520227)
			(xy 372.422206 -238.546876) (xy 372.372592 -238.566348) (xy 372.32063 -238.578208) (xy 372.26748 -238.582192)
			(xy 372.21433 -238.578208) (xy 372.162368 -238.566348) (xy 372.112754 -238.546876) (xy 372.066596 -238.520227)
			(xy 372.024925 -238.486996) (xy 371.988673 -238.447925) (xy 371.958649 -238.403888) (xy 371.935523 -238.355867)
			(xy 371.919813 -238.304937) (xy 371.91187 -238.252233) (xy 371.68329 -238.252233) (xy 371.675347 -238.304937)
			(xy 371.659637 -238.355867) (xy 371.636511 -238.403888) (xy 371.606487 -238.447925) (xy 371.570235 -238.486996)
			(xy 371.528564 -238.520227) (xy 371.482406 -238.546876) (xy 371.432792 -238.566348) (xy 371.38083 -238.578208)
			(xy 371.32768 -238.582192) (xy 371.27453 -238.578208) (xy 371.222568 -238.566348) (xy 371.172954 -238.546876)
			(xy 371.126796 -238.520227) (xy 371.085125 -238.486996) (xy 371.048873 -238.447925) (xy 371.018849 -238.403888)
			(xy 370.995723 -238.355867) (xy 370.980013 -238.304937) (xy 370.97207 -238.252233) (xy 370.74349 -238.252233)
			(xy 370.735547 -238.304937) (xy 370.719837 -238.355867) (xy 370.696711 -238.403888) (xy 370.666687 -238.447925)
			(xy 370.630435 -238.486996) (xy 370.588764 -238.520227) (xy 370.542606 -238.546876) (xy 370.492992 -238.566348)
			(xy 370.44103 -238.578208) (xy 370.38788 -238.582192) (xy 370.33473 -238.578208) (xy 370.282768 -238.566348)
			(xy 370.233154 -238.546876) (xy 370.186996 -238.520227) (xy 370.145325 -238.486996) (xy 370.109073 -238.447925)
			(xy 370.079049 -238.403888) (xy 370.055923 -238.355867) (xy 370.040213 -238.304937) (xy 370.03227 -238.252233)
			(xy 369.80369 -238.252233) (xy 369.795747 -238.304937) (xy 369.780037 -238.355867) (xy 369.756911 -238.403888)
			(xy 369.726887 -238.447925) (xy 369.690635 -238.486996) (xy 369.648964 -238.520227) (xy 369.602806 -238.546876)
			(xy 369.553192 -238.566348) (xy 369.50123 -238.578208) (xy 369.44808 -238.582192) (xy 369.39493 -238.578208)
			(xy 369.342968 -238.566348) (xy 369.293354 -238.546876) (xy 369.247196 -238.520227) (xy 369.205525 -238.486996)
			(xy 369.169273 -238.447925) (xy 369.139249 -238.403888) (xy 369.116123 -238.355867) (xy 369.100413 -238.304937)
			(xy 369.09247 -238.252233) (xy 368.91468 -238.252233) (xy 368.91468 -239.066049) (xy 369.562624 -239.066049)
			(xy 369.562624 -239.012751) (xy 369.570567 -238.960047) (xy 369.586277 -238.909117) (xy 369.609403 -238.861096)
			(xy 369.639427 -238.817059) (xy 369.675679 -238.777988) (xy 369.71735 -238.744757) (xy 369.763508 -238.718108)
			(xy 369.813122 -238.698636) (xy 369.865084 -238.686776) (xy 369.918234 -238.682793) (xy 369.971384 -238.686776)
			(xy 370.023346 -238.698636) (xy 370.07296 -238.718108) (xy 370.119118 -238.744757) (xy 370.160789 -238.777988)
			(xy 370.197041 -238.817059) (xy 370.227065 -238.861096) (xy 370.250191 -238.909117) (xy 370.265901 -238.960047)
			(xy 370.273844 -239.012751) (xy 370.274342 -239.0394) (xy 370.273844 -239.066049) (xy 370.50217 -239.066049)
			(xy 370.50217 -239.012751) (xy 370.510113 -238.960047) (xy 370.525823 -238.909117) (xy 370.548949 -238.861096)
			(xy 370.578973 -238.817059) (xy 370.615225 -238.777988) (xy 370.656896 -238.744757) (xy 370.703054 -238.718108)
			(xy 370.752668 -238.698636) (xy 370.80463 -238.686776) (xy 370.85778 -238.682793) (xy 370.91093 -238.686776)
			(xy 370.962892 -238.698636) (xy 371.012506 -238.718108) (xy 371.058664 -238.744757) (xy 371.100335 -238.777988)
			(xy 371.136587 -238.817059) (xy 371.166611 -238.861096) (xy 371.189737 -238.909117) (xy 371.205447 -238.960047)
			(xy 371.21339 -239.012751) (xy 371.213888 -239.0394) (xy 371.21339 -239.066049) (xy 371.442224 -239.066049)
			(xy 371.442224 -239.012751) (xy 371.450167 -238.960047) (xy 371.465877 -238.909117) (xy 371.489003 -238.861096)
			(xy 371.519027 -238.817059) (xy 371.555279 -238.777988) (xy 371.59695 -238.744757) (xy 371.643108 -238.718108)
			(xy 371.692722 -238.698636) (xy 371.744684 -238.686776) (xy 371.797834 -238.682793) (xy 371.850984 -238.686776)
			(xy 371.902946 -238.698636) (xy 371.95256 -238.718108) (xy 371.998718 -238.744757) (xy 372.040389 -238.777988)
			(xy 372.076641 -238.817059) (xy 372.106665 -238.861096) (xy 372.129791 -238.909117) (xy 372.145501 -238.960047)
			(xy 372.153444 -239.012751) (xy 372.153942 -239.0394) (xy 372.153444 -239.066049) (xy 372.382024 -239.066049)
			(xy 372.382024 -239.012751) (xy 372.389967 -238.960047) (xy 372.405677 -238.909117) (xy 372.428803 -238.861096)
			(xy 372.458827 -238.817059) (xy 372.495079 -238.777988) (xy 372.53675 -238.744757) (xy 372.582908 -238.718108)
			(xy 372.632522 -238.698636) (xy 372.684484 -238.686776) (xy 372.737634 -238.682793) (xy 372.790784 -238.686776)
			(xy 372.842746 -238.698636) (xy 372.89236 -238.718108) (xy 372.938518 -238.744757) (xy 372.980189 -238.777988)
			(xy 373.016441 -238.817059) (xy 373.046465 -238.861096) (xy 373.069591 -238.909117) (xy 373.085301 -238.960047)
			(xy 373.093244 -239.012751) (xy 373.093742 -239.0394) (xy 373.093244 -239.066049) (xy 373.321824 -239.066049)
			(xy 373.321824 -239.012751) (xy 373.329767 -238.960047) (xy 373.345477 -238.909117) (xy 373.368603 -238.861096)
			(xy 373.398627 -238.817059) (xy 373.434879 -238.777988) (xy 373.47655 -238.744757) (xy 373.522708 -238.718108)
			(xy 373.572322 -238.698636) (xy 373.624284 -238.686776) (xy 373.677434 -238.682793) (xy 373.730584 -238.686776)
			(xy 373.782546 -238.698636) (xy 373.83216 -238.718108) (xy 373.878318 -238.744757) (xy 373.919989 -238.777988)
			(xy 373.956241 -238.817059) (xy 373.986265 -238.861096) (xy 374.009391 -238.909117) (xy 374.025101 -238.960047)
			(xy 374.033044 -239.012751) (xy 374.033542 -239.0394) (xy 374.033044 -239.066049) (xy 374.261624 -239.066049)
			(xy 374.261624 -239.012751) (xy 374.269567 -238.960047) (xy 374.285277 -238.909117) (xy 374.308403 -238.861096)
			(xy 374.338427 -238.817059) (xy 374.374679 -238.777988) (xy 374.41635 -238.744757) (xy 374.462508 -238.718108)
			(xy 374.512122 -238.698636) (xy 374.564084 -238.686776) (xy 374.617234 -238.682793) (xy 374.670384 -238.686776)
			(xy 374.722346 -238.698636) (xy 374.77196 -238.718108) (xy 374.818118 -238.744757) (xy 374.859789 -238.777988)
			(xy 374.896041 -238.817059) (xy 374.926065 -238.861096) (xy 374.949191 -238.909117) (xy 374.964901 -238.960047)
			(xy 374.972844 -239.012751) (xy 374.973342 -239.0394) (xy 374.972844 -239.066049) (xy 375.201424 -239.066049)
			(xy 375.201424 -239.012751) (xy 375.209367 -238.960047) (xy 375.225077 -238.909117) (xy 375.248203 -238.861096)
			(xy 375.278227 -238.817059) (xy 375.314479 -238.777988) (xy 375.35615 -238.744757) (xy 375.402308 -238.718108)
			(xy 375.451922 -238.698636) (xy 375.503884 -238.686776) (xy 375.557034 -238.682793) (xy 375.610184 -238.686776)
			(xy 375.662146 -238.698636) (xy 375.71176 -238.718108) (xy 375.757918 -238.744757) (xy 375.799589 -238.777988)
			(xy 375.835841 -238.817059) (xy 375.865865 -238.861096) (xy 375.888991 -238.909117) (xy 375.904701 -238.960047)
			(xy 375.912644 -239.012751) (xy 375.913142 -239.0394) (xy 375.912644 -239.066049) (xy 376.141224 -239.066049)
			(xy 376.141224 -239.012751) (xy 376.149167 -238.960047) (xy 376.164877 -238.909117) (xy 376.188003 -238.861096)
			(xy 376.218027 -238.817059) (xy 376.254279 -238.777988) (xy 376.29595 -238.744757) (xy 376.342108 -238.718108)
			(xy 376.391722 -238.698636) (xy 376.443684 -238.686776) (xy 376.496834 -238.682793) (xy 376.549984 -238.686776)
			(xy 376.601946 -238.698636) (xy 376.65156 -238.718108) (xy 376.697718 -238.744757) (xy 376.739389 -238.777988)
			(xy 376.775641 -238.817059) (xy 376.805665 -238.861096) (xy 376.828791 -238.909117) (xy 376.844501 -238.960047)
			(xy 376.852444 -239.012751) (xy 376.852942 -239.0394) (xy 376.852444 -239.066049) (xy 377.08077 -239.066049)
			(xy 377.08077 -239.012751) (xy 377.088713 -238.960047) (xy 377.104423 -238.909117) (xy 377.127549 -238.861096)
			(xy 377.157573 -238.817059) (xy 377.193825 -238.777988) (xy 377.235496 -238.744757) (xy 377.281654 -238.718108)
			(xy 377.331268 -238.698636) (xy 377.38323 -238.686776) (xy 377.43638 -238.682793) (xy 377.48953 -238.686776)
			(xy 377.541492 -238.698636) (xy 377.591106 -238.718108) (xy 377.637264 -238.744757) (xy 377.678935 -238.777988)
			(xy 377.715187 -238.817059) (xy 377.745211 -238.861096) (xy 377.768337 -238.909117) (xy 377.784047 -238.960047)
			(xy 377.79199 -239.012751) (xy 377.792488 -239.0394) (xy 377.79199 -239.066049) (xy 378.020824 -239.066049)
			(xy 378.020824 -239.012751) (xy 378.028767 -238.960047) (xy 378.044477 -238.909117) (xy 378.067603 -238.861096)
			(xy 378.097627 -238.817059) (xy 378.133879 -238.777988) (xy 378.17555 -238.744757) (xy 378.221708 -238.718108)
			(xy 378.271322 -238.698636) (xy 378.323284 -238.686776) (xy 378.376434 -238.682793) (xy 378.429584 -238.686776)
			(xy 378.481546 -238.698636) (xy 378.53116 -238.718108) (xy 378.577318 -238.744757) (xy 378.618989 -238.777988)
			(xy 378.655241 -238.817059) (xy 378.685265 -238.861096) (xy 378.708391 -238.909117) (xy 378.724101 -238.960047)
			(xy 378.732044 -239.012751) (xy 378.732542 -239.0394) (xy 378.732044 -239.066049) (xy 378.960624 -239.066049)
			(xy 378.960624 -239.012751) (xy 378.968567 -238.960047) (xy 378.984277 -238.909117) (xy 379.007403 -238.861096)
			(xy 379.037427 -238.817059) (xy 379.073679 -238.777988) (xy 379.11535 -238.744757) (xy 379.161508 -238.718108)
			(xy 379.211122 -238.698636) (xy 379.263084 -238.686776) (xy 379.316234 -238.682793) (xy 379.369384 -238.686776)
			(xy 379.421346 -238.698636) (xy 379.47096 -238.718108) (xy 379.517118 -238.744757) (xy 379.558789 -238.777988)
			(xy 379.595041 -238.817059) (xy 379.625065 -238.861096) (xy 379.648191 -238.909117) (xy 379.663901 -238.960047)
			(xy 379.671844 -239.012751) (xy 379.672342 -239.0394) (xy 379.671844 -239.066049) (xy 379.900424 -239.066049)
			(xy 379.900424 -239.012751) (xy 379.908367 -238.960047) (xy 379.924077 -238.909117) (xy 379.947203 -238.861096)
			(xy 379.977227 -238.817059) (xy 380.013479 -238.777988) (xy 380.05515 -238.744757) (xy 380.101308 -238.718108)
			(xy 380.150922 -238.698636) (xy 380.202884 -238.686776) (xy 380.256034 -238.682793) (xy 380.309184 -238.686776)
			(xy 380.361146 -238.698636) (xy 380.41076 -238.718108) (xy 380.456918 -238.744757) (xy 380.498589 -238.777988)
			(xy 380.534841 -238.817059) (xy 380.564865 -238.861096) (xy 380.587991 -238.909117) (xy 380.603701 -238.960047)
			(xy 380.611644 -239.012751) (xy 380.612142 -239.0394) (xy 380.611644 -239.066049) (xy 380.840224 -239.066049)
			(xy 380.840224 -239.012751) (xy 380.848167 -238.960047) (xy 380.863877 -238.909117) (xy 380.887003 -238.861096)
			(xy 380.917027 -238.817059) (xy 380.953279 -238.777988) (xy 380.99495 -238.744757) (xy 381.041108 -238.718108)
			(xy 381.090722 -238.698636) (xy 381.142684 -238.686776) (xy 381.195834 -238.682793) (xy 381.248984 -238.686776)
			(xy 381.300946 -238.698636) (xy 381.35056 -238.718108) (xy 381.396718 -238.744757) (xy 381.438389 -238.777988)
			(xy 381.474641 -238.817059) (xy 381.504665 -238.861096) (xy 381.527791 -238.909117) (xy 381.543501 -238.960047)
			(xy 381.551444 -239.012751) (xy 381.551942 -239.0394) (xy 381.551444 -239.066049) (xy 381.543501 -239.118753)
			(xy 381.527791 -239.169683) (xy 381.504665 -239.217704) (xy 381.474641 -239.261741) (xy 381.438389 -239.300812)
			(xy 381.396718 -239.334043) (xy 381.35056 -239.360692) (xy 381.300946 -239.380164) (xy 381.248984 -239.392024)
			(xy 381.195834 -239.396008) (xy 381.142684 -239.392024) (xy 381.090722 -239.380164) (xy 381.041108 -239.360692)
			(xy 380.99495 -239.334043) (xy 380.953279 -239.300812) (xy 380.917027 -239.261741) (xy 380.887003 -239.217704)
			(xy 380.863877 -239.169683) (xy 380.848167 -239.118753) (xy 380.840224 -239.066049) (xy 380.611644 -239.066049)
			(xy 380.603701 -239.118753) (xy 380.587991 -239.169683) (xy 380.564865 -239.217704) (xy 380.534841 -239.261741)
			(xy 380.498589 -239.300812) (xy 380.456918 -239.334043) (xy 380.41076 -239.360692) (xy 380.361146 -239.380164)
			(xy 380.309184 -239.392024) (xy 380.256034 -239.396008) (xy 380.202884 -239.392024) (xy 380.150922 -239.380164)
			(xy 380.101308 -239.360692) (xy 380.05515 -239.334043) (xy 380.013479 -239.300812) (xy 379.977227 -239.261741)
			(xy 379.947203 -239.217704) (xy 379.924077 -239.169683) (xy 379.908367 -239.118753) (xy 379.900424 -239.066049)
			(xy 379.671844 -239.066049) (xy 379.663901 -239.118753) (xy 379.648191 -239.169683) (xy 379.625065 -239.217704)
			(xy 379.595041 -239.261741) (xy 379.558789 -239.300812) (xy 379.517118 -239.334043) (xy 379.47096 -239.360692)
			(xy 379.421346 -239.380164) (xy 379.369384 -239.392024) (xy 379.316234 -239.396008) (xy 379.263084 -239.392024)
			(xy 379.211122 -239.380164) (xy 379.161508 -239.360692) (xy 379.11535 -239.334043) (xy 379.073679 -239.300812)
			(xy 379.037427 -239.261741) (xy 379.007403 -239.217704) (xy 378.984277 -239.169683) (xy 378.968567 -239.118753)
			(xy 378.960624 -239.066049) (xy 378.732044 -239.066049) (xy 378.724101 -239.118753) (xy 378.708391 -239.169683)
			(xy 378.685265 -239.217704) (xy 378.655241 -239.261741) (xy 378.618989 -239.300812) (xy 378.577318 -239.334043)
			(xy 378.53116 -239.360692) (xy 378.481546 -239.380164) (xy 378.429584 -239.392024) (xy 378.376434 -239.396008)
			(xy 378.323284 -239.392024) (xy 378.271322 -239.380164) (xy 378.221708 -239.360692) (xy 378.17555 -239.334043)
			(xy 378.133879 -239.300812) (xy 378.097627 -239.261741) (xy 378.067603 -239.217704) (xy 378.044477 -239.169683)
			(xy 378.028767 -239.118753) (xy 378.020824 -239.066049) (xy 377.79199 -239.066049) (xy 377.784047 -239.118753)
			(xy 377.768337 -239.169683) (xy 377.745211 -239.217704) (xy 377.715187 -239.261741) (xy 377.678935 -239.300812)
			(xy 377.637264 -239.334043) (xy 377.591106 -239.360692) (xy 377.541492 -239.380164) (xy 377.48953 -239.392024)
			(xy 377.43638 -239.396008) (xy 377.38323 -239.392024) (xy 377.331268 -239.380164) (xy 377.281654 -239.360692)
			(xy 377.235496 -239.334043) (xy 377.193825 -239.300812) (xy 377.157573 -239.261741) (xy 377.127549 -239.217704)
			(xy 377.104423 -239.169683) (xy 377.088713 -239.118753) (xy 377.08077 -239.066049) (xy 376.852444 -239.066049)
			(xy 376.844501 -239.118753) (xy 376.828791 -239.169683) (xy 376.805665 -239.217704) (xy 376.775641 -239.261741)
			(xy 376.739389 -239.300812) (xy 376.697718 -239.334043) (xy 376.65156 -239.360692) (xy 376.601946 -239.380164)
			(xy 376.549984 -239.392024) (xy 376.496834 -239.396008) (xy 376.443684 -239.392024) (xy 376.391722 -239.380164)
			(xy 376.342108 -239.360692) (xy 376.29595 -239.334043) (xy 376.254279 -239.300812) (xy 376.218027 -239.261741)
			(xy 376.188003 -239.217704) (xy 376.164877 -239.169683) (xy 376.149167 -239.118753) (xy 376.141224 -239.066049)
			(xy 375.912644 -239.066049) (xy 375.904701 -239.118753) (xy 375.888991 -239.169683) (xy 375.865865 -239.217704)
			(xy 375.835841 -239.261741) (xy 375.799589 -239.300812) (xy 375.757918 -239.334043) (xy 375.71176 -239.360692)
			(xy 375.662146 -239.380164) (xy 375.610184 -239.392024) (xy 375.557034 -239.396008) (xy 375.503884 -239.392024)
			(xy 375.451922 -239.380164) (xy 375.402308 -239.360692) (xy 375.35615 -239.334043) (xy 375.314479 -239.300812)
			(xy 375.278227 -239.261741) (xy 375.248203 -239.217704) (xy 375.225077 -239.169683) (xy 375.209367 -239.118753)
			(xy 375.201424 -239.066049) (xy 374.972844 -239.066049) (xy 374.964901 -239.118753) (xy 374.949191 -239.169683)
			(xy 374.926065 -239.217704) (xy 374.896041 -239.261741) (xy 374.859789 -239.300812) (xy 374.818118 -239.334043)
			(xy 374.77196 -239.360692) (xy 374.722346 -239.380164) (xy 374.670384 -239.392024) (xy 374.617234 -239.396008)
			(xy 374.564084 -239.392024) (xy 374.512122 -239.380164) (xy 374.462508 -239.360692) (xy 374.41635 -239.334043)
			(xy 374.374679 -239.300812) (xy 374.338427 -239.261741) (xy 374.308403 -239.217704) (xy 374.285277 -239.169683)
			(xy 374.269567 -239.118753) (xy 374.261624 -239.066049) (xy 374.033044 -239.066049) (xy 374.025101 -239.118753)
			(xy 374.009391 -239.169683) (xy 373.986265 -239.217704) (xy 373.956241 -239.261741) (xy 373.919989 -239.300812)
			(xy 373.878318 -239.334043) (xy 373.83216 -239.360692) (xy 373.782546 -239.380164) (xy 373.730584 -239.392024)
			(xy 373.677434 -239.396008) (xy 373.624284 -239.392024) (xy 373.572322 -239.380164) (xy 373.522708 -239.360692)
			(xy 373.47655 -239.334043) (xy 373.434879 -239.300812) (xy 373.398627 -239.261741) (xy 373.368603 -239.217704)
			(xy 373.345477 -239.169683) (xy 373.329767 -239.118753) (xy 373.321824 -239.066049) (xy 373.093244 -239.066049)
			(xy 373.085301 -239.118753) (xy 373.069591 -239.169683) (xy 373.046465 -239.217704) (xy 373.016441 -239.261741)
			(xy 372.980189 -239.300812) (xy 372.938518 -239.334043) (xy 372.89236 -239.360692) (xy 372.842746 -239.380164)
			(xy 372.790784 -239.392024) (xy 372.737634 -239.396008) (xy 372.684484 -239.392024) (xy 372.632522 -239.380164)
			(xy 372.582908 -239.360692) (xy 372.53675 -239.334043) (xy 372.495079 -239.300812) (xy 372.458827 -239.261741)
			(xy 372.428803 -239.217704) (xy 372.405677 -239.169683) (xy 372.389967 -239.118753) (xy 372.382024 -239.066049)
			(xy 372.153444 -239.066049) (xy 372.145501 -239.118753) (xy 372.129791 -239.169683) (xy 372.106665 -239.217704)
			(xy 372.076641 -239.261741) (xy 372.040389 -239.300812) (xy 371.998718 -239.334043) (xy 371.95256 -239.360692)
			(xy 371.902946 -239.380164) (xy 371.850984 -239.392024) (xy 371.797834 -239.396008) (xy 371.744684 -239.392024)
			(xy 371.692722 -239.380164) (xy 371.643108 -239.360692) (xy 371.59695 -239.334043) (xy 371.555279 -239.300812)
			(xy 371.519027 -239.261741) (xy 371.489003 -239.217704) (xy 371.465877 -239.169683) (xy 371.450167 -239.118753)
			(xy 371.442224 -239.066049) (xy 371.21339 -239.066049) (xy 371.205447 -239.118753) (xy 371.189737 -239.169683)
			(xy 371.166611 -239.217704) (xy 371.136587 -239.261741) (xy 371.100335 -239.300812) (xy 371.058664 -239.334043)
			(xy 371.012506 -239.360692) (xy 370.962892 -239.380164) (xy 370.91093 -239.392024) (xy 370.85778 -239.396008)
			(xy 370.80463 -239.392024) (xy 370.752668 -239.380164) (xy 370.703054 -239.360692) (xy 370.656896 -239.334043)
			(xy 370.615225 -239.300812) (xy 370.578973 -239.261741) (xy 370.548949 -239.217704) (xy 370.525823 -239.169683)
			(xy 370.510113 -239.118753) (xy 370.50217 -239.066049) (xy 370.273844 -239.066049) (xy 370.265901 -239.118753)
			(xy 370.250191 -239.169683) (xy 370.227065 -239.217704) (xy 370.197041 -239.261741) (xy 370.160789 -239.300812)
			(xy 370.119118 -239.334043) (xy 370.07296 -239.360692) (xy 370.023346 -239.380164) (xy 369.971384 -239.392024)
			(xy 369.918234 -239.396008) (xy 369.865084 -239.392024) (xy 369.813122 -239.380164) (xy 369.763508 -239.360692)
			(xy 369.71735 -239.334043) (xy 369.675679 -239.300812) (xy 369.639427 -239.261741) (xy 369.609403 -239.217704)
			(xy 369.586277 -239.169683) (xy 369.570567 -239.118753) (xy 369.562624 -239.066049) (xy 368.91468 -239.066049)
			(xy 368.91468 -239.762284) (xy 368.956082 -239.770158) (xy 368.965583 -239.771998) (xy 368.984389 -239.776574)
			(xy 368.993674 -239.779302) (xy 369.008288 -239.783197) (xy 369.038517 -239.783196) (xy 369.067424 -239.774354)
			(xy 369.092481 -239.757444) (xy 369.111496 -239.733945) (xy 369.117626 -239.72012) (xy 369.127974 -239.695769)
			(xy 369.154813 -239.650173) (xy 369.188097 -239.609045) (xy 369.227097 -239.573291) (xy 369.270954 -239.543696)
			(xy 369.318704 -239.52091) (xy 369.369299 -239.505434) (xy 369.421626 -239.497609) (xy 369.44808 -239.497108)
			(xy 369.474731 -239.49758) (xy 369.527438 -239.505521) (xy 369.578372 -239.52123) (xy 369.626396 -239.544355)
			(xy 369.670437 -239.574379) (xy 369.709512 -239.610633) (xy 369.742746 -239.652305) (xy 369.769397 -239.698465)
			(xy 369.788871 -239.748082) (xy 369.800733 -239.800047) (xy 369.804716 -239.8532) (xy 369.802718 -239.879865)
			(xy 370.032524 -239.879865) (xy 370.032524 -239.826567) (xy 370.040467 -239.773863) (xy 370.056177 -239.722933)
			(xy 370.079303 -239.674912) (xy 370.109327 -239.630875) (xy 370.145579 -239.591804) (xy 370.18725 -239.558573)
			(xy 370.233408 -239.531924) (xy 370.283022 -239.512452) (xy 370.334984 -239.500592) (xy 370.388134 -239.496609)
			(xy 370.441284 -239.500592) (xy 370.493246 -239.512452) (xy 370.54286 -239.531924) (xy 370.589018 -239.558573)
			(xy 370.630689 -239.591804) (xy 370.666941 -239.630875) (xy 370.696965 -239.674912) (xy 370.720091 -239.722933)
			(xy 370.735801 -239.773863) (xy 370.743744 -239.826567) (xy 370.744242 -239.853216) (xy 370.743744 -239.879865)
			(xy 370.97207 -239.879865) (xy 370.97207 -239.826567) (xy 370.980013 -239.773863) (xy 370.995723 -239.722933)
			(xy 371.018849 -239.674912) (xy 371.048873 -239.630875) (xy 371.085125 -239.591804) (xy 371.126796 -239.558573)
			(xy 371.172954 -239.531924) (xy 371.222568 -239.512452) (xy 371.27453 -239.500592) (xy 371.32768 -239.496609)
			(xy 371.38083 -239.500592) (xy 371.432792 -239.512452) (xy 371.482406 -239.531924) (xy 371.528564 -239.558573)
			(xy 371.570235 -239.591804) (xy 371.606487 -239.630875) (xy 371.636511 -239.674912) (xy 371.659637 -239.722933)
			(xy 371.675347 -239.773863) (xy 371.68329 -239.826567) (xy 371.683788 -239.853216) (xy 371.68329 -239.879865)
			(xy 371.91187 -239.879865) (xy 371.91187 -239.826567) (xy 371.919813 -239.773863) (xy 371.935523 -239.722933)
			(xy 371.958649 -239.674912) (xy 371.988673 -239.630875) (xy 372.024925 -239.591804) (xy 372.066596 -239.558573)
			(xy 372.112754 -239.531924) (xy 372.162368 -239.512452) (xy 372.21433 -239.500592) (xy 372.26748 -239.496609)
			(xy 372.32063 -239.500592) (xy 372.372592 -239.512452) (xy 372.422206 -239.531924) (xy 372.468364 -239.558573)
			(xy 372.510035 -239.591804) (xy 372.546287 -239.630875) (xy 372.576311 -239.674912) (xy 372.599437 -239.722933)
			(xy 372.615147 -239.773863) (xy 372.62309 -239.826567) (xy 372.623588 -239.853216) (xy 372.62309 -239.879865)
			(xy 372.851924 -239.879865) (xy 372.851924 -239.826567) (xy 372.859867 -239.773863) (xy 372.875577 -239.722933)
			(xy 372.898703 -239.674912) (xy 372.928727 -239.630875) (xy 372.964979 -239.591804) (xy 373.00665 -239.558573)
			(xy 373.052808 -239.531924) (xy 373.102422 -239.512452) (xy 373.154384 -239.500592) (xy 373.207534 -239.496609)
			(xy 373.260684 -239.500592) (xy 373.312646 -239.512452) (xy 373.36226 -239.531924) (xy 373.408418 -239.558573)
			(xy 373.450089 -239.591804) (xy 373.486341 -239.630875) (xy 373.516365 -239.674912) (xy 373.539491 -239.722933)
			(xy 373.555201 -239.773863) (xy 373.563144 -239.826567) (xy 373.563642 -239.853216) (xy 373.563144 -239.879865)
			(xy 373.79147 -239.879865) (xy 373.79147 -239.826567) (xy 373.799413 -239.773863) (xy 373.815123 -239.722933)
			(xy 373.838249 -239.674912) (xy 373.868273 -239.630875) (xy 373.904525 -239.591804) (xy 373.946196 -239.558573)
			(xy 373.992354 -239.531924) (xy 374.041968 -239.512452) (xy 374.09393 -239.500592) (xy 374.14708 -239.496609)
			(xy 374.20023 -239.500592) (xy 374.252192 -239.512452) (xy 374.301806 -239.531924) (xy 374.347964 -239.558573)
			(xy 374.389635 -239.591804) (xy 374.425887 -239.630875) (xy 374.455911 -239.674912) (xy 374.479037 -239.722933)
			(xy 374.494747 -239.773863) (xy 374.50269 -239.826567) (xy 374.503188 -239.853216) (xy 374.50269 -239.879865)
			(xy 374.73127 -239.879865) (xy 374.73127 -239.826567) (xy 374.739213 -239.773863) (xy 374.754923 -239.722933)
			(xy 374.778049 -239.674912) (xy 374.808073 -239.630875) (xy 374.844325 -239.591804) (xy 374.885996 -239.558573)
			(xy 374.932154 -239.531924) (xy 374.981768 -239.512452) (xy 375.03373 -239.500592) (xy 375.08688 -239.496609)
			(xy 375.14003 -239.500592) (xy 375.191992 -239.512452) (xy 375.241606 -239.531924) (xy 375.287764 -239.558573)
			(xy 375.329435 -239.591804) (xy 375.365687 -239.630875) (xy 375.395711 -239.674912) (xy 375.418837 -239.722933)
			(xy 375.434547 -239.773863) (xy 375.44249 -239.826567) (xy 375.442988 -239.853216) (xy 375.44249 -239.879865)
			(xy 375.67107 -239.879865) (xy 375.67107 -239.826567) (xy 375.679013 -239.773863) (xy 375.694723 -239.722933)
			(xy 375.717849 -239.674912) (xy 375.747873 -239.630875) (xy 375.784125 -239.591804) (xy 375.825796 -239.558573)
			(xy 375.871954 -239.531924) (xy 375.921568 -239.512452) (xy 375.97353 -239.500592) (xy 376.02668 -239.496609)
			(xy 376.07983 -239.500592) (xy 376.131792 -239.512452) (xy 376.181406 -239.531924) (xy 376.227564 -239.558573)
			(xy 376.269235 -239.591804) (xy 376.305487 -239.630875) (xy 376.335511 -239.674912) (xy 376.358637 -239.722933)
			(xy 376.374347 -239.773863) (xy 376.38229 -239.826567) (xy 376.382788 -239.853216) (xy 376.38229 -239.879865)
			(xy 376.61087 -239.879865) (xy 376.61087 -239.826567) (xy 376.618813 -239.773863) (xy 376.634523 -239.722933)
			(xy 376.657649 -239.674912) (xy 376.687673 -239.630875) (xy 376.723925 -239.591804) (xy 376.765596 -239.558573)
			(xy 376.811754 -239.531924) (xy 376.861368 -239.512452) (xy 376.91333 -239.500592) (xy 376.96648 -239.496609)
			(xy 377.01963 -239.500592) (xy 377.071592 -239.512452) (xy 377.121206 -239.531924) (xy 377.167364 -239.558573)
			(xy 377.209035 -239.591804) (xy 377.245287 -239.630875) (xy 377.275311 -239.674912) (xy 377.298437 -239.722933)
			(xy 377.314147 -239.773863) (xy 377.32209 -239.826567) (xy 377.322588 -239.853216) (xy 377.32209 -239.879865)
			(xy 377.55067 -239.879865) (xy 377.55067 -239.826567) (xy 377.558613 -239.773863) (xy 377.574323 -239.722933)
			(xy 377.597449 -239.674912) (xy 377.627473 -239.630875) (xy 377.663725 -239.591804) (xy 377.705396 -239.558573)
			(xy 377.751554 -239.531924) (xy 377.801168 -239.512452) (xy 377.85313 -239.500592) (xy 377.90628 -239.496609)
			(xy 377.95943 -239.500592) (xy 378.011392 -239.512452) (xy 378.061006 -239.531924) (xy 378.107164 -239.558573)
			(xy 378.148835 -239.591804) (xy 378.185087 -239.630875) (xy 378.215111 -239.674912) (xy 378.238237 -239.722933)
			(xy 378.253947 -239.773863) (xy 378.26189 -239.826567) (xy 378.262388 -239.853216) (xy 378.26189 -239.879865)
			(xy 378.49047 -239.879865) (xy 378.49047 -239.826567) (xy 378.498413 -239.773863) (xy 378.514123 -239.722933)
			(xy 378.537249 -239.674912) (xy 378.567273 -239.630875) (xy 378.603525 -239.591804) (xy 378.645196 -239.558573)
			(xy 378.691354 -239.531924) (xy 378.740968 -239.512452) (xy 378.79293 -239.500592) (xy 378.84608 -239.496609)
			(xy 378.89923 -239.500592) (xy 378.951192 -239.512452) (xy 379.000806 -239.531924) (xy 379.046964 -239.558573)
			(xy 379.088635 -239.591804) (xy 379.124887 -239.630875) (xy 379.154911 -239.674912) (xy 379.178037 -239.722933)
			(xy 379.193747 -239.773863) (xy 379.20169 -239.826567) (xy 379.202188 -239.853216) (xy 379.20169 -239.879865)
			(xy 379.430524 -239.879865) (xy 379.430524 -239.826567) (xy 379.438467 -239.773863) (xy 379.454177 -239.722933)
			(xy 379.477303 -239.674912) (xy 379.507327 -239.630875) (xy 379.543579 -239.591804) (xy 379.58525 -239.558573)
			(xy 379.631408 -239.531924) (xy 379.681022 -239.512452) (xy 379.732984 -239.500592) (xy 379.786134 -239.496609)
			(xy 379.839284 -239.500592) (xy 379.891246 -239.512452) (xy 379.94086 -239.531924) (xy 379.987018 -239.558573)
			(xy 380.028689 -239.591804) (xy 380.064941 -239.630875) (xy 380.094965 -239.674912) (xy 380.118091 -239.722933)
			(xy 380.133801 -239.773863) (xy 380.141744 -239.826567) (xy 380.142242 -239.853216) (xy 380.141744 -239.879865)
			(xy 380.37007 -239.879865) (xy 380.37007 -239.826567) (xy 380.378013 -239.773863) (xy 380.393723 -239.722933)
			(xy 380.416849 -239.674912) (xy 380.446873 -239.630875) (xy 380.483125 -239.591804) (xy 380.524796 -239.558573)
			(xy 380.570954 -239.531924) (xy 380.620568 -239.512452) (xy 380.67253 -239.500592) (xy 380.72568 -239.496609)
			(xy 380.77883 -239.500592) (xy 380.830792 -239.512452) (xy 380.880406 -239.531924) (xy 380.926564 -239.558573)
			(xy 380.968235 -239.591804) (xy 381.004487 -239.630875) (xy 381.034511 -239.674912) (xy 381.057637 -239.722933)
			(xy 381.073347 -239.773863) (xy 381.08129 -239.826567) (xy 381.081788 -239.853216) (xy 381.08129 -239.879865)
			(xy 381.073347 -239.932569) (xy 381.057637 -239.983499) (xy 381.034511 -240.03152) (xy 381.004487 -240.075557)
			(xy 380.968235 -240.114628) (xy 380.926564 -240.147859) (xy 380.880406 -240.174508) (xy 380.830792 -240.19398)
			(xy 380.77883 -240.20584) (xy 380.72568 -240.209824) (xy 380.67253 -240.20584) (xy 380.620568 -240.19398)
			(xy 380.570954 -240.174508) (xy 380.524796 -240.147859) (xy 380.483125 -240.114628) (xy 380.446873 -240.075557)
			(xy 380.416849 -240.03152) (xy 380.393723 -239.983499) (xy 380.378013 -239.932569) (xy 380.37007 -239.879865)
			(xy 380.141744 -239.879865) (xy 380.133801 -239.932569) (xy 380.118091 -239.983499) (xy 380.094965 -240.03152)
			(xy 380.064941 -240.075557) (xy 380.028689 -240.114628) (xy 379.987018 -240.147859) (xy 379.94086 -240.174508)
			(xy 379.891246 -240.19398) (xy 379.839284 -240.20584) (xy 379.786134 -240.209824) (xy 379.732984 -240.20584)
			(xy 379.681022 -240.19398) (xy 379.631408 -240.174508) (xy 379.58525 -240.147859) (xy 379.543579 -240.114628)
			(xy 379.507327 -240.075557) (xy 379.477303 -240.03152) (xy 379.454177 -239.983499) (xy 379.438467 -239.932569)
			(xy 379.430524 -239.879865) (xy 379.20169 -239.879865) (xy 379.193747 -239.932569) (xy 379.178037 -239.983499)
			(xy 379.154911 -240.03152) (xy 379.124887 -240.075557) (xy 379.088635 -240.114628) (xy 379.046964 -240.147859)
			(xy 379.000806 -240.174508) (xy 378.951192 -240.19398) (xy 378.89923 -240.20584) (xy 378.84608 -240.209824)
			(xy 378.79293 -240.20584) (xy 378.740968 -240.19398) (xy 378.691354 -240.174508) (xy 378.645196 -240.147859)
			(xy 378.603525 -240.114628) (xy 378.567273 -240.075557) (xy 378.537249 -240.03152) (xy 378.514123 -239.983499)
			(xy 378.498413 -239.932569) (xy 378.49047 -239.879865) (xy 378.26189 -239.879865) (xy 378.253947 -239.932569)
			(xy 378.238237 -239.983499) (xy 378.215111 -240.03152) (xy 378.185087 -240.075557) (xy 378.148835 -240.114628)
			(xy 378.107164 -240.147859) (xy 378.061006 -240.174508) (xy 378.011392 -240.19398) (xy 377.95943 -240.20584)
			(xy 377.90628 -240.209824) (xy 377.85313 -240.20584) (xy 377.801168 -240.19398) (xy 377.751554 -240.174508)
			(xy 377.705396 -240.147859) (xy 377.663725 -240.114628) (xy 377.627473 -240.075557) (xy 377.597449 -240.03152)
			(xy 377.574323 -239.983499) (xy 377.558613 -239.932569) (xy 377.55067 -239.879865) (xy 377.32209 -239.879865)
			(xy 377.314147 -239.932569) (xy 377.298437 -239.983499) (xy 377.275311 -240.03152) (xy 377.245287 -240.075557)
			(xy 377.209035 -240.114628) (xy 377.167364 -240.147859) (xy 377.121206 -240.174508) (xy 377.071592 -240.19398)
			(xy 377.01963 -240.20584) (xy 376.96648 -240.209824) (xy 376.91333 -240.20584) (xy 376.861368 -240.19398)
			(xy 376.811754 -240.174508) (xy 376.765596 -240.147859) (xy 376.723925 -240.114628) (xy 376.687673 -240.075557)
			(xy 376.657649 -240.03152) (xy 376.634523 -239.983499) (xy 376.618813 -239.932569) (xy 376.61087 -239.879865)
			(xy 376.38229 -239.879865) (xy 376.374347 -239.932569) (xy 376.358637 -239.983499) (xy 376.335511 -240.03152)
			(xy 376.305487 -240.075557) (xy 376.269235 -240.114628) (xy 376.227564 -240.147859) (xy 376.181406 -240.174508)
			(xy 376.131792 -240.19398) (xy 376.07983 -240.20584) (xy 376.02668 -240.209824) (xy 375.97353 -240.20584)
			(xy 375.921568 -240.19398) (xy 375.871954 -240.174508) (xy 375.825796 -240.147859) (xy 375.784125 -240.114628)
			(xy 375.747873 -240.075557) (xy 375.717849 -240.03152) (xy 375.694723 -239.983499) (xy 375.679013 -239.932569)
			(xy 375.67107 -239.879865) (xy 375.44249 -239.879865) (xy 375.434547 -239.932569) (xy 375.418837 -239.983499)
			(xy 375.395711 -240.03152) (xy 375.365687 -240.075557) (xy 375.329435 -240.114628) (xy 375.287764 -240.147859)
			(xy 375.241606 -240.174508) (xy 375.191992 -240.19398) (xy 375.14003 -240.20584) (xy 375.08688 -240.209824)
			(xy 375.03373 -240.20584) (xy 374.981768 -240.19398) (xy 374.932154 -240.174508) (xy 374.885996 -240.147859)
			(xy 374.844325 -240.114628) (xy 374.808073 -240.075557) (xy 374.778049 -240.03152) (xy 374.754923 -239.983499)
			(xy 374.739213 -239.932569) (xy 374.73127 -239.879865) (xy 374.50269 -239.879865) (xy 374.494747 -239.932569)
			(xy 374.479037 -239.983499) (xy 374.455911 -240.03152) (xy 374.425887 -240.075557) (xy 374.389635 -240.114628)
			(xy 374.347964 -240.147859) (xy 374.301806 -240.174508) (xy 374.252192 -240.19398) (xy 374.20023 -240.20584)
			(xy 374.14708 -240.209824) (xy 374.09393 -240.20584) (xy 374.041968 -240.19398) (xy 373.992354 -240.174508)
			(xy 373.946196 -240.147859) (xy 373.904525 -240.114628) (xy 373.868273 -240.075557) (xy 373.838249 -240.03152)
			(xy 373.815123 -239.983499) (xy 373.799413 -239.932569) (xy 373.79147 -239.879865) (xy 373.563144 -239.879865)
			(xy 373.555201 -239.932569) (xy 373.539491 -239.983499) (xy 373.516365 -240.03152) (xy 373.486341 -240.075557)
			(xy 373.450089 -240.114628) (xy 373.408418 -240.147859) (xy 373.36226 -240.174508) (xy 373.312646 -240.19398)
			(xy 373.260684 -240.20584) (xy 373.207534 -240.209824) (xy 373.154384 -240.20584) (xy 373.102422 -240.19398)
			(xy 373.052808 -240.174508) (xy 373.00665 -240.147859) (xy 372.964979 -240.114628) (xy 372.928727 -240.075557)
			(xy 372.898703 -240.03152) (xy 372.875577 -239.983499) (xy 372.859867 -239.932569) (xy 372.851924 -239.879865)
			(xy 372.62309 -239.879865) (xy 372.615147 -239.932569) (xy 372.599437 -239.983499) (xy 372.576311 -240.03152)
			(xy 372.546287 -240.075557) (xy 372.510035 -240.114628) (xy 372.468364 -240.147859) (xy 372.422206 -240.174508)
			(xy 372.372592 -240.19398) (xy 372.32063 -240.20584) (xy 372.26748 -240.209824) (xy 372.21433 -240.20584)
			(xy 372.162368 -240.19398) (xy 372.112754 -240.174508) (xy 372.066596 -240.147859) (xy 372.024925 -240.114628)
			(xy 371.988673 -240.075557) (xy 371.958649 -240.03152) (xy 371.935523 -239.983499) (xy 371.919813 -239.932569)
			(xy 371.91187 -239.879865) (xy 371.68329 -239.879865) (xy 371.675347 -239.932569) (xy 371.659637 -239.983499)
			(xy 371.636511 -240.03152) (xy 371.606487 -240.075557) (xy 371.570235 -240.114628) (xy 371.528564 -240.147859)
			(xy 371.482406 -240.174508) (xy 371.432792 -240.19398) (xy 371.38083 -240.20584) (xy 371.32768 -240.209824)
			(xy 371.27453 -240.20584) (xy 371.222568 -240.19398) (xy 371.172954 -240.174508) (xy 371.126796 -240.147859)
			(xy 371.085125 -240.114628) (xy 371.048873 -240.075557) (xy 371.018849 -240.03152) (xy 370.995723 -239.983499)
			(xy 370.980013 -239.932569) (xy 370.97207 -239.879865) (xy 370.743744 -239.879865) (xy 370.735801 -239.932569)
			(xy 370.720091 -239.983499) (xy 370.696965 -240.03152) (xy 370.666941 -240.075557) (xy 370.630689 -240.114628)
			(xy 370.589018 -240.147859) (xy 370.54286 -240.174508) (xy 370.493246 -240.19398) (xy 370.441284 -240.20584)
			(xy 370.388134 -240.209824) (xy 370.334984 -240.20584) (xy 370.283022 -240.19398) (xy 370.233408 -240.174508)
			(xy 370.18725 -240.147859) (xy 370.145579 -240.114628) (xy 370.109327 -240.075557) (xy 370.079303 -240.03152)
			(xy 370.056177 -239.983499) (xy 370.040467 -239.932569) (xy 370.032524 -239.879865) (xy 369.802718 -239.879865)
			(xy 369.800733 -239.906353) (xy 369.788871 -239.958318) (xy 369.769397 -240.007935) (xy 369.742746 -240.054095)
			(xy 369.709512 -240.095767) (xy 369.670437 -240.132021) (xy 369.626396 -240.162045) (xy 369.578372 -240.18517)
			(xy 369.527438 -240.200879) (xy 369.474731 -240.20882) (xy 369.44808 -240.209324) (xy 369.447572 -240.209324)
			(xy 369.421268 -240.208834) (xy 369.369236 -240.201059) (xy 369.34394 -240.19383) (xy 369.329326 -240.189932)
			(xy 369.299095 -240.189929) (xy 369.270187 -240.19877) (xy 369.245129 -240.215683) (xy 369.226116 -240.239185)
			(xy 369.219988 -240.253012) (xy 369.209164 -240.278383) (xy 369.180839 -240.325713) (xy 369.1636 -240.347246)
			(xy 369.154973 -240.358375) (xy 369.143626 -240.384134) (xy 369.139748 -240.412012) (xy 369.143633 -240.43989)
			(xy 369.154986 -240.465646) (xy 369.1636 -240.476786) (xy 369.179037 -240.496034) (xy 369.205009 -240.537984)
			(xy 369.224933 -240.583121) (xy 369.238427 -240.630579) (xy 369.245231 -240.679446) (xy 369.245472 -240.693935)
			(xy 369.562624 -240.693935) (xy 369.562624 -240.640637) (xy 369.570567 -240.587933) (xy 369.586277 -240.537003)
			(xy 369.609403 -240.488982) (xy 369.639427 -240.444945) (xy 369.675679 -240.405874) (xy 369.71735 -240.372643)
			(xy 369.763508 -240.345994) (xy 369.813122 -240.326522) (xy 369.865084 -240.314662) (xy 369.918234 -240.310679)
			(xy 369.971384 -240.314662) (xy 370.023346 -240.326522) (xy 370.07296 -240.345994) (xy 370.119118 -240.372643)
			(xy 370.160789 -240.405874) (xy 370.197041 -240.444945) (xy 370.227065 -240.488982) (xy 370.250191 -240.537003)
			(xy 370.265901 -240.587933) (xy 370.273844 -240.640637) (xy 370.274342 -240.667286) (xy 370.273844 -240.693935)
			(xy 370.50217 -240.693935) (xy 370.50217 -240.640637) (xy 370.510113 -240.587933) (xy 370.525823 -240.537003)
			(xy 370.548949 -240.488982) (xy 370.578973 -240.444945) (xy 370.615225 -240.405874) (xy 370.656896 -240.372643)
			(xy 370.703054 -240.345994) (xy 370.752668 -240.326522) (xy 370.80463 -240.314662) (xy 370.85778 -240.310679)
			(xy 370.91093 -240.314662) (xy 370.962892 -240.326522) (xy 371.012506 -240.345994) (xy 371.058664 -240.372643)
			(xy 371.100335 -240.405874) (xy 371.136587 -240.444945) (xy 371.166611 -240.488982) (xy 371.189737 -240.537003)
			(xy 371.205447 -240.587933) (xy 371.21339 -240.640637) (xy 371.213888 -240.667286) (xy 371.21339 -240.693935)
			(xy 371.442224 -240.693935) (xy 371.442224 -240.640637) (xy 371.450167 -240.587933) (xy 371.465877 -240.537003)
			(xy 371.489003 -240.488982) (xy 371.519027 -240.444945) (xy 371.555279 -240.405874) (xy 371.59695 -240.372643)
			(xy 371.643108 -240.345994) (xy 371.692722 -240.326522) (xy 371.744684 -240.314662) (xy 371.797834 -240.310679)
			(xy 371.850984 -240.314662) (xy 371.902946 -240.326522) (xy 371.95256 -240.345994) (xy 371.998718 -240.372643)
			(xy 372.040389 -240.405874) (xy 372.076641 -240.444945) (xy 372.106665 -240.488982) (xy 372.129791 -240.537003)
			(xy 372.145501 -240.587933) (xy 372.153444 -240.640637) (xy 372.153942 -240.667286) (xy 372.153444 -240.693935)
			(xy 372.382024 -240.693935) (xy 372.382024 -240.640637) (xy 372.389967 -240.587933) (xy 372.405677 -240.537003)
			(xy 372.428803 -240.488982) (xy 372.458827 -240.444945) (xy 372.495079 -240.405874) (xy 372.53675 -240.372643)
			(xy 372.582908 -240.345994) (xy 372.632522 -240.326522) (xy 372.684484 -240.314662) (xy 372.737634 -240.310679)
			(xy 372.790784 -240.314662) (xy 372.842746 -240.326522) (xy 372.89236 -240.345994) (xy 372.938518 -240.372643)
			(xy 372.980189 -240.405874) (xy 373.016441 -240.444945) (xy 373.046465 -240.488982) (xy 373.069591 -240.537003)
			(xy 373.085301 -240.587933) (xy 373.093244 -240.640637) (xy 373.093742 -240.667286) (xy 373.093244 -240.693935)
			(xy 373.32157 -240.693935) (xy 373.32157 -240.640637) (xy 373.329513 -240.587933) (xy 373.345223 -240.537003)
			(xy 373.368349 -240.488982) (xy 373.398373 -240.444945) (xy 373.434625 -240.405874) (xy 373.476296 -240.372643)
			(xy 373.522454 -240.345994) (xy 373.572068 -240.326522) (xy 373.62403 -240.314662) (xy 373.67718 -240.310679)
			(xy 373.73033 -240.314662) (xy 373.782292 -240.326522) (xy 373.831906 -240.345994) (xy 373.878064 -240.372643)
			(xy 373.919735 -240.405874) (xy 373.955987 -240.444945) (xy 373.986011 -240.488982) (xy 374.009137 -240.537003)
			(xy 374.024847 -240.587933) (xy 374.03279 -240.640637) (xy 374.033288 -240.667286) (xy 374.03279 -240.693935)
			(xy 374.261624 -240.693935) (xy 374.261624 -240.640637) (xy 374.269567 -240.587933) (xy 374.285277 -240.537003)
			(xy 374.308403 -240.488982) (xy 374.338427 -240.444945) (xy 374.374679 -240.405874) (xy 374.41635 -240.372643)
			(xy 374.462508 -240.345994) (xy 374.512122 -240.326522) (xy 374.564084 -240.314662) (xy 374.617234 -240.310679)
			(xy 374.670384 -240.314662) (xy 374.722346 -240.326522) (xy 374.77196 -240.345994) (xy 374.818118 -240.372643)
			(xy 374.859789 -240.405874) (xy 374.896041 -240.444945) (xy 374.926065 -240.488982) (xy 374.949191 -240.537003)
			(xy 374.964901 -240.587933) (xy 374.972844 -240.640637) (xy 374.973342 -240.667286) (xy 374.972844 -240.693935)
			(xy 375.201424 -240.693935) (xy 375.201424 -240.640637) (xy 375.209367 -240.587933) (xy 375.225077 -240.537003)
			(xy 375.248203 -240.488982) (xy 375.278227 -240.444945) (xy 375.314479 -240.405874) (xy 375.35615 -240.372643)
			(xy 375.402308 -240.345994) (xy 375.451922 -240.326522) (xy 375.503884 -240.314662) (xy 375.557034 -240.310679)
			(xy 375.610184 -240.314662) (xy 375.662146 -240.326522) (xy 375.71176 -240.345994) (xy 375.757918 -240.372643)
			(xy 375.799589 -240.405874) (xy 375.835841 -240.444945) (xy 375.865865 -240.488982) (xy 375.888991 -240.537003)
			(xy 375.904701 -240.587933) (xy 375.912644 -240.640637) (xy 375.913142 -240.667286) (xy 375.912644 -240.693935)
			(xy 376.141224 -240.693935) (xy 376.141224 -240.640637) (xy 376.149167 -240.587933) (xy 376.164877 -240.537003)
			(xy 376.188003 -240.488982) (xy 376.218027 -240.444945) (xy 376.254279 -240.405874) (xy 376.29595 -240.372643)
			(xy 376.342108 -240.345994) (xy 376.391722 -240.326522) (xy 376.443684 -240.314662) (xy 376.496834 -240.310679)
			(xy 376.549984 -240.314662) (xy 376.601946 -240.326522) (xy 376.65156 -240.345994) (xy 376.697718 -240.372643)
			(xy 376.739389 -240.405874) (xy 376.775641 -240.444945) (xy 376.805665 -240.488982) (xy 376.828791 -240.537003)
			(xy 376.844501 -240.587933) (xy 376.852444 -240.640637) (xy 376.852942 -240.667286) (xy 376.852444 -240.693935)
			(xy 377.081024 -240.693935) (xy 377.081024 -240.640637) (xy 377.088967 -240.587933) (xy 377.104677 -240.537003)
			(xy 377.127803 -240.488982) (xy 377.157827 -240.444945) (xy 377.194079 -240.405874) (xy 377.23575 -240.372643)
			(xy 377.281908 -240.345994) (xy 377.331522 -240.326522) (xy 377.383484 -240.314662) (xy 377.436634 -240.310679)
			(xy 377.489784 -240.314662) (xy 377.541746 -240.326522) (xy 377.59136 -240.345994) (xy 377.637518 -240.372643)
			(xy 377.679189 -240.405874) (xy 377.715441 -240.444945) (xy 377.745465 -240.488982) (xy 377.768591 -240.537003)
			(xy 377.784301 -240.587933) (xy 377.792244 -240.640637) (xy 377.792742 -240.667286) (xy 377.792244 -240.693935)
			(xy 378.020824 -240.693935) (xy 378.020824 -240.640637) (xy 378.028767 -240.587933) (xy 378.044477 -240.537003)
			(xy 378.067603 -240.488982) (xy 378.097627 -240.444945) (xy 378.133879 -240.405874) (xy 378.17555 -240.372643)
			(xy 378.221708 -240.345994) (xy 378.271322 -240.326522) (xy 378.323284 -240.314662) (xy 378.376434 -240.310679)
			(xy 378.429584 -240.314662) (xy 378.481546 -240.326522) (xy 378.53116 -240.345994) (xy 378.577318 -240.372643)
			(xy 378.618989 -240.405874) (xy 378.655241 -240.444945) (xy 378.685265 -240.488982) (xy 378.708391 -240.537003)
			(xy 378.724101 -240.587933) (xy 378.732044 -240.640637) (xy 378.732542 -240.667286) (xy 378.732044 -240.693935)
			(xy 378.960624 -240.693935) (xy 378.960624 -240.640637) (xy 378.968567 -240.587933) (xy 378.984277 -240.537003)
			(xy 379.007403 -240.488982) (xy 379.037427 -240.444945) (xy 379.073679 -240.405874) (xy 379.11535 -240.372643)
			(xy 379.161508 -240.345994) (xy 379.211122 -240.326522) (xy 379.263084 -240.314662) (xy 379.316234 -240.310679)
			(xy 379.369384 -240.314662) (xy 379.421346 -240.326522) (xy 379.47096 -240.345994) (xy 379.517118 -240.372643)
			(xy 379.558789 -240.405874) (xy 379.595041 -240.444945) (xy 379.625065 -240.488982) (xy 379.648191 -240.537003)
			(xy 379.663901 -240.587933) (xy 379.671844 -240.640637) (xy 379.672342 -240.667286) (xy 379.671844 -240.693935)
			(xy 379.90017 -240.693935) (xy 379.90017 -240.640637) (xy 379.908113 -240.587933) (xy 379.923823 -240.537003)
			(xy 379.946949 -240.488982) (xy 379.976973 -240.444945) (xy 380.013225 -240.405874) (xy 380.054896 -240.372643)
			(xy 380.101054 -240.345994) (xy 380.150668 -240.326522) (xy 380.20263 -240.314662) (xy 380.25578 -240.310679)
			(xy 380.30893 -240.314662) (xy 380.360892 -240.326522) (xy 380.410506 -240.345994) (xy 380.456664 -240.372643)
			(xy 380.498335 -240.405874) (xy 380.534587 -240.444945) (xy 380.564611 -240.488982) (xy 380.587737 -240.537003)
			(xy 380.603447 -240.587933) (xy 380.61139 -240.640637) (xy 380.611888 -240.667286) (xy 380.61139 -240.693935)
			(xy 380.840224 -240.693935) (xy 380.840224 -240.640637) (xy 380.848167 -240.587933) (xy 380.863877 -240.537003)
			(xy 380.887003 -240.488982) (xy 380.917027 -240.444945) (xy 380.953279 -240.405874) (xy 380.99495 -240.372643)
			(xy 381.041108 -240.345994) (xy 381.090722 -240.326522) (xy 381.142684 -240.314662) (xy 381.195834 -240.310679)
			(xy 381.248984 -240.314662) (xy 381.300946 -240.326522) (xy 381.35056 -240.345994) (xy 381.396718 -240.372643)
			(xy 381.438389 -240.405874) (xy 381.474641 -240.444945) (xy 381.504665 -240.488982) (xy 381.527791 -240.537003)
			(xy 381.543501 -240.587933) (xy 381.551444 -240.640637) (xy 381.551942 -240.667286) (xy 381.551444 -240.693935)
			(xy 381.543501 -240.746639) (xy 381.527791 -240.797569) (xy 381.504665 -240.84559) (xy 381.474641 -240.889627)
			(xy 381.438389 -240.928698) (xy 381.396718 -240.961929) (xy 381.35056 -240.988578) (xy 381.300946 -241.00805)
			(xy 381.248984 -241.01991) (xy 381.195834 -241.023894) (xy 381.142684 -241.01991) (xy 381.090722 -241.00805)
			(xy 381.041108 -240.988578) (xy 380.99495 -240.961929) (xy 380.953279 -240.928698) (xy 380.917027 -240.889627)
			(xy 380.887003 -240.84559) (xy 380.863877 -240.797569) (xy 380.848167 -240.746639) (xy 380.840224 -240.693935)
			(xy 380.61139 -240.693935) (xy 380.603447 -240.746639) (xy 380.587737 -240.797569) (xy 380.564611 -240.84559)
			(xy 380.534587 -240.889627) (xy 380.498335 -240.928698) (xy 380.456664 -240.961929) (xy 380.410506 -240.988578)
			(xy 380.360892 -241.00805) (xy 380.30893 -241.01991) (xy 380.25578 -241.023894) (xy 380.20263 -241.01991)
			(xy 380.150668 -241.00805) (xy 380.101054 -240.988578) (xy 380.054896 -240.961929) (xy 380.013225 -240.928698)
			(xy 379.976973 -240.889627) (xy 379.946949 -240.84559) (xy 379.923823 -240.797569) (xy 379.908113 -240.746639)
			(xy 379.90017 -240.693935) (xy 379.671844 -240.693935) (xy 379.663901 -240.746639) (xy 379.648191 -240.797569)
			(xy 379.625065 -240.84559) (xy 379.595041 -240.889627) (xy 379.558789 -240.928698) (xy 379.517118 -240.961929)
			(xy 379.47096 -240.988578) (xy 379.421346 -241.00805) (xy 379.369384 -241.01991) (xy 379.316234 -241.023894)
			(xy 379.263084 -241.01991) (xy 379.211122 -241.00805) (xy 379.161508 -240.988578) (xy 379.11535 -240.961929)
			(xy 379.073679 -240.928698) (xy 379.037427 -240.889627) (xy 379.007403 -240.84559) (xy 378.984277 -240.797569)
			(xy 378.968567 -240.746639) (xy 378.960624 -240.693935) (xy 378.732044 -240.693935) (xy 378.724101 -240.746639)
			(xy 378.708391 -240.797569) (xy 378.685265 -240.84559) (xy 378.655241 -240.889627) (xy 378.618989 -240.928698)
			(xy 378.577318 -240.961929) (xy 378.53116 -240.988578) (xy 378.481546 -241.00805) (xy 378.429584 -241.01991)
			(xy 378.376434 -241.023894) (xy 378.323284 -241.01991) (xy 378.271322 -241.00805) (xy 378.221708 -240.988578)
			(xy 378.17555 -240.961929) (xy 378.133879 -240.928698) (xy 378.097627 -240.889627) (xy 378.067603 -240.84559)
			(xy 378.044477 -240.797569) (xy 378.028767 -240.746639) (xy 378.020824 -240.693935) (xy 377.792244 -240.693935)
			(xy 377.784301 -240.746639) (xy 377.768591 -240.797569) (xy 377.745465 -240.84559) (xy 377.715441 -240.889627)
			(xy 377.679189 -240.928698) (xy 377.637518 -240.961929) (xy 377.59136 -240.988578) (xy 377.541746 -241.00805)
			(xy 377.489784 -241.01991) (xy 377.436634 -241.023894) (xy 377.383484 -241.01991) (xy 377.331522 -241.00805)
			(xy 377.281908 -240.988578) (xy 377.23575 -240.961929) (xy 377.194079 -240.928698) (xy 377.157827 -240.889627)
			(xy 377.127803 -240.84559) (xy 377.104677 -240.797569) (xy 377.088967 -240.746639) (xy 377.081024 -240.693935)
			(xy 376.852444 -240.693935) (xy 376.844501 -240.746639) (xy 376.828791 -240.797569) (xy 376.805665 -240.84559)
			(xy 376.775641 -240.889627) (xy 376.739389 -240.928698) (xy 376.697718 -240.961929) (xy 376.65156 -240.988578)
			(xy 376.601946 -241.00805) (xy 376.549984 -241.01991) (xy 376.496834 -241.023894) (xy 376.443684 -241.01991)
			(xy 376.391722 -241.00805) (xy 376.342108 -240.988578) (xy 376.29595 -240.961929) (xy 376.254279 -240.928698)
			(xy 376.218027 -240.889627) (xy 376.188003 -240.84559) (xy 376.164877 -240.797569) (xy 376.149167 -240.746639)
			(xy 376.141224 -240.693935) (xy 375.912644 -240.693935) (xy 375.904701 -240.746639) (xy 375.888991 -240.797569)
			(xy 375.865865 -240.84559) (xy 375.835841 -240.889627) (xy 375.799589 -240.928698) (xy 375.757918 -240.961929)
			(xy 375.71176 -240.988578) (xy 375.662146 -241.00805) (xy 375.610184 -241.01991) (xy 375.557034 -241.023894)
			(xy 375.503884 -241.01991) (xy 375.451922 -241.00805) (xy 375.402308 -240.988578) (xy 375.35615 -240.961929)
			(xy 375.314479 -240.928698) (xy 375.278227 -240.889627) (xy 375.248203 -240.84559) (xy 375.225077 -240.797569)
			(xy 375.209367 -240.746639) (xy 375.201424 -240.693935) (xy 374.972844 -240.693935) (xy 374.964901 -240.746639)
			(xy 374.949191 -240.797569) (xy 374.926065 -240.84559) (xy 374.896041 -240.889627) (xy 374.859789 -240.928698)
			(xy 374.818118 -240.961929) (xy 374.77196 -240.988578) (xy 374.722346 -241.00805) (xy 374.670384 -241.01991)
			(xy 374.617234 -241.023894) (xy 374.564084 -241.01991) (xy 374.512122 -241.00805) (xy 374.462508 -240.988578)
			(xy 374.41635 -240.961929) (xy 374.374679 -240.928698) (xy 374.338427 -240.889627) (xy 374.308403 -240.84559)
			(xy 374.285277 -240.797569) (xy 374.269567 -240.746639) (xy 374.261624 -240.693935) (xy 374.03279 -240.693935)
			(xy 374.024847 -240.746639) (xy 374.009137 -240.797569) (xy 373.986011 -240.84559) (xy 373.955987 -240.889627)
			(xy 373.919735 -240.928698) (xy 373.878064 -240.961929) (xy 373.831906 -240.988578) (xy 373.782292 -241.00805)
			(xy 373.73033 -241.01991) (xy 373.67718 -241.023894) (xy 373.62403 -241.01991) (xy 373.572068 -241.00805)
			(xy 373.522454 -240.988578) (xy 373.476296 -240.961929) (xy 373.434625 -240.928698) (xy 373.398373 -240.889627)
			(xy 373.368349 -240.84559) (xy 373.345223 -240.797569) (xy 373.329513 -240.746639) (xy 373.32157 -240.693935)
			(xy 373.093244 -240.693935) (xy 373.085301 -240.746639) (xy 373.069591 -240.797569) (xy 373.046465 -240.84559)
			(xy 373.016441 -240.889627) (xy 372.980189 -240.928698) (xy 372.938518 -240.961929) (xy 372.89236 -240.988578)
			(xy 372.842746 -241.00805) (xy 372.790784 -241.01991) (xy 372.737634 -241.023894) (xy 372.684484 -241.01991)
			(xy 372.632522 -241.00805) (xy 372.582908 -240.988578) (xy 372.53675 -240.961929) (xy 372.495079 -240.928698)
			(xy 372.458827 -240.889627) (xy 372.428803 -240.84559) (xy 372.405677 -240.797569) (xy 372.389967 -240.746639)
			(xy 372.382024 -240.693935) (xy 372.153444 -240.693935) (xy 372.145501 -240.746639) (xy 372.129791 -240.797569)
			(xy 372.106665 -240.84559) (xy 372.076641 -240.889627) (xy 372.040389 -240.928698) (xy 371.998718 -240.961929)
			(xy 371.95256 -240.988578) (xy 371.902946 -241.00805) (xy 371.850984 -241.01991) (xy 371.797834 -241.023894)
			(xy 371.744684 -241.01991) (xy 371.692722 -241.00805) (xy 371.643108 -240.988578) (xy 371.59695 -240.961929)
			(xy 371.555279 -240.928698) (xy 371.519027 -240.889627) (xy 371.489003 -240.84559) (xy 371.465877 -240.797569)
			(xy 371.450167 -240.746639) (xy 371.442224 -240.693935) (xy 371.21339 -240.693935) (xy 371.205447 -240.746639)
			(xy 371.189737 -240.797569) (xy 371.166611 -240.84559) (xy 371.136587 -240.889627) (xy 371.100335 -240.928698)
			(xy 371.058664 -240.961929) (xy 371.012506 -240.988578) (xy 370.962892 -241.00805) (xy 370.91093 -241.01991)
			(xy 370.85778 -241.023894) (xy 370.80463 -241.01991) (xy 370.752668 -241.00805) (xy 370.703054 -240.988578)
			(xy 370.656896 -240.961929) (xy 370.615225 -240.928698) (xy 370.578973 -240.889627) (xy 370.548949 -240.84559)
			(xy 370.525823 -240.797569) (xy 370.510113 -240.746639) (xy 370.50217 -240.693935) (xy 370.273844 -240.693935)
			(xy 370.265901 -240.746639) (xy 370.250191 -240.797569) (xy 370.227065 -240.84559) (xy 370.197041 -240.889627)
			(xy 370.160789 -240.928698) (xy 370.119118 -240.961929) (xy 370.07296 -240.988578) (xy 370.023346 -241.00805)
			(xy 369.971384 -241.01991) (xy 369.918234 -241.023894) (xy 369.865084 -241.01991) (xy 369.813122 -241.00805)
			(xy 369.763508 -240.988578) (xy 369.71735 -240.961929) (xy 369.675679 -240.928698) (xy 369.639427 -240.889627)
			(xy 369.609403 -240.84559) (xy 369.586277 -240.797569) (xy 369.570567 -240.746639) (xy 369.562624 -240.693935)
			(xy 369.245472 -240.693935) (xy 369.245642 -240.704116) (xy 369.245147 -240.731488) (xy 369.236778 -240.785589)
			(xy 369.220224 -240.83777) (xy 369.195876 -240.886801) (xy 369.164308 -240.931526) (xy 369.126264 -240.970891)
			(xy 369.082642 -241.003967) (xy 369.03447 -241.029974) (xy 368.982884 -241.048298) (xy 368.956082 -241.053874)
			(xy 368.91468 -241.061748) (xy 368.91468 -241.507751) (xy 369.09247 -241.507751) (xy 369.09247 -241.454453)
			(xy 369.100413 -241.401749) (xy 369.116123 -241.350819) (xy 369.139249 -241.302798) (xy 369.169273 -241.258761)
			(xy 369.205525 -241.21969) (xy 369.247196 -241.186459) (xy 369.293354 -241.15981) (xy 369.342968 -241.140338)
			(xy 369.39493 -241.128478) (xy 369.44808 -241.124495) (xy 369.50123 -241.128478) (xy 369.553192 -241.140338)
			(xy 369.602806 -241.15981) (xy 369.648964 -241.186459) (xy 369.690635 -241.21969) (xy 369.726887 -241.258761)
			(xy 369.756911 -241.302798) (xy 369.780037 -241.350819) (xy 369.795747 -241.401749) (xy 369.80369 -241.454453)
			(xy 369.804188 -241.481102) (xy 369.80369 -241.507751) (xy 370.032524 -241.507751) (xy 370.032524 -241.454453)
			(xy 370.040467 -241.401749) (xy 370.056177 -241.350819) (xy 370.079303 -241.302798) (xy 370.109327 -241.258761)
			(xy 370.145579 -241.21969) (xy 370.18725 -241.186459) (xy 370.233408 -241.15981) (xy 370.283022 -241.140338)
			(xy 370.334984 -241.128478) (xy 370.388134 -241.124495) (xy 370.441284 -241.128478) (xy 370.493246 -241.140338)
			(xy 370.54286 -241.15981) (xy 370.589018 -241.186459) (xy 370.630689 -241.21969) (xy 370.666941 -241.258761)
			(xy 370.696965 -241.302798) (xy 370.720091 -241.350819) (xy 370.735801 -241.401749) (xy 370.743744 -241.454453)
			(xy 370.744242 -241.481102) (xy 370.743744 -241.507751) (xy 370.97207 -241.507751) (xy 370.97207 -241.454453)
			(xy 370.980013 -241.401749) (xy 370.995723 -241.350819) (xy 371.018849 -241.302798) (xy 371.048873 -241.258761)
			(xy 371.085125 -241.21969) (xy 371.126796 -241.186459) (xy 371.172954 -241.15981) (xy 371.222568 -241.140338)
			(xy 371.27453 -241.128478) (xy 371.32768 -241.124495) (xy 371.38083 -241.128478) (xy 371.432792 -241.140338)
			(xy 371.482406 -241.15981) (xy 371.528564 -241.186459) (xy 371.570235 -241.21969) (xy 371.606487 -241.258761)
			(xy 371.636511 -241.302798) (xy 371.659637 -241.350819) (xy 371.675347 -241.401749) (xy 371.68329 -241.454453)
			(xy 371.683788 -241.481102) (xy 371.68329 -241.507751) (xy 371.91187 -241.507751) (xy 371.91187 -241.454453)
			(xy 371.919813 -241.401749) (xy 371.935523 -241.350819) (xy 371.958649 -241.302798) (xy 371.988673 -241.258761)
			(xy 372.024925 -241.21969) (xy 372.066596 -241.186459) (xy 372.112754 -241.15981) (xy 372.162368 -241.140338)
			(xy 372.21433 -241.128478) (xy 372.26748 -241.124495) (xy 372.32063 -241.128478) (xy 372.372592 -241.140338)
			(xy 372.422206 -241.15981) (xy 372.468364 -241.186459) (xy 372.510035 -241.21969) (xy 372.546287 -241.258761)
			(xy 372.576311 -241.302798) (xy 372.599437 -241.350819) (xy 372.615147 -241.401749) (xy 372.62309 -241.454453)
			(xy 372.623588 -241.481102) (xy 372.62309 -241.507751) (xy 372.85167 -241.507751) (xy 372.85167 -241.454453)
			(xy 372.859613 -241.401749) (xy 372.875323 -241.350819) (xy 372.898449 -241.302798) (xy 372.928473 -241.258761)
			(xy 372.964725 -241.21969) (xy 373.006396 -241.186459) (xy 373.052554 -241.15981) (xy 373.102168 -241.140338)
			(xy 373.15413 -241.128478) (xy 373.20728 -241.124495) (xy 373.26043 -241.128478) (xy 373.312392 -241.140338)
			(xy 373.362006 -241.15981) (xy 373.408164 -241.186459) (xy 373.449835 -241.21969) (xy 373.486087 -241.258761)
			(xy 373.516111 -241.302798) (xy 373.539237 -241.350819) (xy 373.554947 -241.401749) (xy 373.56289 -241.454453)
			(xy 373.563388 -241.481102) (xy 373.56289 -241.507751) (xy 373.79147 -241.507751) (xy 373.79147 -241.454453)
			(xy 373.799413 -241.401749) (xy 373.815123 -241.350819) (xy 373.838249 -241.302798) (xy 373.868273 -241.258761)
			(xy 373.904525 -241.21969) (xy 373.946196 -241.186459) (xy 373.992354 -241.15981) (xy 374.041968 -241.140338)
			(xy 374.09393 -241.128478) (xy 374.14708 -241.124495) (xy 374.20023 -241.128478) (xy 374.252192 -241.140338)
			(xy 374.301806 -241.15981) (xy 374.347964 -241.186459) (xy 374.389635 -241.21969) (xy 374.425887 -241.258761)
			(xy 374.455911 -241.302798) (xy 374.479037 -241.350819) (xy 374.494747 -241.401749) (xy 374.50269 -241.454453)
			(xy 374.503188 -241.481102) (xy 374.50269 -241.507751) (xy 374.73127 -241.507751) (xy 374.73127 -241.454453)
			(xy 374.739213 -241.401749) (xy 374.754923 -241.350819) (xy 374.778049 -241.302798) (xy 374.808073 -241.258761)
			(xy 374.844325 -241.21969) (xy 374.885996 -241.186459) (xy 374.932154 -241.15981) (xy 374.981768 -241.140338)
			(xy 375.03373 -241.128478) (xy 375.08688 -241.124495) (xy 375.14003 -241.128478) (xy 375.191992 -241.140338)
			(xy 375.241606 -241.15981) (xy 375.287764 -241.186459) (xy 375.329435 -241.21969) (xy 375.365687 -241.258761)
			(xy 375.395711 -241.302798) (xy 375.418837 -241.350819) (xy 375.434547 -241.401749) (xy 375.44249 -241.454453)
			(xy 375.442988 -241.481102) (xy 375.44249 -241.507751) (xy 375.67107 -241.507751) (xy 375.67107 -241.454453)
			(xy 375.679013 -241.401749) (xy 375.694723 -241.350819) (xy 375.717849 -241.302798) (xy 375.747873 -241.258761)
			(xy 375.784125 -241.21969) (xy 375.825796 -241.186459) (xy 375.871954 -241.15981) (xy 375.921568 -241.140338)
			(xy 375.97353 -241.128478) (xy 376.02668 -241.124495) (xy 376.07983 -241.128478) (xy 376.131792 -241.140338)
			(xy 376.181406 -241.15981) (xy 376.227564 -241.186459) (xy 376.269235 -241.21969) (xy 376.305487 -241.258761)
			(xy 376.335511 -241.302798) (xy 376.358637 -241.350819) (xy 376.374347 -241.401749) (xy 376.38229 -241.454453)
			(xy 376.382788 -241.481102) (xy 376.38229 -241.507751) (xy 376.611124 -241.507751) (xy 376.611124 -241.454453)
			(xy 376.619067 -241.401749) (xy 376.634777 -241.350819) (xy 376.657903 -241.302798) (xy 376.687927 -241.258761)
			(xy 376.724179 -241.21969) (xy 376.76585 -241.186459) (xy 376.812008 -241.15981) (xy 376.861622 -241.140338)
			(xy 376.913584 -241.128478) (xy 376.966734 -241.124495) (xy 377.019884 -241.128478) (xy 377.071846 -241.140338)
			(xy 377.12146 -241.15981) (xy 377.167618 -241.186459) (xy 377.209289 -241.21969) (xy 377.245541 -241.258761)
			(xy 377.275565 -241.302798) (xy 377.298691 -241.350819) (xy 377.314401 -241.401749) (xy 377.322344 -241.454453)
			(xy 377.322842 -241.481102) (xy 377.322344 -241.507751) (xy 377.55067 -241.507751) (xy 377.55067 -241.454453)
			(xy 377.558613 -241.401749) (xy 377.574323 -241.350819) (xy 377.597449 -241.302798) (xy 377.627473 -241.258761)
			(xy 377.663725 -241.21969) (xy 377.705396 -241.186459) (xy 377.751554 -241.15981) (xy 377.801168 -241.140338)
			(xy 377.85313 -241.128478) (xy 377.90628 -241.124495) (xy 377.95943 -241.128478) (xy 378.011392 -241.140338)
			(xy 378.061006 -241.15981) (xy 378.107164 -241.186459) (xy 378.148835 -241.21969) (xy 378.185087 -241.258761)
			(xy 378.215111 -241.302798) (xy 378.238237 -241.350819) (xy 378.253947 -241.401749) (xy 378.26189 -241.454453)
			(xy 378.262388 -241.481102) (xy 378.26189 -241.507751) (xy 378.49047 -241.507751) (xy 378.49047 -241.454453)
			(xy 378.498413 -241.401749) (xy 378.514123 -241.350819) (xy 378.537249 -241.302798) (xy 378.567273 -241.258761)
			(xy 378.603525 -241.21969) (xy 378.645196 -241.186459) (xy 378.691354 -241.15981) (xy 378.740968 -241.140338)
			(xy 378.79293 -241.128478) (xy 378.84608 -241.124495) (xy 378.89923 -241.128478) (xy 378.951192 -241.140338)
			(xy 379.000806 -241.15981) (xy 379.046964 -241.186459) (xy 379.088635 -241.21969) (xy 379.124887 -241.258761)
			(xy 379.154911 -241.302798) (xy 379.178037 -241.350819) (xy 379.193747 -241.401749) (xy 379.20169 -241.454453)
			(xy 379.202188 -241.481102) (xy 379.20169 -241.507751) (xy 379.43027 -241.507751) (xy 379.43027 -241.454453)
			(xy 379.438213 -241.401749) (xy 379.453923 -241.350819) (xy 379.477049 -241.302798) (xy 379.507073 -241.258761)
			(xy 379.543325 -241.21969) (xy 379.584996 -241.186459) (xy 379.631154 -241.15981) (xy 379.680768 -241.140338)
			(xy 379.73273 -241.128478) (xy 379.78588 -241.124495) (xy 379.83903 -241.128478) (xy 379.890992 -241.140338)
			(xy 379.940606 -241.15981) (xy 379.986764 -241.186459) (xy 380.028435 -241.21969) (xy 380.064687 -241.258761)
			(xy 380.094711 -241.302798) (xy 380.117837 -241.350819) (xy 380.133547 -241.401749) (xy 380.14149 -241.454453)
			(xy 380.141988 -241.481102) (xy 380.14149 -241.507751) (xy 380.37007 -241.507751) (xy 380.37007 -241.454453)
			(xy 380.378013 -241.401749) (xy 380.393723 -241.350819) (xy 380.416849 -241.302798) (xy 380.446873 -241.258761)
			(xy 380.483125 -241.21969) (xy 380.524796 -241.186459) (xy 380.570954 -241.15981) (xy 380.620568 -241.140338)
			(xy 380.67253 -241.128478) (xy 380.72568 -241.124495) (xy 380.77883 -241.128478) (xy 380.830792 -241.140338)
			(xy 380.880406 -241.15981) (xy 380.926564 -241.186459) (xy 380.968235 -241.21969) (xy 381.004487 -241.258761)
			(xy 381.034511 -241.302798) (xy 381.057637 -241.350819) (xy 381.073347 -241.401749) (xy 381.08129 -241.454453)
			(xy 381.081788 -241.481102) (xy 381.08129 -241.507751) (xy 381.073347 -241.560455) (xy 381.057637 -241.611385)
			(xy 381.034511 -241.659406) (xy 381.004487 -241.703443) (xy 380.968235 -241.742514) (xy 380.926564 -241.775745)
			(xy 380.880406 -241.802394) (xy 380.830792 -241.821866) (xy 380.77883 -241.833726) (xy 380.72568 -241.83771)
			(xy 380.67253 -241.833726) (xy 380.620568 -241.821866) (xy 380.570954 -241.802394) (xy 380.524796 -241.775745)
			(xy 380.483125 -241.742514) (xy 380.446873 -241.703443) (xy 380.416849 -241.659406) (xy 380.393723 -241.611385)
			(xy 380.378013 -241.560455) (xy 380.37007 -241.507751) (xy 380.14149 -241.507751) (xy 380.133547 -241.560455)
			(xy 380.117837 -241.611385) (xy 380.094711 -241.659406) (xy 380.064687 -241.703443) (xy 380.028435 -241.742514)
			(xy 379.986764 -241.775745) (xy 379.940606 -241.802394) (xy 379.890992 -241.821866) (xy 379.83903 -241.833726)
			(xy 379.78588 -241.83771) (xy 379.73273 -241.833726) (xy 379.680768 -241.821866) (xy 379.631154 -241.802394)
			(xy 379.584996 -241.775745) (xy 379.543325 -241.742514) (xy 379.507073 -241.703443) (xy 379.477049 -241.659406)
			(xy 379.453923 -241.611385) (xy 379.438213 -241.560455) (xy 379.43027 -241.507751) (xy 379.20169 -241.507751)
			(xy 379.193747 -241.560455) (xy 379.178037 -241.611385) (xy 379.154911 -241.659406) (xy 379.124887 -241.703443)
			(xy 379.088635 -241.742514) (xy 379.046964 -241.775745) (xy 379.000806 -241.802394) (xy 378.951192 -241.821866)
			(xy 378.89923 -241.833726) (xy 378.84608 -241.83771) (xy 378.79293 -241.833726) (xy 378.740968 -241.821866)
			(xy 378.691354 -241.802394) (xy 378.645196 -241.775745) (xy 378.603525 -241.742514) (xy 378.567273 -241.703443)
			(xy 378.537249 -241.659406) (xy 378.514123 -241.611385) (xy 378.498413 -241.560455) (xy 378.49047 -241.507751)
			(xy 378.26189 -241.507751) (xy 378.253947 -241.560455) (xy 378.238237 -241.611385) (xy 378.215111 -241.659406)
			(xy 378.185087 -241.703443) (xy 378.148835 -241.742514) (xy 378.107164 -241.775745) (xy 378.061006 -241.802394)
			(xy 378.011392 -241.821866) (xy 377.95943 -241.833726) (xy 377.90628 -241.83771) (xy 377.85313 -241.833726)
			(xy 377.801168 -241.821866) (xy 377.751554 -241.802394) (xy 377.705396 -241.775745) (xy 377.663725 -241.742514)
			(xy 377.627473 -241.703443) (xy 377.597449 -241.659406) (xy 377.574323 -241.611385) (xy 377.558613 -241.560455)
			(xy 377.55067 -241.507751) (xy 377.322344 -241.507751) (xy 377.314401 -241.560455) (xy 377.298691 -241.611385)
			(xy 377.275565 -241.659406) (xy 377.245541 -241.703443) (xy 377.209289 -241.742514) (xy 377.167618 -241.775745)
			(xy 377.12146 -241.802394) (xy 377.071846 -241.821866) (xy 377.019884 -241.833726) (xy 376.966734 -241.83771)
			(xy 376.913584 -241.833726) (xy 376.861622 -241.821866) (xy 376.812008 -241.802394) (xy 376.76585 -241.775745)
			(xy 376.724179 -241.742514) (xy 376.687927 -241.703443) (xy 376.657903 -241.659406) (xy 376.634777 -241.611385)
			(xy 376.619067 -241.560455) (xy 376.611124 -241.507751) (xy 376.38229 -241.507751) (xy 376.374347 -241.560455)
			(xy 376.358637 -241.611385) (xy 376.335511 -241.659406) (xy 376.305487 -241.703443) (xy 376.269235 -241.742514)
			(xy 376.227564 -241.775745) (xy 376.181406 -241.802394) (xy 376.131792 -241.821866) (xy 376.07983 -241.833726)
			(xy 376.02668 -241.83771) (xy 375.97353 -241.833726) (xy 375.921568 -241.821866) (xy 375.871954 -241.802394)
			(xy 375.825796 -241.775745) (xy 375.784125 -241.742514) (xy 375.747873 -241.703443) (xy 375.717849 -241.659406)
			(xy 375.694723 -241.611385) (xy 375.679013 -241.560455) (xy 375.67107 -241.507751) (xy 375.44249 -241.507751)
			(xy 375.434547 -241.560455) (xy 375.418837 -241.611385) (xy 375.395711 -241.659406) (xy 375.365687 -241.703443)
			(xy 375.329435 -241.742514) (xy 375.287764 -241.775745) (xy 375.241606 -241.802394) (xy 375.191992 -241.821866)
			(xy 375.14003 -241.833726) (xy 375.08688 -241.83771) (xy 375.03373 -241.833726) (xy 374.981768 -241.821866)
			(xy 374.932154 -241.802394) (xy 374.885996 -241.775745) (xy 374.844325 -241.742514) (xy 374.808073 -241.703443)
			(xy 374.778049 -241.659406) (xy 374.754923 -241.611385) (xy 374.739213 -241.560455) (xy 374.73127 -241.507751)
			(xy 374.50269 -241.507751) (xy 374.494747 -241.560455) (xy 374.479037 -241.611385) (xy 374.455911 -241.659406)
			(xy 374.425887 -241.703443) (xy 374.389635 -241.742514) (xy 374.347964 -241.775745) (xy 374.301806 -241.802394)
			(xy 374.252192 -241.821866) (xy 374.20023 -241.833726) (xy 374.14708 -241.83771) (xy 374.09393 -241.833726)
			(xy 374.041968 -241.821866) (xy 373.992354 -241.802394) (xy 373.946196 -241.775745) (xy 373.904525 -241.742514)
			(xy 373.868273 -241.703443) (xy 373.838249 -241.659406) (xy 373.815123 -241.611385) (xy 373.799413 -241.560455)
			(xy 373.79147 -241.507751) (xy 373.56289 -241.507751) (xy 373.554947 -241.560455) (xy 373.539237 -241.611385)
			(xy 373.516111 -241.659406) (xy 373.486087 -241.703443) (xy 373.449835 -241.742514) (xy 373.408164 -241.775745)
			(xy 373.362006 -241.802394) (xy 373.312392 -241.821866) (xy 373.26043 -241.833726) (xy 373.20728 -241.83771)
			(xy 373.15413 -241.833726) (xy 373.102168 -241.821866) (xy 373.052554 -241.802394) (xy 373.006396 -241.775745)
			(xy 372.964725 -241.742514) (xy 372.928473 -241.703443) (xy 372.898449 -241.659406) (xy 372.875323 -241.611385)
			(xy 372.859613 -241.560455) (xy 372.85167 -241.507751) (xy 372.62309 -241.507751) (xy 372.615147 -241.560455)
			(xy 372.599437 -241.611385) (xy 372.576311 -241.659406) (xy 372.546287 -241.703443) (xy 372.510035 -241.742514)
			(xy 372.468364 -241.775745) (xy 372.422206 -241.802394) (xy 372.372592 -241.821866) (xy 372.32063 -241.833726)
			(xy 372.26748 -241.83771) (xy 372.21433 -241.833726) (xy 372.162368 -241.821866) (xy 372.112754 -241.802394)
			(xy 372.066596 -241.775745) (xy 372.024925 -241.742514) (xy 371.988673 -241.703443) (xy 371.958649 -241.659406)
			(xy 371.935523 -241.611385) (xy 371.919813 -241.560455) (xy 371.91187 -241.507751) (xy 371.68329 -241.507751)
			(xy 371.675347 -241.560455) (xy 371.659637 -241.611385) (xy 371.636511 -241.659406) (xy 371.606487 -241.703443)
			(xy 371.570235 -241.742514) (xy 371.528564 -241.775745) (xy 371.482406 -241.802394) (xy 371.432792 -241.821866)
			(xy 371.38083 -241.833726) (xy 371.32768 -241.83771) (xy 371.27453 -241.833726) (xy 371.222568 -241.821866)
			(xy 371.172954 -241.802394) (xy 371.126796 -241.775745) (xy 371.085125 -241.742514) (xy 371.048873 -241.703443)
			(xy 371.018849 -241.659406) (xy 370.995723 -241.611385) (xy 370.980013 -241.560455) (xy 370.97207 -241.507751)
			(xy 370.743744 -241.507751) (xy 370.735801 -241.560455) (xy 370.720091 -241.611385) (xy 370.696965 -241.659406)
			(xy 370.666941 -241.703443) (xy 370.630689 -241.742514) (xy 370.589018 -241.775745) (xy 370.54286 -241.802394)
			(xy 370.493246 -241.821866) (xy 370.441284 -241.833726) (xy 370.388134 -241.83771) (xy 370.334984 -241.833726)
			(xy 370.283022 -241.821866) (xy 370.233408 -241.802394) (xy 370.18725 -241.775745) (xy 370.145579 -241.742514)
			(xy 370.109327 -241.703443) (xy 370.079303 -241.659406) (xy 370.056177 -241.611385) (xy 370.040467 -241.560455)
			(xy 370.032524 -241.507751) (xy 369.80369 -241.507751) (xy 369.795747 -241.560455) (xy 369.780037 -241.611385)
			(xy 369.756911 -241.659406) (xy 369.726887 -241.703443) (xy 369.690635 -241.742514) (xy 369.648964 -241.775745)
			(xy 369.602806 -241.802394) (xy 369.553192 -241.821866) (xy 369.50123 -241.833726) (xy 369.44808 -241.83771)
			(xy 369.39493 -241.833726) (xy 369.342968 -241.821866) (xy 369.293354 -241.802394) (xy 369.247196 -241.775745)
			(xy 369.205525 -241.742514) (xy 369.169273 -241.703443) (xy 369.139249 -241.659406) (xy 369.116123 -241.611385)
			(xy 369.100413 -241.560455) (xy 369.09247 -241.507751) (xy 368.91468 -241.507751) (xy 368.91468 -242.321567)
			(xy 369.562624 -242.321567) (xy 369.562624 -242.268269) (xy 369.570567 -242.215565) (xy 369.586277 -242.164635)
			(xy 369.609403 -242.116614) (xy 369.639427 -242.072577) (xy 369.675679 -242.033506) (xy 369.71735 -242.000275)
			(xy 369.763508 -241.973626) (xy 369.813122 -241.954154) (xy 369.865084 -241.942294) (xy 369.918234 -241.938311)
			(xy 369.971384 -241.942294) (xy 370.023346 -241.954154) (xy 370.07296 -241.973626) (xy 370.119118 -242.000275)
			(xy 370.160789 -242.033506) (xy 370.197041 -242.072577) (xy 370.227065 -242.116614) (xy 370.250191 -242.164635)
			(xy 370.265901 -242.215565) (xy 370.273844 -242.268269) (xy 370.274342 -242.294918) (xy 370.273844 -242.321567)
			(xy 370.502424 -242.321567) (xy 370.502424 -242.268269) (xy 370.510367 -242.215565) (xy 370.526077 -242.164635)
			(xy 370.549203 -242.116614) (xy 370.579227 -242.072577) (xy 370.615479 -242.033506) (xy 370.65715 -242.000275)
			(xy 370.703308 -241.973626) (xy 370.752922 -241.954154) (xy 370.804884 -241.942294) (xy 370.858034 -241.938311)
			(xy 370.911184 -241.942294) (xy 370.963146 -241.954154) (xy 371.01276 -241.973626) (xy 371.058918 -242.000275)
			(xy 371.100589 -242.033506) (xy 371.136841 -242.072577) (xy 371.166865 -242.116614) (xy 371.189991 -242.164635)
			(xy 371.205701 -242.215565) (xy 371.213644 -242.268269) (xy 371.214142 -242.294918) (xy 371.213644 -242.321567)
			(xy 371.442224 -242.321567) (xy 371.442224 -242.268269) (xy 371.450167 -242.215565) (xy 371.465877 -242.164635)
			(xy 371.489003 -242.116614) (xy 371.519027 -242.072577) (xy 371.555279 -242.033506) (xy 371.59695 -242.000275)
			(xy 371.643108 -241.973626) (xy 371.692722 -241.954154) (xy 371.744684 -241.942294) (xy 371.797834 -241.938311)
			(xy 371.850984 -241.942294) (xy 371.902946 -241.954154) (xy 371.95256 -241.973626) (xy 371.998718 -242.000275)
			(xy 372.040389 -242.033506) (xy 372.076641 -242.072577) (xy 372.106665 -242.116614) (xy 372.129791 -242.164635)
			(xy 372.145501 -242.215565) (xy 372.153444 -242.268269) (xy 372.153942 -242.294918) (xy 372.153444 -242.321567)
			(xy 372.382024 -242.321567) (xy 372.382024 -242.268269) (xy 372.389967 -242.215565) (xy 372.405677 -242.164635)
			(xy 372.428803 -242.116614) (xy 372.458827 -242.072577) (xy 372.495079 -242.033506) (xy 372.53675 -242.000275)
			(xy 372.582908 -241.973626) (xy 372.632522 -241.954154) (xy 372.684484 -241.942294) (xy 372.737634 -241.938311)
			(xy 372.790784 -241.942294) (xy 372.842746 -241.954154) (xy 372.89236 -241.973626) (xy 372.938518 -242.000275)
			(xy 372.980189 -242.033506) (xy 373.016441 -242.072577) (xy 373.046465 -242.116614) (xy 373.069591 -242.164635)
			(xy 373.085301 -242.215565) (xy 373.093244 -242.268269) (xy 373.093742 -242.294918) (xy 373.093244 -242.321567)
			(xy 373.321824 -242.321567) (xy 373.321824 -242.268269) (xy 373.329767 -242.215565) (xy 373.345477 -242.164635)
			(xy 373.368603 -242.116614) (xy 373.398627 -242.072577) (xy 373.434879 -242.033506) (xy 373.47655 -242.000275)
			(xy 373.522708 -241.973626) (xy 373.572322 -241.954154) (xy 373.624284 -241.942294) (xy 373.677434 -241.938311)
			(xy 373.730584 -241.942294) (xy 373.782546 -241.954154) (xy 373.83216 -241.973626) (xy 373.878318 -242.000275)
			(xy 373.919989 -242.033506) (xy 373.956241 -242.072577) (xy 373.986265 -242.116614) (xy 374.009391 -242.164635)
			(xy 374.025101 -242.215565) (xy 374.033044 -242.268269) (xy 374.033542 -242.294918) (xy 374.033044 -242.321567)
			(xy 374.261624 -242.321567) (xy 374.261624 -242.268269) (xy 374.269567 -242.215565) (xy 374.285277 -242.164635)
			(xy 374.308403 -242.116614) (xy 374.338427 -242.072577) (xy 374.374679 -242.033506) (xy 374.41635 -242.000275)
			(xy 374.462508 -241.973626) (xy 374.512122 -241.954154) (xy 374.564084 -241.942294) (xy 374.617234 -241.938311)
			(xy 374.670384 -241.942294) (xy 374.722346 -241.954154) (xy 374.77196 -241.973626) (xy 374.818118 -242.000275)
			(xy 374.859789 -242.033506) (xy 374.896041 -242.072577) (xy 374.926065 -242.116614) (xy 374.949191 -242.164635)
			(xy 374.964901 -242.215565) (xy 374.972844 -242.268269) (xy 374.973342 -242.294918) (xy 374.972844 -242.321567)
			(xy 375.201424 -242.321567) (xy 375.201424 -242.268269) (xy 375.209367 -242.215565) (xy 375.225077 -242.164635)
			(xy 375.248203 -242.116614) (xy 375.278227 -242.072577) (xy 375.314479 -242.033506) (xy 375.35615 -242.000275)
			(xy 375.402308 -241.973626) (xy 375.451922 -241.954154) (xy 375.503884 -241.942294) (xy 375.557034 -241.938311)
			(xy 375.610184 -241.942294) (xy 375.662146 -241.954154) (xy 375.71176 -241.973626) (xy 375.757918 -242.000275)
			(xy 375.799589 -242.033506) (xy 375.835841 -242.072577) (xy 375.865865 -242.116614) (xy 375.888991 -242.164635)
			(xy 375.904701 -242.215565) (xy 375.912644 -242.268269) (xy 375.913142 -242.294918) (xy 375.912644 -242.321567)
			(xy 376.141224 -242.321567) (xy 376.141224 -242.268269) (xy 376.149167 -242.215565) (xy 376.164877 -242.164635)
			(xy 376.188003 -242.116614) (xy 376.218027 -242.072577) (xy 376.254279 -242.033506) (xy 376.29595 -242.000275)
			(xy 376.342108 -241.973626) (xy 376.391722 -241.954154) (xy 376.443684 -241.942294) (xy 376.496834 -241.938311)
			(xy 376.549984 -241.942294) (xy 376.601946 -241.954154) (xy 376.65156 -241.973626) (xy 376.697718 -242.000275)
			(xy 376.739389 -242.033506) (xy 376.775641 -242.072577) (xy 376.805665 -242.116614) (xy 376.828791 -242.164635)
			(xy 376.844501 -242.215565) (xy 376.852444 -242.268269) (xy 376.852942 -242.294918) (xy 376.852444 -242.321567)
			(xy 377.081024 -242.321567) (xy 377.081024 -242.268269) (xy 377.088967 -242.215565) (xy 377.104677 -242.164635)
			(xy 377.127803 -242.116614) (xy 377.157827 -242.072577) (xy 377.194079 -242.033506) (xy 377.23575 -242.000275)
			(xy 377.281908 -241.973626) (xy 377.331522 -241.954154) (xy 377.383484 -241.942294) (xy 377.436634 -241.938311)
			(xy 377.489784 -241.942294) (xy 377.541746 -241.954154) (xy 377.59136 -241.973626) (xy 377.637518 -242.000275)
			(xy 377.679189 -242.033506) (xy 377.715441 -242.072577) (xy 377.745465 -242.116614) (xy 377.768591 -242.164635)
			(xy 377.784301 -242.215565) (xy 377.792244 -242.268269) (xy 377.792742 -242.294918) (xy 377.792244 -242.321567)
			(xy 378.020824 -242.321567) (xy 378.020824 -242.268269) (xy 378.028767 -242.215565) (xy 378.044477 -242.164635)
			(xy 378.067603 -242.116614) (xy 378.097627 -242.072577) (xy 378.133879 -242.033506) (xy 378.17555 -242.000275)
			(xy 378.221708 -241.973626) (xy 378.271322 -241.954154) (xy 378.323284 -241.942294) (xy 378.376434 -241.938311)
			(xy 378.429584 -241.942294) (xy 378.481546 -241.954154) (xy 378.53116 -241.973626) (xy 378.577318 -242.000275)
			(xy 378.618989 -242.033506) (xy 378.655241 -242.072577) (xy 378.685265 -242.116614) (xy 378.708391 -242.164635)
			(xy 378.724101 -242.215565) (xy 378.732044 -242.268269) (xy 378.732542 -242.294918) (xy 378.732044 -242.321567)
			(xy 378.960624 -242.321567) (xy 378.960624 -242.268269) (xy 378.968567 -242.215565) (xy 378.984277 -242.164635)
			(xy 379.007403 -242.116614) (xy 379.037427 -242.072577) (xy 379.073679 -242.033506) (xy 379.11535 -242.000275)
			(xy 379.161508 -241.973626) (xy 379.211122 -241.954154) (xy 379.263084 -241.942294) (xy 379.316234 -241.938311)
			(xy 379.369384 -241.942294) (xy 379.421346 -241.954154) (xy 379.47096 -241.973626) (xy 379.517118 -242.000275)
			(xy 379.558789 -242.033506) (xy 379.595041 -242.072577) (xy 379.625065 -242.116614) (xy 379.648191 -242.164635)
			(xy 379.663901 -242.215565) (xy 379.671844 -242.268269) (xy 379.672342 -242.294918) (xy 379.671844 -242.321567)
			(xy 379.900424 -242.321567) (xy 379.900424 -242.268269) (xy 379.908367 -242.215565) (xy 379.924077 -242.164635)
			(xy 379.947203 -242.116614) (xy 379.977227 -242.072577) (xy 380.013479 -242.033506) (xy 380.05515 -242.000275)
			(xy 380.101308 -241.973626) (xy 380.150922 -241.954154) (xy 380.202884 -241.942294) (xy 380.256034 -241.938311)
			(xy 380.309184 -241.942294) (xy 380.361146 -241.954154) (xy 380.41076 -241.973626) (xy 380.456918 -242.000275)
			(xy 380.498589 -242.033506) (xy 380.534841 -242.072577) (xy 380.564865 -242.116614) (xy 380.587991 -242.164635)
			(xy 380.603701 -242.215565) (xy 380.611644 -242.268269) (xy 380.612142 -242.294918) (xy 380.611644 -242.321567)
			(xy 380.840224 -242.321567) (xy 380.840224 -242.268269) (xy 380.848167 -242.215565) (xy 380.863877 -242.164635)
			(xy 380.887003 -242.116614) (xy 380.917027 -242.072577) (xy 380.953279 -242.033506) (xy 380.99495 -242.000275)
			(xy 381.041108 -241.973626) (xy 381.090722 -241.954154) (xy 381.142684 -241.942294) (xy 381.195834 -241.938311)
			(xy 381.248984 -241.942294) (xy 381.300946 -241.954154) (xy 381.35056 -241.973626) (xy 381.396718 -242.000275)
			(xy 381.438389 -242.033506) (xy 381.474641 -242.072577) (xy 381.504665 -242.116614) (xy 381.527791 -242.164635)
			(xy 381.543501 -242.215565) (xy 381.551444 -242.268269) (xy 381.551942 -242.294918) (xy 381.551444 -242.321567)
			(xy 381.543501 -242.374271) (xy 381.527791 -242.425201) (xy 381.504665 -242.473222) (xy 381.474641 -242.517259)
			(xy 381.438389 -242.55633) (xy 381.396718 -242.589561) (xy 381.35056 -242.61621) (xy 381.300946 -242.635682)
			(xy 381.248984 -242.647542) (xy 381.195834 -242.651526) (xy 381.142684 -242.647542) (xy 381.090722 -242.635682)
			(xy 381.041108 -242.61621) (xy 380.99495 -242.589561) (xy 380.953279 -242.55633) (xy 380.917027 -242.517259)
			(xy 380.887003 -242.473222) (xy 380.863877 -242.425201) (xy 380.848167 -242.374271) (xy 380.840224 -242.321567)
			(xy 380.611644 -242.321567) (xy 380.603701 -242.374271) (xy 380.587991 -242.425201) (xy 380.564865 -242.473222)
			(xy 380.534841 -242.517259) (xy 380.498589 -242.55633) (xy 380.456918 -242.589561) (xy 380.41076 -242.61621)
			(xy 380.361146 -242.635682) (xy 380.309184 -242.647542) (xy 380.256034 -242.651526) (xy 380.202884 -242.647542)
			(xy 380.150922 -242.635682) (xy 380.101308 -242.61621) (xy 380.05515 -242.589561) (xy 380.013479 -242.55633)
			(xy 379.977227 -242.517259) (xy 379.947203 -242.473222) (xy 379.924077 -242.425201) (xy 379.908367 -242.374271)
			(xy 379.900424 -242.321567) (xy 379.671844 -242.321567) (xy 379.663901 -242.374271) (xy 379.648191 -242.425201)
			(xy 379.625065 -242.473222) (xy 379.595041 -242.517259) (xy 379.558789 -242.55633) (xy 379.517118 -242.589561)
			(xy 379.47096 -242.61621) (xy 379.421346 -242.635682) (xy 379.369384 -242.647542) (xy 379.316234 -242.651526)
			(xy 379.263084 -242.647542) (xy 379.211122 -242.635682) (xy 379.161508 -242.61621) (xy 379.11535 -242.589561)
			(xy 379.073679 -242.55633) (xy 379.037427 -242.517259) (xy 379.007403 -242.473222) (xy 378.984277 -242.425201)
			(xy 378.968567 -242.374271) (xy 378.960624 -242.321567) (xy 378.732044 -242.321567) (xy 378.724101 -242.374271)
			(xy 378.708391 -242.425201) (xy 378.685265 -242.473222) (xy 378.655241 -242.517259) (xy 378.618989 -242.55633)
			(xy 378.577318 -242.589561) (xy 378.53116 -242.61621) (xy 378.481546 -242.635682) (xy 378.429584 -242.647542)
			(xy 378.376434 -242.651526) (xy 378.323284 -242.647542) (xy 378.271322 -242.635682) (xy 378.221708 -242.61621)
			(xy 378.17555 -242.589561) (xy 378.133879 -242.55633) (xy 378.097627 -242.517259) (xy 378.067603 -242.473222)
			(xy 378.044477 -242.425201) (xy 378.028767 -242.374271) (xy 378.020824 -242.321567) (xy 377.792244 -242.321567)
			(xy 377.784301 -242.374271) (xy 377.768591 -242.425201) (xy 377.745465 -242.473222) (xy 377.715441 -242.517259)
			(xy 377.679189 -242.55633) (xy 377.637518 -242.589561) (xy 377.59136 -242.61621) (xy 377.541746 -242.635682)
			(xy 377.489784 -242.647542) (xy 377.436634 -242.651526) (xy 377.383484 -242.647542) (xy 377.331522 -242.635682)
			(xy 377.281908 -242.61621) (xy 377.23575 -242.589561) (xy 377.194079 -242.55633) (xy 377.157827 -242.517259)
			(xy 377.127803 -242.473222) (xy 377.104677 -242.425201) (xy 377.088967 -242.374271) (xy 377.081024 -242.321567)
			(xy 376.852444 -242.321567) (xy 376.844501 -242.374271) (xy 376.828791 -242.425201) (xy 376.805665 -242.473222)
			(xy 376.775641 -242.517259) (xy 376.739389 -242.55633) (xy 376.697718 -242.589561) (xy 376.65156 -242.61621)
			(xy 376.601946 -242.635682) (xy 376.549984 -242.647542) (xy 376.496834 -242.651526) (xy 376.443684 -242.647542)
			(xy 376.391722 -242.635682) (xy 376.342108 -242.61621) (xy 376.29595 -242.589561) (xy 376.254279 -242.55633)
			(xy 376.218027 -242.517259) (xy 376.188003 -242.473222) (xy 376.164877 -242.425201) (xy 376.149167 -242.374271)
			(xy 376.141224 -242.321567) (xy 375.912644 -242.321567) (xy 375.904701 -242.374271) (xy 375.888991 -242.425201)
			(xy 375.865865 -242.473222) (xy 375.835841 -242.517259) (xy 375.799589 -242.55633) (xy 375.757918 -242.589561)
			(xy 375.71176 -242.61621) (xy 375.662146 -242.635682) (xy 375.610184 -242.647542) (xy 375.557034 -242.651526)
			(xy 375.503884 -242.647542) (xy 375.451922 -242.635682) (xy 375.402308 -242.61621) (xy 375.35615 -242.589561)
			(xy 375.314479 -242.55633) (xy 375.278227 -242.517259) (xy 375.248203 -242.473222) (xy 375.225077 -242.425201)
			(xy 375.209367 -242.374271) (xy 375.201424 -242.321567) (xy 374.972844 -242.321567) (xy 374.964901 -242.374271)
			(xy 374.949191 -242.425201) (xy 374.926065 -242.473222) (xy 374.896041 -242.517259) (xy 374.859789 -242.55633)
			(xy 374.818118 -242.589561) (xy 374.77196 -242.61621) (xy 374.722346 -242.635682) (xy 374.670384 -242.647542)
			(xy 374.617234 -242.651526) (xy 374.564084 -242.647542) (xy 374.512122 -242.635682) (xy 374.462508 -242.61621)
			(xy 374.41635 -242.589561) (xy 374.374679 -242.55633) (xy 374.338427 -242.517259) (xy 374.308403 -242.473222)
			(xy 374.285277 -242.425201) (xy 374.269567 -242.374271) (xy 374.261624 -242.321567) (xy 374.033044 -242.321567)
			(xy 374.025101 -242.374271) (xy 374.009391 -242.425201) (xy 373.986265 -242.473222) (xy 373.956241 -242.517259)
			(xy 373.919989 -242.55633) (xy 373.878318 -242.589561) (xy 373.83216 -242.61621) (xy 373.782546 -242.635682)
			(xy 373.730584 -242.647542) (xy 373.677434 -242.651526) (xy 373.624284 -242.647542) (xy 373.572322 -242.635682)
			(xy 373.522708 -242.61621) (xy 373.47655 -242.589561) (xy 373.434879 -242.55633) (xy 373.398627 -242.517259)
			(xy 373.368603 -242.473222) (xy 373.345477 -242.425201) (xy 373.329767 -242.374271) (xy 373.321824 -242.321567)
			(xy 373.093244 -242.321567) (xy 373.085301 -242.374271) (xy 373.069591 -242.425201) (xy 373.046465 -242.473222)
			(xy 373.016441 -242.517259) (xy 372.980189 -242.55633) (xy 372.938518 -242.589561) (xy 372.89236 -242.61621)
			(xy 372.842746 -242.635682) (xy 372.790784 -242.647542) (xy 372.737634 -242.651526) (xy 372.684484 -242.647542)
			(xy 372.632522 -242.635682) (xy 372.582908 -242.61621) (xy 372.53675 -242.589561) (xy 372.495079 -242.55633)
			(xy 372.458827 -242.517259) (xy 372.428803 -242.473222) (xy 372.405677 -242.425201) (xy 372.389967 -242.374271)
			(xy 372.382024 -242.321567) (xy 372.153444 -242.321567) (xy 372.145501 -242.374271) (xy 372.129791 -242.425201)
			(xy 372.106665 -242.473222) (xy 372.076641 -242.517259) (xy 372.040389 -242.55633) (xy 371.998718 -242.589561)
			(xy 371.95256 -242.61621) (xy 371.902946 -242.635682) (xy 371.850984 -242.647542) (xy 371.797834 -242.651526)
			(xy 371.744684 -242.647542) (xy 371.692722 -242.635682) (xy 371.643108 -242.61621) (xy 371.59695 -242.589561)
			(xy 371.555279 -242.55633) (xy 371.519027 -242.517259) (xy 371.489003 -242.473222) (xy 371.465877 -242.425201)
			(xy 371.450167 -242.374271) (xy 371.442224 -242.321567) (xy 371.213644 -242.321567) (xy 371.205701 -242.374271)
			(xy 371.189991 -242.425201) (xy 371.166865 -242.473222) (xy 371.136841 -242.517259) (xy 371.100589 -242.55633)
			(xy 371.058918 -242.589561) (xy 371.01276 -242.61621) (xy 370.963146 -242.635682) (xy 370.911184 -242.647542)
			(xy 370.858034 -242.651526) (xy 370.804884 -242.647542) (xy 370.752922 -242.635682) (xy 370.703308 -242.61621)
			(xy 370.65715 -242.589561) (xy 370.615479 -242.55633) (xy 370.579227 -242.517259) (xy 370.549203 -242.473222)
			(xy 370.526077 -242.425201) (xy 370.510367 -242.374271) (xy 370.502424 -242.321567) (xy 370.273844 -242.321567)
			(xy 370.265901 -242.374271) (xy 370.250191 -242.425201) (xy 370.227065 -242.473222) (xy 370.197041 -242.517259)
			(xy 370.160789 -242.55633) (xy 370.119118 -242.589561) (xy 370.07296 -242.61621) (xy 370.023346 -242.635682)
			(xy 369.971384 -242.647542) (xy 369.918234 -242.651526) (xy 369.865084 -242.647542) (xy 369.813122 -242.635682)
			(xy 369.763508 -242.61621) (xy 369.71735 -242.589561) (xy 369.675679 -242.55633) (xy 369.639427 -242.517259)
			(xy 369.609403 -242.473222) (xy 369.586277 -242.425201) (xy 369.570567 -242.374271) (xy 369.562624 -242.321567)
			(xy 368.91468 -242.321567) (xy 368.91468 -243.135637) (xy 369.09247 -243.135637) (xy 369.09247 -243.082339)
			(xy 369.100413 -243.029635) (xy 369.116123 -242.978705) (xy 369.139249 -242.930684) (xy 369.169273 -242.886647)
			(xy 369.205525 -242.847576) (xy 369.247196 -242.814345) (xy 369.293354 -242.787696) (xy 369.342968 -242.768224)
			(xy 369.39493 -242.756364) (xy 369.44808 -242.752381) (xy 369.50123 -242.756364) (xy 369.553192 -242.768224)
			(xy 369.602806 -242.787696) (xy 369.648964 -242.814345) (xy 369.690635 -242.847576) (xy 369.726887 -242.886647)
			(xy 369.756911 -242.930684) (xy 369.780037 -242.978705) (xy 369.795747 -243.029635) (xy 369.80369 -243.082339)
			(xy 369.804188 -243.108988) (xy 369.80369 -243.135637) (xy 370.03227 -243.135637) (xy 370.03227 -243.082339)
			(xy 370.040213 -243.029635) (xy 370.055923 -242.978705) (xy 370.079049 -242.930684) (xy 370.109073 -242.886647)
			(xy 370.145325 -242.847576) (xy 370.186996 -242.814345) (xy 370.233154 -242.787696) (xy 370.282768 -242.768224)
			(xy 370.33473 -242.756364) (xy 370.38788 -242.752381) (xy 370.44103 -242.756364) (xy 370.492992 -242.768224)
			(xy 370.542606 -242.787696) (xy 370.588764 -242.814345) (xy 370.630435 -242.847576) (xy 370.666687 -242.886647)
			(xy 370.696711 -242.930684) (xy 370.719837 -242.978705) (xy 370.735547 -243.029635) (xy 370.74349 -243.082339)
			(xy 370.743988 -243.108988) (xy 370.74349 -243.135637) (xy 370.97207 -243.135637) (xy 370.97207 -243.082339)
			(xy 370.980013 -243.029635) (xy 370.995723 -242.978705) (xy 371.018849 -242.930684) (xy 371.048873 -242.886647)
			(xy 371.085125 -242.847576) (xy 371.126796 -242.814345) (xy 371.172954 -242.787696) (xy 371.222568 -242.768224)
			(xy 371.27453 -242.756364) (xy 371.32768 -242.752381) (xy 371.38083 -242.756364) (xy 371.432792 -242.768224)
			(xy 371.482406 -242.787696) (xy 371.528564 -242.814345) (xy 371.570235 -242.847576) (xy 371.606487 -242.886647)
			(xy 371.636511 -242.930684) (xy 371.659637 -242.978705) (xy 371.675347 -243.029635) (xy 371.68329 -243.082339)
			(xy 371.683788 -243.108988) (xy 371.68329 -243.135637) (xy 371.91187 -243.135637) (xy 371.91187 -243.082339)
			(xy 371.919813 -243.029635) (xy 371.935523 -242.978705) (xy 371.958649 -242.930684) (xy 371.988673 -242.886647)
			(xy 372.024925 -242.847576) (xy 372.066596 -242.814345) (xy 372.112754 -242.787696) (xy 372.162368 -242.768224)
			(xy 372.21433 -242.756364) (xy 372.26748 -242.752381) (xy 372.32063 -242.756364) (xy 372.372592 -242.768224)
			(xy 372.422206 -242.787696) (xy 372.468364 -242.814345) (xy 372.510035 -242.847576) (xy 372.546287 -242.886647)
			(xy 372.576311 -242.930684) (xy 372.599437 -242.978705) (xy 372.615147 -243.029635) (xy 372.62309 -243.082339)
			(xy 372.623588 -243.108988) (xy 372.62309 -243.135637) (xy 372.85167 -243.135637) (xy 372.85167 -243.082339)
			(xy 372.859613 -243.029635) (xy 372.875323 -242.978705) (xy 372.898449 -242.930684) (xy 372.928473 -242.886647)
			(xy 372.964725 -242.847576) (xy 373.006396 -242.814345) (xy 373.052554 -242.787696) (xy 373.102168 -242.768224)
			(xy 373.15413 -242.756364) (xy 373.20728 -242.752381) (xy 373.26043 -242.756364) (xy 373.312392 -242.768224)
			(xy 373.362006 -242.787696) (xy 373.408164 -242.814345) (xy 373.449835 -242.847576) (xy 373.486087 -242.886647)
			(xy 373.516111 -242.930684) (xy 373.539237 -242.978705) (xy 373.554947 -243.029635) (xy 373.56289 -243.082339)
			(xy 373.563388 -243.108988) (xy 373.56289 -243.135637) (xy 373.791724 -243.135637) (xy 373.791724 -243.082339)
			(xy 373.799667 -243.029635) (xy 373.815377 -242.978705) (xy 373.838503 -242.930684) (xy 373.868527 -242.886647)
			(xy 373.904779 -242.847576) (xy 373.94645 -242.814345) (xy 373.992608 -242.787696) (xy 374.042222 -242.768224)
			(xy 374.094184 -242.756364) (xy 374.147334 -242.752381) (xy 374.200484 -242.756364) (xy 374.252446 -242.768224)
			(xy 374.30206 -242.787696) (xy 374.348218 -242.814345) (xy 374.389889 -242.847576) (xy 374.426141 -242.886647)
			(xy 374.456165 -242.930684) (xy 374.479291 -242.978705) (xy 374.495001 -243.029635) (xy 374.502944 -243.082339)
			(xy 374.503442 -243.108988) (xy 374.502944 -243.135637) (xy 374.73127 -243.135637) (xy 374.73127 -243.082339)
			(xy 374.739213 -243.029635) (xy 374.754923 -242.978705) (xy 374.778049 -242.930684) (xy 374.808073 -242.886647)
			(xy 374.844325 -242.847576) (xy 374.885996 -242.814345) (xy 374.932154 -242.787696) (xy 374.981768 -242.768224)
			(xy 375.03373 -242.756364) (xy 375.08688 -242.752381) (xy 375.14003 -242.756364) (xy 375.191992 -242.768224)
			(xy 375.241606 -242.787696) (xy 375.287764 -242.814345) (xy 375.329435 -242.847576) (xy 375.365687 -242.886647)
			(xy 375.395711 -242.930684) (xy 375.418837 -242.978705) (xy 375.434547 -243.029635) (xy 375.44249 -243.082339)
			(xy 375.442988 -243.108988) (xy 375.44249 -243.135637) (xy 375.67107 -243.135637) (xy 375.67107 -243.082339)
			(xy 375.679013 -243.029635) (xy 375.694723 -242.978705) (xy 375.717849 -242.930684) (xy 375.747873 -242.886647)
			(xy 375.784125 -242.847576) (xy 375.825796 -242.814345) (xy 375.871954 -242.787696) (xy 375.921568 -242.768224)
			(xy 375.97353 -242.756364) (xy 376.02668 -242.752381) (xy 376.07983 -242.756364) (xy 376.131792 -242.768224)
			(xy 376.181406 -242.787696) (xy 376.227564 -242.814345) (xy 376.269235 -242.847576) (xy 376.305487 -242.886647)
			(xy 376.335511 -242.930684) (xy 376.358637 -242.978705) (xy 376.374347 -243.029635) (xy 376.38229 -243.082339)
			(xy 376.382788 -243.108988) (xy 376.38229 -243.135637) (xy 376.61087 -243.135637) (xy 376.61087 -243.082339)
			(xy 376.618813 -243.029635) (xy 376.634523 -242.978705) (xy 376.657649 -242.930684) (xy 376.687673 -242.886647)
			(xy 376.723925 -242.847576) (xy 376.765596 -242.814345) (xy 376.811754 -242.787696) (xy 376.861368 -242.768224)
			(xy 376.91333 -242.756364) (xy 376.96648 -242.752381) (xy 377.01963 -242.756364) (xy 377.071592 -242.768224)
			(xy 377.121206 -242.787696) (xy 377.167364 -242.814345) (xy 377.209035 -242.847576) (xy 377.245287 -242.886647)
			(xy 377.275311 -242.930684) (xy 377.298437 -242.978705) (xy 377.314147 -243.029635) (xy 377.32209 -243.082339)
			(xy 377.322588 -243.108988) (xy 377.32209 -243.135637) (xy 377.55067 -243.135637) (xy 377.55067 -243.082339)
			(xy 377.558613 -243.029635) (xy 377.574323 -242.978705) (xy 377.597449 -242.930684) (xy 377.627473 -242.886647)
			(xy 377.663725 -242.847576) (xy 377.705396 -242.814345) (xy 377.751554 -242.787696) (xy 377.801168 -242.768224)
			(xy 377.85313 -242.756364) (xy 377.90628 -242.752381) (xy 377.95943 -242.756364) (xy 378.011392 -242.768224)
			(xy 378.061006 -242.787696) (xy 378.107164 -242.814345) (xy 378.148835 -242.847576) (xy 378.185087 -242.886647)
			(xy 378.215111 -242.930684) (xy 378.238237 -242.978705) (xy 378.253947 -243.029635) (xy 378.26189 -243.082339)
			(xy 378.262388 -243.108988) (xy 378.26189 -243.135637) (xy 378.49047 -243.135637) (xy 378.49047 -243.082339)
			(xy 378.498413 -243.029635) (xy 378.514123 -242.978705) (xy 378.537249 -242.930684) (xy 378.567273 -242.886647)
			(xy 378.603525 -242.847576) (xy 378.645196 -242.814345) (xy 378.691354 -242.787696) (xy 378.740968 -242.768224)
			(xy 378.79293 -242.756364) (xy 378.84608 -242.752381) (xy 378.89923 -242.756364) (xy 378.951192 -242.768224)
			(xy 379.000806 -242.787696) (xy 379.046964 -242.814345) (xy 379.088635 -242.847576) (xy 379.124887 -242.886647)
			(xy 379.154911 -242.930684) (xy 379.178037 -242.978705) (xy 379.193747 -243.029635) (xy 379.20169 -243.082339)
			(xy 379.202188 -243.108988) (xy 379.20169 -243.135637) (xy 379.43027 -243.135637) (xy 379.43027 -243.082339)
			(xy 379.438213 -243.029635) (xy 379.453923 -242.978705) (xy 379.477049 -242.930684) (xy 379.507073 -242.886647)
			(xy 379.543325 -242.847576) (xy 379.584996 -242.814345) (xy 379.631154 -242.787696) (xy 379.680768 -242.768224)
			(xy 379.73273 -242.756364) (xy 379.78588 -242.752381) (xy 379.83903 -242.756364) (xy 379.890992 -242.768224)
			(xy 379.940606 -242.787696) (xy 379.986764 -242.814345) (xy 380.028435 -242.847576) (xy 380.064687 -242.886647)
			(xy 380.094711 -242.930684) (xy 380.117837 -242.978705) (xy 380.133547 -243.029635) (xy 380.14149 -243.082339)
			(xy 380.141988 -243.108988) (xy 380.14149 -243.135637) (xy 380.370324 -243.135637) (xy 380.370324 -243.082339)
			(xy 380.378267 -243.029635) (xy 380.393977 -242.978705) (xy 380.417103 -242.930684) (xy 380.447127 -242.886647)
			(xy 380.483379 -242.847576) (xy 380.52505 -242.814345) (xy 380.571208 -242.787696) (xy 380.620822 -242.768224)
			(xy 380.672784 -242.756364) (xy 380.725934 -242.752381) (xy 380.779084 -242.756364) (xy 380.831046 -242.768224)
			(xy 380.88066 -242.787696) (xy 380.926818 -242.814345) (xy 380.968489 -242.847576) (xy 381.004741 -242.886647)
			(xy 381.034765 -242.930684) (xy 381.057891 -242.978705) (xy 381.073601 -243.029635) (xy 381.081544 -243.082339)
			(xy 381.082042 -243.108988) (xy 381.081544 -243.135637) (xy 381.073601 -243.188341) (xy 381.057891 -243.239271)
			(xy 381.034765 -243.287292) (xy 381.004741 -243.331329) (xy 380.968489 -243.3704) (xy 380.926818 -243.403631)
			(xy 380.88066 -243.43028) (xy 380.831046 -243.449752) (xy 380.779084 -243.461612) (xy 380.725934 -243.465596)
			(xy 380.672784 -243.461612) (xy 380.620822 -243.449752) (xy 380.571208 -243.43028) (xy 380.52505 -243.403631)
			(xy 380.483379 -243.3704) (xy 380.447127 -243.331329) (xy 380.417103 -243.287292) (xy 380.393977 -243.239271)
			(xy 380.378267 -243.188341) (xy 380.370324 -243.135637) (xy 380.14149 -243.135637) (xy 380.133547 -243.188341)
			(xy 380.117837 -243.239271) (xy 380.094711 -243.287292) (xy 380.064687 -243.331329) (xy 380.028435 -243.3704)
			(xy 379.986764 -243.403631) (xy 379.940606 -243.43028) (xy 379.890992 -243.449752) (xy 379.83903 -243.461612)
			(xy 379.78588 -243.465596) (xy 379.73273 -243.461612) (xy 379.680768 -243.449752) (xy 379.631154 -243.43028)
			(xy 379.584996 -243.403631) (xy 379.543325 -243.3704) (xy 379.507073 -243.331329) (xy 379.477049 -243.287292)
			(xy 379.453923 -243.239271) (xy 379.438213 -243.188341) (xy 379.43027 -243.135637) (xy 379.20169 -243.135637)
			(xy 379.193747 -243.188341) (xy 379.178037 -243.239271) (xy 379.154911 -243.287292) (xy 379.124887 -243.331329)
			(xy 379.088635 -243.3704) (xy 379.046964 -243.403631) (xy 379.000806 -243.43028) (xy 378.951192 -243.449752)
			(xy 378.89923 -243.461612) (xy 378.84608 -243.465596) (xy 378.79293 -243.461612) (xy 378.740968 -243.449752)
			(xy 378.691354 -243.43028) (xy 378.645196 -243.403631) (xy 378.603525 -243.3704) (xy 378.567273 -243.331329)
			(xy 378.537249 -243.287292) (xy 378.514123 -243.239271) (xy 378.498413 -243.188341) (xy 378.49047 -243.135637)
			(xy 378.26189 -243.135637) (xy 378.253947 -243.188341) (xy 378.238237 -243.239271) (xy 378.215111 -243.287292)
			(xy 378.185087 -243.331329) (xy 378.148835 -243.3704) (xy 378.107164 -243.403631) (xy 378.061006 -243.43028)
			(xy 378.011392 -243.449752) (xy 377.95943 -243.461612) (xy 377.90628 -243.465596) (xy 377.85313 -243.461612)
			(xy 377.801168 -243.449752) (xy 377.751554 -243.43028) (xy 377.705396 -243.403631) (xy 377.663725 -243.3704)
			(xy 377.627473 -243.331329) (xy 377.597449 -243.287292) (xy 377.574323 -243.239271) (xy 377.558613 -243.188341)
			(xy 377.55067 -243.135637) (xy 377.32209 -243.135637) (xy 377.314147 -243.188341) (xy 377.298437 -243.239271)
			(xy 377.275311 -243.287292) (xy 377.245287 -243.331329) (xy 377.209035 -243.3704) (xy 377.167364 -243.403631)
			(xy 377.121206 -243.43028) (xy 377.071592 -243.449752) (xy 377.01963 -243.461612) (xy 376.96648 -243.465596)
			(xy 376.91333 -243.461612) (xy 376.861368 -243.449752) (xy 376.811754 -243.43028) (xy 376.765596 -243.403631)
			(xy 376.723925 -243.3704) (xy 376.687673 -243.331329) (xy 376.657649 -243.287292) (xy 376.634523 -243.239271)
			(xy 376.618813 -243.188341) (xy 376.61087 -243.135637) (xy 376.38229 -243.135637) (xy 376.374347 -243.188341)
			(xy 376.358637 -243.239271) (xy 376.335511 -243.287292) (xy 376.305487 -243.331329) (xy 376.269235 -243.3704)
			(xy 376.227564 -243.403631) (xy 376.181406 -243.43028) (xy 376.131792 -243.449752) (xy 376.07983 -243.461612)
			(xy 376.02668 -243.465596) (xy 375.97353 -243.461612) (xy 375.921568 -243.449752) (xy 375.871954 -243.43028)
			(xy 375.825796 -243.403631) (xy 375.784125 -243.3704) (xy 375.747873 -243.331329) (xy 375.717849 -243.287292)
			(xy 375.694723 -243.239271) (xy 375.679013 -243.188341) (xy 375.67107 -243.135637) (xy 375.44249 -243.135637)
			(xy 375.434547 -243.188341) (xy 375.418837 -243.239271) (xy 375.395711 -243.287292) (xy 375.365687 -243.331329)
			(xy 375.329435 -243.3704) (xy 375.287764 -243.403631) (xy 375.241606 -243.43028) (xy 375.191992 -243.449752)
			(xy 375.14003 -243.461612) (xy 375.08688 -243.465596) (xy 375.03373 -243.461612) (xy 374.981768 -243.449752)
			(xy 374.932154 -243.43028) (xy 374.885996 -243.403631) (xy 374.844325 -243.3704) (xy 374.808073 -243.331329)
			(xy 374.778049 -243.287292) (xy 374.754923 -243.239271) (xy 374.739213 -243.188341) (xy 374.73127 -243.135637)
			(xy 374.502944 -243.135637) (xy 374.495001 -243.188341) (xy 374.479291 -243.239271) (xy 374.456165 -243.287292)
			(xy 374.426141 -243.331329) (xy 374.389889 -243.3704) (xy 374.348218 -243.403631) (xy 374.30206 -243.43028)
			(xy 374.252446 -243.449752) (xy 374.200484 -243.461612) (xy 374.147334 -243.465596) (xy 374.094184 -243.461612)
			(xy 374.042222 -243.449752) (xy 373.992608 -243.43028) (xy 373.94645 -243.403631) (xy 373.904779 -243.3704)
			(xy 373.868527 -243.331329) (xy 373.838503 -243.287292) (xy 373.815377 -243.239271) (xy 373.799667 -243.188341)
			(xy 373.791724 -243.135637) (xy 373.56289 -243.135637) (xy 373.554947 -243.188341) (xy 373.539237 -243.239271)
			(xy 373.516111 -243.287292) (xy 373.486087 -243.331329) (xy 373.449835 -243.3704) (xy 373.408164 -243.403631)
			(xy 373.362006 -243.43028) (xy 373.312392 -243.449752) (xy 373.26043 -243.461612) (xy 373.20728 -243.465596)
			(xy 373.15413 -243.461612) (xy 373.102168 -243.449752) (xy 373.052554 -243.43028) (xy 373.006396 -243.403631)
			(xy 372.964725 -243.3704) (xy 372.928473 -243.331329) (xy 372.898449 -243.287292) (xy 372.875323 -243.239271)
			(xy 372.859613 -243.188341) (xy 372.85167 -243.135637) (xy 372.62309 -243.135637) (xy 372.615147 -243.188341)
			(xy 372.599437 -243.239271) (xy 372.576311 -243.287292) (xy 372.546287 -243.331329) (xy 372.510035 -243.3704)
			(xy 372.468364 -243.403631) (xy 372.422206 -243.43028) (xy 372.372592 -243.449752) (xy 372.32063 -243.461612)
			(xy 372.26748 -243.465596) (xy 372.21433 -243.461612) (xy 372.162368 -243.449752) (xy 372.112754 -243.43028)
			(xy 372.066596 -243.403631) (xy 372.024925 -243.3704) (xy 371.988673 -243.331329) (xy 371.958649 -243.287292)
			(xy 371.935523 -243.239271) (xy 371.919813 -243.188341) (xy 371.91187 -243.135637) (xy 371.68329 -243.135637)
			(xy 371.675347 -243.188341) (xy 371.659637 -243.239271) (xy 371.636511 -243.287292) (xy 371.606487 -243.331329)
			(xy 371.570235 -243.3704) (xy 371.528564 -243.403631) (xy 371.482406 -243.43028) (xy 371.432792 -243.449752)
			(xy 371.38083 -243.461612) (xy 371.32768 -243.465596) (xy 371.27453 -243.461612) (xy 371.222568 -243.449752)
			(xy 371.172954 -243.43028) (xy 371.126796 -243.403631) (xy 371.085125 -243.3704) (xy 371.048873 -243.331329)
			(xy 371.018849 -243.287292) (xy 370.995723 -243.239271) (xy 370.980013 -243.188341) (xy 370.97207 -243.135637)
			(xy 370.74349 -243.135637) (xy 370.735547 -243.188341) (xy 370.719837 -243.239271) (xy 370.696711 -243.287292)
			(xy 370.666687 -243.331329) (xy 370.630435 -243.3704) (xy 370.588764 -243.403631) (xy 370.542606 -243.43028)
			(xy 370.492992 -243.449752) (xy 370.44103 -243.461612) (xy 370.38788 -243.465596) (xy 370.33473 -243.461612)
			(xy 370.282768 -243.449752) (xy 370.233154 -243.43028) (xy 370.186996 -243.403631) (xy 370.145325 -243.3704)
			(xy 370.109073 -243.331329) (xy 370.079049 -243.287292) (xy 370.055923 -243.239271) (xy 370.040213 -243.188341)
			(xy 370.03227 -243.135637) (xy 369.80369 -243.135637) (xy 369.795747 -243.188341) (xy 369.780037 -243.239271)
			(xy 369.756911 -243.287292) (xy 369.726887 -243.331329) (xy 369.690635 -243.3704) (xy 369.648964 -243.403631)
			(xy 369.602806 -243.43028) (xy 369.553192 -243.449752) (xy 369.50123 -243.461612) (xy 369.44808 -243.465596)
			(xy 369.39493 -243.461612) (xy 369.342968 -243.449752) (xy 369.293354 -243.43028) (xy 369.247196 -243.403631)
			(xy 369.205525 -243.3704) (xy 369.169273 -243.331329) (xy 369.139249 -243.287292) (xy 369.116123 -243.239271)
			(xy 369.100413 -243.188341) (xy 369.09247 -243.135637) (xy 368.91468 -243.135637) (xy 368.91468 -243.487448)
			(xy 368.959384 -243.492782) (xy 368.984961 -243.496364) (xy 369.034786 -243.509955) (xy 369.082125 -243.530603)
			(xy 369.125984 -243.557873) (xy 369.165442 -243.591194) (xy 369.199672 -243.629867) (xy 369.227955 -243.673079)
			(xy 369.249698 -243.719925) (xy 369.264444 -243.76942) (xy 369.271885 -243.820527) (xy 369.272312 -243.84635)
			(xy 369.271889 -243.871018) (xy 369.265072 -243.919881) (xy 369.256661 -243.949453) (xy 369.56237 -243.949453)
			(xy 369.56237 -243.896155) (xy 369.570313 -243.843451) (xy 369.586023 -243.792521) (xy 369.609149 -243.7445)
			(xy 369.639173 -243.700463) (xy 369.675425 -243.661392) (xy 369.717096 -243.628161) (xy 369.763254 -243.601512)
			(xy 369.812868 -243.58204) (xy 369.86483 -243.57018) (xy 369.91798 -243.566197) (xy 369.97113 -243.57018)
			(xy 370.023092 -243.58204) (xy 370.072706 -243.601512) (xy 370.118864 -243.628161) (xy 370.160535 -243.661392)
			(xy 370.196787 -243.700463) (xy 370.226811 -243.7445) (xy 370.249937 -243.792521) (xy 370.265647 -243.843451)
			(xy 370.27359 -243.896155) (xy 370.274088 -243.922804) (xy 370.27359 -243.949453) (xy 370.50217 -243.949453)
			(xy 370.50217 -243.896155) (xy 370.510113 -243.843451) (xy 370.525823 -243.792521) (xy 370.548949 -243.7445)
			(xy 370.578973 -243.700463) (xy 370.615225 -243.661392) (xy 370.656896 -243.628161) (xy 370.703054 -243.601512)
			(xy 370.752668 -243.58204) (xy 370.80463 -243.57018) (xy 370.85778 -243.566197) (xy 370.91093 -243.57018)
			(xy 370.962892 -243.58204) (xy 371.012506 -243.601512) (xy 371.058664 -243.628161) (xy 371.100335 -243.661392)
			(xy 371.136587 -243.700463) (xy 371.166611 -243.7445) (xy 371.189737 -243.792521) (xy 371.205447 -243.843451)
			(xy 371.21339 -243.896155) (xy 371.213888 -243.922804) (xy 371.21339 -243.949453) (xy 371.442224 -243.949453)
			(xy 371.442224 -243.896155) (xy 371.450167 -243.843451) (xy 371.465877 -243.792521) (xy 371.489003 -243.7445)
			(xy 371.519027 -243.700463) (xy 371.555279 -243.661392) (xy 371.59695 -243.628161) (xy 371.643108 -243.601512)
			(xy 371.692722 -243.58204) (xy 371.744684 -243.57018) (xy 371.797834 -243.566197) (xy 371.850984 -243.57018)
			(xy 371.902946 -243.58204) (xy 371.95256 -243.601512) (xy 371.998718 -243.628161) (xy 372.040389 -243.661392)
			(xy 372.076641 -243.700463) (xy 372.106665 -243.7445) (xy 372.129791 -243.792521) (xy 372.145501 -243.843451)
			(xy 372.153444 -243.896155) (xy 372.153942 -243.922804) (xy 372.153444 -243.949453) (xy 372.382024 -243.949453)
			(xy 372.382024 -243.896155) (xy 372.389967 -243.843451) (xy 372.405677 -243.792521) (xy 372.428803 -243.7445)
			(xy 372.458827 -243.700463) (xy 372.495079 -243.661392) (xy 372.53675 -243.628161) (xy 372.582908 -243.601512)
			(xy 372.632522 -243.58204) (xy 372.684484 -243.57018) (xy 372.737634 -243.566197) (xy 372.790784 -243.57018)
			(xy 372.842746 -243.58204) (xy 372.89236 -243.601512) (xy 372.938518 -243.628161) (xy 372.980189 -243.661392)
			(xy 373.016441 -243.700463) (xy 373.046465 -243.7445) (xy 373.069591 -243.792521) (xy 373.085301 -243.843451)
			(xy 373.093244 -243.896155) (xy 373.093742 -243.922804) (xy 373.093244 -243.949453) (xy 373.321824 -243.949453)
			(xy 373.321824 -243.896155) (xy 373.329767 -243.843451) (xy 373.345477 -243.792521) (xy 373.368603 -243.7445)
			(xy 373.398627 -243.700463) (xy 373.434879 -243.661392) (xy 373.47655 -243.628161) (xy 373.522708 -243.601512)
			(xy 373.572322 -243.58204) (xy 373.624284 -243.57018) (xy 373.677434 -243.566197) (xy 373.730584 -243.57018)
			(xy 373.782546 -243.58204) (xy 373.83216 -243.601512) (xy 373.878318 -243.628161) (xy 373.919989 -243.661392)
			(xy 373.956241 -243.700463) (xy 373.986265 -243.7445) (xy 374.009391 -243.792521) (xy 374.025101 -243.843451)
			(xy 374.033044 -243.896155) (xy 374.033542 -243.922804) (xy 374.033044 -243.949453) (xy 374.261624 -243.949453)
			(xy 374.261624 -243.896155) (xy 374.269567 -243.843451) (xy 374.285277 -243.792521) (xy 374.308403 -243.7445)
			(xy 374.338427 -243.700463) (xy 374.374679 -243.661392) (xy 374.41635 -243.628161) (xy 374.462508 -243.601512)
			(xy 374.512122 -243.58204) (xy 374.564084 -243.57018) (xy 374.617234 -243.566197) (xy 374.670384 -243.57018)
			(xy 374.722346 -243.58204) (xy 374.77196 -243.601512) (xy 374.818118 -243.628161) (xy 374.859789 -243.661392)
			(xy 374.896041 -243.700463) (xy 374.926065 -243.7445) (xy 374.949191 -243.792521) (xy 374.964901 -243.843451)
			(xy 374.972844 -243.896155) (xy 374.973342 -243.922804) (xy 374.972844 -243.949453) (xy 375.201424 -243.949453)
			(xy 375.201424 -243.896155) (xy 375.209367 -243.843451) (xy 375.225077 -243.792521) (xy 375.248203 -243.7445)
			(xy 375.278227 -243.700463) (xy 375.314479 -243.661392) (xy 375.35615 -243.628161) (xy 375.402308 -243.601512)
			(xy 375.451922 -243.58204) (xy 375.503884 -243.57018) (xy 375.557034 -243.566197) (xy 375.610184 -243.57018)
			(xy 375.662146 -243.58204) (xy 375.71176 -243.601512) (xy 375.757918 -243.628161) (xy 375.799589 -243.661392)
			(xy 375.835841 -243.700463) (xy 375.865865 -243.7445) (xy 375.888991 -243.792521) (xy 375.904701 -243.843451)
			(xy 375.912644 -243.896155) (xy 375.913142 -243.922804) (xy 375.912644 -243.949453) (xy 376.141224 -243.949453)
			(xy 376.141224 -243.896155) (xy 376.149167 -243.843451) (xy 376.164877 -243.792521) (xy 376.188003 -243.7445)
			(xy 376.218027 -243.700463) (xy 376.254279 -243.661392) (xy 376.29595 -243.628161) (xy 376.342108 -243.601512)
			(xy 376.391722 -243.58204) (xy 376.443684 -243.57018) (xy 376.496834 -243.566197) (xy 376.549984 -243.57018)
			(xy 376.601946 -243.58204) (xy 376.65156 -243.601512) (xy 376.697718 -243.628161) (xy 376.739389 -243.661392)
			(xy 376.775641 -243.700463) (xy 376.805665 -243.7445) (xy 376.828791 -243.792521) (xy 376.844501 -243.843451)
			(xy 376.852444 -243.896155) (xy 376.852942 -243.922804) (xy 376.852444 -243.949453) (xy 377.08077 -243.949453)
			(xy 377.08077 -243.896155) (xy 377.088713 -243.843451) (xy 377.104423 -243.792521) (xy 377.127549 -243.7445)
			(xy 377.157573 -243.700463) (xy 377.193825 -243.661392) (xy 377.235496 -243.628161) (xy 377.281654 -243.601512)
			(xy 377.331268 -243.58204) (xy 377.38323 -243.57018) (xy 377.43638 -243.566197) (xy 377.48953 -243.57018)
			(xy 377.541492 -243.58204) (xy 377.591106 -243.601512) (xy 377.637264 -243.628161) (xy 377.678935 -243.661392)
			(xy 377.715187 -243.700463) (xy 377.745211 -243.7445) (xy 377.768337 -243.792521) (xy 377.784047 -243.843451)
			(xy 377.79199 -243.896155) (xy 377.792488 -243.922804) (xy 377.79199 -243.949453) (xy 378.020824 -243.949453)
			(xy 378.020824 -243.896155) (xy 378.028767 -243.843451) (xy 378.044477 -243.792521) (xy 378.067603 -243.7445)
			(xy 378.097627 -243.700463) (xy 378.133879 -243.661392) (xy 378.17555 -243.628161) (xy 378.221708 -243.601512)
			(xy 378.271322 -243.58204) (xy 378.323284 -243.57018) (xy 378.376434 -243.566197) (xy 378.429584 -243.57018)
			(xy 378.481546 -243.58204) (xy 378.53116 -243.601512) (xy 378.577318 -243.628161) (xy 378.618989 -243.661392)
			(xy 378.655241 -243.700463) (xy 378.685265 -243.7445) (xy 378.708391 -243.792521) (xy 378.724101 -243.843451)
			(xy 378.732044 -243.896155) (xy 378.732542 -243.922804) (xy 378.732044 -243.949453) (xy 378.960624 -243.949453)
			(xy 378.960624 -243.896155) (xy 378.968567 -243.843451) (xy 378.984277 -243.792521) (xy 379.007403 -243.7445)
			(xy 379.037427 -243.700463) (xy 379.073679 -243.661392) (xy 379.11535 -243.628161) (xy 379.161508 -243.601512)
			(xy 379.211122 -243.58204) (xy 379.263084 -243.57018) (xy 379.316234 -243.566197) (xy 379.369384 -243.57018)
			(xy 379.421346 -243.58204) (xy 379.47096 -243.601512) (xy 379.517118 -243.628161) (xy 379.558789 -243.661392)
			(xy 379.595041 -243.700463) (xy 379.625065 -243.7445) (xy 379.648191 -243.792521) (xy 379.663901 -243.843451)
			(xy 379.671844 -243.896155) (xy 379.672342 -243.922804) (xy 379.671844 -243.949453) (xy 379.900424 -243.949453)
			(xy 379.900424 -243.896155) (xy 379.908367 -243.843451) (xy 379.924077 -243.792521) (xy 379.947203 -243.7445)
			(xy 379.977227 -243.700463) (xy 380.013479 -243.661392) (xy 380.05515 -243.628161) (xy 380.101308 -243.601512)
			(xy 380.150922 -243.58204) (xy 380.202884 -243.57018) (xy 380.256034 -243.566197) (xy 380.309184 -243.57018)
			(xy 380.361146 -243.58204) (xy 380.41076 -243.601512) (xy 380.456918 -243.628161) (xy 380.498589 -243.661392)
			(xy 380.534841 -243.700463) (xy 380.564865 -243.7445) (xy 380.587991 -243.792521) (xy 380.603701 -243.843451)
			(xy 380.611644 -243.896155) (xy 380.612142 -243.922804) (xy 380.611644 -243.949453) (xy 380.840224 -243.949453)
			(xy 380.840224 -243.896155) (xy 380.848167 -243.843451) (xy 380.863877 -243.792521) (xy 380.887003 -243.7445)
			(xy 380.917027 -243.700463) (xy 380.953279 -243.661392) (xy 380.99495 -243.628161) (xy 381.041108 -243.601512)
			(xy 381.090722 -243.58204) (xy 381.142684 -243.57018) (xy 381.195834 -243.566197) (xy 381.248984 -243.57018)
			(xy 381.300946 -243.58204) (xy 381.35056 -243.601512) (xy 381.396718 -243.628161) (xy 381.438389 -243.661392)
			(xy 381.474641 -243.700463) (xy 381.504665 -243.7445) (xy 381.527791 -243.792521) (xy 381.543501 -243.843451)
			(xy 381.551444 -243.896155) (xy 381.551942 -243.922804) (xy 381.551444 -243.949453) (xy 381.543501 -244.002157)
			(xy 381.527791 -244.053087) (xy 381.504665 -244.101108) (xy 381.474641 -244.145145) (xy 381.438389 -244.184216)
			(xy 381.396718 -244.217447) (xy 381.35056 -244.244096) (xy 381.300946 -244.263568) (xy 381.248984 -244.275428)
			(xy 381.195834 -244.279412) (xy 381.142684 -244.275428) (xy 381.090722 -244.263568) (xy 381.041108 -244.244096)
			(xy 380.99495 -244.217447) (xy 380.953279 -244.184216) (xy 380.917027 -244.145145) (xy 380.887003 -244.101108)
			(xy 380.863877 -244.053087) (xy 380.848167 -244.002157) (xy 380.840224 -243.949453) (xy 380.611644 -243.949453)
			(xy 380.603701 -244.002157) (xy 380.587991 -244.053087) (xy 380.564865 -244.101108) (xy 380.534841 -244.145145)
			(xy 380.498589 -244.184216) (xy 380.456918 -244.217447) (xy 380.41076 -244.244096) (xy 380.361146 -244.263568)
			(xy 380.309184 -244.275428) (xy 380.256034 -244.279412) (xy 380.202884 -244.275428) (xy 380.150922 -244.263568)
			(xy 380.101308 -244.244096) (xy 380.05515 -244.217447) (xy 380.013479 -244.184216) (xy 379.977227 -244.145145)
			(xy 379.947203 -244.101108) (xy 379.924077 -244.053087) (xy 379.908367 -244.002157) (xy 379.900424 -243.949453)
			(xy 379.671844 -243.949453) (xy 379.663901 -244.002157) (xy 379.648191 -244.053087) (xy 379.625065 -244.101108)
			(xy 379.595041 -244.145145) (xy 379.558789 -244.184216) (xy 379.517118 -244.217447) (xy 379.47096 -244.244096)
			(xy 379.421346 -244.263568) (xy 379.369384 -244.275428) (xy 379.316234 -244.279412) (xy 379.263084 -244.275428)
			(xy 379.211122 -244.263568) (xy 379.161508 -244.244096) (xy 379.11535 -244.217447) (xy 379.073679 -244.184216)
			(xy 379.037427 -244.145145) (xy 379.007403 -244.101108) (xy 378.984277 -244.053087) (xy 378.968567 -244.002157)
			(xy 378.960624 -243.949453) (xy 378.732044 -243.949453) (xy 378.724101 -244.002157) (xy 378.708391 -244.053087)
			(xy 378.685265 -244.101108) (xy 378.655241 -244.145145) (xy 378.618989 -244.184216) (xy 378.577318 -244.217447)
			(xy 378.53116 -244.244096) (xy 378.481546 -244.263568) (xy 378.429584 -244.275428) (xy 378.376434 -244.279412)
			(xy 378.323284 -244.275428) (xy 378.271322 -244.263568) (xy 378.221708 -244.244096) (xy 378.17555 -244.217447)
			(xy 378.133879 -244.184216) (xy 378.097627 -244.145145) (xy 378.067603 -244.101108) (xy 378.044477 -244.053087)
			(xy 378.028767 -244.002157) (xy 378.020824 -243.949453) (xy 377.79199 -243.949453) (xy 377.784047 -244.002157)
			(xy 377.768337 -244.053087) (xy 377.745211 -244.101108) (xy 377.715187 -244.145145) (xy 377.678935 -244.184216)
			(xy 377.637264 -244.217447) (xy 377.591106 -244.244096) (xy 377.541492 -244.263568) (xy 377.48953 -244.275428)
			(xy 377.43638 -244.279412) (xy 377.38323 -244.275428) (xy 377.331268 -244.263568) (xy 377.281654 -244.244096)
			(xy 377.235496 -244.217447) (xy 377.193825 -244.184216) (xy 377.157573 -244.145145) (xy 377.127549 -244.101108)
			(xy 377.104423 -244.053087) (xy 377.088713 -244.002157) (xy 377.08077 -243.949453) (xy 376.852444 -243.949453)
			(xy 376.844501 -244.002157) (xy 376.828791 -244.053087) (xy 376.805665 -244.101108) (xy 376.775641 -244.145145)
			(xy 376.739389 -244.184216) (xy 376.697718 -244.217447) (xy 376.65156 -244.244096) (xy 376.601946 -244.263568)
			(xy 376.549984 -244.275428) (xy 376.496834 -244.279412) (xy 376.443684 -244.275428) (xy 376.391722 -244.263568)
			(xy 376.342108 -244.244096) (xy 376.29595 -244.217447) (xy 376.254279 -244.184216) (xy 376.218027 -244.145145)
			(xy 376.188003 -244.101108) (xy 376.164877 -244.053087) (xy 376.149167 -244.002157) (xy 376.141224 -243.949453)
			(xy 375.912644 -243.949453) (xy 375.904701 -244.002157) (xy 375.888991 -244.053087) (xy 375.865865 -244.101108)
			(xy 375.835841 -244.145145) (xy 375.799589 -244.184216) (xy 375.757918 -244.217447) (xy 375.71176 -244.244096)
			(xy 375.662146 -244.263568) (xy 375.610184 -244.275428) (xy 375.557034 -244.279412) (xy 375.503884 -244.275428)
			(xy 375.451922 -244.263568) (xy 375.402308 -244.244096) (xy 375.35615 -244.217447) (xy 375.314479 -244.184216)
			(xy 375.278227 -244.145145) (xy 375.248203 -244.101108) (xy 375.225077 -244.053087) (xy 375.209367 -244.002157)
			(xy 375.201424 -243.949453) (xy 374.972844 -243.949453) (xy 374.964901 -244.002157) (xy 374.949191 -244.053087)
			(xy 374.926065 -244.101108) (xy 374.896041 -244.145145) (xy 374.859789 -244.184216) (xy 374.818118 -244.217447)
			(xy 374.77196 -244.244096) (xy 374.722346 -244.263568) (xy 374.670384 -244.275428) (xy 374.617234 -244.279412)
			(xy 374.564084 -244.275428) (xy 374.512122 -244.263568) (xy 374.462508 -244.244096) (xy 374.41635 -244.217447)
			(xy 374.374679 -244.184216) (xy 374.338427 -244.145145) (xy 374.308403 -244.101108) (xy 374.285277 -244.053087)
			(xy 374.269567 -244.002157) (xy 374.261624 -243.949453) (xy 374.033044 -243.949453) (xy 374.025101 -244.002157)
			(xy 374.009391 -244.053087) (xy 373.986265 -244.101108) (xy 373.956241 -244.145145) (xy 373.919989 -244.184216)
			(xy 373.878318 -244.217447) (xy 373.83216 -244.244096) (xy 373.782546 -244.263568) (xy 373.730584 -244.275428)
			(xy 373.677434 -244.279412) (xy 373.624284 -244.275428) (xy 373.572322 -244.263568) (xy 373.522708 -244.244096)
			(xy 373.47655 -244.217447) (xy 373.434879 -244.184216) (xy 373.398627 -244.145145) (xy 373.368603 -244.101108)
			(xy 373.345477 -244.053087) (xy 373.329767 -244.002157) (xy 373.321824 -243.949453) (xy 373.093244 -243.949453)
			(xy 373.085301 -244.002157) (xy 373.069591 -244.053087) (xy 373.046465 -244.101108) (xy 373.016441 -244.145145)
			(xy 372.980189 -244.184216) (xy 372.938518 -244.217447) (xy 372.89236 -244.244096) (xy 372.842746 -244.263568)
			(xy 372.790784 -244.275428) (xy 372.737634 -244.279412) (xy 372.684484 -244.275428) (xy 372.632522 -244.263568)
			(xy 372.582908 -244.244096) (xy 372.53675 -244.217447) (xy 372.495079 -244.184216) (xy 372.458827 -244.145145)
			(xy 372.428803 -244.101108) (xy 372.405677 -244.053087) (xy 372.389967 -244.002157) (xy 372.382024 -243.949453)
			(xy 372.153444 -243.949453) (xy 372.145501 -244.002157) (xy 372.129791 -244.053087) (xy 372.106665 -244.101108)
			(xy 372.076641 -244.145145) (xy 372.040389 -244.184216) (xy 371.998718 -244.217447) (xy 371.95256 -244.244096)
			(xy 371.902946 -244.263568) (xy 371.850984 -244.275428) (xy 371.797834 -244.279412) (xy 371.744684 -244.275428)
			(xy 371.692722 -244.263568) (xy 371.643108 -244.244096) (xy 371.59695 -244.217447) (xy 371.555279 -244.184216)
			(xy 371.519027 -244.145145) (xy 371.489003 -244.101108) (xy 371.465877 -244.053087) (xy 371.450167 -244.002157)
			(xy 371.442224 -243.949453) (xy 371.21339 -243.949453) (xy 371.205447 -244.002157) (xy 371.189737 -244.053087)
			(xy 371.166611 -244.101108) (xy 371.136587 -244.145145) (xy 371.100335 -244.184216) (xy 371.058664 -244.217447)
			(xy 371.012506 -244.244096) (xy 370.962892 -244.263568) (xy 370.91093 -244.275428) (xy 370.85778 -244.279412)
			(xy 370.80463 -244.275428) (xy 370.752668 -244.263568) (xy 370.703054 -244.244096) (xy 370.656896 -244.217447)
			(xy 370.615225 -244.184216) (xy 370.578973 -244.145145) (xy 370.548949 -244.101108) (xy 370.525823 -244.053087)
			(xy 370.510113 -244.002157) (xy 370.50217 -243.949453) (xy 370.27359 -243.949453) (xy 370.265647 -244.002157)
			(xy 370.249937 -244.053087) (xy 370.226811 -244.101108) (xy 370.196787 -244.145145) (xy 370.160535 -244.184216)
			(xy 370.118864 -244.217447) (xy 370.072706 -244.244096) (xy 370.023092 -244.263568) (xy 369.97113 -244.275428)
			(xy 369.91798 -244.279412) (xy 369.86483 -244.275428) (xy 369.812868 -244.263568) (xy 369.763254 -244.244096)
			(xy 369.717096 -244.217447) (xy 369.675425 -244.184216) (xy 369.639173 -244.145145) (xy 369.609149 -244.101108)
			(xy 369.586023 -244.053087) (xy 369.570313 -244.002157) (xy 369.56237 -243.949453) (xy 369.256661 -243.949453)
			(xy 369.251575 -243.967335) (xy 369.231656 -244.012472) (xy 369.205698 -244.054427) (xy 369.19027 -244.07368)
			(xy 369.18165 -244.084809) (xy 369.170316 -244.110566) (xy 369.166447 -244.138439) (xy 369.170337 -244.166309)
			(xy 369.181691 -244.192056) (xy 369.19027 -244.20322) (xy 369.204338 -244.220733) (xy 369.228421 -244.258655)
			(xy 369.247544 -244.299304) (xy 369.254786 -244.320568) (xy 369.259879 -244.334667) (xy 369.276939 -244.359297)
			(xy 369.300417 -244.377913) (xy 369.328288 -244.388908) (xy 369.358151 -244.391336) (xy 369.372896 -244.38864)
			(xy 369.391461 -244.384847) (xy 369.429134 -244.38077) (xy 369.44808 -244.380512) (xy 369.474731 -244.380984)
			(xy 369.527437 -244.388925) (xy 369.578371 -244.404634) (xy 369.626394 -244.427758) (xy 369.670435 -244.457782)
			(xy 369.709509 -244.494035) (xy 369.742742 -244.535707) (xy 369.769394 -244.581867) (xy 369.788868 -244.631483)
			(xy 369.800729 -244.683448) (xy 369.804712 -244.7366) (xy 369.802733 -244.763015) (xy 370.03227 -244.763015)
			(xy 370.03227 -244.709717) (xy 370.040213 -244.657013) (xy 370.055923 -244.606083) (xy 370.079049 -244.558062)
			(xy 370.109073 -244.514025) (xy 370.145325 -244.474954) (xy 370.186996 -244.441723) (xy 370.233154 -244.415074)
			(xy 370.282768 -244.395602) (xy 370.33473 -244.383742) (xy 370.38788 -244.379759) (xy 370.44103 -244.383742)
			(xy 370.492992 -244.395602) (xy 370.542606 -244.415074) (xy 370.588764 -244.441723) (xy 370.630435 -244.474954)
			(xy 370.666687 -244.514025) (xy 370.696711 -244.558062) (xy 370.719837 -244.606083) (xy 370.735547 -244.657013)
			(xy 370.74349 -244.709717) (xy 370.743988 -244.736366) (xy 370.74349 -244.763015) (xy 370.743452 -244.763269)
			(xy 370.97207 -244.763269) (xy 370.97207 -244.709971) (xy 370.980013 -244.657267) (xy 370.995723 -244.606337)
			(xy 371.018849 -244.558316) (xy 371.048873 -244.514279) (xy 371.085125 -244.475208) (xy 371.126796 -244.441977)
			(xy 371.172954 -244.415328) (xy 371.222568 -244.395856) (xy 371.27453 -244.383996) (xy 371.32768 -244.380013)
			(xy 371.38083 -244.383996) (xy 371.432792 -244.395856) (xy 371.482406 -244.415328) (xy 371.528564 -244.441977)
			(xy 371.570235 -244.475208) (xy 371.606487 -244.514279) (xy 371.636511 -244.558316) (xy 371.659637 -244.606337)
			(xy 371.675347 -244.657267) (xy 371.68329 -244.709971) (xy 371.683788 -244.73662) (xy 371.68329 -244.763269)
			(xy 371.91187 -244.763269) (xy 371.91187 -244.709971) (xy 371.919813 -244.657267) (xy 371.935523 -244.606337)
			(xy 371.958649 -244.558316) (xy 371.988673 -244.514279) (xy 372.024925 -244.475208) (xy 372.066596 -244.441977)
			(xy 372.112754 -244.415328) (xy 372.162368 -244.395856) (xy 372.21433 -244.383996) (xy 372.26748 -244.380013)
			(xy 372.32063 -244.383996) (xy 372.372592 -244.395856) (xy 372.422206 -244.415328) (xy 372.468364 -244.441977)
			(xy 372.510035 -244.475208) (xy 372.546287 -244.514279) (xy 372.576311 -244.558316) (xy 372.599437 -244.606337)
			(xy 372.615147 -244.657267) (xy 372.62309 -244.709971) (xy 372.623588 -244.73662) (xy 372.62309 -244.763269)
			(xy 372.851924 -244.763269) (xy 372.851924 -244.709971) (xy 372.859867 -244.657267) (xy 372.875577 -244.606337)
			(xy 372.898703 -244.558316) (xy 372.928727 -244.514279) (xy 372.964979 -244.475208) (xy 373.00665 -244.441977)
			(xy 373.052808 -244.415328) (xy 373.102422 -244.395856) (xy 373.154384 -244.383996) (xy 373.207534 -244.380013)
			(xy 373.260684 -244.383996) (xy 373.312646 -244.395856) (xy 373.36226 -244.415328) (xy 373.408418 -244.441977)
			(xy 373.450089 -244.475208) (xy 373.486341 -244.514279) (xy 373.516365 -244.558316) (xy 373.539491 -244.606337)
			(xy 373.555201 -244.657267) (xy 373.563144 -244.709971) (xy 373.563642 -244.73662) (xy 373.563144 -244.763269)
			(xy 373.79147 -244.763269) (xy 373.79147 -244.709971) (xy 373.799413 -244.657267) (xy 373.815123 -244.606337)
			(xy 373.838249 -244.558316) (xy 373.868273 -244.514279) (xy 373.904525 -244.475208) (xy 373.946196 -244.441977)
			(xy 373.992354 -244.415328) (xy 374.041968 -244.395856) (xy 374.09393 -244.383996) (xy 374.14708 -244.380013)
			(xy 374.20023 -244.383996) (xy 374.252192 -244.395856) (xy 374.301806 -244.415328) (xy 374.347964 -244.441977)
			(xy 374.389635 -244.475208) (xy 374.425887 -244.514279) (xy 374.455911 -244.558316) (xy 374.479037 -244.606337)
			(xy 374.494747 -244.657267) (xy 374.50269 -244.709971) (xy 374.503188 -244.73662) (xy 374.50269 -244.763269)
			(xy 374.731524 -244.763269) (xy 374.731524 -244.709971) (xy 374.739467 -244.657267) (xy 374.755177 -244.606337)
			(xy 374.778303 -244.558316) (xy 374.808327 -244.514279) (xy 374.844579 -244.475208) (xy 374.88625 -244.441977)
			(xy 374.932408 -244.415328) (xy 374.982022 -244.395856) (xy 375.033984 -244.383996) (xy 375.087134 -244.380013)
			(xy 375.140284 -244.383996) (xy 375.192246 -244.395856) (xy 375.24186 -244.415328) (xy 375.288018 -244.441977)
			(xy 375.329689 -244.475208) (xy 375.365941 -244.514279) (xy 375.395965 -244.558316) (xy 375.419091 -244.606337)
			(xy 375.434801 -244.657267) (xy 375.442744 -244.709971) (xy 375.443242 -244.73662) (xy 375.442744 -244.763269)
			(xy 375.67107 -244.763269) (xy 375.67107 -244.709971) (xy 375.679013 -244.657267) (xy 375.694723 -244.606337)
			(xy 375.717849 -244.558316) (xy 375.747873 -244.514279) (xy 375.784125 -244.475208) (xy 375.825796 -244.441977)
			(xy 375.871954 -244.415328) (xy 375.921568 -244.395856) (xy 375.97353 -244.383996) (xy 376.02668 -244.380013)
			(xy 376.07983 -244.383996) (xy 376.131792 -244.395856) (xy 376.181406 -244.415328) (xy 376.227564 -244.441977)
			(xy 376.269235 -244.475208) (xy 376.305487 -244.514279) (xy 376.335511 -244.558316) (xy 376.358637 -244.606337)
			(xy 376.374347 -244.657267) (xy 376.38229 -244.709971) (xy 376.382788 -244.73662) (xy 376.38229 -244.763269)
			(xy 376.61087 -244.763269) (xy 376.61087 -244.709971) (xy 376.618813 -244.657267) (xy 376.634523 -244.606337)
			(xy 376.657649 -244.558316) (xy 376.687673 -244.514279) (xy 376.723925 -244.475208) (xy 376.765596 -244.441977)
			(xy 376.811754 -244.415328) (xy 376.861368 -244.395856) (xy 376.91333 -244.383996) (xy 376.96648 -244.380013)
			(xy 377.01963 -244.383996) (xy 377.071592 -244.395856) (xy 377.121206 -244.415328) (xy 377.167364 -244.441977)
			(xy 377.209035 -244.475208) (xy 377.245287 -244.514279) (xy 377.275311 -244.558316) (xy 377.298437 -244.606337)
			(xy 377.314147 -244.657267) (xy 377.32209 -244.709971) (xy 377.322588 -244.73662) (xy 377.32209 -244.763269)
			(xy 377.55067 -244.763269) (xy 377.55067 -244.709971) (xy 377.558613 -244.657267) (xy 377.574323 -244.606337)
			(xy 377.597449 -244.558316) (xy 377.627473 -244.514279) (xy 377.663725 -244.475208) (xy 377.705396 -244.441977)
			(xy 377.751554 -244.415328) (xy 377.801168 -244.395856) (xy 377.85313 -244.383996) (xy 377.90628 -244.380013)
			(xy 377.95943 -244.383996) (xy 378.011392 -244.395856) (xy 378.061006 -244.415328) (xy 378.107164 -244.441977)
			(xy 378.148835 -244.475208) (xy 378.185087 -244.514279) (xy 378.215111 -244.558316) (xy 378.238237 -244.606337)
			(xy 378.253947 -244.657267) (xy 378.26189 -244.709971) (xy 378.262388 -244.73662) (xy 378.26189 -244.763269)
			(xy 378.49047 -244.763269) (xy 378.49047 -244.709971) (xy 378.498413 -244.657267) (xy 378.514123 -244.606337)
			(xy 378.537249 -244.558316) (xy 378.567273 -244.514279) (xy 378.603525 -244.475208) (xy 378.645196 -244.441977)
			(xy 378.691354 -244.415328) (xy 378.740968 -244.395856) (xy 378.79293 -244.383996) (xy 378.84608 -244.380013)
			(xy 378.89923 -244.383996) (xy 378.951192 -244.395856) (xy 379.000806 -244.415328) (xy 379.046964 -244.441977)
			(xy 379.088635 -244.475208) (xy 379.124887 -244.514279) (xy 379.154911 -244.558316) (xy 379.178037 -244.606337)
			(xy 379.193747 -244.657267) (xy 379.20169 -244.709971) (xy 379.202188 -244.73662) (xy 379.20169 -244.763269)
			(xy 379.430524 -244.763269) (xy 379.430524 -244.709971) (xy 379.438467 -244.657267) (xy 379.454177 -244.606337)
			(xy 379.477303 -244.558316) (xy 379.507327 -244.514279) (xy 379.543579 -244.475208) (xy 379.58525 -244.441977)
			(xy 379.631408 -244.415328) (xy 379.681022 -244.395856) (xy 379.732984 -244.383996) (xy 379.786134 -244.380013)
			(xy 379.839284 -244.383996) (xy 379.891246 -244.395856) (xy 379.94086 -244.415328) (xy 379.987018 -244.441977)
			(xy 380.028689 -244.475208) (xy 380.064941 -244.514279) (xy 380.094965 -244.558316) (xy 380.118091 -244.606337)
			(xy 380.133801 -244.657267) (xy 380.141744 -244.709971) (xy 380.142242 -244.73662) (xy 380.141744 -244.763269)
			(xy 380.37007 -244.763269) (xy 380.37007 -244.709971) (xy 380.378013 -244.657267) (xy 380.393723 -244.606337)
			(xy 380.416849 -244.558316) (xy 380.446873 -244.514279) (xy 380.483125 -244.475208) (xy 380.524796 -244.441977)
			(xy 380.570954 -244.415328) (xy 380.620568 -244.395856) (xy 380.67253 -244.383996) (xy 380.72568 -244.380013)
			(xy 380.77883 -244.383996) (xy 380.830792 -244.395856) (xy 380.880406 -244.415328) (xy 380.926564 -244.441977)
			(xy 380.968235 -244.475208) (xy 381.004487 -244.514279) (xy 381.034511 -244.558316) (xy 381.057637 -244.606337)
			(xy 381.073347 -244.657267) (xy 381.08129 -244.709971) (xy 381.081788 -244.73662) (xy 381.08129 -244.763269)
			(xy 381.073347 -244.815973) (xy 381.057637 -244.866903) (xy 381.034511 -244.914924) (xy 381.004487 -244.958961)
			(xy 380.968235 -244.998032) (xy 380.926564 -245.031263) (xy 380.880406 -245.057912) (xy 380.830792 -245.077384)
			(xy 380.77883 -245.089244) (xy 380.72568 -245.093228) (xy 380.67253 -245.089244) (xy 380.620568 -245.077384)
			(xy 380.570954 -245.057912) (xy 380.524796 -245.031263) (xy 380.483125 -244.998032) (xy 380.446873 -244.958961)
			(xy 380.416849 -244.914924) (xy 380.393723 -244.866903) (xy 380.378013 -244.815973) (xy 380.37007 -244.763269)
			(xy 380.141744 -244.763269) (xy 380.133801 -244.815973) (xy 380.118091 -244.866903) (xy 380.094965 -244.914924)
			(xy 380.064941 -244.958961) (xy 380.028689 -244.998032) (xy 379.987018 -245.031263) (xy 379.94086 -245.057912)
			(xy 379.891246 -245.077384) (xy 379.839284 -245.089244) (xy 379.786134 -245.093228) (xy 379.732984 -245.089244)
			(xy 379.681022 -245.077384) (xy 379.631408 -245.057912) (xy 379.58525 -245.031263) (xy 379.543579 -244.998032)
			(xy 379.507327 -244.958961) (xy 379.477303 -244.914924) (xy 379.454177 -244.866903) (xy 379.438467 -244.815973)
			(xy 379.430524 -244.763269) (xy 379.20169 -244.763269) (xy 379.193747 -244.815973) (xy 379.178037 -244.866903)
			(xy 379.154911 -244.914924) (xy 379.124887 -244.958961) (xy 379.088635 -244.998032) (xy 379.046964 -245.031263)
			(xy 379.000806 -245.057912) (xy 378.951192 -245.077384) (xy 378.89923 -245.089244) (xy 378.84608 -245.093228)
			(xy 378.79293 -245.089244) (xy 378.740968 -245.077384) (xy 378.691354 -245.057912) (xy 378.645196 -245.031263)
			(xy 378.603525 -244.998032) (xy 378.567273 -244.958961) (xy 378.537249 -244.914924) (xy 378.514123 -244.866903)
			(xy 378.498413 -244.815973) (xy 378.49047 -244.763269) (xy 378.26189 -244.763269) (xy 378.253947 -244.815973)
			(xy 378.238237 -244.866903) (xy 378.215111 -244.914924) (xy 378.185087 -244.958961) (xy 378.148835 -244.998032)
			(xy 378.107164 -245.031263) (xy 378.061006 -245.057912) (xy 378.011392 -245.077384) (xy 377.95943 -245.089244)
			(xy 377.90628 -245.093228) (xy 377.85313 -245.089244) (xy 377.801168 -245.077384) (xy 377.751554 -245.057912)
			(xy 377.705396 -245.031263) (xy 377.663725 -244.998032) (xy 377.627473 -244.958961) (xy 377.597449 -244.914924)
			(xy 377.574323 -244.866903) (xy 377.558613 -244.815973) (xy 377.55067 -244.763269) (xy 377.32209 -244.763269)
			(xy 377.314147 -244.815973) (xy 377.298437 -244.866903) (xy 377.275311 -244.914924) (xy 377.245287 -244.958961)
			(xy 377.209035 -244.998032) (xy 377.167364 -245.031263) (xy 377.121206 -245.057912) (xy 377.071592 -245.077384)
			(xy 377.01963 -245.089244) (xy 376.96648 -245.093228) (xy 376.91333 -245.089244) (xy 376.861368 -245.077384)
			(xy 376.811754 -245.057912) (xy 376.765596 -245.031263) (xy 376.723925 -244.998032) (xy 376.687673 -244.958961)
			(xy 376.657649 -244.914924) (xy 376.634523 -244.866903) (xy 376.618813 -244.815973) (xy 376.61087 -244.763269)
			(xy 376.38229 -244.763269) (xy 376.374347 -244.815973) (xy 376.358637 -244.866903) (xy 376.335511 -244.914924)
			(xy 376.305487 -244.958961) (xy 376.269235 -244.998032) (xy 376.227564 -245.031263) (xy 376.181406 -245.057912)
			(xy 376.131792 -245.077384) (xy 376.07983 -245.089244) (xy 376.02668 -245.093228) (xy 375.97353 -245.089244)
			(xy 375.921568 -245.077384) (xy 375.871954 -245.057912) (xy 375.825796 -245.031263) (xy 375.784125 -244.998032)
			(xy 375.747873 -244.958961) (xy 375.717849 -244.914924) (xy 375.694723 -244.866903) (xy 375.679013 -244.815973)
			(xy 375.67107 -244.763269) (xy 375.442744 -244.763269) (xy 375.434801 -244.815973) (xy 375.419091 -244.866903)
			(xy 375.395965 -244.914924) (xy 375.365941 -244.958961) (xy 375.329689 -244.998032) (xy 375.288018 -245.031263)
			(xy 375.24186 -245.057912) (xy 375.192246 -245.077384) (xy 375.140284 -245.089244) (xy 375.087134 -245.093228)
			(xy 375.033984 -245.089244) (xy 374.982022 -245.077384) (xy 374.932408 -245.057912) (xy 374.88625 -245.031263)
			(xy 374.844579 -244.998032) (xy 374.808327 -244.958961) (xy 374.778303 -244.914924) (xy 374.755177 -244.866903)
			(xy 374.739467 -244.815973) (xy 374.731524 -244.763269) (xy 374.50269 -244.763269) (xy 374.494747 -244.815973)
			(xy 374.479037 -244.866903) (xy 374.455911 -244.914924) (xy 374.425887 -244.958961) (xy 374.389635 -244.998032)
			(xy 374.347964 -245.031263) (xy 374.301806 -245.057912) (xy 374.252192 -245.077384) (xy 374.20023 -245.089244)
			(xy 374.14708 -245.093228) (xy 374.09393 -245.089244) (xy 374.041968 -245.077384) (xy 373.992354 -245.057912)
			(xy 373.946196 -245.031263) (xy 373.904525 -244.998032) (xy 373.868273 -244.958961) (xy 373.838249 -244.914924)
			(xy 373.815123 -244.866903) (xy 373.799413 -244.815973) (xy 373.79147 -244.763269) (xy 373.563144 -244.763269)
			(xy 373.555201 -244.815973) (xy 373.539491 -244.866903) (xy 373.516365 -244.914924) (xy 373.486341 -244.958961)
			(xy 373.450089 -244.998032) (xy 373.408418 -245.031263) (xy 373.36226 -245.057912) (xy 373.312646 -245.077384)
			(xy 373.260684 -245.089244) (xy 373.207534 -245.093228) (xy 373.154384 -245.089244) (xy 373.102422 -245.077384)
			(xy 373.052808 -245.057912) (xy 373.00665 -245.031263) (xy 372.964979 -244.998032) (xy 372.928727 -244.958961)
			(xy 372.898703 -244.914924) (xy 372.875577 -244.866903) (xy 372.859867 -244.815973) (xy 372.851924 -244.763269)
			(xy 372.62309 -244.763269) (xy 372.615147 -244.815973) (xy 372.599437 -244.866903) (xy 372.576311 -244.914924)
			(xy 372.546287 -244.958961) (xy 372.510035 -244.998032) (xy 372.468364 -245.031263) (xy 372.422206 -245.057912)
			(xy 372.372592 -245.077384) (xy 372.32063 -245.089244) (xy 372.26748 -245.093228) (xy 372.21433 -245.089244)
			(xy 372.162368 -245.077384) (xy 372.112754 -245.057912) (xy 372.066596 -245.031263) (xy 372.024925 -244.998032)
			(xy 371.988673 -244.958961) (xy 371.958649 -244.914924) (xy 371.935523 -244.866903) (xy 371.919813 -244.815973)
			(xy 371.91187 -244.763269) (xy 371.68329 -244.763269) (xy 371.675347 -244.815973) (xy 371.659637 -244.866903)
			(xy 371.636511 -244.914924) (xy 371.606487 -244.958961) (xy 371.570235 -244.998032) (xy 371.528564 -245.031263)
			(xy 371.482406 -245.057912) (xy 371.432792 -245.077384) (xy 371.38083 -245.089244) (xy 371.32768 -245.093228)
			(xy 371.27453 -245.089244) (xy 371.222568 -245.077384) (xy 371.172954 -245.057912) (xy 371.126796 -245.031263)
			(xy 371.085125 -244.998032) (xy 371.048873 -244.958961) (xy 371.018849 -244.914924) (xy 370.995723 -244.866903)
			(xy 370.980013 -244.815973) (xy 370.97207 -244.763269) (xy 370.743452 -244.763269) (xy 370.735547 -244.815719)
			(xy 370.719837 -244.866649) (xy 370.696711 -244.91467) (xy 370.666687 -244.958707) (xy 370.630435 -244.997778)
			(xy 370.588764 -245.031009) (xy 370.542606 -245.057658) (xy 370.492992 -245.07713) (xy 370.44103 -245.08899)
			(xy 370.38788 -245.092974) (xy 370.33473 -245.08899) (xy 370.282768 -245.07713) (xy 370.233154 -245.057658)
			(xy 370.186996 -245.031009) (xy 370.145325 -244.997778) (xy 370.109073 -244.958707) (xy 370.079049 -244.91467)
			(xy 370.055923 -244.866649) (xy 370.040213 -244.815719) (xy 370.03227 -244.763015) (xy 369.802733 -244.763015)
			(xy 369.800729 -244.789752) (xy 369.788868 -244.841717) (xy 369.769394 -244.891333) (xy 369.742742 -244.937493)
			(xy 369.709509 -244.979165) (xy 369.670435 -245.015418) (xy 369.626394 -245.045442) (xy 369.578371 -245.068566)
			(xy 369.527437 -245.084275) (xy 369.474731 -245.092216) (xy 369.44808 -245.092728) (xy 369.427311 -245.092438)
			(xy 369.386056 -245.087603) (xy 369.365784 -245.083076) (xy 369.3515 -245.080133) (xy 369.322386 -245.081622)
			(xy 369.294882 -245.091286) (xy 369.271235 -245.108335) (xy 369.253377 -245.131377) (xy 369.247674 -245.144798)
			(xy 369.236797 -245.171011) (xy 369.207956 -245.219885) (xy 369.19027 -245.24208) (xy 369.18165 -245.253209)
			(xy 369.170316 -245.278966) (xy 369.166447 -245.306839) (xy 369.170337 -245.334709) (xy 369.181691 -245.360456)
			(xy 369.19027 -245.37162) (xy 369.205706 -245.390868) (xy 369.231676 -245.432818) (xy 369.251598 -245.477955)
			(xy 369.265088 -245.525413) (xy 369.271889 -245.574281) (xy 369.271941 -245.577339) (xy 369.562624 -245.577339)
			(xy 369.562624 -245.524041) (xy 369.570567 -245.471337) (xy 369.586277 -245.420407) (xy 369.609403 -245.372386)
			(xy 369.639427 -245.328349) (xy 369.675679 -245.289278) (xy 369.71735 -245.256047) (xy 369.763508 -245.229398)
			(xy 369.813122 -245.209926) (xy 369.865084 -245.198066) (xy 369.918234 -245.194083) (xy 369.971384 -245.198066)
			(xy 370.023346 -245.209926) (xy 370.07296 -245.229398) (xy 370.119118 -245.256047) (xy 370.160789 -245.289278)
			(xy 370.197041 -245.328349) (xy 370.227065 -245.372386) (xy 370.250191 -245.420407) (xy 370.265901 -245.471337)
			(xy 370.273844 -245.524041) (xy 370.274342 -245.55069) (xy 370.273844 -245.577339) (xy 370.502424 -245.577339)
			(xy 370.502424 -245.524041) (xy 370.510367 -245.471337) (xy 370.526077 -245.420407) (xy 370.549203 -245.372386)
			(xy 370.579227 -245.328349) (xy 370.615479 -245.289278) (xy 370.65715 -245.256047) (xy 370.703308 -245.229398)
			(xy 370.752922 -245.209926) (xy 370.804884 -245.198066) (xy 370.858034 -245.194083) (xy 370.911184 -245.198066)
			(xy 370.963146 -245.209926) (xy 371.01276 -245.229398) (xy 371.058918 -245.256047) (xy 371.100589 -245.289278)
			(xy 371.136841 -245.328349) (xy 371.166865 -245.372386) (xy 371.189991 -245.420407) (xy 371.205701 -245.471337)
			(xy 371.213644 -245.524041) (xy 371.214142 -245.55069) (xy 371.213644 -245.577339) (xy 371.442224 -245.577339)
			(xy 371.442224 -245.524041) (xy 371.450167 -245.471337) (xy 371.465877 -245.420407) (xy 371.489003 -245.372386)
			(xy 371.519027 -245.328349) (xy 371.555279 -245.289278) (xy 371.59695 -245.256047) (xy 371.643108 -245.229398)
			(xy 371.692722 -245.209926) (xy 371.744684 -245.198066) (xy 371.797834 -245.194083) (xy 371.850984 -245.198066)
			(xy 371.902946 -245.209926) (xy 371.95256 -245.229398) (xy 371.998718 -245.256047) (xy 372.040389 -245.289278)
			(xy 372.076641 -245.328349) (xy 372.106665 -245.372386) (xy 372.129791 -245.420407) (xy 372.145501 -245.471337)
			(xy 372.153444 -245.524041) (xy 372.153942 -245.55069) (xy 372.153444 -245.577339) (xy 372.382024 -245.577339)
			(xy 372.382024 -245.524041) (xy 372.389967 -245.471337) (xy 372.405677 -245.420407) (xy 372.428803 -245.372386)
			(xy 372.458827 -245.328349) (xy 372.495079 -245.289278) (xy 372.53675 -245.256047) (xy 372.582908 -245.229398)
			(xy 372.632522 -245.209926) (xy 372.684484 -245.198066) (xy 372.737634 -245.194083) (xy 372.790784 -245.198066)
			(xy 372.842746 -245.209926) (xy 372.89236 -245.229398) (xy 372.938518 -245.256047) (xy 372.980189 -245.289278)
			(xy 373.016441 -245.328349) (xy 373.046465 -245.372386) (xy 373.069591 -245.420407) (xy 373.085301 -245.471337)
			(xy 373.093244 -245.524041) (xy 373.093742 -245.55069) (xy 373.093244 -245.577339) (xy 373.32157 -245.577339)
			(xy 373.32157 -245.524041) (xy 373.329513 -245.471337) (xy 373.345223 -245.420407) (xy 373.368349 -245.372386)
			(xy 373.398373 -245.328349) (xy 373.434625 -245.289278) (xy 373.476296 -245.256047) (xy 373.522454 -245.229398)
			(xy 373.572068 -245.209926) (xy 373.62403 -245.198066) (xy 373.67718 -245.194083) (xy 373.73033 -245.198066)
			(xy 373.782292 -245.209926) (xy 373.831906 -245.229398) (xy 373.878064 -245.256047) (xy 373.919735 -245.289278)
			(xy 373.955987 -245.328349) (xy 373.986011 -245.372386) (xy 374.009137 -245.420407) (xy 374.024847 -245.471337)
			(xy 374.03279 -245.524041) (xy 374.033288 -245.55069) (xy 374.03279 -245.577339) (xy 374.261624 -245.577339)
			(xy 374.261624 -245.524041) (xy 374.269567 -245.471337) (xy 374.285277 -245.420407) (xy 374.308403 -245.372386)
			(xy 374.338427 -245.328349) (xy 374.374679 -245.289278) (xy 374.41635 -245.256047) (xy 374.462508 -245.229398)
			(xy 374.512122 -245.209926) (xy 374.564084 -245.198066) (xy 374.617234 -245.194083) (xy 374.670384 -245.198066)
			(xy 374.722346 -245.209926) (xy 374.77196 -245.229398) (xy 374.818118 -245.256047) (xy 374.859789 -245.289278)
			(xy 374.896041 -245.328349) (xy 374.926065 -245.372386) (xy 374.949191 -245.420407) (xy 374.964901 -245.471337)
			(xy 374.972844 -245.524041) (xy 374.973342 -245.55069) (xy 374.972844 -245.577339) (xy 375.20117 -245.577339)
			(xy 375.20117 -245.524041) (xy 375.209113 -245.471337) (xy 375.224823 -245.420407) (xy 375.247949 -245.372386)
			(xy 375.277973 -245.328349) (xy 375.314225 -245.289278) (xy 375.355896 -245.256047) (xy 375.402054 -245.229398)
			(xy 375.451668 -245.209926) (xy 375.50363 -245.198066) (xy 375.55678 -245.194083) (xy 375.60993 -245.198066)
			(xy 375.661892 -245.209926) (xy 375.711506 -245.229398) (xy 375.757664 -245.256047) (xy 375.799335 -245.289278)
			(xy 375.835587 -245.328349) (xy 375.865611 -245.372386) (xy 375.888737 -245.420407) (xy 375.904447 -245.471337)
			(xy 375.91239 -245.524041) (xy 375.912888 -245.55069) (xy 375.91239 -245.577339) (xy 376.141224 -245.577339)
			(xy 376.141224 -245.524041) (xy 376.149167 -245.471337) (xy 376.164877 -245.420407) (xy 376.188003 -245.372386)
			(xy 376.218027 -245.328349) (xy 376.254279 -245.289278) (xy 376.29595 -245.256047) (xy 376.342108 -245.229398)
			(xy 376.391722 -245.209926) (xy 376.443684 -245.198066) (xy 376.496834 -245.194083) (xy 376.549984 -245.198066)
			(xy 376.601946 -245.209926) (xy 376.65156 -245.229398) (xy 376.697718 -245.256047) (xy 376.739389 -245.289278)
			(xy 376.775641 -245.328349) (xy 376.805665 -245.372386) (xy 376.828791 -245.420407) (xy 376.844501 -245.471337)
			(xy 376.852444 -245.524041) (xy 376.852942 -245.55069) (xy 376.852444 -245.577339) (xy 377.081024 -245.577339)
			(xy 377.081024 -245.524041) (xy 377.088967 -245.471337) (xy 377.104677 -245.420407) (xy 377.127803 -245.372386)
			(xy 377.157827 -245.328349) (xy 377.194079 -245.289278) (xy 377.23575 -245.256047) (xy 377.281908 -245.229398)
			(xy 377.331522 -245.209926) (xy 377.383484 -245.198066) (xy 377.436634 -245.194083) (xy 377.489784 -245.198066)
			(xy 377.541746 -245.209926) (xy 377.59136 -245.229398) (xy 377.637518 -245.256047) (xy 377.679189 -245.289278)
			(xy 377.715441 -245.328349) (xy 377.745465 -245.372386) (xy 377.768591 -245.420407) (xy 377.784301 -245.471337)
			(xy 377.792244 -245.524041) (xy 377.792742 -245.55069) (xy 377.792244 -245.577339) (xy 378.020824 -245.577339)
			(xy 378.020824 -245.524041) (xy 378.028767 -245.471337) (xy 378.044477 -245.420407) (xy 378.067603 -245.372386)
			(xy 378.097627 -245.328349) (xy 378.133879 -245.289278) (xy 378.17555 -245.256047) (xy 378.221708 -245.229398)
			(xy 378.271322 -245.209926) (xy 378.323284 -245.198066) (xy 378.376434 -245.194083) (xy 378.429584 -245.198066)
			(xy 378.481546 -245.209926) (xy 378.53116 -245.229398) (xy 378.577318 -245.256047) (xy 378.618989 -245.289278)
			(xy 378.655241 -245.328349) (xy 378.685265 -245.372386) (xy 378.708391 -245.420407) (xy 378.724101 -245.471337)
			(xy 378.732044 -245.524041) (xy 378.732542 -245.55069) (xy 378.732044 -245.577339) (xy 378.960624 -245.577339)
			(xy 378.960624 -245.524041) (xy 378.968567 -245.471337) (xy 378.984277 -245.420407) (xy 379.007403 -245.372386)
			(xy 379.037427 -245.328349) (xy 379.073679 -245.289278) (xy 379.11535 -245.256047) (xy 379.161508 -245.229398)
			(xy 379.211122 -245.209926) (xy 379.263084 -245.198066) (xy 379.316234 -245.194083) (xy 379.369384 -245.198066)
			(xy 379.421346 -245.209926) (xy 379.47096 -245.229398) (xy 379.517118 -245.256047) (xy 379.558789 -245.289278)
			(xy 379.595041 -245.328349) (xy 379.625065 -245.372386) (xy 379.648191 -245.420407) (xy 379.663901 -245.471337)
			(xy 379.671844 -245.524041) (xy 379.672342 -245.55069) (xy 379.671844 -245.577339) (xy 379.90017 -245.577339)
			(xy 379.90017 -245.524041) (xy 379.908113 -245.471337) (xy 379.923823 -245.420407) (xy 379.946949 -245.372386)
			(xy 379.976973 -245.328349) (xy 380.013225 -245.289278) (xy 380.054896 -245.256047) (xy 380.101054 -245.229398)
			(xy 380.150668 -245.209926) (xy 380.20263 -245.198066) (xy 380.25578 -245.194083) (xy 380.30893 -245.198066)
			(xy 380.360892 -245.209926) (xy 380.410506 -245.229398) (xy 380.456664 -245.256047) (xy 380.498335 -245.289278)
			(xy 380.534587 -245.328349) (xy 380.564611 -245.372386) (xy 380.587737 -245.420407) (xy 380.603447 -245.471337)
			(xy 380.61139 -245.524041) (xy 380.611888 -245.55069) (xy 380.61139 -245.577339) (xy 380.840224 -245.577339)
			(xy 380.840224 -245.524041) (xy 380.848167 -245.471337) (xy 380.863877 -245.420407) (xy 380.887003 -245.372386)
			(xy 380.917027 -245.328349) (xy 380.953279 -245.289278) (xy 380.99495 -245.256047) (xy 381.041108 -245.229398)
			(xy 381.090722 -245.209926) (xy 381.142684 -245.198066) (xy 381.195834 -245.194083) (xy 381.248984 -245.198066)
			(xy 381.300946 -245.209926) (xy 381.35056 -245.229398) (xy 381.396718 -245.256047) (xy 381.438389 -245.289278)
			(xy 381.474641 -245.328349) (xy 381.504665 -245.372386) (xy 381.527791 -245.420407) (xy 381.543501 -245.471337)
			(xy 381.551444 -245.524041) (xy 381.551942 -245.55069) (xy 381.551444 -245.577339) (xy 381.543501 -245.630043)
			(xy 381.527791 -245.680973) (xy 381.504665 -245.728994) (xy 381.474641 -245.773031) (xy 381.438389 -245.812102)
			(xy 381.396718 -245.845333) (xy 381.35056 -245.871982) (xy 381.300946 -245.891454) (xy 381.248984 -245.903314)
			(xy 381.195834 -245.907298) (xy 381.142684 -245.903314) (xy 381.090722 -245.891454) (xy 381.041108 -245.871982)
			(xy 380.99495 -245.845333) (xy 380.953279 -245.812102) (xy 380.917027 -245.773031) (xy 380.887003 -245.728994)
			(xy 380.863877 -245.680973) (xy 380.848167 -245.630043) (xy 380.840224 -245.577339) (xy 380.61139 -245.577339)
			(xy 380.603447 -245.630043) (xy 380.587737 -245.680973) (xy 380.564611 -245.728994) (xy 380.534587 -245.773031)
			(xy 380.498335 -245.812102) (xy 380.456664 -245.845333) (xy 380.410506 -245.871982) (xy 380.360892 -245.891454)
			(xy 380.30893 -245.903314) (xy 380.25578 -245.907298) (xy 380.20263 -245.903314) (xy 380.150668 -245.891454)
			(xy 380.101054 -245.871982) (xy 380.054896 -245.845333) (xy 380.013225 -245.812102) (xy 379.976973 -245.773031)
			(xy 379.946949 -245.728994) (xy 379.923823 -245.680973) (xy 379.908113 -245.630043) (xy 379.90017 -245.577339)
			(xy 379.671844 -245.577339) (xy 379.663901 -245.630043) (xy 379.648191 -245.680973) (xy 379.625065 -245.728994)
			(xy 379.595041 -245.773031) (xy 379.558789 -245.812102) (xy 379.517118 -245.845333) (xy 379.47096 -245.871982)
			(xy 379.421346 -245.891454) (xy 379.369384 -245.903314) (xy 379.316234 -245.907298) (xy 379.263084 -245.903314)
			(xy 379.211122 -245.891454) (xy 379.161508 -245.871982) (xy 379.11535 -245.845333) (xy 379.073679 -245.812102)
			(xy 379.037427 -245.773031) (xy 379.007403 -245.728994) (xy 378.984277 -245.680973) (xy 378.968567 -245.630043)
			(xy 378.960624 -245.577339) (xy 378.732044 -245.577339) (xy 378.724101 -245.630043) (xy 378.708391 -245.680973)
			(xy 378.685265 -245.728994) (xy 378.655241 -245.773031) (xy 378.618989 -245.812102) (xy 378.577318 -245.845333)
			(xy 378.53116 -245.871982) (xy 378.481546 -245.891454) (xy 378.429584 -245.903314) (xy 378.376434 -245.907298)
			(xy 378.323284 -245.903314) (xy 378.271322 -245.891454) (xy 378.221708 -245.871982) (xy 378.17555 -245.845333)
			(xy 378.133879 -245.812102) (xy 378.097627 -245.773031) (xy 378.067603 -245.728994) (xy 378.044477 -245.680973)
			(xy 378.028767 -245.630043) (xy 378.020824 -245.577339) (xy 377.792244 -245.577339) (xy 377.784301 -245.630043)
			(xy 377.768591 -245.680973) (xy 377.745465 -245.728994) (xy 377.715441 -245.773031) (xy 377.679189 -245.812102)
			(xy 377.637518 -245.845333) (xy 377.59136 -245.871982) (xy 377.541746 -245.891454) (xy 377.489784 -245.903314)
			(xy 377.436634 -245.907298) (xy 377.383484 -245.903314) (xy 377.331522 -245.891454) (xy 377.281908 -245.871982)
			(xy 377.23575 -245.845333) (xy 377.194079 -245.812102) (xy 377.157827 -245.773031) (xy 377.127803 -245.728994)
			(xy 377.104677 -245.680973) (xy 377.088967 -245.630043) (xy 377.081024 -245.577339) (xy 376.852444 -245.577339)
			(xy 376.844501 -245.630043) (xy 376.828791 -245.680973) (xy 376.805665 -245.728994) (xy 376.775641 -245.773031)
			(xy 376.739389 -245.812102) (xy 376.697718 -245.845333) (xy 376.65156 -245.871982) (xy 376.601946 -245.891454)
			(xy 376.549984 -245.903314) (xy 376.496834 -245.907298) (xy 376.443684 -245.903314) (xy 376.391722 -245.891454)
			(xy 376.342108 -245.871982) (xy 376.29595 -245.845333) (xy 376.254279 -245.812102) (xy 376.218027 -245.773031)
			(xy 376.188003 -245.728994) (xy 376.164877 -245.680973) (xy 376.149167 -245.630043) (xy 376.141224 -245.577339)
			(xy 375.91239 -245.577339) (xy 375.904447 -245.630043) (xy 375.888737 -245.680973) (xy 375.865611 -245.728994)
			(xy 375.835587 -245.773031) (xy 375.799335 -245.812102) (xy 375.757664 -245.845333) (xy 375.711506 -245.871982)
			(xy 375.661892 -245.891454) (xy 375.60993 -245.903314) (xy 375.55678 -245.907298) (xy 375.50363 -245.903314)
			(xy 375.451668 -245.891454) (xy 375.402054 -245.871982) (xy 375.355896 -245.845333) (xy 375.314225 -245.812102)
			(xy 375.277973 -245.773031) (xy 375.247949 -245.728994) (xy 375.224823 -245.680973) (xy 375.209113 -245.630043)
			(xy 375.20117 -245.577339) (xy 374.972844 -245.577339) (xy 374.964901 -245.630043) (xy 374.949191 -245.680973)
			(xy 374.926065 -245.728994) (xy 374.896041 -245.773031) (xy 374.859789 -245.812102) (xy 374.818118 -245.845333)
			(xy 374.77196 -245.871982) (xy 374.722346 -245.891454) (xy 374.670384 -245.903314) (xy 374.617234 -245.907298)
			(xy 374.564084 -245.903314) (xy 374.512122 -245.891454) (xy 374.462508 -245.871982) (xy 374.41635 -245.845333)
			(xy 374.374679 -245.812102) (xy 374.338427 -245.773031) (xy 374.308403 -245.728994) (xy 374.285277 -245.680973)
			(xy 374.269567 -245.630043) (xy 374.261624 -245.577339) (xy 374.03279 -245.577339) (xy 374.024847 -245.630043)
			(xy 374.009137 -245.680973) (xy 373.986011 -245.728994) (xy 373.955987 -245.773031) (xy 373.919735 -245.812102)
			(xy 373.878064 -245.845333) (xy 373.831906 -245.871982) (xy 373.782292 -245.891454) (xy 373.73033 -245.903314)
			(xy 373.67718 -245.907298) (xy 373.62403 -245.903314) (xy 373.572068 -245.891454) (xy 373.522454 -245.871982)
			(xy 373.476296 -245.845333) (xy 373.434625 -245.812102) (xy 373.398373 -245.773031) (xy 373.368349 -245.728994)
			(xy 373.345223 -245.680973) (xy 373.329513 -245.630043) (xy 373.32157 -245.577339) (xy 373.093244 -245.577339)
			(xy 373.085301 -245.630043) (xy 373.069591 -245.680973) (xy 373.046465 -245.728994) (xy 373.016441 -245.773031)
			(xy 372.980189 -245.812102) (xy 372.938518 -245.845333) (xy 372.89236 -245.871982) (xy 372.842746 -245.891454)
			(xy 372.790784 -245.903314) (xy 372.737634 -245.907298) (xy 372.684484 -245.903314) (xy 372.632522 -245.891454)
			(xy 372.582908 -245.871982) (xy 372.53675 -245.845333) (xy 372.495079 -245.812102) (xy 372.458827 -245.773031)
			(xy 372.428803 -245.728994) (xy 372.405677 -245.680973) (xy 372.389967 -245.630043) (xy 372.382024 -245.577339)
			(xy 372.153444 -245.577339) (xy 372.145501 -245.630043) (xy 372.129791 -245.680973) (xy 372.106665 -245.728994)
			(xy 372.076641 -245.773031) (xy 372.040389 -245.812102) (xy 371.998718 -245.845333) (xy 371.95256 -245.871982)
			(xy 371.902946 -245.891454) (xy 371.850984 -245.903314) (xy 371.797834 -245.907298) (xy 371.744684 -245.903314)
			(xy 371.692722 -245.891454) (xy 371.643108 -245.871982) (xy 371.59695 -245.845333) (xy 371.555279 -245.812102)
			(xy 371.519027 -245.773031) (xy 371.489003 -245.728994) (xy 371.465877 -245.680973) (xy 371.450167 -245.630043)
			(xy 371.442224 -245.577339) (xy 371.213644 -245.577339) (xy 371.205701 -245.630043) (xy 371.189991 -245.680973)
			(xy 371.166865 -245.728994) (xy 371.136841 -245.773031) (xy 371.100589 -245.812102) (xy 371.058918 -245.845333)
			(xy 371.01276 -245.871982) (xy 370.963146 -245.891454) (xy 370.911184 -245.903314) (xy 370.858034 -245.907298)
			(xy 370.804884 -245.903314) (xy 370.752922 -245.891454) (xy 370.703308 -245.871982) (xy 370.65715 -245.845333)
			(xy 370.615479 -245.812102) (xy 370.579227 -245.773031) (xy 370.549203 -245.728994) (xy 370.526077 -245.680973)
			(xy 370.510367 -245.630043) (xy 370.502424 -245.577339) (xy 370.273844 -245.577339) (xy 370.265901 -245.630043)
			(xy 370.250191 -245.680973) (xy 370.227065 -245.728994) (xy 370.197041 -245.773031) (xy 370.160789 -245.812102)
			(xy 370.119118 -245.845333) (xy 370.07296 -245.871982) (xy 370.023346 -245.891454) (xy 369.971384 -245.903314)
			(xy 369.918234 -245.907298) (xy 369.865084 -245.903314) (xy 369.813122 -245.891454) (xy 369.763508 -245.871982)
			(xy 369.71735 -245.845333) (xy 369.675679 -245.812102) (xy 369.639427 -245.773031) (xy 369.609403 -245.728994)
			(xy 369.586277 -245.680973) (xy 369.570567 -245.630043) (xy 369.562624 -245.577339) (xy 369.271941 -245.577339)
			(xy 369.272312 -245.59895) (xy 369.271849 -245.624769) (xy 369.264388 -245.675866) (xy 369.249629 -245.72535)
			(xy 369.227882 -245.772186) (xy 369.199601 -245.815392) (xy 369.16538 -245.854062) (xy 369.125934 -245.887388)
			(xy 369.082092 -245.914671) (xy 369.03477 -245.93534) (xy 368.98496 -245.948961) (xy 368.959384 -245.952518)
			(xy 368.91468 -245.957852) (xy 368.91468 -246.408448) (xy 368.959384 -246.413782) (xy 368.976148 -246.416322)
			(xy 368.98988 -246.418172) (xy 369.017427 -246.415286) (xy 369.043187 -246.405111) (xy 369.065271 -246.388394)
			(xy 369.082056 -246.366362) (xy 369.09231 -246.340633) (xy 369.094258 -246.326914) (xy 369.097466 -246.30101)
			(xy 369.110492 -246.250467) (xy 369.130756 -246.202366) (xy 369.157824 -246.157737) (xy 369.191116 -246.117538)
			(xy 369.229919 -246.082629) (xy 369.273402 -246.053757) (xy 369.320633 -246.031542) (xy 369.370602 -246.016459)
			(xy 369.422236 -246.008831) (xy 369.448334 -246.008398) (xy 369.474981 -246.008898) (xy 369.52768 -246.016846)
			(xy 369.578605 -246.032559) (xy 369.62662 -246.055685) (xy 369.670653 -246.08571) (xy 369.709718 -246.121961)
			(xy 369.742945 -246.16363) (xy 369.769591 -246.209785) (xy 369.789061 -246.259396) (xy 369.800919 -246.311355)
			(xy 369.804902 -246.3645) (xy 369.802904 -246.391155) (xy 370.032524 -246.391155) (xy 370.032524 -246.337857)
			(xy 370.040467 -246.285153) (xy 370.056177 -246.234223) (xy 370.079303 -246.186202) (xy 370.109327 -246.142165)
			(xy 370.145579 -246.103094) (xy 370.18725 -246.069863) (xy 370.233408 -246.043214) (xy 370.283022 -246.023742)
			(xy 370.334984 -246.011882) (xy 370.388134 -246.007899) (xy 370.441284 -246.011882) (xy 370.493246 -246.023742)
			(xy 370.54286 -246.043214) (xy 370.589018 -246.069863) (xy 370.630689 -246.103094) (xy 370.666941 -246.142165)
			(xy 370.696965 -246.186202) (xy 370.720091 -246.234223) (xy 370.735801 -246.285153) (xy 370.743744 -246.337857)
			(xy 370.744242 -246.364506) (xy 370.743744 -246.391155) (xy 370.97207 -246.391155) (xy 370.97207 -246.337857)
			(xy 370.980013 -246.285153) (xy 370.995723 -246.234223) (xy 371.018849 -246.186202) (xy 371.048873 -246.142165)
			(xy 371.085125 -246.103094) (xy 371.126796 -246.069863) (xy 371.172954 -246.043214) (xy 371.222568 -246.023742)
			(xy 371.27453 -246.011882) (xy 371.32768 -246.007899) (xy 371.38083 -246.011882) (xy 371.432792 -246.023742)
			(xy 371.482406 -246.043214) (xy 371.528564 -246.069863) (xy 371.570235 -246.103094) (xy 371.606487 -246.142165)
			(xy 371.636511 -246.186202) (xy 371.659637 -246.234223) (xy 371.675347 -246.285153) (xy 371.68329 -246.337857)
			(xy 371.683788 -246.364506) (xy 371.68329 -246.391155) (xy 371.91187 -246.391155) (xy 371.91187 -246.337857)
			(xy 371.919813 -246.285153) (xy 371.935523 -246.234223) (xy 371.958649 -246.186202) (xy 371.988673 -246.142165)
			(xy 372.024925 -246.103094) (xy 372.066596 -246.069863) (xy 372.112754 -246.043214) (xy 372.162368 -246.023742)
			(xy 372.21433 -246.011882) (xy 372.26748 -246.007899) (xy 372.32063 -246.011882) (xy 372.372592 -246.023742)
			(xy 372.422206 -246.043214) (xy 372.468364 -246.069863) (xy 372.510035 -246.103094) (xy 372.546287 -246.142165)
			(xy 372.576311 -246.186202) (xy 372.599437 -246.234223) (xy 372.615147 -246.285153) (xy 372.62309 -246.337857)
			(xy 372.623588 -246.364506) (xy 372.62309 -246.391155) (xy 372.85167 -246.391155) (xy 372.85167 -246.337857)
			(xy 372.859613 -246.285153) (xy 372.875323 -246.234223) (xy 372.898449 -246.186202) (xy 372.928473 -246.142165)
			(xy 372.964725 -246.103094) (xy 373.006396 -246.069863) (xy 373.052554 -246.043214) (xy 373.102168 -246.023742)
			(xy 373.15413 -246.011882) (xy 373.20728 -246.007899) (xy 373.26043 -246.011882) (xy 373.312392 -246.023742)
			(xy 373.362006 -246.043214) (xy 373.408164 -246.069863) (xy 373.449835 -246.103094) (xy 373.486087 -246.142165)
			(xy 373.516111 -246.186202) (xy 373.539237 -246.234223) (xy 373.554947 -246.285153) (xy 373.56289 -246.337857)
			(xy 373.563388 -246.364506) (xy 373.56289 -246.391155) (xy 373.79147 -246.391155) (xy 373.79147 -246.337857)
			(xy 373.799413 -246.285153) (xy 373.815123 -246.234223) (xy 373.838249 -246.186202) (xy 373.868273 -246.142165)
			(xy 373.904525 -246.103094) (xy 373.946196 -246.069863) (xy 373.992354 -246.043214) (xy 374.041968 -246.023742)
			(xy 374.09393 -246.011882) (xy 374.14708 -246.007899) (xy 374.20023 -246.011882) (xy 374.252192 -246.023742)
			(xy 374.301806 -246.043214) (xy 374.347964 -246.069863) (xy 374.389635 -246.103094) (xy 374.425887 -246.142165)
			(xy 374.455911 -246.186202) (xy 374.479037 -246.234223) (xy 374.494747 -246.285153) (xy 374.50269 -246.337857)
			(xy 374.503188 -246.364506) (xy 374.50269 -246.391155) (xy 374.73127 -246.391155) (xy 374.73127 -246.337857)
			(xy 374.739213 -246.285153) (xy 374.754923 -246.234223) (xy 374.778049 -246.186202) (xy 374.808073 -246.142165)
			(xy 374.844325 -246.103094) (xy 374.885996 -246.069863) (xy 374.932154 -246.043214) (xy 374.981768 -246.023742)
			(xy 375.03373 -246.011882) (xy 375.08688 -246.007899) (xy 375.14003 -246.011882) (xy 375.191992 -246.023742)
			(xy 375.241606 -246.043214) (xy 375.287764 -246.069863) (xy 375.329435 -246.103094) (xy 375.365687 -246.142165)
			(xy 375.395711 -246.186202) (xy 375.418837 -246.234223) (xy 375.434547 -246.285153) (xy 375.44249 -246.337857)
			(xy 375.442988 -246.364506) (xy 375.44249 -246.391155) (xy 375.67107 -246.391155) (xy 375.67107 -246.337857)
			(xy 375.679013 -246.285153) (xy 375.694723 -246.234223) (xy 375.717849 -246.186202) (xy 375.747873 -246.142165)
			(xy 375.784125 -246.103094) (xy 375.825796 -246.069863) (xy 375.871954 -246.043214) (xy 375.921568 -246.023742)
			(xy 375.97353 -246.011882) (xy 376.02668 -246.007899) (xy 376.07983 -246.011882) (xy 376.131792 -246.023742)
			(xy 376.181406 -246.043214) (xy 376.227564 -246.069863) (xy 376.269235 -246.103094) (xy 376.305487 -246.142165)
			(xy 376.335511 -246.186202) (xy 376.358637 -246.234223) (xy 376.374347 -246.285153) (xy 376.38229 -246.337857)
			(xy 376.382788 -246.364506) (xy 376.38229 -246.391155) (xy 376.611124 -246.391155) (xy 376.611124 -246.337857)
			(xy 376.619067 -246.285153) (xy 376.634777 -246.234223) (xy 376.657903 -246.186202) (xy 376.687927 -246.142165)
			(xy 376.724179 -246.103094) (xy 376.76585 -246.069863) (xy 376.812008 -246.043214) (xy 376.861622 -246.023742)
			(xy 376.913584 -246.011882) (xy 376.966734 -246.007899) (xy 377.019884 -246.011882) (xy 377.071846 -246.023742)
			(xy 377.12146 -246.043214) (xy 377.167618 -246.069863) (xy 377.209289 -246.103094) (xy 377.245541 -246.142165)
			(xy 377.275565 -246.186202) (xy 377.298691 -246.234223) (xy 377.314401 -246.285153) (xy 377.322344 -246.337857)
			(xy 377.322842 -246.364506) (xy 377.322344 -246.391155) (xy 377.55067 -246.391155) (xy 377.55067 -246.337857)
			(xy 377.558613 -246.285153) (xy 377.574323 -246.234223) (xy 377.597449 -246.186202) (xy 377.627473 -246.142165)
			(xy 377.663725 -246.103094) (xy 377.705396 -246.069863) (xy 377.751554 -246.043214) (xy 377.801168 -246.023742)
			(xy 377.85313 -246.011882) (xy 377.90628 -246.007899) (xy 377.95943 -246.011882) (xy 378.011392 -246.023742)
			(xy 378.061006 -246.043214) (xy 378.107164 -246.069863) (xy 378.148835 -246.103094) (xy 378.185087 -246.142165)
			(xy 378.215111 -246.186202) (xy 378.238237 -246.234223) (xy 378.253947 -246.285153) (xy 378.26189 -246.337857)
			(xy 378.262388 -246.364506) (xy 378.26189 -246.391155) (xy 378.49047 -246.391155) (xy 378.49047 -246.337857)
			(xy 378.498413 -246.285153) (xy 378.514123 -246.234223) (xy 378.537249 -246.186202) (xy 378.567273 -246.142165)
			(xy 378.603525 -246.103094) (xy 378.645196 -246.069863) (xy 378.691354 -246.043214) (xy 378.740968 -246.023742)
			(xy 378.79293 -246.011882) (xy 378.84608 -246.007899) (xy 378.89923 -246.011882) (xy 378.951192 -246.023742)
			(xy 379.000806 -246.043214) (xy 379.046964 -246.069863) (xy 379.088635 -246.103094) (xy 379.124887 -246.142165)
			(xy 379.154911 -246.186202) (xy 379.178037 -246.234223) (xy 379.193747 -246.285153) (xy 379.20169 -246.337857)
			(xy 379.202188 -246.364506) (xy 379.20169 -246.391155) (xy 379.43027 -246.391155) (xy 379.43027 -246.337857)
			(xy 379.438213 -246.285153) (xy 379.453923 -246.234223) (xy 379.477049 -246.186202) (xy 379.507073 -246.142165)
			(xy 379.543325 -246.103094) (xy 379.584996 -246.069863) (xy 379.631154 -246.043214) (xy 379.680768 -246.023742)
			(xy 379.73273 -246.011882) (xy 379.78588 -246.007899) (xy 379.83903 -246.011882) (xy 379.890992 -246.023742)
			(xy 379.940606 -246.043214) (xy 379.986764 -246.069863) (xy 380.028435 -246.103094) (xy 380.064687 -246.142165)
			(xy 380.094711 -246.186202) (xy 380.117837 -246.234223) (xy 380.133547 -246.285153) (xy 380.14149 -246.337857)
			(xy 380.141988 -246.364506) (xy 380.14149 -246.391155) (xy 380.37007 -246.391155) (xy 380.37007 -246.337857)
			(xy 380.378013 -246.285153) (xy 380.393723 -246.234223) (xy 380.416849 -246.186202) (xy 380.446873 -246.142165)
			(xy 380.483125 -246.103094) (xy 380.524796 -246.069863) (xy 380.570954 -246.043214) (xy 380.620568 -246.023742)
			(xy 380.67253 -246.011882) (xy 380.72568 -246.007899) (xy 380.77883 -246.011882) (xy 380.830792 -246.023742)
			(xy 380.880406 -246.043214) (xy 380.926564 -246.069863) (xy 380.968235 -246.103094) (xy 381.004487 -246.142165)
			(xy 381.034511 -246.186202) (xy 381.057637 -246.234223) (xy 381.073347 -246.285153) (xy 381.08129 -246.337857)
			(xy 381.081788 -246.364506) (xy 381.08129 -246.391155) (xy 381.073347 -246.443859) (xy 381.057637 -246.494789)
			(xy 381.034511 -246.54281) (xy 381.004487 -246.586847) (xy 380.968235 -246.625918) (xy 380.926564 -246.659149)
			(xy 380.880406 -246.685798) (xy 380.830792 -246.70527) (xy 380.77883 -246.71713) (xy 380.72568 -246.721114)
			(xy 380.67253 -246.71713) (xy 380.620568 -246.70527) (xy 380.570954 -246.685798) (xy 380.524796 -246.659149)
			(xy 380.483125 -246.625918) (xy 380.446873 -246.586847) (xy 380.416849 -246.54281) (xy 380.393723 -246.494789)
			(xy 380.378013 -246.443859) (xy 380.37007 -246.391155) (xy 380.14149 -246.391155) (xy 380.133547 -246.443859)
			(xy 380.117837 -246.494789) (xy 380.094711 -246.54281) (xy 380.064687 -246.586847) (xy 380.028435 -246.625918)
			(xy 379.986764 -246.659149) (xy 379.940606 -246.685798) (xy 379.890992 -246.70527) (xy 379.83903 -246.71713)
			(xy 379.78588 -246.721114) (xy 379.73273 -246.71713) (xy 379.680768 -246.70527) (xy 379.631154 -246.685798)
			(xy 379.584996 -246.659149) (xy 379.543325 -246.625918) (xy 379.507073 -246.586847) (xy 379.477049 -246.54281)
			(xy 379.453923 -246.494789) (xy 379.438213 -246.443859) (xy 379.43027 -246.391155) (xy 379.20169 -246.391155)
			(xy 379.193747 -246.443859) (xy 379.178037 -246.494789) (xy 379.154911 -246.54281) (xy 379.124887 -246.586847)
			(xy 379.088635 -246.625918) (xy 379.046964 -246.659149) (xy 379.000806 -246.685798) (xy 378.951192 -246.70527)
			(xy 378.89923 -246.71713) (xy 378.84608 -246.721114) (xy 378.79293 -246.71713) (xy 378.740968 -246.70527)
			(xy 378.691354 -246.685798) (xy 378.645196 -246.659149) (xy 378.603525 -246.625918) (xy 378.567273 -246.586847)
			(xy 378.537249 -246.54281) (xy 378.514123 -246.494789) (xy 378.498413 -246.443859) (xy 378.49047 -246.391155)
			(xy 378.26189 -246.391155) (xy 378.253947 -246.443859) (xy 378.238237 -246.494789) (xy 378.215111 -246.54281)
			(xy 378.185087 -246.586847) (xy 378.148835 -246.625918) (xy 378.107164 -246.659149) (xy 378.061006 -246.685798)
			(xy 378.011392 -246.70527) (xy 377.95943 -246.71713) (xy 377.90628 -246.721114) (xy 377.85313 -246.71713)
			(xy 377.801168 -246.70527) (xy 377.751554 -246.685798) (xy 377.705396 -246.659149) (xy 377.663725 -246.625918)
			(xy 377.627473 -246.586847) (xy 377.597449 -246.54281) (xy 377.574323 -246.494789) (xy 377.558613 -246.443859)
			(xy 377.55067 -246.391155) (xy 377.322344 -246.391155) (xy 377.314401 -246.443859) (xy 377.298691 -246.494789)
			(xy 377.275565 -246.54281) (xy 377.245541 -246.586847) (xy 377.209289 -246.625918) (xy 377.167618 -246.659149)
			(xy 377.12146 -246.685798) (xy 377.071846 -246.70527) (xy 377.019884 -246.71713) (xy 376.966734 -246.721114)
			(xy 376.913584 -246.71713) (xy 376.861622 -246.70527) (xy 376.812008 -246.685798) (xy 376.76585 -246.659149)
			(xy 376.724179 -246.625918) (xy 376.687927 -246.586847) (xy 376.657903 -246.54281) (xy 376.634777 -246.494789)
			(xy 376.619067 -246.443859) (xy 376.611124 -246.391155) (xy 376.38229 -246.391155) (xy 376.374347 -246.443859)
			(xy 376.358637 -246.494789) (xy 376.335511 -246.54281) (xy 376.305487 -246.586847) (xy 376.269235 -246.625918)
			(xy 376.227564 -246.659149) (xy 376.181406 -246.685798) (xy 376.131792 -246.70527) (xy 376.07983 -246.71713)
			(xy 376.02668 -246.721114) (xy 375.97353 -246.71713) (xy 375.921568 -246.70527) (xy 375.871954 -246.685798)
			(xy 375.825796 -246.659149) (xy 375.784125 -246.625918) (xy 375.747873 -246.586847) (xy 375.717849 -246.54281)
			(xy 375.694723 -246.494789) (xy 375.679013 -246.443859) (xy 375.67107 -246.391155) (xy 375.44249 -246.391155)
			(xy 375.434547 -246.443859) (xy 375.418837 -246.494789) (xy 375.395711 -246.54281) (xy 375.365687 -246.586847)
			(xy 375.329435 -246.625918) (xy 375.287764 -246.659149) (xy 375.241606 -246.685798) (xy 375.191992 -246.70527)
			(xy 375.14003 -246.71713) (xy 375.08688 -246.721114) (xy 375.03373 -246.71713) (xy 374.981768 -246.70527)
			(xy 374.932154 -246.685798) (xy 374.885996 -246.659149) (xy 374.844325 -246.625918) (xy 374.808073 -246.586847)
			(xy 374.778049 -246.54281) (xy 374.754923 -246.494789) (xy 374.739213 -246.443859) (xy 374.73127 -246.391155)
			(xy 374.50269 -246.391155) (xy 374.494747 -246.443859) (xy 374.479037 -246.494789) (xy 374.455911 -246.54281)
			(xy 374.425887 -246.586847) (xy 374.389635 -246.625918) (xy 374.347964 -246.659149) (xy 374.301806 -246.685798)
			(xy 374.252192 -246.70527) (xy 374.20023 -246.71713) (xy 374.14708 -246.721114) (xy 374.09393 -246.71713)
			(xy 374.041968 -246.70527) (xy 373.992354 -246.685798) (xy 373.946196 -246.659149) (xy 373.904525 -246.625918)
			(xy 373.868273 -246.586847) (xy 373.838249 -246.54281) (xy 373.815123 -246.494789) (xy 373.799413 -246.443859)
			(xy 373.79147 -246.391155) (xy 373.56289 -246.391155) (xy 373.554947 -246.443859) (xy 373.539237 -246.494789)
			(xy 373.516111 -246.54281) (xy 373.486087 -246.586847) (xy 373.449835 -246.625918) (xy 373.408164 -246.659149)
			(xy 373.362006 -246.685798) (xy 373.312392 -246.70527) (xy 373.26043 -246.71713) (xy 373.20728 -246.721114)
			(xy 373.15413 -246.71713) (xy 373.102168 -246.70527) (xy 373.052554 -246.685798) (xy 373.006396 -246.659149)
			(xy 372.964725 -246.625918) (xy 372.928473 -246.586847) (xy 372.898449 -246.54281) (xy 372.875323 -246.494789)
			(xy 372.859613 -246.443859) (xy 372.85167 -246.391155) (xy 372.62309 -246.391155) (xy 372.615147 -246.443859)
			(xy 372.599437 -246.494789) (xy 372.576311 -246.54281) (xy 372.546287 -246.586847) (xy 372.510035 -246.625918)
			(xy 372.468364 -246.659149) (xy 372.422206 -246.685798) (xy 372.372592 -246.70527) (xy 372.32063 -246.71713)
			(xy 372.26748 -246.721114) (xy 372.21433 -246.71713) (xy 372.162368 -246.70527) (xy 372.112754 -246.685798)
			(xy 372.066596 -246.659149) (xy 372.024925 -246.625918) (xy 371.988673 -246.586847) (xy 371.958649 -246.54281)
			(xy 371.935523 -246.494789) (xy 371.919813 -246.443859) (xy 371.91187 -246.391155) (xy 371.68329 -246.391155)
			(xy 371.675347 -246.443859) (xy 371.659637 -246.494789) (xy 371.636511 -246.54281) (xy 371.606487 -246.586847)
			(xy 371.570235 -246.625918) (xy 371.528564 -246.659149) (xy 371.482406 -246.685798) (xy 371.432792 -246.70527)
			(xy 371.38083 -246.71713) (xy 371.32768 -246.721114) (xy 371.27453 -246.71713) (xy 371.222568 -246.70527)
			(xy 371.172954 -246.685798) (xy 371.126796 -246.659149) (xy 371.085125 -246.625918) (xy 371.048873 -246.586847)
			(xy 371.018849 -246.54281) (xy 370.995723 -246.494789) (xy 370.980013 -246.443859) (xy 370.97207 -246.391155)
			(xy 370.743744 -246.391155) (xy 370.735801 -246.443859) (xy 370.720091 -246.494789) (xy 370.696965 -246.54281)
			(xy 370.666941 -246.586847) (xy 370.630689 -246.625918) (xy 370.589018 -246.659149) (xy 370.54286 -246.685798)
			(xy 370.493246 -246.70527) (xy 370.441284 -246.71713) (xy 370.388134 -246.721114) (xy 370.334984 -246.71713)
			(xy 370.283022 -246.70527) (xy 370.233408 -246.685798) (xy 370.18725 -246.659149) (xy 370.145579 -246.625918)
			(xy 370.109327 -246.586847) (xy 370.079303 -246.54281) (xy 370.056177 -246.494789) (xy 370.040467 -246.443859)
			(xy 370.032524 -246.391155) (xy 369.802904 -246.391155) (xy 369.800919 -246.417645) (xy 369.789061 -246.469604)
			(xy 369.769591 -246.519215) (xy 369.742945 -246.56537) (xy 369.709718 -246.607039) (xy 369.670653 -246.64329)
			(xy 369.62662 -246.673315) (xy 369.578605 -246.696441) (xy 369.52768 -246.712154) (xy 369.474981 -246.720102)
			(xy 369.448334 -246.720614) (xy 369.433274 -246.720454) (xy 369.403263 -246.717906) (xy 369.38839 -246.715534)
			(xy 369.374657 -246.713679) (xy 369.347107 -246.716557) (xy 369.321342 -246.726729) (xy 369.299257 -246.743449)
			(xy 369.282474 -246.765486) (xy 369.272227 -246.791221) (xy 369.27028 -246.804942) (xy 369.267063 -246.830872)
			(xy 369.254009 -246.881465) (xy 369.233704 -246.929609) (xy 369.206583 -246.974269) (xy 369.19027 -246.99468)
			(xy 369.18165 -247.005809) (xy 369.170316 -247.031566) (xy 369.166447 -247.059439) (xy 369.170337 -247.087309)
			(xy 369.181691 -247.113056) (xy 369.19027 -247.12422) (xy 369.205706 -247.143468) (xy 369.231676 -247.185418)
			(xy 369.240306 -247.204971) (xy 369.562624 -247.204971) (xy 369.562624 -247.151673) (xy 369.570567 -247.098969)
			(xy 369.586277 -247.048039) (xy 369.609403 -247.000018) (xy 369.639427 -246.955981) (xy 369.675679 -246.91691)
			(xy 369.71735 -246.883679) (xy 369.763508 -246.85703) (xy 369.813122 -246.837558) (xy 369.865084 -246.825698)
			(xy 369.918234 -246.821715) (xy 369.971384 -246.825698) (xy 370.023346 -246.837558) (xy 370.07296 -246.85703)
			(xy 370.119118 -246.883679) (xy 370.160789 -246.91691) (xy 370.197041 -246.955981) (xy 370.227065 -247.000018)
			(xy 370.250191 -247.048039) (xy 370.265901 -247.098969) (xy 370.273844 -247.151673) (xy 370.274342 -247.178322)
			(xy 370.273844 -247.204971) (xy 370.502424 -247.204971) (xy 370.502424 -247.151673) (xy 370.510367 -247.098969)
			(xy 370.526077 -247.048039) (xy 370.549203 -247.000018) (xy 370.579227 -246.955981) (xy 370.615479 -246.91691)
			(xy 370.65715 -246.883679) (xy 370.703308 -246.85703) (xy 370.752922 -246.837558) (xy 370.804884 -246.825698)
			(xy 370.858034 -246.821715) (xy 370.911184 -246.825698) (xy 370.963146 -246.837558) (xy 371.01276 -246.85703)
			(xy 371.058918 -246.883679) (xy 371.100589 -246.91691) (xy 371.136841 -246.955981) (xy 371.166865 -247.000018)
			(xy 371.189991 -247.048039) (xy 371.205701 -247.098969) (xy 371.213644 -247.151673) (xy 371.214142 -247.178322)
			(xy 371.213644 -247.204971) (xy 371.442224 -247.204971) (xy 371.442224 -247.151673) (xy 371.450167 -247.098969)
			(xy 371.465877 -247.048039) (xy 371.489003 -247.000018) (xy 371.519027 -246.955981) (xy 371.555279 -246.91691)
			(xy 371.59695 -246.883679) (xy 371.643108 -246.85703) (xy 371.692722 -246.837558) (xy 371.744684 -246.825698)
			(xy 371.797834 -246.821715) (xy 371.850984 -246.825698) (xy 371.902946 -246.837558) (xy 371.95256 -246.85703)
			(xy 371.998718 -246.883679) (xy 372.040389 -246.91691) (xy 372.076641 -246.955981) (xy 372.106665 -247.000018)
			(xy 372.129791 -247.048039) (xy 372.145501 -247.098969) (xy 372.153444 -247.151673) (xy 372.153942 -247.178322)
			(xy 372.153444 -247.204971) (xy 372.382024 -247.204971) (xy 372.382024 -247.151673) (xy 372.389967 -247.098969)
			(xy 372.405677 -247.048039) (xy 372.428803 -247.000018) (xy 372.458827 -246.955981) (xy 372.495079 -246.91691)
			(xy 372.53675 -246.883679) (xy 372.582908 -246.85703) (xy 372.632522 -246.837558) (xy 372.684484 -246.825698)
			(xy 372.737634 -246.821715) (xy 372.790784 -246.825698) (xy 372.842746 -246.837558) (xy 372.89236 -246.85703)
			(xy 372.938518 -246.883679) (xy 372.980189 -246.91691) (xy 373.016441 -246.955981) (xy 373.046465 -247.000018)
			(xy 373.069591 -247.048039) (xy 373.085301 -247.098969) (xy 373.093244 -247.151673) (xy 373.093742 -247.178322)
			(xy 373.093244 -247.204971) (xy 373.321824 -247.204971) (xy 373.321824 -247.151673) (xy 373.329767 -247.098969)
			(xy 373.345477 -247.048039) (xy 373.368603 -247.000018) (xy 373.398627 -246.955981) (xy 373.434879 -246.91691)
			(xy 373.47655 -246.883679) (xy 373.522708 -246.85703) (xy 373.572322 -246.837558) (xy 373.624284 -246.825698)
			(xy 373.677434 -246.821715) (xy 373.730584 -246.825698) (xy 373.782546 -246.837558) (xy 373.83216 -246.85703)
			(xy 373.878318 -246.883679) (xy 373.919989 -246.91691) (xy 373.956241 -246.955981) (xy 373.986265 -247.000018)
			(xy 374.009391 -247.048039) (xy 374.025101 -247.098969) (xy 374.033044 -247.151673) (xy 374.033542 -247.178322)
			(xy 374.033044 -247.204971) (xy 374.26137 -247.204971) (xy 374.26137 -247.151673) (xy 374.269313 -247.098969)
			(xy 374.285023 -247.048039) (xy 374.308149 -247.000018) (xy 374.338173 -246.955981) (xy 374.374425 -246.91691)
			(xy 374.416096 -246.883679) (xy 374.462254 -246.85703) (xy 374.511868 -246.837558) (xy 374.56383 -246.825698)
			(xy 374.61698 -246.821715) (xy 374.67013 -246.825698) (xy 374.722092 -246.837558) (xy 374.771706 -246.85703)
			(xy 374.817864 -246.883679) (xy 374.859535 -246.91691) (xy 374.895787 -246.955981) (xy 374.925811 -247.000018)
			(xy 374.948937 -247.048039) (xy 374.964647 -247.098969) (xy 374.97259 -247.151673) (xy 374.973088 -247.178322)
			(xy 374.97259 -247.204971) (xy 375.201424 -247.204971) (xy 375.201424 -247.151673) (xy 375.209367 -247.098969)
			(xy 375.225077 -247.048039) (xy 375.248203 -247.000018) (xy 375.278227 -246.955981) (xy 375.314479 -246.91691)
			(xy 375.35615 -246.883679) (xy 375.402308 -246.85703) (xy 375.451922 -246.837558) (xy 375.503884 -246.825698)
			(xy 375.557034 -246.821715) (xy 375.610184 -246.825698) (xy 375.662146 -246.837558) (xy 375.71176 -246.85703)
			(xy 375.757918 -246.883679) (xy 375.799589 -246.91691) (xy 375.835841 -246.955981) (xy 375.865865 -247.000018)
			(xy 375.888991 -247.048039) (xy 375.904701 -247.098969) (xy 375.912644 -247.151673) (xy 375.913142 -247.178322)
			(xy 375.912644 -247.204971) (xy 376.141224 -247.204971) (xy 376.141224 -247.151673) (xy 376.149167 -247.098969)
			(xy 376.164877 -247.048039) (xy 376.188003 -247.000018) (xy 376.218027 -246.955981) (xy 376.254279 -246.91691)
			(xy 376.29595 -246.883679) (xy 376.342108 -246.85703) (xy 376.391722 -246.837558) (xy 376.443684 -246.825698)
			(xy 376.496834 -246.821715) (xy 376.549984 -246.825698) (xy 376.601946 -246.837558) (xy 376.65156 -246.85703)
			(xy 376.697718 -246.883679) (xy 376.739389 -246.91691) (xy 376.775641 -246.955981) (xy 376.805665 -247.000018)
			(xy 376.828791 -247.048039) (xy 376.844501 -247.098969) (xy 376.852444 -247.151673) (xy 376.852942 -247.178322)
			(xy 376.852444 -247.204971) (xy 377.081024 -247.204971) (xy 377.081024 -247.151673) (xy 377.088967 -247.098969)
			(xy 377.104677 -247.048039) (xy 377.127803 -247.000018) (xy 377.157827 -246.955981) (xy 377.194079 -246.91691)
			(xy 377.23575 -246.883679) (xy 377.281908 -246.85703) (xy 377.331522 -246.837558) (xy 377.383484 -246.825698)
			(xy 377.436634 -246.821715) (xy 377.489784 -246.825698) (xy 377.541746 -246.837558) (xy 377.59136 -246.85703)
			(xy 377.637518 -246.883679) (xy 377.679189 -246.91691) (xy 377.715441 -246.955981) (xy 377.745465 -247.000018)
			(xy 377.768591 -247.048039) (xy 377.784301 -247.098969) (xy 377.792244 -247.151673) (xy 377.792742 -247.178322)
			(xy 377.792244 -247.204971) (xy 378.020824 -247.204971) (xy 378.020824 -247.151673) (xy 378.028767 -247.098969)
			(xy 378.044477 -247.048039) (xy 378.067603 -247.000018) (xy 378.097627 -246.955981) (xy 378.133879 -246.91691)
			(xy 378.17555 -246.883679) (xy 378.221708 -246.85703) (xy 378.271322 -246.837558) (xy 378.323284 -246.825698)
			(xy 378.376434 -246.821715) (xy 378.429584 -246.825698) (xy 378.481546 -246.837558) (xy 378.53116 -246.85703)
			(xy 378.577318 -246.883679) (xy 378.618989 -246.91691) (xy 378.655241 -246.955981) (xy 378.685265 -247.000018)
			(xy 378.708391 -247.048039) (xy 378.724101 -247.098969) (xy 378.732044 -247.151673) (xy 378.732542 -247.178322)
			(xy 378.732044 -247.204971) (xy 378.96037 -247.204971) (xy 378.96037 -247.151673) (xy 378.968313 -247.098969)
			(xy 378.984023 -247.048039) (xy 379.007149 -247.000018) (xy 379.037173 -246.955981) (xy 379.073425 -246.91691)
			(xy 379.115096 -246.883679) (xy 379.161254 -246.85703) (xy 379.210868 -246.837558) (xy 379.26283 -246.825698)
			(xy 379.31598 -246.821715) (xy 379.36913 -246.825698) (xy 379.421092 -246.837558) (xy 379.470706 -246.85703)
			(xy 379.516864 -246.883679) (xy 379.558535 -246.91691) (xy 379.594787 -246.955981) (xy 379.624811 -247.000018)
			(xy 379.647937 -247.048039) (xy 379.663647 -247.098969) (xy 379.67159 -247.151673) (xy 379.672088 -247.178322)
			(xy 379.67159 -247.204971) (xy 379.900424 -247.204971) (xy 379.900424 -247.151673) (xy 379.908367 -247.098969)
			(xy 379.924077 -247.048039) (xy 379.947203 -247.000018) (xy 379.977227 -246.955981) (xy 380.013479 -246.91691)
			(xy 380.05515 -246.883679) (xy 380.101308 -246.85703) (xy 380.150922 -246.837558) (xy 380.202884 -246.825698)
			(xy 380.256034 -246.821715) (xy 380.309184 -246.825698) (xy 380.361146 -246.837558) (xy 380.41076 -246.85703)
			(xy 380.456918 -246.883679) (xy 380.498589 -246.91691) (xy 380.534841 -246.955981) (xy 380.564865 -247.000018)
			(xy 380.587991 -247.048039) (xy 380.603701 -247.098969) (xy 380.611644 -247.151673) (xy 380.612142 -247.178322)
			(xy 380.611644 -247.204971) (xy 380.83997 -247.204971) (xy 380.83997 -247.151673) (xy 380.847913 -247.098969)
			(xy 380.863623 -247.048039) (xy 380.886749 -247.000018) (xy 380.916773 -246.955981) (xy 380.953025 -246.91691)
			(xy 380.994696 -246.883679) (xy 381.040854 -246.85703) (xy 381.090468 -246.837558) (xy 381.14243 -246.825698)
			(xy 381.19558 -246.821715) (xy 381.24873 -246.825698) (xy 381.300692 -246.837558) (xy 381.350306 -246.85703)
			(xy 381.396464 -246.883679) (xy 381.438135 -246.91691) (xy 381.474387 -246.955981) (xy 381.504411 -247.000018)
			(xy 381.527537 -247.048039) (xy 381.543247 -247.098969) (xy 381.55119 -247.151673) (xy 381.551688 -247.178322)
			(xy 381.55119 -247.204971) (xy 381.543247 -247.257675) (xy 381.527537 -247.308605) (xy 381.504411 -247.356626)
			(xy 381.474387 -247.400663) (xy 381.438135 -247.439734) (xy 381.396464 -247.472965) (xy 381.350306 -247.499614)
			(xy 381.300692 -247.519086) (xy 381.24873 -247.530946) (xy 381.19558 -247.53493) (xy 381.14243 -247.530946)
			(xy 381.090468 -247.519086) (xy 381.040854 -247.499614) (xy 380.994696 -247.472965) (xy 380.953025 -247.439734)
			(xy 380.916773 -247.400663) (xy 380.886749 -247.356626) (xy 380.863623 -247.308605) (xy 380.847913 -247.257675)
			(xy 380.83997 -247.204971) (xy 380.611644 -247.204971) (xy 380.603701 -247.257675) (xy 380.587991 -247.308605)
			(xy 380.564865 -247.356626) (xy 380.534841 -247.400663) (xy 380.498589 -247.439734) (xy 380.456918 -247.472965)
			(xy 380.41076 -247.499614) (xy 380.361146 -247.519086) (xy 380.309184 -247.530946) (xy 380.256034 -247.53493)
			(xy 380.202884 -247.530946) (xy 380.150922 -247.519086) (xy 380.101308 -247.499614) (xy 380.05515 -247.472965)
			(xy 380.013479 -247.439734) (xy 379.977227 -247.400663) (xy 379.947203 -247.356626) (xy 379.924077 -247.308605)
			(xy 379.908367 -247.257675) (xy 379.900424 -247.204971) (xy 379.67159 -247.204971) (xy 379.663647 -247.257675)
			(xy 379.647937 -247.308605) (xy 379.624811 -247.356626) (xy 379.594787 -247.400663) (xy 379.558535 -247.439734)
			(xy 379.516864 -247.472965) (xy 379.470706 -247.499614) (xy 379.421092 -247.519086) (xy 379.36913 -247.530946)
			(xy 379.31598 -247.53493) (xy 379.26283 -247.530946) (xy 379.210868 -247.519086) (xy 379.161254 -247.499614)
			(xy 379.115096 -247.472965) (xy 379.073425 -247.439734) (xy 379.037173 -247.400663) (xy 379.007149 -247.356626)
			(xy 378.984023 -247.308605) (xy 378.968313 -247.257675) (xy 378.96037 -247.204971) (xy 378.732044 -247.204971)
			(xy 378.724101 -247.257675) (xy 378.708391 -247.308605) (xy 378.685265 -247.356626) (xy 378.655241 -247.400663)
			(xy 378.618989 -247.439734) (xy 378.577318 -247.472965) (xy 378.53116 -247.499614) (xy 378.481546 -247.519086)
			(xy 378.429584 -247.530946) (xy 378.376434 -247.53493) (xy 378.323284 -247.530946) (xy 378.271322 -247.519086)
			(xy 378.221708 -247.499614) (xy 378.17555 -247.472965) (xy 378.133879 -247.439734) (xy 378.097627 -247.400663)
			(xy 378.067603 -247.356626) (xy 378.044477 -247.308605) (xy 378.028767 -247.257675) (xy 378.020824 -247.204971)
			(xy 377.792244 -247.204971) (xy 377.784301 -247.257675) (xy 377.768591 -247.308605) (xy 377.745465 -247.356626)
			(xy 377.715441 -247.400663) (xy 377.679189 -247.439734) (xy 377.637518 -247.472965) (xy 377.59136 -247.499614)
			(xy 377.541746 -247.519086) (xy 377.489784 -247.530946) (xy 377.436634 -247.53493) (xy 377.383484 -247.530946)
			(xy 377.331522 -247.519086) (xy 377.281908 -247.499614) (xy 377.23575 -247.472965) (xy 377.194079 -247.439734)
			(xy 377.157827 -247.400663) (xy 377.127803 -247.356626) (xy 377.104677 -247.308605) (xy 377.088967 -247.257675)
			(xy 377.081024 -247.204971) (xy 376.852444 -247.204971) (xy 376.844501 -247.257675) (xy 376.828791 -247.308605)
			(xy 376.805665 -247.356626) (xy 376.775641 -247.400663) (xy 376.739389 -247.439734) (xy 376.697718 -247.472965)
			(xy 376.65156 -247.499614) (xy 376.601946 -247.519086) (xy 376.549984 -247.530946) (xy 376.496834 -247.53493)
			(xy 376.443684 -247.530946) (xy 376.391722 -247.519086) (xy 376.342108 -247.499614) (xy 376.29595 -247.472965)
			(xy 376.254279 -247.439734) (xy 376.218027 -247.400663) (xy 376.188003 -247.356626) (xy 376.164877 -247.308605)
			(xy 376.149167 -247.257675) (xy 376.141224 -247.204971) (xy 375.912644 -247.204971) (xy 375.904701 -247.257675)
			(xy 375.888991 -247.308605) (xy 375.865865 -247.356626) (xy 375.835841 -247.400663) (xy 375.799589 -247.439734)
			(xy 375.757918 -247.472965) (xy 375.71176 -247.499614) (xy 375.662146 -247.519086) (xy 375.610184 -247.530946)
			(xy 375.557034 -247.53493) (xy 375.503884 -247.530946) (xy 375.451922 -247.519086) (xy 375.402308 -247.499614)
			(xy 375.35615 -247.472965) (xy 375.314479 -247.439734) (xy 375.278227 -247.400663) (xy 375.248203 -247.356626)
			(xy 375.225077 -247.308605) (xy 375.209367 -247.257675) (xy 375.201424 -247.204971) (xy 374.97259 -247.204971)
			(xy 374.964647 -247.257675) (xy 374.948937 -247.308605) (xy 374.925811 -247.356626) (xy 374.895787 -247.400663)
			(xy 374.859535 -247.439734) (xy 374.817864 -247.472965) (xy 374.771706 -247.499614) (xy 374.722092 -247.519086)
			(xy 374.67013 -247.530946) (xy 374.61698 -247.53493) (xy 374.56383 -247.530946) (xy 374.511868 -247.519086)
			(xy 374.462254 -247.499614) (xy 374.416096 -247.472965) (xy 374.374425 -247.439734) (xy 374.338173 -247.400663)
			(xy 374.308149 -247.356626) (xy 374.285023 -247.308605) (xy 374.269313 -247.257675) (xy 374.26137 -247.204971)
			(xy 374.033044 -247.204971) (xy 374.025101 -247.257675) (xy 374.009391 -247.308605) (xy 373.986265 -247.356626)
			(xy 373.956241 -247.400663) (xy 373.919989 -247.439734) (xy 373.878318 -247.472965) (xy 373.83216 -247.499614)
			(xy 373.782546 -247.519086) (xy 373.730584 -247.530946) (xy 373.677434 -247.53493) (xy 373.624284 -247.530946)
			(xy 373.572322 -247.519086) (xy 373.522708 -247.499614) (xy 373.47655 -247.472965) (xy 373.434879 -247.439734)
			(xy 373.398627 -247.400663) (xy 373.368603 -247.356626) (xy 373.345477 -247.308605) (xy 373.329767 -247.257675)
			(xy 373.321824 -247.204971) (xy 373.093244 -247.204971) (xy 373.085301 -247.257675) (xy 373.069591 -247.308605)
			(xy 373.046465 -247.356626) (xy 373.016441 -247.400663) (xy 372.980189 -247.439734) (xy 372.938518 -247.472965)
			(xy 372.89236 -247.499614) (xy 372.842746 -247.519086) (xy 372.790784 -247.530946) (xy 372.737634 -247.53493)
			(xy 372.684484 -247.530946) (xy 372.632522 -247.519086) (xy 372.582908 -247.499614) (xy 372.53675 -247.472965)
			(xy 372.495079 -247.439734) (xy 372.458827 -247.400663) (xy 372.428803 -247.356626) (xy 372.405677 -247.308605)
			(xy 372.389967 -247.257675) (xy 372.382024 -247.204971) (xy 372.153444 -247.204971) (xy 372.145501 -247.257675)
			(xy 372.129791 -247.308605) (xy 372.106665 -247.356626) (xy 372.076641 -247.400663) (xy 372.040389 -247.439734)
			(xy 371.998718 -247.472965) (xy 371.95256 -247.499614) (xy 371.902946 -247.519086) (xy 371.850984 -247.530946)
			(xy 371.797834 -247.53493) (xy 371.744684 -247.530946) (xy 371.692722 -247.519086) (xy 371.643108 -247.499614)
			(xy 371.59695 -247.472965) (xy 371.555279 -247.439734) (xy 371.519027 -247.400663) (xy 371.489003 -247.356626)
			(xy 371.465877 -247.308605) (xy 371.450167 -247.257675) (xy 371.442224 -247.204971) (xy 371.213644 -247.204971)
			(xy 371.205701 -247.257675) (xy 371.189991 -247.308605) (xy 371.166865 -247.356626) (xy 371.136841 -247.400663)
			(xy 371.100589 -247.439734) (xy 371.058918 -247.472965) (xy 371.01276 -247.499614) (xy 370.963146 -247.519086)
			(xy 370.911184 -247.530946) (xy 370.858034 -247.53493) (xy 370.804884 -247.530946) (xy 370.752922 -247.519086)
			(xy 370.703308 -247.499614) (xy 370.65715 -247.472965) (xy 370.615479 -247.439734) (xy 370.579227 -247.400663)
			(xy 370.549203 -247.356626) (xy 370.526077 -247.308605) (xy 370.510367 -247.257675) (xy 370.502424 -247.204971)
			(xy 370.273844 -247.204971) (xy 370.265901 -247.257675) (xy 370.250191 -247.308605) (xy 370.227065 -247.356626)
			(xy 370.197041 -247.400663) (xy 370.160789 -247.439734) (xy 370.119118 -247.472965) (xy 370.07296 -247.499614)
			(xy 370.023346 -247.519086) (xy 369.971384 -247.530946) (xy 369.918234 -247.53493) (xy 369.865084 -247.530946)
			(xy 369.813122 -247.519086) (xy 369.763508 -247.499614) (xy 369.71735 -247.472965) (xy 369.675679 -247.439734)
			(xy 369.639427 -247.400663) (xy 369.609403 -247.356626) (xy 369.586277 -247.308605) (xy 369.570567 -247.257675)
			(xy 369.562624 -247.204971) (xy 369.240306 -247.204971) (xy 369.251598 -247.230555) (xy 369.265088 -247.278013)
			(xy 369.271889 -247.326881) (xy 369.272312 -247.35155) (xy 369.271849 -247.377369) (xy 369.264388 -247.428466)
			(xy 369.249629 -247.47795) (xy 369.227882 -247.524786) (xy 369.199601 -247.567992) (xy 369.16538 -247.606662)
			(xy 369.125934 -247.639988) (xy 369.082092 -247.667271) (xy 369.03477 -247.68794) (xy 368.98496 -247.701561)
			(xy 368.959384 -247.705118) (xy 368.91468 -247.710452) (xy 368.91468 -247.97004) (xy 368.956336 -247.97766)
			(xy 368.978688 -247.982486) (xy 368.991777 -247.985335) (xy 369.018551 -247.984842) (xy 369.044278 -247.97741)
			(xy 369.067191 -247.96355) (xy 369.085716 -247.944213) (xy 369.098582 -247.920726) (xy 369.102132 -247.90781)
			(xy 369.10884 -247.882318) (xy 369.128743 -247.83351) (xy 369.155623 -247.788169) (xy 369.188893 -247.747286)
			(xy 369.227825 -247.711753) (xy 369.271571 -247.682347) (xy 369.319173 -247.659711) (xy 369.369591 -247.644338)
			(xy 369.421725 -247.636566) (xy 369.44808 -247.63603) (xy 369.474729 -247.636502) (xy 369.527433 -247.644443)
			(xy 369.578364 -247.66015) (xy 369.626385 -247.683274) (xy 369.670424 -247.713296) (xy 369.709495 -247.749547)
			(xy 369.742727 -247.791217) (xy 369.769378 -247.837375) (xy 369.78885 -247.886988) (xy 369.800711 -247.938951)
			(xy 369.804694 -247.9921) (xy 369.802694 -248.018787) (xy 370.03227 -248.018787) (xy 370.03227 -247.965489)
			(xy 370.040213 -247.912785) (xy 370.055923 -247.861855) (xy 370.079049 -247.813834) (xy 370.109073 -247.769797)
			(xy 370.145325 -247.730726) (xy 370.186996 -247.697495) (xy 370.233154 -247.670846) (xy 370.282768 -247.651374)
			(xy 370.33473 -247.639514) (xy 370.38788 -247.635531) (xy 370.44103 -247.639514) (xy 370.492992 -247.651374)
			(xy 370.542606 -247.670846) (xy 370.588764 -247.697495) (xy 370.630435 -247.730726) (xy 370.666687 -247.769797)
			(xy 370.696711 -247.813834) (xy 370.719837 -247.861855) (xy 370.735547 -247.912785) (xy 370.74349 -247.965489)
			(xy 370.743988 -247.992138) (xy 370.74349 -248.018787) (xy 370.97207 -248.018787) (xy 370.97207 -247.965489)
			(xy 370.980013 -247.912785) (xy 370.995723 -247.861855) (xy 371.018849 -247.813834) (xy 371.048873 -247.769797)
			(xy 371.085125 -247.730726) (xy 371.126796 -247.697495) (xy 371.172954 -247.670846) (xy 371.222568 -247.651374)
			(xy 371.27453 -247.639514) (xy 371.32768 -247.635531) (xy 371.38083 -247.639514) (xy 371.432792 -247.651374)
			(xy 371.482406 -247.670846) (xy 371.528564 -247.697495) (xy 371.570235 -247.730726) (xy 371.606487 -247.769797)
			(xy 371.636511 -247.813834) (xy 371.659637 -247.861855) (xy 371.675347 -247.912785) (xy 371.68329 -247.965489)
			(xy 371.683788 -247.992138) (xy 371.68329 -248.018787) (xy 371.91187 -248.018787) (xy 371.91187 -247.965489)
			(xy 371.919813 -247.912785) (xy 371.935523 -247.861855) (xy 371.958649 -247.813834) (xy 371.988673 -247.769797)
			(xy 372.024925 -247.730726) (xy 372.066596 -247.697495) (xy 372.112754 -247.670846) (xy 372.162368 -247.651374)
			(xy 372.21433 -247.639514) (xy 372.26748 -247.635531) (xy 372.32063 -247.639514) (xy 372.372592 -247.651374)
			(xy 372.422206 -247.670846) (xy 372.468364 -247.697495) (xy 372.510035 -247.730726) (xy 372.546287 -247.769797)
			(xy 372.576311 -247.813834) (xy 372.599437 -247.861855) (xy 372.615147 -247.912785) (xy 372.62309 -247.965489)
			(xy 372.623588 -247.992138) (xy 372.62309 -248.018787) (xy 372.85167 -248.018787) (xy 372.85167 -247.965489)
			(xy 372.859613 -247.912785) (xy 372.875323 -247.861855) (xy 372.898449 -247.813834) (xy 372.928473 -247.769797)
			(xy 372.964725 -247.730726) (xy 373.006396 -247.697495) (xy 373.052554 -247.670846) (xy 373.102168 -247.651374)
			(xy 373.15413 -247.639514) (xy 373.20728 -247.635531) (xy 373.26043 -247.639514) (xy 373.312392 -247.651374)
			(xy 373.362006 -247.670846) (xy 373.408164 -247.697495) (xy 373.449835 -247.730726) (xy 373.486087 -247.769797)
			(xy 373.516111 -247.813834) (xy 373.539237 -247.861855) (xy 373.554947 -247.912785) (xy 373.56289 -247.965489)
			(xy 373.563388 -247.992138) (xy 373.56289 -248.018787) (xy 373.791724 -248.018787) (xy 373.791724 -247.965489)
			(xy 373.799667 -247.912785) (xy 373.815377 -247.861855) (xy 373.838503 -247.813834) (xy 373.868527 -247.769797)
			(xy 373.904779 -247.730726) (xy 373.94645 -247.697495) (xy 373.992608 -247.670846) (xy 374.042222 -247.651374)
			(xy 374.094184 -247.639514) (xy 374.147334 -247.635531) (xy 374.200484 -247.639514) (xy 374.252446 -247.651374)
			(xy 374.30206 -247.670846) (xy 374.348218 -247.697495) (xy 374.389889 -247.730726) (xy 374.426141 -247.769797)
			(xy 374.456165 -247.813834) (xy 374.479291 -247.861855) (xy 374.495001 -247.912785) (xy 374.502944 -247.965489)
			(xy 374.503442 -247.992138) (xy 374.502944 -248.018787) (xy 374.73127 -248.018787) (xy 374.73127 -247.965489)
			(xy 374.739213 -247.912785) (xy 374.754923 -247.861855) (xy 374.778049 -247.813834) (xy 374.808073 -247.769797)
			(xy 374.844325 -247.730726) (xy 374.885996 -247.697495) (xy 374.932154 -247.670846) (xy 374.981768 -247.651374)
			(xy 375.03373 -247.639514) (xy 375.08688 -247.635531) (xy 375.14003 -247.639514) (xy 375.191992 -247.651374)
			(xy 375.241606 -247.670846) (xy 375.287764 -247.697495) (xy 375.329435 -247.730726) (xy 375.365687 -247.769797)
			(xy 375.395711 -247.813834) (xy 375.418837 -247.861855) (xy 375.434547 -247.912785) (xy 375.44249 -247.965489)
			(xy 375.442988 -247.992138) (xy 375.44249 -248.018787) (xy 375.67107 -248.018787) (xy 375.67107 -247.965489)
			(xy 375.679013 -247.912785) (xy 375.694723 -247.861855) (xy 375.717849 -247.813834) (xy 375.747873 -247.769797)
			(xy 375.784125 -247.730726) (xy 375.825796 -247.697495) (xy 375.871954 -247.670846) (xy 375.921568 -247.651374)
			(xy 375.97353 -247.639514) (xy 376.02668 -247.635531) (xy 376.07983 -247.639514) (xy 376.131792 -247.651374)
			(xy 376.181406 -247.670846) (xy 376.227564 -247.697495) (xy 376.269235 -247.730726) (xy 376.305487 -247.769797)
			(xy 376.335511 -247.813834) (xy 376.358637 -247.861855) (xy 376.374347 -247.912785) (xy 376.38229 -247.965489)
			(xy 376.382788 -247.992138) (xy 376.38229 -248.018787) (xy 376.61087 -248.018787) (xy 376.61087 -247.965489)
			(xy 376.618813 -247.912785) (xy 376.634523 -247.861855) (xy 376.657649 -247.813834) (xy 376.687673 -247.769797)
			(xy 376.723925 -247.730726) (xy 376.765596 -247.697495) (xy 376.811754 -247.670846) (xy 376.861368 -247.651374)
			(xy 376.91333 -247.639514) (xy 376.96648 -247.635531) (xy 377.01963 -247.639514) (xy 377.071592 -247.651374)
			(xy 377.121206 -247.670846) (xy 377.167364 -247.697495) (xy 377.209035 -247.730726) (xy 377.245287 -247.769797)
			(xy 377.275311 -247.813834) (xy 377.298437 -247.861855) (xy 377.314147 -247.912785) (xy 377.32209 -247.965489)
			(xy 377.322588 -247.992138) (xy 377.32209 -248.018787) (xy 377.55067 -248.018787) (xy 377.55067 -247.965489)
			(xy 377.558613 -247.912785) (xy 377.574323 -247.861855) (xy 377.597449 -247.813834) (xy 377.627473 -247.769797)
			(xy 377.663725 -247.730726) (xy 377.705396 -247.697495) (xy 377.751554 -247.670846) (xy 377.801168 -247.651374)
			(xy 377.85313 -247.639514) (xy 377.90628 -247.635531) (xy 377.95943 -247.639514) (xy 378.011392 -247.651374)
			(xy 378.061006 -247.670846) (xy 378.107164 -247.697495) (xy 378.148835 -247.730726) (xy 378.185087 -247.769797)
			(xy 378.215111 -247.813834) (xy 378.238237 -247.861855) (xy 378.253947 -247.912785) (xy 378.26189 -247.965489)
			(xy 378.262388 -247.992138) (xy 378.26189 -248.018787) (xy 378.490724 -248.018787) (xy 378.490724 -247.965489)
			(xy 378.498667 -247.912785) (xy 378.514377 -247.861855) (xy 378.537503 -247.813834) (xy 378.567527 -247.769797)
			(xy 378.603779 -247.730726) (xy 378.64545 -247.697495) (xy 378.691608 -247.670846) (xy 378.741222 -247.651374)
			(xy 378.793184 -247.639514) (xy 378.846334 -247.635531) (xy 378.899484 -247.639514) (xy 378.951446 -247.651374)
			(xy 379.00106 -247.670846) (xy 379.047218 -247.697495) (xy 379.088889 -247.730726) (xy 379.125141 -247.769797)
			(xy 379.155165 -247.813834) (xy 379.178291 -247.861855) (xy 379.194001 -247.912785) (xy 379.201944 -247.965489)
			(xy 379.202442 -247.992138) (xy 379.201944 -248.018787) (xy 379.43027 -248.018787) (xy 379.43027 -247.965489)
			(xy 379.438213 -247.912785) (xy 379.453923 -247.861855) (xy 379.477049 -247.813834) (xy 379.507073 -247.769797)
			(xy 379.543325 -247.730726) (xy 379.584996 -247.697495) (xy 379.631154 -247.670846) (xy 379.680768 -247.651374)
			(xy 379.73273 -247.639514) (xy 379.78588 -247.635531) (xy 379.83903 -247.639514) (xy 379.890992 -247.651374)
			(xy 379.940606 -247.670846) (xy 379.986764 -247.697495) (xy 380.028435 -247.730726) (xy 380.064687 -247.769797)
			(xy 380.094711 -247.813834) (xy 380.117837 -247.861855) (xy 380.133547 -247.912785) (xy 380.14149 -247.965489)
			(xy 380.141988 -247.992138) (xy 380.14149 -248.018787) (xy 380.370324 -248.018787) (xy 380.370324 -247.965489)
			(xy 380.378267 -247.912785) (xy 380.393977 -247.861855) (xy 380.417103 -247.813834) (xy 380.447127 -247.769797)
			(xy 380.483379 -247.730726) (xy 380.52505 -247.697495) (xy 380.571208 -247.670846) (xy 380.620822 -247.651374)
			(xy 380.672784 -247.639514) (xy 380.725934 -247.635531) (xy 380.779084 -247.639514) (xy 380.831046 -247.651374)
			(xy 380.88066 -247.670846) (xy 380.926818 -247.697495) (xy 380.968489 -247.730726) (xy 381.004741 -247.769797)
			(xy 381.034765 -247.813834) (xy 381.057891 -247.861855) (xy 381.073601 -247.912785) (xy 381.081544 -247.965489)
			(xy 381.082042 -247.992138) (xy 381.081544 -248.018787) (xy 381.073601 -248.071491) (xy 381.057891 -248.122421)
			(xy 381.034765 -248.170442) (xy 381.004741 -248.214479) (xy 380.968489 -248.25355) (xy 380.926818 -248.286781)
			(xy 380.88066 -248.31343) (xy 380.831046 -248.332902) (xy 380.779084 -248.344762) (xy 380.725934 -248.348746)
			(xy 380.672784 -248.344762) (xy 380.620822 -248.332902) (xy 380.571208 -248.31343) (xy 380.52505 -248.286781)
			(xy 380.483379 -248.25355) (xy 380.447127 -248.214479) (xy 380.417103 -248.170442) (xy 380.393977 -248.122421)
			(xy 380.378267 -248.071491) (xy 380.370324 -248.018787) (xy 380.14149 -248.018787) (xy 380.133547 -248.071491)
			(xy 380.117837 -248.122421) (xy 380.094711 -248.170442) (xy 380.064687 -248.214479) (xy 380.028435 -248.25355)
			(xy 379.986764 -248.286781) (xy 379.940606 -248.31343) (xy 379.890992 -248.332902) (xy 379.83903 -248.344762)
			(xy 379.78588 -248.348746) (xy 379.73273 -248.344762) (xy 379.680768 -248.332902) (xy 379.631154 -248.31343)
			(xy 379.584996 -248.286781) (xy 379.543325 -248.25355) (xy 379.507073 -248.214479) (xy 379.477049 -248.170442)
			(xy 379.453923 -248.122421) (xy 379.438213 -248.071491) (xy 379.43027 -248.018787) (xy 379.201944 -248.018787)
			(xy 379.194001 -248.071491) (xy 379.178291 -248.122421) (xy 379.155165 -248.170442) (xy 379.125141 -248.214479)
			(xy 379.088889 -248.25355) (xy 379.047218 -248.286781) (xy 379.00106 -248.31343) (xy 378.951446 -248.332902)
			(xy 378.899484 -248.344762) (xy 378.846334 -248.348746) (xy 378.793184 -248.344762) (xy 378.741222 -248.332902)
			(xy 378.691608 -248.31343) (xy 378.64545 -248.286781) (xy 378.603779 -248.25355) (xy 378.567527 -248.214479)
			(xy 378.537503 -248.170442) (xy 378.514377 -248.122421) (xy 378.498667 -248.071491) (xy 378.490724 -248.018787)
			(xy 378.26189 -248.018787) (xy 378.253947 -248.071491) (xy 378.238237 -248.122421) (xy 378.215111 -248.170442)
			(xy 378.185087 -248.214479) (xy 378.148835 -248.25355) (xy 378.107164 -248.286781) (xy 378.061006 -248.31343)
			(xy 378.011392 -248.332902) (xy 377.95943 -248.344762) (xy 377.90628 -248.348746) (xy 377.85313 -248.344762)
			(xy 377.801168 -248.332902) (xy 377.751554 -248.31343) (xy 377.705396 -248.286781) (xy 377.663725 -248.25355)
			(xy 377.627473 -248.214479) (xy 377.597449 -248.170442) (xy 377.574323 -248.122421) (xy 377.558613 -248.071491)
			(xy 377.55067 -248.018787) (xy 377.32209 -248.018787) (xy 377.314147 -248.071491) (xy 377.298437 -248.122421)
			(xy 377.275311 -248.170442) (xy 377.245287 -248.214479) (xy 377.209035 -248.25355) (xy 377.167364 -248.286781)
			(xy 377.121206 -248.31343) (xy 377.071592 -248.332902) (xy 377.01963 -248.344762) (xy 376.96648 -248.348746)
			(xy 376.91333 -248.344762) (xy 376.861368 -248.332902) (xy 376.811754 -248.31343) (xy 376.765596 -248.286781)
			(xy 376.723925 -248.25355) (xy 376.687673 -248.214479) (xy 376.657649 -248.170442) (xy 376.634523 -248.122421)
			(xy 376.618813 -248.071491) (xy 376.61087 -248.018787) (xy 376.38229 -248.018787) (xy 376.374347 -248.071491)
			(xy 376.358637 -248.122421) (xy 376.335511 -248.170442) (xy 376.305487 -248.214479) (xy 376.269235 -248.25355)
			(xy 376.227564 -248.286781) (xy 376.181406 -248.31343) (xy 376.131792 -248.332902) (xy 376.07983 -248.344762)
			(xy 376.02668 -248.348746) (xy 375.97353 -248.344762) (xy 375.921568 -248.332902) (xy 375.871954 -248.31343)
			(xy 375.825796 -248.286781) (xy 375.784125 -248.25355) (xy 375.747873 -248.214479) (xy 375.717849 -248.170442)
			(xy 375.694723 -248.122421) (xy 375.679013 -248.071491) (xy 375.67107 -248.018787) (xy 375.44249 -248.018787)
			(xy 375.434547 -248.071491) (xy 375.418837 -248.122421) (xy 375.395711 -248.170442) (xy 375.365687 -248.214479)
			(xy 375.329435 -248.25355) (xy 375.287764 -248.286781) (xy 375.241606 -248.31343) (xy 375.191992 -248.332902)
			(xy 375.14003 -248.344762) (xy 375.08688 -248.348746) (xy 375.03373 -248.344762) (xy 374.981768 -248.332902)
			(xy 374.932154 -248.31343) (xy 374.885996 -248.286781) (xy 374.844325 -248.25355) (xy 374.808073 -248.214479)
			(xy 374.778049 -248.170442) (xy 374.754923 -248.122421) (xy 374.739213 -248.071491) (xy 374.73127 -248.018787)
			(xy 374.502944 -248.018787) (xy 374.495001 -248.071491) (xy 374.479291 -248.122421) (xy 374.456165 -248.170442)
			(xy 374.426141 -248.214479) (xy 374.389889 -248.25355) (xy 374.348218 -248.286781) (xy 374.30206 -248.31343)
			(xy 374.252446 -248.332902) (xy 374.200484 -248.344762) (xy 374.147334 -248.348746) (xy 374.094184 -248.344762)
			(xy 374.042222 -248.332902) (xy 373.992608 -248.31343) (xy 373.94645 -248.286781) (xy 373.904779 -248.25355)
			(xy 373.868527 -248.214479) (xy 373.838503 -248.170442) (xy 373.815377 -248.122421) (xy 373.799667 -248.071491)
			(xy 373.791724 -248.018787) (xy 373.56289 -248.018787) (xy 373.554947 -248.071491) (xy 373.539237 -248.122421)
			(xy 373.516111 -248.170442) (xy 373.486087 -248.214479) (xy 373.449835 -248.25355) (xy 373.408164 -248.286781)
			(xy 373.362006 -248.31343) (xy 373.312392 -248.332902) (xy 373.26043 -248.344762) (xy 373.20728 -248.348746)
			(xy 373.15413 -248.344762) (xy 373.102168 -248.332902) (xy 373.052554 -248.31343) (xy 373.006396 -248.286781)
			(xy 372.964725 -248.25355) (xy 372.928473 -248.214479) (xy 372.898449 -248.170442) (xy 372.875323 -248.122421)
			(xy 372.859613 -248.071491) (xy 372.85167 -248.018787) (xy 372.62309 -248.018787) (xy 372.615147 -248.071491)
			(xy 372.599437 -248.122421) (xy 372.576311 -248.170442) (xy 372.546287 -248.214479) (xy 372.510035 -248.25355)
			(xy 372.468364 -248.286781) (xy 372.422206 -248.31343) (xy 372.372592 -248.332902) (xy 372.32063 -248.344762)
			(xy 372.26748 -248.348746) (xy 372.21433 -248.344762) (xy 372.162368 -248.332902) (xy 372.112754 -248.31343)
			(xy 372.066596 -248.286781) (xy 372.024925 -248.25355) (xy 371.988673 -248.214479) (xy 371.958649 -248.170442)
			(xy 371.935523 -248.122421) (xy 371.919813 -248.071491) (xy 371.91187 -248.018787) (xy 371.68329 -248.018787)
			(xy 371.675347 -248.071491) (xy 371.659637 -248.122421) (xy 371.636511 -248.170442) (xy 371.606487 -248.214479)
			(xy 371.570235 -248.25355) (xy 371.528564 -248.286781) (xy 371.482406 -248.31343) (xy 371.432792 -248.332902)
			(xy 371.38083 -248.344762) (xy 371.32768 -248.348746) (xy 371.27453 -248.344762) (xy 371.222568 -248.332902)
			(xy 371.172954 -248.31343) (xy 371.126796 -248.286781) (xy 371.085125 -248.25355) (xy 371.048873 -248.214479)
			(xy 371.018849 -248.170442) (xy 370.995723 -248.122421) (xy 370.980013 -248.071491) (xy 370.97207 -248.018787)
			(xy 370.74349 -248.018787) (xy 370.735547 -248.071491) (xy 370.719837 -248.122421) (xy 370.696711 -248.170442)
			(xy 370.666687 -248.214479) (xy 370.630435 -248.25355) (xy 370.588764 -248.286781) (xy 370.542606 -248.31343)
			(xy 370.492992 -248.332902) (xy 370.44103 -248.344762) (xy 370.38788 -248.348746) (xy 370.33473 -248.344762)
			(xy 370.282768 -248.332902) (xy 370.233154 -248.31343) (xy 370.186996 -248.286781) (xy 370.145325 -248.25355)
			(xy 370.109073 -248.214479) (xy 370.079049 -248.170442) (xy 370.055923 -248.122421) (xy 370.040213 -248.071491)
			(xy 370.03227 -248.018787) (xy 369.802694 -248.018787) (xy 369.800711 -248.045249) (xy 369.78885 -248.097212)
			(xy 369.769378 -248.146825) (xy 369.742727 -248.192983) (xy 369.709495 -248.234653) (xy 369.670424 -248.270904)
			(xy 369.626385 -248.300926) (xy 369.578364 -248.32405) (xy 369.527433 -248.339757) (xy 369.474729 -248.347698)
			(xy 369.44808 -248.348246) (xy 369.426329 -248.347887) (xy 369.383155 -248.342537) (xy 369.361974 -248.337578)
			(xy 369.348889 -248.334733) (xy 369.322126 -248.335233) (xy 369.296411 -248.342672) (xy 369.273514 -248.356537)
			(xy 369.255006 -248.375877) (xy 369.242161 -248.399362) (xy 369.23853 -248.412254) (xy 369.231888 -248.437552)
			(xy 369.212205 -248.486009) (xy 369.185653 -248.531071) (xy 369.152801 -248.571768) (xy 369.114356 -248.607229)
			(xy 369.092988 -248.622312) (xy 369.080994 -248.631072) (xy 369.062268 -248.654107) (xy 369.05096 -248.681556)
			(xy 369.048029 -248.711097) (xy 369.053721 -248.740233) (xy 369.067555 -248.766499) (xy 369.088362 -248.787675)
			(xy 369.101116 -248.795286) (xy 369.124609 -248.808854) (xy 369.155714 -248.832857) (xy 369.562624 -248.832857)
			(xy 369.562624 -248.779559) (xy 369.570567 -248.726855) (xy 369.586277 -248.675925) (xy 369.609403 -248.627904)
			(xy 369.639427 -248.583867) (xy 369.675679 -248.544796) (xy 369.71735 -248.511565) (xy 369.763508 -248.484916)
			(xy 369.813122 -248.465444) (xy 369.865084 -248.453584) (xy 369.918234 -248.449601) (xy 369.971384 -248.453584)
			(xy 370.023346 -248.465444) (xy 370.07296 -248.484916) (xy 370.119118 -248.511565) (xy 370.160789 -248.544796)
			(xy 370.197041 -248.583867) (xy 370.227065 -248.627904) (xy 370.250191 -248.675925) (xy 370.265901 -248.726855)
			(xy 370.273844 -248.779559) (xy 370.274342 -248.806208) (xy 370.273844 -248.832857) (xy 370.50217 -248.832857)
			(xy 370.50217 -248.779559) (xy 370.510113 -248.726855) (xy 370.525823 -248.675925) (xy 370.548949 -248.627904)
			(xy 370.578973 -248.583867) (xy 370.615225 -248.544796) (xy 370.656896 -248.511565) (xy 370.703054 -248.484916)
			(xy 370.752668 -248.465444) (xy 370.80463 -248.453584) (xy 370.85778 -248.449601) (xy 370.91093 -248.453584)
			(xy 370.962892 -248.465444) (xy 371.012506 -248.484916) (xy 371.058664 -248.511565) (xy 371.100335 -248.544796)
			(xy 371.136587 -248.583867) (xy 371.166611 -248.627904) (xy 371.189737 -248.675925) (xy 371.205447 -248.726855)
			(xy 371.21339 -248.779559) (xy 371.213888 -248.806208) (xy 371.21339 -248.832857) (xy 371.442224 -248.832857)
			(xy 371.442224 -248.779559) (xy 371.450167 -248.726855) (xy 371.465877 -248.675925) (xy 371.489003 -248.627904)
			(xy 371.519027 -248.583867) (xy 371.555279 -248.544796) (xy 371.59695 -248.511565) (xy 371.643108 -248.484916)
			(xy 371.692722 -248.465444) (xy 371.744684 -248.453584) (xy 371.797834 -248.449601) (xy 371.850984 -248.453584)
			(xy 371.902946 -248.465444) (xy 371.95256 -248.484916) (xy 371.998718 -248.511565) (xy 372.040389 -248.544796)
			(xy 372.076641 -248.583867) (xy 372.106665 -248.627904) (xy 372.129791 -248.675925) (xy 372.145501 -248.726855)
			(xy 372.153444 -248.779559) (xy 372.153942 -248.806208) (xy 372.153444 -248.832857) (xy 372.382024 -248.832857)
			(xy 372.382024 -248.779559) (xy 372.389967 -248.726855) (xy 372.405677 -248.675925) (xy 372.428803 -248.627904)
			(xy 372.458827 -248.583867) (xy 372.495079 -248.544796) (xy 372.53675 -248.511565) (xy 372.582908 -248.484916)
			(xy 372.632522 -248.465444) (xy 372.684484 -248.453584) (xy 372.737634 -248.449601) (xy 372.790784 -248.453584)
			(xy 372.842746 -248.465444) (xy 372.89236 -248.484916) (xy 372.938518 -248.511565) (xy 372.980189 -248.544796)
			(xy 373.016441 -248.583867) (xy 373.046465 -248.627904) (xy 373.069591 -248.675925) (xy 373.085301 -248.726855)
			(xy 373.093244 -248.779559) (xy 373.093742 -248.806208) (xy 373.093244 -248.832857) (xy 373.321824 -248.832857)
			(xy 373.321824 -248.779559) (xy 373.329767 -248.726855) (xy 373.345477 -248.675925) (xy 373.368603 -248.627904)
			(xy 373.398627 -248.583867) (xy 373.434879 -248.544796) (xy 373.47655 -248.511565) (xy 373.522708 -248.484916)
			(xy 373.572322 -248.465444) (xy 373.624284 -248.453584) (xy 373.677434 -248.449601) (xy 373.730584 -248.453584)
			(xy 373.782546 -248.465444) (xy 373.83216 -248.484916) (xy 373.878318 -248.511565) (xy 373.919989 -248.544796)
			(xy 373.956241 -248.583867) (xy 373.986265 -248.627904) (xy 374.009391 -248.675925) (xy 374.025101 -248.726855)
			(xy 374.033044 -248.779559) (xy 374.033542 -248.806208) (xy 374.033044 -248.832857) (xy 374.261624 -248.832857)
			(xy 374.261624 -248.779559) (xy 374.269567 -248.726855) (xy 374.285277 -248.675925) (xy 374.308403 -248.627904)
			(xy 374.338427 -248.583867) (xy 374.374679 -248.544796) (xy 374.41635 -248.511565) (xy 374.462508 -248.484916)
			(xy 374.512122 -248.465444) (xy 374.564084 -248.453584) (xy 374.617234 -248.449601) (xy 374.670384 -248.453584)
			(xy 374.722346 -248.465444) (xy 374.77196 -248.484916) (xy 374.818118 -248.511565) (xy 374.859789 -248.544796)
			(xy 374.896041 -248.583867) (xy 374.926065 -248.627904) (xy 374.949191 -248.675925) (xy 374.964901 -248.726855)
			(xy 374.972844 -248.779559) (xy 374.973342 -248.806208) (xy 374.972844 -248.832857) (xy 375.201424 -248.832857)
			(xy 375.201424 -248.779559) (xy 375.209367 -248.726855) (xy 375.225077 -248.675925) (xy 375.248203 -248.627904)
			(xy 375.278227 -248.583867) (xy 375.314479 -248.544796) (xy 375.35615 -248.511565) (xy 375.402308 -248.484916)
			(xy 375.451922 -248.465444) (xy 375.503884 -248.453584) (xy 375.557034 -248.449601) (xy 375.610184 -248.453584)
			(xy 375.662146 -248.465444) (xy 375.71176 -248.484916) (xy 375.757918 -248.511565) (xy 375.799589 -248.544796)
			(xy 375.835841 -248.583867) (xy 375.865865 -248.627904) (xy 375.888991 -248.675925) (xy 375.904701 -248.726855)
			(xy 375.912644 -248.779559) (xy 375.913142 -248.806208) (xy 375.912644 -248.832857) (xy 376.141224 -248.832857)
			(xy 376.141224 -248.779559) (xy 376.149167 -248.726855) (xy 376.164877 -248.675925) (xy 376.188003 -248.627904)
			(xy 376.218027 -248.583867) (xy 376.254279 -248.544796) (xy 376.29595 -248.511565) (xy 376.342108 -248.484916)
			(xy 376.391722 -248.465444) (xy 376.443684 -248.453584) (xy 376.496834 -248.449601) (xy 376.549984 -248.453584)
			(xy 376.601946 -248.465444) (xy 376.65156 -248.484916) (xy 376.697718 -248.511565) (xy 376.739389 -248.544796)
			(xy 376.775641 -248.583867) (xy 376.805665 -248.627904) (xy 376.828791 -248.675925) (xy 376.844501 -248.726855)
			(xy 376.852444 -248.779559) (xy 376.852942 -248.806208) (xy 376.852444 -248.832857) (xy 377.08077 -248.832857)
			(xy 377.08077 -248.779559) (xy 377.088713 -248.726855) (xy 377.104423 -248.675925) (xy 377.127549 -248.627904)
			(xy 377.157573 -248.583867) (xy 377.193825 -248.544796) (xy 377.235496 -248.511565) (xy 377.281654 -248.484916)
			(xy 377.331268 -248.465444) (xy 377.38323 -248.453584) (xy 377.43638 -248.449601) (xy 377.48953 -248.453584)
			(xy 377.541492 -248.465444) (xy 377.591106 -248.484916) (xy 377.637264 -248.511565) (xy 377.678935 -248.544796)
			(xy 377.715187 -248.583867) (xy 377.745211 -248.627904) (xy 377.768337 -248.675925) (xy 377.784047 -248.726855)
			(xy 377.79199 -248.779559) (xy 377.792488 -248.806208) (xy 377.79199 -248.832857) (xy 378.020824 -248.832857)
			(xy 378.020824 -248.779559) (xy 378.028767 -248.726855) (xy 378.044477 -248.675925) (xy 378.067603 -248.627904)
			(xy 378.097627 -248.583867) (xy 378.133879 -248.544796) (xy 378.17555 -248.511565) (xy 378.221708 -248.484916)
			(xy 378.271322 -248.465444) (xy 378.323284 -248.453584) (xy 378.376434 -248.449601) (xy 378.429584 -248.453584)
			(xy 378.481546 -248.465444) (xy 378.53116 -248.484916) (xy 378.577318 -248.511565) (xy 378.618989 -248.544796)
			(xy 378.655241 -248.583867) (xy 378.685265 -248.627904) (xy 378.708391 -248.675925) (xy 378.724101 -248.726855)
			(xy 378.732044 -248.779559) (xy 378.732542 -248.806208) (xy 378.732044 -248.832857) (xy 378.960624 -248.832857)
			(xy 378.960624 -248.779559) (xy 378.968567 -248.726855) (xy 378.984277 -248.675925) (xy 379.007403 -248.627904)
			(xy 379.037427 -248.583867) (xy 379.073679 -248.544796) (xy 379.11535 -248.511565) (xy 379.161508 -248.484916)
			(xy 379.211122 -248.465444) (xy 379.263084 -248.453584) (xy 379.316234 -248.449601) (xy 379.369384 -248.453584)
			(xy 379.421346 -248.465444) (xy 379.47096 -248.484916) (xy 379.517118 -248.511565) (xy 379.558789 -248.544796)
			(xy 379.595041 -248.583867) (xy 379.625065 -248.627904) (xy 379.648191 -248.675925) (xy 379.663901 -248.726855)
			(xy 379.671844 -248.779559) (xy 379.672342 -248.806208) (xy 379.671844 -248.832857) (xy 379.900424 -248.832857)
			(xy 379.900424 -248.779559) (xy 379.908367 -248.726855) (xy 379.924077 -248.675925) (xy 379.947203 -248.627904)
			(xy 379.977227 -248.583867) (xy 380.013479 -248.544796) (xy 380.05515 -248.511565) (xy 380.101308 -248.484916)
			(xy 380.150922 -248.465444) (xy 380.202884 -248.453584) (xy 380.256034 -248.449601) (xy 380.309184 -248.453584)
			(xy 380.361146 -248.465444) (xy 380.41076 -248.484916) (xy 380.456918 -248.511565) (xy 380.498589 -248.544796)
			(xy 380.534841 -248.583867) (xy 380.564865 -248.627904) (xy 380.587991 -248.675925) (xy 380.603701 -248.726855)
			(xy 380.611644 -248.779559) (xy 380.612142 -248.806208) (xy 380.611644 -248.832857) (xy 380.603701 -248.885561)
			(xy 380.587991 -248.936491) (xy 380.564865 -248.984512) (xy 380.534841 -249.028549) (xy 380.498589 -249.06762)
			(xy 380.456918 -249.100851) (xy 380.41076 -249.1275) (xy 380.361146 -249.146972) (xy 380.309184 -249.158832)
			(xy 380.256034 -249.162816) (xy 380.202884 -249.158832) (xy 380.150922 -249.146972) (xy 380.101308 -249.1275)
			(xy 380.05515 -249.100851) (xy 380.013479 -249.06762) (xy 379.977227 -249.028549) (xy 379.947203 -248.984512)
			(xy 379.924077 -248.936491) (xy 379.908367 -248.885561) (xy 379.900424 -248.832857) (xy 379.671844 -248.832857)
			(xy 379.663901 -248.885561) (xy 379.648191 -248.936491) (xy 379.625065 -248.984512) (xy 379.595041 -249.028549)
			(xy 379.558789 -249.06762) (xy 379.517118 -249.100851) (xy 379.47096 -249.1275) (xy 379.421346 -249.146972)
			(xy 379.369384 -249.158832) (xy 379.316234 -249.162816) (xy 379.263084 -249.158832) (xy 379.211122 -249.146972)
			(xy 379.161508 -249.1275) (xy 379.11535 -249.100851) (xy 379.073679 -249.06762) (xy 379.037427 -249.028549)
			(xy 379.007403 -248.984512) (xy 378.984277 -248.936491) (xy 378.968567 -248.885561) (xy 378.960624 -248.832857)
			(xy 378.732044 -248.832857) (xy 378.724101 -248.885561) (xy 378.708391 -248.936491) (xy 378.685265 -248.984512)
			(xy 378.655241 -249.028549) (xy 378.618989 -249.06762) (xy 378.577318 -249.100851) (xy 378.53116 -249.1275)
			(xy 378.481546 -249.146972) (xy 378.429584 -249.158832) (xy 378.376434 -249.162816) (xy 378.323284 -249.158832)
			(xy 378.271322 -249.146972) (xy 378.221708 -249.1275) (xy 378.17555 -249.100851) (xy 378.133879 -249.06762)
			(xy 378.097627 -249.028549) (xy 378.067603 -248.984512) (xy 378.044477 -248.936491) (xy 378.028767 -248.885561)
			(xy 378.020824 -248.832857) (xy 377.79199 -248.832857) (xy 377.784047 -248.885561) (xy 377.768337 -248.936491)
			(xy 377.745211 -248.984512) (xy 377.715187 -249.028549) (xy 377.678935 -249.06762) (xy 377.637264 -249.100851)
			(xy 377.591106 -249.1275) (xy 377.541492 -249.146972) (xy 377.48953 -249.158832) (xy 377.43638 -249.162816)
			(xy 377.38323 -249.158832) (xy 377.331268 -249.146972) (xy 377.281654 -249.1275) (xy 377.235496 -249.100851)
			(xy 377.193825 -249.06762) (xy 377.157573 -249.028549) (xy 377.127549 -248.984512) (xy 377.104423 -248.936491)
			(xy 377.088713 -248.885561) (xy 377.08077 -248.832857) (xy 376.852444 -248.832857) (xy 376.844501 -248.885561)
			(xy 376.828791 -248.936491) (xy 376.805665 -248.984512) (xy 376.775641 -249.028549) (xy 376.739389 -249.06762)
			(xy 376.697718 -249.100851) (xy 376.65156 -249.1275) (xy 376.601946 -249.146972) (xy 376.549984 -249.158832)
			(xy 376.496834 -249.162816) (xy 376.443684 -249.158832) (xy 376.391722 -249.146972) (xy 376.342108 -249.1275)
			(xy 376.29595 -249.100851) (xy 376.254279 -249.06762) (xy 376.218027 -249.028549) (xy 376.188003 -248.984512)
			(xy 376.164877 -248.936491) (xy 376.149167 -248.885561) (xy 376.141224 -248.832857) (xy 375.912644 -248.832857)
			(xy 375.904701 -248.885561) (xy 375.888991 -248.936491) (xy 375.865865 -248.984512) (xy 375.835841 -249.028549)
			(xy 375.799589 -249.06762) (xy 375.757918 -249.100851) (xy 375.71176 -249.1275) (xy 375.662146 -249.146972)
			(xy 375.610184 -249.158832) (xy 375.557034 -249.162816) (xy 375.503884 -249.158832) (xy 375.451922 -249.146972)
			(xy 375.402308 -249.1275) (xy 375.35615 -249.100851) (xy 375.314479 -249.06762) (xy 375.278227 -249.028549)
			(xy 375.248203 -248.984512) (xy 375.225077 -248.936491) (xy 375.209367 -248.885561) (xy 375.201424 -248.832857)
			(xy 374.972844 -248.832857) (xy 374.964901 -248.885561) (xy 374.949191 -248.936491) (xy 374.926065 -248.984512)
			(xy 374.896041 -249.028549) (xy 374.859789 -249.06762) (xy 374.818118 -249.100851) (xy 374.77196 -249.1275)
			(xy 374.722346 -249.146972) (xy 374.670384 -249.158832) (xy 374.617234 -249.162816) (xy 374.564084 -249.158832)
			(xy 374.512122 -249.146972) (xy 374.462508 -249.1275) (xy 374.41635 -249.100851) (xy 374.374679 -249.06762)
			(xy 374.338427 -249.028549) (xy 374.308403 -248.984512) (xy 374.285277 -248.936491) (xy 374.269567 -248.885561)
			(xy 374.261624 -248.832857) (xy 374.033044 -248.832857) (xy 374.025101 -248.885561) (xy 374.009391 -248.936491)
			(xy 373.986265 -248.984512) (xy 373.956241 -249.028549) (xy 373.919989 -249.06762) (xy 373.878318 -249.100851)
			(xy 373.83216 -249.1275) (xy 373.782546 -249.146972) (xy 373.730584 -249.158832) (xy 373.677434 -249.162816)
			(xy 373.624284 -249.158832) (xy 373.572322 -249.146972) (xy 373.522708 -249.1275) (xy 373.47655 -249.100851)
			(xy 373.434879 -249.06762) (xy 373.398627 -249.028549) (xy 373.368603 -248.984512) (xy 373.345477 -248.936491)
			(xy 373.329767 -248.885561) (xy 373.321824 -248.832857) (xy 373.093244 -248.832857) (xy 373.085301 -248.885561)
			(xy 373.069591 -248.936491) (xy 373.046465 -248.984512) (xy 373.016441 -249.028549) (xy 372.980189 -249.06762)
			(xy 372.938518 -249.100851) (xy 372.89236 -249.1275) (xy 372.842746 -249.146972) (xy 372.790784 -249.158832)
			(xy 372.737634 -249.162816) (xy 372.684484 -249.158832) (xy 372.632522 -249.146972) (xy 372.582908 -249.1275)
			(xy 372.53675 -249.100851) (xy 372.495079 -249.06762) (xy 372.458827 -249.028549) (xy 372.428803 -248.984512)
			(xy 372.405677 -248.936491) (xy 372.389967 -248.885561) (xy 372.382024 -248.832857) (xy 372.153444 -248.832857)
			(xy 372.145501 -248.885561) (xy 372.129791 -248.936491) (xy 372.106665 -248.984512) (xy 372.076641 -249.028549)
			(xy 372.040389 -249.06762) (xy 371.998718 -249.100851) (xy 371.95256 -249.1275) (xy 371.902946 -249.146972)
			(xy 371.850984 -249.158832) (xy 371.797834 -249.162816) (xy 371.744684 -249.158832) (xy 371.692722 -249.146972)
			(xy 371.643108 -249.1275) (xy 371.59695 -249.100851) (xy 371.555279 -249.06762) (xy 371.519027 -249.028549)
			(xy 371.489003 -248.984512) (xy 371.465877 -248.936491) (xy 371.450167 -248.885561) (xy 371.442224 -248.832857)
			(xy 371.21339 -248.832857) (xy 371.205447 -248.885561) (xy 371.189737 -248.936491) (xy 371.166611 -248.984512)
			(xy 371.136587 -249.028549) (xy 371.100335 -249.06762) (xy 371.058664 -249.100851) (xy 371.012506 -249.1275)
			(xy 370.962892 -249.146972) (xy 370.91093 -249.158832) (xy 370.85778 -249.162816) (xy 370.80463 -249.158832)
			(xy 370.752668 -249.146972) (xy 370.703054 -249.1275) (xy 370.656896 -249.100851) (xy 370.615225 -249.06762)
			(xy 370.578973 -249.028549) (xy 370.548949 -248.984512) (xy 370.525823 -248.936491) (xy 370.510113 -248.885561)
			(xy 370.50217 -248.832857) (xy 370.273844 -248.832857) (xy 370.265901 -248.885561) (xy 370.250191 -248.936491)
			(xy 370.227065 -248.984512) (xy 370.197041 -249.028549) (xy 370.160789 -249.06762) (xy 370.119118 -249.100851)
			(xy 370.07296 -249.1275) (xy 370.023346 -249.146972) (xy 369.971384 -249.158832) (xy 369.918234 -249.162816)
			(xy 369.865084 -249.158832) (xy 369.813122 -249.146972) (xy 369.763508 -249.1275) (xy 369.71735 -249.100851)
			(xy 369.675679 -249.06762) (xy 369.639427 -249.028549) (xy 369.609403 -248.984512) (xy 369.586277 -248.936491)
			(xy 369.570567 -248.885561) (xy 369.562624 -248.832857) (xy 369.155714 -248.832857) (xy 369.167557 -248.841996)
			(xy 369.204983 -248.881268) (xy 369.236021 -248.925762) (xy 369.259952 -248.974447) (xy 369.276224 -249.026199)
			(xy 369.284459 -249.079819) (xy 369.285012 -249.106944) (xy 369.285012 -249.107452) (xy 369.284911 -249.119043)
			(xy 369.283385 -249.142176) (xy 369.281964 -249.15368) (xy 369.280636 -249.167031) (xy 369.284217 -249.193612)
			(xy 369.294592 -249.218345) (xy 369.311047 -249.239526) (xy 369.332448 -249.255694) (xy 369.357318 -249.265735)
			(xy 369.383945 -249.268958) (xy 369.39728 -249.267472) (xy 369.409911 -249.265782) (xy 369.435336 -249.264002)
			(xy 369.44808 -249.263916) (xy 369.475158 -249.26442) (xy 369.528691 -249.272618) (xy 369.580365 -249.288827)
			(xy 369.628988 -249.312675) (xy 369.67344 -249.34361) (xy 369.712694 -249.38092) (xy 369.745846 -249.423744)
			(xy 369.772131 -249.471094) (xy 369.790943 -249.521878) (xy 369.801848 -249.574926) (xy 369.804594 -249.629012)
			(xy 369.802799 -249.646673) (xy 370.03227 -249.646673) (xy 370.03227 -249.593375) (xy 370.040213 -249.540671)
			(xy 370.055923 -249.489741) (xy 370.079049 -249.44172) (xy 370.109073 -249.397683) (xy 370.145325 -249.358612)
			(xy 370.186996 -249.325381) (xy 370.233154 -249.298732) (xy 370.282768 -249.27926) (xy 370.33473 -249.2674)
			(xy 370.38788 -249.263417) (xy 370.44103 -249.2674) (xy 370.492992 -249.27926) (xy 370.542606 -249.298732)
			(xy 370.588764 -249.325381) (xy 370.630435 -249.358612) (xy 370.666687 -249.397683) (xy 370.696711 -249.44172)
			(xy 370.719837 -249.489741) (xy 370.735547 -249.540671) (xy 370.74349 -249.593375) (xy 370.743988 -249.620024)
			(xy 370.74349 -249.646673) (xy 370.97207 -249.646673) (xy 370.97207 -249.593375) (xy 370.980013 -249.540671)
			(xy 370.995723 -249.489741) (xy 371.018849 -249.44172) (xy 371.048873 -249.397683) (xy 371.085125 -249.358612)
			(xy 371.126796 -249.325381) (xy 371.172954 -249.298732) (xy 371.222568 -249.27926) (xy 371.27453 -249.2674)
			(xy 371.32768 -249.263417) (xy 371.38083 -249.2674) (xy 371.432792 -249.27926) (xy 371.482406 -249.298732)
			(xy 371.528564 -249.325381) (xy 371.570235 -249.358612) (xy 371.606487 -249.397683) (xy 371.636511 -249.44172)
			(xy 371.659637 -249.489741) (xy 371.675347 -249.540671) (xy 371.68329 -249.593375) (xy 371.683788 -249.620024)
			(xy 371.68329 -249.646673) (xy 371.91187 -249.646673) (xy 371.91187 -249.593375) (xy 371.919813 -249.540671)
			(xy 371.935523 -249.489741) (xy 371.958649 -249.44172) (xy 371.988673 -249.397683) (xy 372.024925 -249.358612)
			(xy 372.066596 -249.325381) (xy 372.112754 -249.298732) (xy 372.162368 -249.27926) (xy 372.21433 -249.2674)
			(xy 372.26748 -249.263417) (xy 372.32063 -249.2674) (xy 372.372592 -249.27926) (xy 372.422206 -249.298732)
			(xy 372.468364 -249.325381) (xy 372.510035 -249.358612) (xy 372.546287 -249.397683) (xy 372.576311 -249.44172)
			(xy 372.599437 -249.489741) (xy 372.615147 -249.540671) (xy 372.62309 -249.593375) (xy 372.623588 -249.620024)
			(xy 372.62309 -249.646673) (xy 372.851924 -249.646673) (xy 372.851924 -249.593375) (xy 372.859867 -249.540671)
			(xy 372.875577 -249.489741) (xy 372.898703 -249.44172) (xy 372.928727 -249.397683) (xy 372.964979 -249.358612)
			(xy 373.00665 -249.325381) (xy 373.052808 -249.298732) (xy 373.102422 -249.27926) (xy 373.154384 -249.2674)
			(xy 373.207534 -249.263417) (xy 373.260684 -249.2674) (xy 373.312646 -249.27926) (xy 373.36226 -249.298732)
			(xy 373.408418 -249.325381) (xy 373.450089 -249.358612) (xy 373.486341 -249.397683) (xy 373.516365 -249.44172)
			(xy 373.539491 -249.489741) (xy 373.555201 -249.540671) (xy 373.563144 -249.593375) (xy 373.563642 -249.620024)
			(xy 373.563144 -249.646673) (xy 373.79147 -249.646673) (xy 373.79147 -249.593375) (xy 373.799413 -249.540671)
			(xy 373.815123 -249.489741) (xy 373.838249 -249.44172) (xy 373.868273 -249.397683) (xy 373.904525 -249.358612)
			(xy 373.946196 -249.325381) (xy 373.992354 -249.298732) (xy 374.041968 -249.27926) (xy 374.09393 -249.2674)
			(xy 374.14708 -249.263417) (xy 374.20023 -249.2674) (xy 374.252192 -249.27926) (xy 374.301806 -249.298732)
			(xy 374.347964 -249.325381) (xy 374.389635 -249.358612) (xy 374.425887 -249.397683) (xy 374.455911 -249.44172)
			(xy 374.479037 -249.489741) (xy 374.494747 -249.540671) (xy 374.50269 -249.593375) (xy 374.503188 -249.620024)
			(xy 374.50269 -249.646673) (xy 374.73127 -249.646673) (xy 374.73127 -249.593375) (xy 374.739213 -249.540671)
			(xy 374.754923 -249.489741) (xy 374.778049 -249.44172) (xy 374.808073 -249.397683) (xy 374.844325 -249.358612)
			(xy 374.885996 -249.325381) (xy 374.932154 -249.298732) (xy 374.981768 -249.27926) (xy 375.03373 -249.2674)
			(xy 375.08688 -249.263417) (xy 375.14003 -249.2674) (xy 375.191992 -249.27926) (xy 375.241606 -249.298732)
			(xy 375.287764 -249.325381) (xy 375.329435 -249.358612) (xy 375.365687 -249.397683) (xy 375.395711 -249.44172)
			(xy 375.418837 -249.489741) (xy 375.434547 -249.540671) (xy 375.44249 -249.593375) (xy 375.442988 -249.620024)
			(xy 375.44249 -249.646673) (xy 375.67107 -249.646673) (xy 375.67107 -249.593375) (xy 375.679013 -249.540671)
			(xy 375.694723 -249.489741) (xy 375.717849 -249.44172) (xy 375.747873 -249.397683) (xy 375.784125 -249.358612)
			(xy 375.825796 -249.325381) (xy 375.871954 -249.298732) (xy 375.921568 -249.27926) (xy 375.97353 -249.2674)
			(xy 376.02668 -249.263417) (xy 376.07983 -249.2674) (xy 376.131792 -249.27926) (xy 376.181406 -249.298732)
			(xy 376.227564 -249.325381) (xy 376.269235 -249.358612) (xy 376.305487 -249.397683) (xy 376.335511 -249.44172)
			(xy 376.358637 -249.489741) (xy 376.374347 -249.540671) (xy 376.38229 -249.593375) (xy 376.382788 -249.620024)
			(xy 376.38229 -249.646673) (xy 376.61087 -249.646673) (xy 376.61087 -249.593375) (xy 376.618813 -249.540671)
			(xy 376.634523 -249.489741) (xy 376.657649 -249.44172) (xy 376.687673 -249.397683) (xy 376.723925 -249.358612)
			(xy 376.765596 -249.325381) (xy 376.811754 -249.298732) (xy 376.861368 -249.27926) (xy 376.91333 -249.2674)
			(xy 376.96648 -249.263417) (xy 377.01963 -249.2674) (xy 377.071592 -249.27926) (xy 377.121206 -249.298732)
			(xy 377.167364 -249.325381) (xy 377.209035 -249.358612) (xy 377.245287 -249.397683) (xy 377.275311 -249.44172)
			(xy 377.298437 -249.489741) (xy 377.314147 -249.540671) (xy 377.32209 -249.593375) (xy 377.322588 -249.620024)
			(xy 377.32209 -249.646673) (xy 377.55067 -249.646673) (xy 377.55067 -249.593375) (xy 377.558613 -249.540671)
			(xy 377.574323 -249.489741) (xy 377.597449 -249.44172) (xy 377.627473 -249.397683) (xy 377.663725 -249.358612)
			(xy 377.705396 -249.325381) (xy 377.751554 -249.298732) (xy 377.801168 -249.27926) (xy 377.85313 -249.2674)
			(xy 377.90628 -249.263417) (xy 377.95943 -249.2674) (xy 378.011392 -249.27926) (xy 378.061006 -249.298732)
			(xy 378.107164 -249.325381) (xy 378.148835 -249.358612) (xy 378.185087 -249.397683) (xy 378.215111 -249.44172)
			(xy 378.238237 -249.489741) (xy 378.253947 -249.540671) (xy 378.26189 -249.593375) (xy 378.262388 -249.620024)
			(xy 378.26189 -249.646673) (xy 378.49047 -249.646673) (xy 378.49047 -249.593375) (xy 378.498413 -249.540671)
			(xy 378.514123 -249.489741) (xy 378.537249 -249.44172) (xy 378.567273 -249.397683) (xy 378.603525 -249.358612)
			(xy 378.645196 -249.325381) (xy 378.691354 -249.298732) (xy 378.740968 -249.27926) (xy 378.79293 -249.2674)
			(xy 378.84608 -249.263417) (xy 378.89923 -249.2674) (xy 378.951192 -249.27926) (xy 379.000806 -249.298732)
			(xy 379.046964 -249.325381) (xy 379.088635 -249.358612) (xy 379.124887 -249.397683) (xy 379.154911 -249.44172)
			(xy 379.178037 -249.489741) (xy 379.193747 -249.540671) (xy 379.20169 -249.593375) (xy 379.202188 -249.620024)
			(xy 379.20169 -249.646673) (xy 379.430524 -249.646673) (xy 379.430524 -249.593375) (xy 379.438467 -249.540671)
			(xy 379.454177 -249.489741) (xy 379.477303 -249.44172) (xy 379.507327 -249.397683) (xy 379.543579 -249.358612)
			(xy 379.58525 -249.325381) (xy 379.631408 -249.298732) (xy 379.681022 -249.27926) (xy 379.732984 -249.2674)
			(xy 379.786134 -249.263417) (xy 379.839284 -249.2674) (xy 379.891246 -249.27926) (xy 379.94086 -249.298732)
			(xy 379.987018 -249.325381) (xy 380.028689 -249.358612) (xy 380.064941 -249.397683) (xy 380.094965 -249.44172)
			(xy 380.118091 -249.489741) (xy 380.133801 -249.540671) (xy 380.141744 -249.593375) (xy 380.142242 -249.620024)
			(xy 380.141744 -249.646673) (xy 380.133801 -249.699377) (xy 380.118091 -249.750307) (xy 380.094965 -249.798328)
			(xy 380.064941 -249.842365) (xy 380.028689 -249.881436) (xy 379.987018 -249.914667) (xy 379.94086 -249.941316)
			(xy 379.891246 -249.960788) (xy 379.839284 -249.972648) (xy 379.786134 -249.976632) (xy 379.732984 -249.972648)
			(xy 379.681022 -249.960788) (xy 379.631408 -249.941316) (xy 379.58525 -249.914667) (xy 379.543579 -249.881436)
			(xy 379.507327 -249.842365) (xy 379.477303 -249.798328) (xy 379.454177 -249.750307) (xy 379.438467 -249.699377)
			(xy 379.430524 -249.646673) (xy 379.20169 -249.646673) (xy 379.193747 -249.699377) (xy 379.178037 -249.750307)
			(xy 379.154911 -249.798328) (xy 379.124887 -249.842365) (xy 379.088635 -249.881436) (xy 379.046964 -249.914667)
			(xy 379.000806 -249.941316) (xy 378.951192 -249.960788) (xy 378.89923 -249.972648) (xy 378.84608 -249.976632)
			(xy 378.79293 -249.972648) (xy 378.740968 -249.960788) (xy 378.691354 -249.941316) (xy 378.645196 -249.914667)
			(xy 378.603525 -249.881436) (xy 378.567273 -249.842365) (xy 378.537249 -249.798328) (xy 378.514123 -249.750307)
			(xy 378.498413 -249.699377) (xy 378.49047 -249.646673) (xy 378.26189 -249.646673) (xy 378.253947 -249.699377)
			(xy 378.238237 -249.750307) (xy 378.215111 -249.798328) (xy 378.185087 -249.842365) (xy 378.148835 -249.881436)
			(xy 378.107164 -249.914667) (xy 378.061006 -249.941316) (xy 378.011392 -249.960788) (xy 377.95943 -249.972648)
			(xy 377.90628 -249.976632) (xy 377.85313 -249.972648) (xy 377.801168 -249.960788) (xy 377.751554 -249.941316)
			(xy 377.705396 -249.914667) (xy 377.663725 -249.881436) (xy 377.627473 -249.842365) (xy 377.597449 -249.798328)
			(xy 377.574323 -249.750307) (xy 377.558613 -249.699377) (xy 377.55067 -249.646673) (xy 377.32209 -249.646673)
			(xy 377.314147 -249.699377) (xy 377.298437 -249.750307) (xy 377.275311 -249.798328) (xy 377.245287 -249.842365)
			(xy 377.209035 -249.881436) (xy 377.167364 -249.914667) (xy 377.121206 -249.941316) (xy 377.071592 -249.960788)
			(xy 377.01963 -249.972648) (xy 376.96648 -249.976632) (xy 376.91333 -249.972648) (xy 376.861368 -249.960788)
			(xy 376.811754 -249.941316) (xy 376.765596 -249.914667) (xy 376.723925 -249.881436) (xy 376.687673 -249.842365)
			(xy 376.657649 -249.798328) (xy 376.634523 -249.750307) (xy 376.618813 -249.699377) (xy 376.61087 -249.646673)
			(xy 376.38229 -249.646673) (xy 376.374347 -249.699377) (xy 376.358637 -249.750307) (xy 376.335511 -249.798328)
			(xy 376.305487 -249.842365) (xy 376.269235 -249.881436) (xy 376.227564 -249.914667) (xy 376.181406 -249.941316)
			(xy 376.131792 -249.960788) (xy 376.07983 -249.972648) (xy 376.02668 -249.976632) (xy 375.97353 -249.972648)
			(xy 375.921568 -249.960788) (xy 375.871954 -249.941316) (xy 375.825796 -249.914667) (xy 375.784125 -249.881436)
			(xy 375.747873 -249.842365) (xy 375.717849 -249.798328) (xy 375.694723 -249.750307) (xy 375.679013 -249.699377)
			(xy 375.67107 -249.646673) (xy 375.44249 -249.646673) (xy 375.434547 -249.699377) (xy 375.418837 -249.750307)
			(xy 375.395711 -249.798328) (xy 375.365687 -249.842365) (xy 375.329435 -249.881436) (xy 375.287764 -249.914667)
			(xy 375.241606 -249.941316) (xy 375.191992 -249.960788) (xy 375.14003 -249.972648) (xy 375.08688 -249.976632)
			(xy 375.03373 -249.972648) (xy 374.981768 -249.960788) (xy 374.932154 -249.941316) (xy 374.885996 -249.914667)
			(xy 374.844325 -249.881436) (xy 374.808073 -249.842365) (xy 374.778049 -249.798328) (xy 374.754923 -249.750307)
			(xy 374.739213 -249.699377) (xy 374.73127 -249.646673) (xy 374.50269 -249.646673) (xy 374.494747 -249.699377)
			(xy 374.479037 -249.750307) (xy 374.455911 -249.798328) (xy 374.425887 -249.842365) (xy 374.389635 -249.881436)
			(xy 374.347964 -249.914667) (xy 374.301806 -249.941316) (xy 374.252192 -249.960788) (xy 374.20023 -249.972648)
			(xy 374.14708 -249.976632) (xy 374.09393 -249.972648) (xy 374.041968 -249.960788) (xy 373.992354 -249.941316)
			(xy 373.946196 -249.914667) (xy 373.904525 -249.881436) (xy 373.868273 -249.842365) (xy 373.838249 -249.798328)
			(xy 373.815123 -249.750307) (xy 373.799413 -249.699377) (xy 373.79147 -249.646673) (xy 373.563144 -249.646673)
			(xy 373.555201 -249.699377) (xy 373.539491 -249.750307) (xy 373.516365 -249.798328) (xy 373.486341 -249.842365)
			(xy 373.450089 -249.881436) (xy 373.408418 -249.914667) (xy 373.36226 -249.941316) (xy 373.312646 -249.960788)
			(xy 373.260684 -249.972648) (xy 373.207534 -249.976632) (xy 373.154384 -249.972648) (xy 373.102422 -249.960788)
			(xy 373.052808 -249.941316) (xy 373.00665 -249.914667) (xy 372.964979 -249.881436) (xy 372.928727 -249.842365)
			(xy 372.898703 -249.798328) (xy 372.875577 -249.750307) (xy 372.859867 -249.699377) (xy 372.851924 -249.646673)
			(xy 372.62309 -249.646673) (xy 372.615147 -249.699377) (xy 372.599437 -249.750307) (xy 372.576311 -249.798328)
			(xy 372.546287 -249.842365) (xy 372.510035 -249.881436) (xy 372.468364 -249.914667) (xy 372.422206 -249.941316)
			(xy 372.372592 -249.960788) (xy 372.32063 -249.972648) (xy 372.26748 -249.976632) (xy 372.21433 -249.972648)
			(xy 372.162368 -249.960788) (xy 372.112754 -249.941316) (xy 372.066596 -249.914667) (xy 372.024925 -249.881436)
			(xy 371.988673 -249.842365) (xy 371.958649 -249.798328) (xy 371.935523 -249.750307) (xy 371.919813 -249.699377)
			(xy 371.91187 -249.646673) (xy 371.68329 -249.646673) (xy 371.675347 -249.699377) (xy 371.659637 -249.750307)
			(xy 371.636511 -249.798328) (xy 371.606487 -249.842365) (xy 371.570235 -249.881436) (xy 371.528564 -249.914667)
			(xy 371.482406 -249.941316) (xy 371.432792 -249.960788) (xy 371.38083 -249.972648) (xy 371.32768 -249.976632)
			(xy 371.27453 -249.972648) (xy 371.222568 -249.960788) (xy 371.172954 -249.941316) (xy 371.126796 -249.914667)
			(xy 371.085125 -249.881436) (xy 371.048873 -249.842365) (xy 371.018849 -249.798328) (xy 370.995723 -249.750307)
			(xy 370.980013 -249.699377) (xy 370.97207 -249.646673) (xy 370.74349 -249.646673) (xy 370.735547 -249.699377)
			(xy 370.719837 -249.750307) (xy 370.696711 -249.798328) (xy 370.666687 -249.842365) (xy 370.630435 -249.881436)
			(xy 370.588764 -249.914667) (xy 370.542606 -249.941316) (xy 370.492992 -249.960788) (xy 370.44103 -249.972648)
			(xy 370.38788 -249.976632) (xy 370.33473 -249.972648) (xy 370.282768 -249.960788) (xy 370.233154 -249.941316)
			(xy 370.186996 -249.914667) (xy 370.145325 -249.881436) (xy 370.109073 -249.842365) (xy 370.079049 -249.798328)
			(xy 370.055923 -249.750307) (xy 370.040213 -249.699377) (xy 370.03227 -249.646673) (xy 369.802799 -249.646673)
			(xy 369.799118 -249.682892) (xy 369.785547 -249.73532) (xy 369.764193 -249.785089) (xy 369.735549 -249.83105)
			(xy 369.700276 -249.872144) (xy 369.659186 -249.907423) (xy 369.613228 -249.936073) (xy 369.563462 -249.957433)
			(xy 369.511035 -249.971011) (xy 369.457157 -249.976493) (xy 369.403069 -249.973753) (xy 369.350021 -249.962855)
			(xy 369.299234 -249.94405) (xy 369.251881 -249.91777) (xy 369.209053 -249.884624) (xy 369.171738 -249.845374)
			(xy 369.140797 -249.800926) (xy 369.116944 -249.752306) (xy 369.100728 -249.700634) (xy 369.092523 -249.647102)
			(xy 369.091972 -249.620024) (xy 369.091972 -249.619516) (xy 369.092074 -249.607925) (xy 369.093602 -249.584793)
			(xy 369.09502 -249.573288) (xy 369.096344 -249.559941) (xy 369.092757 -249.533368) (xy 369.082379 -249.508645)
			(xy 369.065924 -249.487474) (xy 369.044527 -249.471315) (xy 369.019662 -249.46128) (xy 368.993043 -249.458063)
			(xy 368.979704 -249.459496) (xy 368.960908 -249.461528) (xy 368.951558 -249.46281) (xy 368.934663 -249.471178)
			(xy 368.921929 -249.485083) (xy 368.915077 -249.502648) (xy 368.91468 -249.512074) (xy 368.91468 -250.497848)
			(xy 368.959384 -250.503182) (xy 368.984961 -250.506764) (xy 369.034786 -250.520355) (xy 369.082125 -250.541003)
			(xy 369.125984 -250.568273) (xy 369.165442 -250.601594) (xy 369.199672 -250.640267) (xy 369.227955 -250.683479)
			(xy 369.249698 -250.730325) (xy 369.264444 -250.77982) (xy 369.271885 -250.830927) (xy 369.272312 -250.85675)
			(xy 369.271889 -250.881418) (xy 369.265072 -250.930281) (xy 369.251575 -250.977735) (xy 369.231656 -251.022872)
			(xy 369.205698 -251.064827) (xy 369.19027 -251.08408) (xy 369.18165 -251.095209) (xy 369.170316 -251.120966)
			(xy 369.166447 -251.148839) (xy 369.170337 -251.176709) (xy 369.181691 -251.202456) (xy 369.19027 -251.21362)
			(xy 369.205706 -251.232868) (xy 369.231676 -251.274818) (xy 369.251598 -251.319955) (xy 369.265088 -251.367413)
			(xy 369.271889 -251.416281) (xy 369.272312 -251.44095) (xy 369.271849 -251.466769) (xy 369.264388 -251.517866)
			(xy 369.249629 -251.56735) (xy 369.227882 -251.614186) (xy 369.199601 -251.657392) (xy 369.16538 -251.696062)
			(xy 369.125934 -251.729388) (xy 369.082092 -251.756671) (xy 369.03477 -251.77734) (xy 368.98496 -251.790961)
			(xy 368.959384 -251.794518) (xy 368.91468 -251.799852) (xy 368.91468 -252.250448) (xy 368.959384 -252.255782)
			(xy 368.984961 -252.259364) (xy 369.034786 -252.272955) (xy 369.082125 -252.293603) (xy 369.125984 -252.320873)
			(xy 369.165442 -252.354194) (xy 369.199672 -252.392867) (xy 369.227955 -252.436079) (xy 369.249698 -252.482925)
			(xy 369.264444 -252.53242) (xy 369.271885 -252.583527) (xy 369.272312 -252.60935) (xy 369.271889 -252.634018)
			(xy 369.265072 -252.682881) (xy 369.251575 -252.730335) (xy 369.231656 -252.775472) (xy 369.205698 -252.817427)
			(xy 369.19027 -252.83668) (xy 369.18165 -252.847809) (xy 369.170316 -252.873566) (xy 369.166447 -252.901439)
			(xy 369.170337 -252.929309) (xy 369.181691 -252.955056) (xy 369.19027 -252.96622) (xy 369.205706 -252.985468)
			(xy 369.231676 -253.027418) (xy 369.251598 -253.072555) (xy 369.265088 -253.120013) (xy 369.271889 -253.168881)
			(xy 369.272312 -253.19355) (xy 369.271849 -253.219369) (xy 369.264388 -253.270466) (xy 369.249629 -253.31995)
			(xy 369.227882 -253.366786) (xy 369.199601 -253.409992) (xy 369.16538 -253.448662) (xy 369.125934 -253.481988)
			(xy 369.082092 -253.509271) (xy 369.03477 -253.52994) (xy 368.98496 -253.543561) (xy 368.959384 -253.547118)
			(xy 368.91468 -253.552452) (xy 368.91468 -253.946385) (xy 369.672606 -253.946385) (xy 369.672606 -253.893087)
			(xy 369.680549 -253.840383) (xy 369.696259 -253.789453) (xy 369.719385 -253.741432) (xy 369.749409 -253.697395)
			(xy 369.785661 -253.658324) (xy 369.827332 -253.625093) (xy 369.87349 -253.598444) (xy 369.923104 -253.578972)
			(xy 369.975066 -253.567112) (xy 370.028216 -253.563129) (xy 370.081366 -253.567112) (xy 370.133328 -253.578972)
			(xy 370.182942 -253.598444) (xy 370.2291 -253.625093) (xy 370.270771 -253.658324) (xy 370.307023 -253.697395)
			(xy 370.337047 -253.741432) (xy 370.360173 -253.789453) (xy 370.375883 -253.840383) (xy 370.383826 -253.893087)
			(xy 370.384324 -253.919736) (xy 370.383826 -253.946385) (xy 370.612152 -253.946385) (xy 370.612152 -253.893087)
			(xy 370.620095 -253.840383) (xy 370.635805 -253.789453) (xy 370.658931 -253.741432) (xy 370.688955 -253.697395)
			(xy 370.725207 -253.658324) (xy 370.766878 -253.625093) (xy 370.813036 -253.598444) (xy 370.86265 -253.578972)
			(xy 370.914612 -253.567112) (xy 370.967762 -253.563129) (xy 371.020912 -253.567112) (xy 371.072874 -253.578972)
			(xy 371.122488 -253.598444) (xy 371.168646 -253.625093) (xy 371.210317 -253.658324) (xy 371.246569 -253.697395)
			(xy 371.276593 -253.741432) (xy 371.299719 -253.789453) (xy 371.315429 -253.840383) (xy 371.323372 -253.893087)
			(xy 371.32387 -253.919736) (xy 371.323372 -253.946385) (xy 371.552206 -253.946385) (xy 371.552206 -253.893087)
			(xy 371.560149 -253.840383) (xy 371.575859 -253.789453) (xy 371.598985 -253.741432) (xy 371.629009 -253.697395)
			(xy 371.665261 -253.658324) (xy 371.706932 -253.625093) (xy 371.75309 -253.598444) (xy 371.802704 -253.578972)
			(xy 371.854666 -253.567112) (xy 371.907816 -253.563129) (xy 371.960966 -253.567112) (xy 372.012928 -253.578972)
			(xy 372.062542 -253.598444) (xy 372.1087 -253.625093) (xy 372.150371 -253.658324) (xy 372.186623 -253.697395)
			(xy 372.216647 -253.741432) (xy 372.239773 -253.789453) (xy 372.255483 -253.840383) (xy 372.263426 -253.893087)
			(xy 372.263924 -253.919736) (xy 372.263426 -253.946385) (xy 372.492006 -253.946385) (xy 372.492006 -253.893087)
			(xy 372.499949 -253.840383) (xy 372.515659 -253.789453) (xy 372.538785 -253.741432) (xy 372.568809 -253.697395)
			(xy 372.605061 -253.658324) (xy 372.646732 -253.625093) (xy 372.69289 -253.598444) (xy 372.742504 -253.578972)
			(xy 372.794466 -253.567112) (xy 372.847616 -253.563129) (xy 372.900766 -253.567112) (xy 372.952728 -253.578972)
			(xy 373.002342 -253.598444) (xy 373.0485 -253.625093) (xy 373.090171 -253.658324) (xy 373.126423 -253.697395)
			(xy 373.156447 -253.741432) (xy 373.179573 -253.789453) (xy 373.195283 -253.840383) (xy 373.203226 -253.893087)
			(xy 373.203724 -253.919736) (xy 373.203226 -253.946385) (xy 373.431806 -253.946385) (xy 373.431806 -253.893087)
			(xy 373.439749 -253.840383) (xy 373.455459 -253.789453) (xy 373.478585 -253.741432) (xy 373.508609 -253.697395)
			(xy 373.544861 -253.658324) (xy 373.586532 -253.625093) (xy 373.63269 -253.598444) (xy 373.682304 -253.578972)
			(xy 373.734266 -253.567112) (xy 373.787416 -253.563129) (xy 373.840566 -253.567112) (xy 373.892528 -253.578972)
			(xy 373.942142 -253.598444) (xy 373.9883 -253.625093) (xy 374.029971 -253.658324) (xy 374.066223 -253.697395)
			(xy 374.096247 -253.741432) (xy 374.119373 -253.789453) (xy 374.135083 -253.840383) (xy 374.143026 -253.893087)
			(xy 374.143524 -253.919736) (xy 374.143026 -253.946385) (xy 374.371606 -253.946385) (xy 374.371606 -253.893087)
			(xy 374.379549 -253.840383) (xy 374.395259 -253.789453) (xy 374.418385 -253.741432) (xy 374.448409 -253.697395)
			(xy 374.484661 -253.658324) (xy 374.526332 -253.625093) (xy 374.57249 -253.598444) (xy 374.622104 -253.578972)
			(xy 374.674066 -253.567112) (xy 374.727216 -253.563129) (xy 374.780366 -253.567112) (xy 374.832328 -253.578972)
			(xy 374.881942 -253.598444) (xy 374.9281 -253.625093) (xy 374.969771 -253.658324) (xy 375.006023 -253.697395)
			(xy 375.036047 -253.741432) (xy 375.059173 -253.789453) (xy 375.074883 -253.840383) (xy 375.082826 -253.893087)
			(xy 375.083324 -253.919736) (xy 375.082826 -253.946385) (xy 375.311406 -253.946385) (xy 375.311406 -253.893087)
			(xy 375.319349 -253.840383) (xy 375.335059 -253.789453) (xy 375.358185 -253.741432) (xy 375.388209 -253.697395)
			(xy 375.424461 -253.658324) (xy 375.466132 -253.625093) (xy 375.51229 -253.598444) (xy 375.561904 -253.578972)
			(xy 375.613866 -253.567112) (xy 375.667016 -253.563129) (xy 375.720166 -253.567112) (xy 375.772128 -253.578972)
			(xy 375.821742 -253.598444) (xy 375.8679 -253.625093) (xy 375.909571 -253.658324) (xy 375.945823 -253.697395)
			(xy 375.975847 -253.741432) (xy 375.998973 -253.789453) (xy 376.014683 -253.840383) (xy 376.022626 -253.893087)
			(xy 376.023124 -253.919736) (xy 376.022626 -253.946385) (xy 376.250952 -253.946385) (xy 376.250952 -253.893087)
			(xy 376.258895 -253.840383) (xy 376.274605 -253.789453) (xy 376.297731 -253.741432) (xy 376.327755 -253.697395)
			(xy 376.364007 -253.658324) (xy 376.405678 -253.625093) (xy 376.451836 -253.598444) (xy 376.50145 -253.578972)
			(xy 376.553412 -253.567112) (xy 376.606562 -253.563129) (xy 376.659712 -253.567112) (xy 376.711674 -253.578972)
			(xy 376.761288 -253.598444) (xy 376.807446 -253.625093) (xy 376.849117 -253.658324) (xy 376.885369 -253.697395)
			(xy 376.915393 -253.741432) (xy 376.938519 -253.789453) (xy 376.954229 -253.840383) (xy 376.962172 -253.893087)
			(xy 376.96267 -253.919736) (xy 376.962172 -253.946385) (xy 377.190752 -253.946385) (xy 377.190752 -253.893087)
			(xy 377.198695 -253.840383) (xy 377.214405 -253.789453) (xy 377.237531 -253.741432) (xy 377.267555 -253.697395)
			(xy 377.303807 -253.658324) (xy 377.345478 -253.625093) (xy 377.391636 -253.598444) (xy 377.44125 -253.578972)
			(xy 377.493212 -253.567112) (xy 377.546362 -253.563129) (xy 377.599512 -253.567112) (xy 377.651474 -253.578972)
			(xy 377.701088 -253.598444) (xy 377.747246 -253.625093) (xy 377.788917 -253.658324) (xy 377.825169 -253.697395)
			(xy 377.855193 -253.741432) (xy 377.878319 -253.789453) (xy 377.894029 -253.840383) (xy 377.901972 -253.893087)
			(xy 377.90247 -253.919736) (xy 377.901972 -253.946385) (xy 378.130806 -253.946385) (xy 378.130806 -253.893087)
			(xy 378.138749 -253.840383) (xy 378.154459 -253.789453) (xy 378.177585 -253.741432) (xy 378.207609 -253.697395)
			(xy 378.243861 -253.658324) (xy 378.285532 -253.625093) (xy 378.33169 -253.598444) (xy 378.381304 -253.578972)
			(xy 378.433266 -253.567112) (xy 378.486416 -253.563129) (xy 378.539566 -253.567112) (xy 378.591528 -253.578972)
			(xy 378.641142 -253.598444) (xy 378.6873 -253.625093) (xy 378.728971 -253.658324) (xy 378.765223 -253.697395)
			(xy 378.795247 -253.741432) (xy 378.818373 -253.789453) (xy 378.834083 -253.840383) (xy 378.842026 -253.893087)
			(xy 378.842524 -253.919736) (xy 378.842026 -253.946385) (xy 379.070352 -253.946385) (xy 379.070352 -253.893087)
			(xy 379.078295 -253.840383) (xy 379.094005 -253.789453) (xy 379.117131 -253.741432) (xy 379.147155 -253.697395)
			(xy 379.183407 -253.658324) (xy 379.225078 -253.625093) (xy 379.271236 -253.598444) (xy 379.32085 -253.578972)
			(xy 379.372812 -253.567112) (xy 379.425962 -253.563129) (xy 379.479112 -253.567112) (xy 379.531074 -253.578972)
			(xy 379.580688 -253.598444) (xy 379.626846 -253.625093) (xy 379.668517 -253.658324) (xy 379.704769 -253.697395)
			(xy 379.734793 -253.741432) (xy 379.757919 -253.789453) (xy 379.773629 -253.840383) (xy 379.781572 -253.893087)
			(xy 379.78207 -253.919736) (xy 379.781572 -253.946385) (xy 380.010152 -253.946385) (xy 380.010152 -253.893087)
			(xy 380.018095 -253.840383) (xy 380.033805 -253.789453) (xy 380.056931 -253.741432) (xy 380.086955 -253.697395)
			(xy 380.123207 -253.658324) (xy 380.164878 -253.625093) (xy 380.211036 -253.598444) (xy 380.26065 -253.578972)
			(xy 380.312612 -253.567112) (xy 380.365762 -253.563129) (xy 380.418912 -253.567112) (xy 380.470874 -253.578972)
			(xy 380.520488 -253.598444) (xy 380.566646 -253.625093) (xy 380.608317 -253.658324) (xy 380.644569 -253.697395)
			(xy 380.674593 -253.741432) (xy 380.697719 -253.789453) (xy 380.713429 -253.840383) (xy 380.721372 -253.893087)
			(xy 380.72187 -253.919736) (xy 380.721372 -253.946385) (xy 380.950206 -253.946385) (xy 380.950206 -253.893087)
			(xy 380.958149 -253.840383) (xy 380.973859 -253.789453) (xy 380.996985 -253.741432) (xy 381.027009 -253.697395)
			(xy 381.063261 -253.658324) (xy 381.104932 -253.625093) (xy 381.15109 -253.598444) (xy 381.200704 -253.578972)
			(xy 381.252666 -253.567112) (xy 381.305816 -253.563129) (xy 381.358966 -253.567112) (xy 381.410928 -253.578972)
			(xy 381.460542 -253.598444) (xy 381.5067 -253.625093) (xy 381.548371 -253.658324) (xy 381.584623 -253.697395)
			(xy 381.614647 -253.741432) (xy 381.637773 -253.789453) (xy 381.653483 -253.840383) (xy 381.661426 -253.893087)
			(xy 381.661924 -253.919736) (xy 381.661426 -253.946385) (xy 381.653483 -253.999089) (xy 381.637773 -254.050019)
			(xy 381.614647 -254.09804) (xy 381.584623 -254.142077) (xy 381.548371 -254.181148) (xy 381.5067 -254.214379)
			(xy 381.460542 -254.241028) (xy 381.410928 -254.2605) (xy 381.358966 -254.27236) (xy 381.305816 -254.276344)
			(xy 381.252666 -254.27236) (xy 381.200704 -254.2605) (xy 381.15109 -254.241028) (xy 381.104932 -254.214379)
			(xy 381.063261 -254.181148) (xy 381.027009 -254.142077) (xy 380.996985 -254.09804) (xy 380.973859 -254.050019)
			(xy 380.958149 -253.999089) (xy 380.950206 -253.946385) (xy 380.721372 -253.946385) (xy 380.713429 -253.999089)
			(xy 380.697719 -254.050019) (xy 380.674593 -254.09804) (xy 380.644569 -254.142077) (xy 380.608317 -254.181148)
			(xy 380.566646 -254.214379) (xy 380.520488 -254.241028) (xy 380.470874 -254.2605) (xy 380.418912 -254.27236)
			(xy 380.365762 -254.276344) (xy 380.312612 -254.27236) (xy 380.26065 -254.2605) (xy 380.211036 -254.241028)
			(xy 380.164878 -254.214379) (xy 380.123207 -254.181148) (xy 380.086955 -254.142077) (xy 380.056931 -254.09804)
			(xy 380.033805 -254.050019) (xy 380.018095 -253.999089) (xy 380.010152 -253.946385) (xy 379.781572 -253.946385)
			(xy 379.773629 -253.999089) (xy 379.757919 -254.050019) (xy 379.734793 -254.09804) (xy 379.704769 -254.142077)
			(xy 379.668517 -254.181148) (xy 379.626846 -254.214379) (xy 379.580688 -254.241028) (xy 379.531074 -254.2605)
			(xy 379.479112 -254.27236) (xy 379.425962 -254.276344) (xy 379.372812 -254.27236) (xy 379.32085 -254.2605)
			(xy 379.271236 -254.241028) (xy 379.225078 -254.214379) (xy 379.183407 -254.181148) (xy 379.147155 -254.142077)
			(xy 379.117131 -254.09804) (xy 379.094005 -254.050019) (xy 379.078295 -253.999089) (xy 379.070352 -253.946385)
			(xy 378.842026 -253.946385) (xy 378.834083 -253.999089) (xy 378.818373 -254.050019) (xy 378.795247 -254.09804)
			(xy 378.765223 -254.142077) (xy 378.728971 -254.181148) (xy 378.6873 -254.214379) (xy 378.641142 -254.241028)
			(xy 378.591528 -254.2605) (xy 378.539566 -254.27236) (xy 378.486416 -254.276344) (xy 378.433266 -254.27236)
			(xy 378.381304 -254.2605) (xy 378.33169 -254.241028) (xy 378.285532 -254.214379) (xy 378.243861 -254.181148)
			(xy 378.207609 -254.142077) (xy 378.177585 -254.09804) (xy 378.154459 -254.050019) (xy 378.138749 -253.999089)
			(xy 378.130806 -253.946385) (xy 377.901972 -253.946385) (xy 377.894029 -253.999089) (xy 377.878319 -254.050019)
			(xy 377.855193 -254.09804) (xy 377.825169 -254.142077) (xy 377.788917 -254.181148) (xy 377.747246 -254.214379)
			(xy 377.701088 -254.241028) (xy 377.651474 -254.2605) (xy 377.599512 -254.27236) (xy 377.546362 -254.276344)
			(xy 377.493212 -254.27236) (xy 377.44125 -254.2605) (xy 377.391636 -254.241028) (xy 377.345478 -254.214379)
			(xy 377.303807 -254.181148) (xy 377.267555 -254.142077) (xy 377.237531 -254.09804) (xy 377.214405 -254.050019)
			(xy 377.198695 -253.999089) (xy 377.190752 -253.946385) (xy 376.962172 -253.946385) (xy 376.954229 -253.999089)
			(xy 376.938519 -254.050019) (xy 376.915393 -254.09804) (xy 376.885369 -254.142077) (xy 376.849117 -254.181148)
			(xy 376.807446 -254.214379) (xy 376.761288 -254.241028) (xy 376.711674 -254.2605) (xy 376.659712 -254.27236)
			(xy 376.606562 -254.276344) (xy 376.553412 -254.27236) (xy 376.50145 -254.2605) (xy 376.451836 -254.241028)
			(xy 376.405678 -254.214379) (xy 376.364007 -254.181148) (xy 376.327755 -254.142077) (xy 376.297731 -254.09804)
			(xy 376.274605 -254.050019) (xy 376.258895 -253.999089) (xy 376.250952 -253.946385) (xy 376.022626 -253.946385)
			(xy 376.014683 -253.999089) (xy 375.998973 -254.050019) (xy 375.975847 -254.09804) (xy 375.945823 -254.142077)
			(xy 375.909571 -254.181148) (xy 375.8679 -254.214379) (xy 375.821742 -254.241028) (xy 375.772128 -254.2605)
			(xy 375.720166 -254.27236) (xy 375.667016 -254.276344) (xy 375.613866 -254.27236) (xy 375.561904 -254.2605)
			(xy 375.51229 -254.241028) (xy 375.466132 -254.214379) (xy 375.424461 -254.181148) (xy 375.388209 -254.142077)
			(xy 375.358185 -254.09804) (xy 375.335059 -254.050019) (xy 375.319349 -253.999089) (xy 375.311406 -253.946385)
			(xy 375.082826 -253.946385) (xy 375.074883 -253.999089) (xy 375.059173 -254.050019) (xy 375.036047 -254.09804)
			(xy 375.006023 -254.142077) (xy 374.969771 -254.181148) (xy 374.9281 -254.214379) (xy 374.881942 -254.241028)
			(xy 374.832328 -254.2605) (xy 374.780366 -254.27236) (xy 374.727216 -254.276344) (xy 374.674066 -254.27236)
			(xy 374.622104 -254.2605) (xy 374.57249 -254.241028) (xy 374.526332 -254.214379) (xy 374.484661 -254.181148)
			(xy 374.448409 -254.142077) (xy 374.418385 -254.09804) (xy 374.395259 -254.050019) (xy 374.379549 -253.999089)
			(xy 374.371606 -253.946385) (xy 374.143026 -253.946385) (xy 374.135083 -253.999089) (xy 374.119373 -254.050019)
			(xy 374.096247 -254.09804) (xy 374.066223 -254.142077) (xy 374.029971 -254.181148) (xy 373.9883 -254.214379)
			(xy 373.942142 -254.241028) (xy 373.892528 -254.2605) (xy 373.840566 -254.27236) (xy 373.787416 -254.276344)
			(xy 373.734266 -254.27236) (xy 373.682304 -254.2605) (xy 373.63269 -254.241028) (xy 373.586532 -254.214379)
			(xy 373.544861 -254.181148) (xy 373.508609 -254.142077) (xy 373.478585 -254.09804) (xy 373.455459 -254.050019)
			(xy 373.439749 -253.999089) (xy 373.431806 -253.946385) (xy 373.203226 -253.946385) (xy 373.195283 -253.999089)
			(xy 373.179573 -254.050019) (xy 373.156447 -254.09804) (xy 373.126423 -254.142077) (xy 373.090171 -254.181148)
			(xy 373.0485 -254.214379) (xy 373.002342 -254.241028) (xy 372.952728 -254.2605) (xy 372.900766 -254.27236)
			(xy 372.847616 -254.276344) (xy 372.794466 -254.27236) (xy 372.742504 -254.2605) (xy 372.69289 -254.241028)
			(xy 372.646732 -254.214379) (xy 372.605061 -254.181148) (xy 372.568809 -254.142077) (xy 372.538785 -254.09804)
			(xy 372.515659 -254.050019) (xy 372.499949 -253.999089) (xy 372.492006 -253.946385) (xy 372.263426 -253.946385)
			(xy 372.255483 -253.999089) (xy 372.239773 -254.050019) (xy 372.216647 -254.09804) (xy 372.186623 -254.142077)
			(xy 372.150371 -254.181148) (xy 372.1087 -254.214379) (xy 372.062542 -254.241028) (xy 372.012928 -254.2605)
			(xy 371.960966 -254.27236) (xy 371.907816 -254.276344) (xy 371.854666 -254.27236) (xy 371.802704 -254.2605)
			(xy 371.75309 -254.241028) (xy 371.706932 -254.214379) (xy 371.665261 -254.181148) (xy 371.629009 -254.142077)
			(xy 371.598985 -254.09804) (xy 371.575859 -254.050019) (xy 371.560149 -253.999089) (xy 371.552206 -253.946385)
			(xy 371.323372 -253.946385) (xy 371.315429 -253.999089) (xy 371.299719 -254.050019) (xy 371.276593 -254.09804)
			(xy 371.246569 -254.142077) (xy 371.210317 -254.181148) (xy 371.168646 -254.214379) (xy 371.122488 -254.241028)
			(xy 371.072874 -254.2605) (xy 371.020912 -254.27236) (xy 370.967762 -254.276344) (xy 370.914612 -254.27236)
			(xy 370.86265 -254.2605) (xy 370.813036 -254.241028) (xy 370.766878 -254.214379) (xy 370.725207 -254.181148)
			(xy 370.688955 -254.142077) (xy 370.658931 -254.09804) (xy 370.635805 -254.050019) (xy 370.620095 -253.999089)
			(xy 370.612152 -253.946385) (xy 370.383826 -253.946385) (xy 370.375883 -253.999089) (xy 370.360173 -254.050019)
			(xy 370.337047 -254.09804) (xy 370.307023 -254.142077) (xy 370.270771 -254.181148) (xy 370.2291 -254.214379)
			(xy 370.182942 -254.241028) (xy 370.133328 -254.2605) (xy 370.081366 -254.27236) (xy 370.028216 -254.276344)
			(xy 369.975066 -254.27236) (xy 369.923104 -254.2605) (xy 369.87349 -254.241028) (xy 369.827332 -254.214379)
			(xy 369.785661 -254.181148) (xy 369.749409 -254.142077) (xy 369.719385 -254.09804) (xy 369.696259 -254.050019)
			(xy 369.680549 -253.999089) (xy 369.672606 -253.946385) (xy 368.91468 -253.946385) (xy 368.91468 -254.587248)
			(xy 368.959384 -254.592582) (xy 368.982309 -254.595754) (xy 369.027134 -254.607273) (xy 369.070085 -254.624509)
			(xy 369.090448 -254.635508) (xy 369.102968 -254.642027) (xy 369.130409 -254.648596) (xy 369.158599 -254.647393)
			(xy 369.185381 -254.638511) (xy 369.208703 -254.622629) (xy 369.226779 -254.600964) (xy 369.232942 -254.588264)
			(xy 369.243802 -254.565056) (xy 369.271198 -254.521757) (xy 369.304516 -254.482831) (xy 369.343069 -254.44908)
			(xy 369.38606 -254.421203) (xy 369.432602 -254.399774) (xy 369.481734 -254.385235) (xy 369.532443 -254.377887)
			(xy 369.558062 -254.377444) (xy 369.584719 -254.377915) (xy 369.637437 -254.385855) (xy 369.688383 -254.401565)
			(xy 369.736418 -254.424693) (xy 369.780469 -254.454723) (xy 369.819553 -254.490983) (xy 369.852795 -254.532663)
			(xy 369.879453 -254.578833) (xy 369.898932 -254.62846) (xy 369.910796 -254.680436) (xy 369.91478 -254.7336)
			(xy 369.912787 -254.760201) (xy 370.142252 -254.760201) (xy 370.142252 -254.706903) (xy 370.150195 -254.654199)
			(xy 370.165905 -254.603269) (xy 370.189031 -254.555248) (xy 370.219055 -254.511211) (xy 370.255307 -254.47214)
			(xy 370.296978 -254.438909) (xy 370.343136 -254.41226) (xy 370.39275 -254.392788) (xy 370.444712 -254.380928)
			(xy 370.497862 -254.376945) (xy 370.551012 -254.380928) (xy 370.602974 -254.392788) (xy 370.652588 -254.41226)
			(xy 370.698746 -254.438909) (xy 370.740417 -254.47214) (xy 370.776669 -254.511211) (xy 370.806693 -254.555248)
			(xy 370.829819 -254.603269) (xy 370.845529 -254.654199) (xy 370.853472 -254.706903) (xy 370.85397 -254.733552)
			(xy 370.853472 -254.760201) (xy 371.082052 -254.760201) (xy 371.082052 -254.706903) (xy 371.089995 -254.654199)
			(xy 371.105705 -254.603269) (xy 371.128831 -254.555248) (xy 371.158855 -254.511211) (xy 371.195107 -254.47214)
			(xy 371.236778 -254.438909) (xy 371.282936 -254.41226) (xy 371.33255 -254.392788) (xy 371.384512 -254.380928)
			(xy 371.437662 -254.376945) (xy 371.490812 -254.380928) (xy 371.542774 -254.392788) (xy 371.592388 -254.41226)
			(xy 371.638546 -254.438909) (xy 371.680217 -254.47214) (xy 371.716469 -254.511211) (xy 371.746493 -254.555248)
			(xy 371.769619 -254.603269) (xy 371.785329 -254.654199) (xy 371.793272 -254.706903) (xy 371.79377 -254.733552)
			(xy 371.793272 -254.760201) (xy 372.022106 -254.760201) (xy 372.022106 -254.706903) (xy 372.030049 -254.654199)
			(xy 372.045759 -254.603269) (xy 372.068885 -254.555248) (xy 372.098909 -254.511211) (xy 372.135161 -254.47214)
			(xy 372.176832 -254.438909) (xy 372.22299 -254.41226) (xy 372.272604 -254.392788) (xy 372.324566 -254.380928)
			(xy 372.377716 -254.376945) (xy 372.430866 -254.380928) (xy 372.482828 -254.392788) (xy 372.532442 -254.41226)
			(xy 372.5786 -254.438909) (xy 372.620271 -254.47214) (xy 372.656523 -254.511211) (xy 372.686547 -254.555248)
			(xy 372.709673 -254.603269) (xy 372.725383 -254.654199) (xy 372.733326 -254.706903) (xy 372.733824 -254.733552)
			(xy 372.733326 -254.760201) (xy 372.961652 -254.760201) (xy 372.961652 -254.706903) (xy 372.969595 -254.654199)
			(xy 372.985305 -254.603269) (xy 373.008431 -254.555248) (xy 373.038455 -254.511211) (xy 373.074707 -254.47214)
			(xy 373.116378 -254.438909) (xy 373.162536 -254.41226) (xy 373.21215 -254.392788) (xy 373.264112 -254.380928)
			(xy 373.317262 -254.376945) (xy 373.370412 -254.380928) (xy 373.422374 -254.392788) (xy 373.471988 -254.41226)
			(xy 373.518146 -254.438909) (xy 373.559817 -254.47214) (xy 373.596069 -254.511211) (xy 373.626093 -254.555248)
			(xy 373.649219 -254.603269) (xy 373.664929 -254.654199) (xy 373.672872 -254.706903) (xy 373.67337 -254.733552)
			(xy 373.672872 -254.760201) (xy 373.901706 -254.760201) (xy 373.901706 -254.706903) (xy 373.909649 -254.654199)
			(xy 373.925359 -254.603269) (xy 373.948485 -254.555248) (xy 373.978509 -254.511211) (xy 374.014761 -254.47214)
			(xy 374.056432 -254.438909) (xy 374.10259 -254.41226) (xy 374.152204 -254.392788) (xy 374.204166 -254.380928)
			(xy 374.257316 -254.376945) (xy 374.310466 -254.380928) (xy 374.362428 -254.392788) (xy 374.412042 -254.41226)
			(xy 374.4582 -254.438909) (xy 374.499871 -254.47214) (xy 374.536123 -254.511211) (xy 374.566147 -254.555248)
			(xy 374.589273 -254.603269) (xy 374.604983 -254.654199) (xy 374.612926 -254.706903) (xy 374.613424 -254.733552)
			(xy 374.612926 -254.760201) (xy 374.841252 -254.760201) (xy 374.841252 -254.706903) (xy 374.849195 -254.654199)
			(xy 374.864905 -254.603269) (xy 374.888031 -254.555248) (xy 374.918055 -254.511211) (xy 374.954307 -254.47214)
			(xy 374.995978 -254.438909) (xy 375.042136 -254.41226) (xy 375.09175 -254.392788) (xy 375.143712 -254.380928)
			(xy 375.196862 -254.376945) (xy 375.250012 -254.380928) (xy 375.301974 -254.392788) (xy 375.351588 -254.41226)
			(xy 375.397746 -254.438909) (xy 375.439417 -254.47214) (xy 375.475669 -254.511211) (xy 375.505693 -254.555248)
			(xy 375.528819 -254.603269) (xy 375.544529 -254.654199) (xy 375.552472 -254.706903) (xy 375.55297 -254.733552)
			(xy 375.552472 -254.760201) (xy 375.781052 -254.760201) (xy 375.781052 -254.706903) (xy 375.788995 -254.654199)
			(xy 375.804705 -254.603269) (xy 375.827831 -254.555248) (xy 375.857855 -254.511211) (xy 375.894107 -254.47214)
			(xy 375.935778 -254.438909) (xy 375.981936 -254.41226) (xy 376.03155 -254.392788) (xy 376.083512 -254.380928)
			(xy 376.136662 -254.376945) (xy 376.189812 -254.380928) (xy 376.241774 -254.392788) (xy 376.291388 -254.41226)
			(xy 376.337546 -254.438909) (xy 376.379217 -254.47214) (xy 376.415469 -254.511211) (xy 376.445493 -254.555248)
			(xy 376.468619 -254.603269) (xy 376.484329 -254.654199) (xy 376.492272 -254.706903) (xy 376.49277 -254.733552)
			(xy 376.492272 -254.760201) (xy 376.720852 -254.760201) (xy 376.720852 -254.706903) (xy 376.728795 -254.654199)
			(xy 376.744505 -254.603269) (xy 376.767631 -254.555248) (xy 376.797655 -254.511211) (xy 376.833907 -254.47214)
			(xy 376.875578 -254.438909) (xy 376.921736 -254.41226) (xy 376.97135 -254.392788) (xy 377.023312 -254.380928)
			(xy 377.076462 -254.376945) (xy 377.129612 -254.380928) (xy 377.181574 -254.392788) (xy 377.231188 -254.41226)
			(xy 377.277346 -254.438909) (xy 377.319017 -254.47214) (xy 377.355269 -254.511211) (xy 377.385293 -254.555248)
			(xy 377.408419 -254.603269) (xy 377.424129 -254.654199) (xy 377.432072 -254.706903) (xy 377.43257 -254.733552)
			(xy 377.432072 -254.760201) (xy 377.660652 -254.760201) (xy 377.660652 -254.706903) (xy 377.668595 -254.654199)
			(xy 377.684305 -254.603269) (xy 377.707431 -254.555248) (xy 377.737455 -254.511211) (xy 377.773707 -254.47214)
			(xy 377.815378 -254.438909) (xy 377.861536 -254.41226) (xy 377.91115 -254.392788) (xy 377.963112 -254.380928)
			(xy 378.016262 -254.376945) (xy 378.069412 -254.380928) (xy 378.121374 -254.392788) (xy 378.170988 -254.41226)
			(xy 378.217146 -254.438909) (xy 378.258817 -254.47214) (xy 378.295069 -254.511211) (xy 378.325093 -254.555248)
			(xy 378.348219 -254.603269) (xy 378.363929 -254.654199) (xy 378.371872 -254.706903) (xy 378.37237 -254.733552)
			(xy 378.371872 -254.760201) (xy 378.600452 -254.760201) (xy 378.600452 -254.706903) (xy 378.608395 -254.654199)
			(xy 378.624105 -254.603269) (xy 378.647231 -254.555248) (xy 378.677255 -254.511211) (xy 378.713507 -254.47214)
			(xy 378.755178 -254.438909) (xy 378.801336 -254.41226) (xy 378.85095 -254.392788) (xy 378.902912 -254.380928)
			(xy 378.956062 -254.376945) (xy 379.009212 -254.380928) (xy 379.061174 -254.392788) (xy 379.110788 -254.41226)
			(xy 379.156946 -254.438909) (xy 379.198617 -254.47214) (xy 379.234869 -254.511211) (xy 379.264893 -254.555248)
			(xy 379.288019 -254.603269) (xy 379.303729 -254.654199) (xy 379.311672 -254.706903) (xy 379.31217 -254.733552)
			(xy 379.311672 -254.760201) (xy 379.54076 -254.760201) (xy 379.54076 -254.706903) (xy 379.548703 -254.654199)
			(xy 379.564413 -254.603269) (xy 379.587539 -254.555248) (xy 379.617563 -254.511211) (xy 379.653815 -254.47214)
			(xy 379.695486 -254.438909) (xy 379.741644 -254.41226) (xy 379.791258 -254.392788) (xy 379.84322 -254.380928)
			(xy 379.89637 -254.376945) (xy 379.94952 -254.380928) (xy 380.001482 -254.392788) (xy 380.051096 -254.41226)
			(xy 380.097254 -254.438909) (xy 380.138925 -254.47214) (xy 380.175177 -254.511211) (xy 380.205201 -254.555248)
			(xy 380.228327 -254.603269) (xy 380.244037 -254.654199) (xy 380.25198 -254.706903) (xy 380.252478 -254.733552)
			(xy 380.25198 -254.760201) (xy 380.480306 -254.760201) (xy 380.480306 -254.706903) (xy 380.488249 -254.654199)
			(xy 380.503959 -254.603269) (xy 380.527085 -254.555248) (xy 380.557109 -254.511211) (xy 380.593361 -254.47214)
			(xy 380.635032 -254.438909) (xy 380.68119 -254.41226) (xy 380.730804 -254.392788) (xy 380.782766 -254.380928)
			(xy 380.835916 -254.376945) (xy 380.889066 -254.380928) (xy 380.941028 -254.392788) (xy 380.990642 -254.41226)
			(xy 381.0368 -254.438909) (xy 381.078471 -254.47214) (xy 381.114723 -254.511211) (xy 381.144747 -254.555248)
			(xy 381.167873 -254.603269) (xy 381.183583 -254.654199) (xy 381.191526 -254.706903) (xy 381.192024 -254.733552)
			(xy 381.191526 -254.760201) (xy 381.183583 -254.812905) (xy 381.167873 -254.863835) (xy 381.144747 -254.911856)
			(xy 381.114723 -254.955893) (xy 381.078471 -254.994964) (xy 381.0368 -255.028195) (xy 380.990642 -255.054844)
			(xy 380.941028 -255.074316) (xy 380.889066 -255.086176) (xy 380.835916 -255.09016) (xy 380.782766 -255.086176)
			(xy 380.730804 -255.074316) (xy 380.68119 -255.054844) (xy 380.635032 -255.028195) (xy 380.593361 -254.994964)
			(xy 380.557109 -254.955893) (xy 380.527085 -254.911856) (xy 380.503959 -254.863835) (xy 380.488249 -254.812905)
			(xy 380.480306 -254.760201) (xy 380.25198 -254.760201) (xy 380.244037 -254.812905) (xy 380.228327 -254.863835)
			(xy 380.205201 -254.911856) (xy 380.175177 -254.955893) (xy 380.138925 -254.994964) (xy 380.097254 -255.028195)
			(xy 380.051096 -255.054844) (xy 380.001482 -255.074316) (xy 379.94952 -255.086176) (xy 379.89637 -255.09016)
			(xy 379.84322 -255.086176) (xy 379.791258 -255.074316) (xy 379.741644 -255.054844) (xy 379.695486 -255.028195)
			(xy 379.653815 -254.994964) (xy 379.617563 -254.955893) (xy 379.587539 -254.911856) (xy 379.564413 -254.863835)
			(xy 379.548703 -254.812905) (xy 379.54076 -254.760201) (xy 379.311672 -254.760201) (xy 379.303729 -254.812905)
			(xy 379.288019 -254.863835) (xy 379.264893 -254.911856) (xy 379.234869 -254.955893) (xy 379.198617 -254.994964)
			(xy 379.156946 -255.028195) (xy 379.110788 -255.054844) (xy 379.061174 -255.074316) (xy 379.009212 -255.086176)
			(xy 378.956062 -255.09016) (xy 378.902912 -255.086176) (xy 378.85095 -255.074316) (xy 378.801336 -255.054844)
			(xy 378.755178 -255.028195) (xy 378.713507 -254.994964) (xy 378.677255 -254.955893) (xy 378.647231 -254.911856)
			(xy 378.624105 -254.863835) (xy 378.608395 -254.812905) (xy 378.600452 -254.760201) (xy 378.371872 -254.760201)
			(xy 378.363929 -254.812905) (xy 378.348219 -254.863835) (xy 378.325093 -254.911856) (xy 378.295069 -254.955893)
			(xy 378.258817 -254.994964) (xy 378.217146 -255.028195) (xy 378.170988 -255.054844) (xy 378.121374 -255.074316)
			(xy 378.069412 -255.086176) (xy 378.016262 -255.09016) (xy 377.963112 -255.086176) (xy 377.91115 -255.074316)
			(xy 377.861536 -255.054844) (xy 377.815378 -255.028195) (xy 377.773707 -254.994964) (xy 377.737455 -254.955893)
			(xy 377.707431 -254.911856) (xy 377.684305 -254.863835) (xy 377.668595 -254.812905) (xy 377.660652 -254.760201)
			(xy 377.432072 -254.760201) (xy 377.424129 -254.812905) (xy 377.408419 -254.863835) (xy 377.385293 -254.911856)
			(xy 377.355269 -254.955893) (xy 377.319017 -254.994964) (xy 377.277346 -255.028195) (xy 377.231188 -255.054844)
			(xy 377.181574 -255.074316) (xy 377.129612 -255.086176) (xy 377.076462 -255.09016) (xy 377.023312 -255.086176)
			(xy 376.97135 -255.074316) (xy 376.921736 -255.054844) (xy 376.875578 -255.028195) (xy 376.833907 -254.994964)
			(xy 376.797655 -254.955893) (xy 376.767631 -254.911856) (xy 376.744505 -254.863835) (xy 376.728795 -254.812905)
			(xy 376.720852 -254.760201) (xy 376.492272 -254.760201) (xy 376.484329 -254.812905) (xy 376.468619 -254.863835)
			(xy 376.445493 -254.911856) (xy 376.415469 -254.955893) (xy 376.379217 -254.994964) (xy 376.337546 -255.028195)
			(xy 376.291388 -255.054844) (xy 376.241774 -255.074316) (xy 376.189812 -255.086176) (xy 376.136662 -255.09016)
			(xy 376.083512 -255.086176) (xy 376.03155 -255.074316) (xy 375.981936 -255.054844) (xy 375.935778 -255.028195)
			(xy 375.894107 -254.994964) (xy 375.857855 -254.955893) (xy 375.827831 -254.911856) (xy 375.804705 -254.863835)
			(xy 375.788995 -254.812905) (xy 375.781052 -254.760201) (xy 375.552472 -254.760201) (xy 375.544529 -254.812905)
			(xy 375.528819 -254.863835) (xy 375.505693 -254.911856) (xy 375.475669 -254.955893) (xy 375.439417 -254.994964)
			(xy 375.397746 -255.028195) (xy 375.351588 -255.054844) (xy 375.301974 -255.074316) (xy 375.250012 -255.086176)
			(xy 375.196862 -255.09016) (xy 375.143712 -255.086176) (xy 375.09175 -255.074316) (xy 375.042136 -255.054844)
			(xy 374.995978 -255.028195) (xy 374.954307 -254.994964) (xy 374.918055 -254.955893) (xy 374.888031 -254.911856)
			(xy 374.864905 -254.863835) (xy 374.849195 -254.812905) (xy 374.841252 -254.760201) (xy 374.612926 -254.760201)
			(xy 374.604983 -254.812905) (xy 374.589273 -254.863835) (xy 374.566147 -254.911856) (xy 374.536123 -254.955893)
			(xy 374.499871 -254.994964) (xy 374.4582 -255.028195) (xy 374.412042 -255.054844) (xy 374.362428 -255.074316)
			(xy 374.310466 -255.086176) (xy 374.257316 -255.09016) (xy 374.204166 -255.086176) (xy 374.152204 -255.074316)
			(xy 374.10259 -255.054844) (xy 374.056432 -255.028195) (xy 374.014761 -254.994964) (xy 373.978509 -254.955893)
			(xy 373.948485 -254.911856) (xy 373.925359 -254.863835) (xy 373.909649 -254.812905) (xy 373.901706 -254.760201)
			(xy 373.672872 -254.760201) (xy 373.664929 -254.812905) (xy 373.649219 -254.863835) (xy 373.626093 -254.911856)
			(xy 373.596069 -254.955893) (xy 373.559817 -254.994964) (xy 373.518146 -255.028195) (xy 373.471988 -255.054844)
			(xy 373.422374 -255.074316) (xy 373.370412 -255.086176) (xy 373.317262 -255.09016) (xy 373.264112 -255.086176)
			(xy 373.21215 -255.074316) (xy 373.162536 -255.054844) (xy 373.116378 -255.028195) (xy 373.074707 -254.994964)
			(xy 373.038455 -254.955893) (xy 373.008431 -254.911856) (xy 372.985305 -254.863835) (xy 372.969595 -254.812905)
			(xy 372.961652 -254.760201) (xy 372.733326 -254.760201) (xy 372.725383 -254.812905) (xy 372.709673 -254.863835)
			(xy 372.686547 -254.911856) (xy 372.656523 -254.955893) (xy 372.620271 -254.994964) (xy 372.5786 -255.028195)
			(xy 372.532442 -255.054844) (xy 372.482828 -255.074316) (xy 372.430866 -255.086176) (xy 372.377716 -255.09016)
			(xy 372.324566 -255.086176) (xy 372.272604 -255.074316) (xy 372.22299 -255.054844) (xy 372.176832 -255.028195)
			(xy 372.135161 -254.994964) (xy 372.098909 -254.955893) (xy 372.068885 -254.911856) (xy 372.045759 -254.863835)
			(xy 372.030049 -254.812905) (xy 372.022106 -254.760201) (xy 371.793272 -254.760201) (xy 371.785329 -254.812905)
			(xy 371.769619 -254.863835) (xy 371.746493 -254.911856) (xy 371.716469 -254.955893) (xy 371.680217 -254.994964)
			(xy 371.638546 -255.028195) (xy 371.592388 -255.054844) (xy 371.542774 -255.074316) (xy 371.490812 -255.086176)
			(xy 371.437662 -255.09016) (xy 371.384512 -255.086176) (xy 371.33255 -255.074316) (xy 371.282936 -255.054844)
			(xy 371.236778 -255.028195) (xy 371.195107 -254.994964) (xy 371.158855 -254.955893) (xy 371.128831 -254.911856)
			(xy 371.105705 -254.863835) (xy 371.089995 -254.812905) (xy 371.082052 -254.760201) (xy 370.853472 -254.760201)
			(xy 370.845529 -254.812905) (xy 370.829819 -254.863835) (xy 370.806693 -254.911856) (xy 370.776669 -254.955893)
			(xy 370.740417 -254.994964) (xy 370.698746 -255.028195) (xy 370.652588 -255.054844) (xy 370.602974 -255.074316)
			(xy 370.551012 -255.086176) (xy 370.497862 -255.09016) (xy 370.444712 -255.086176) (xy 370.39275 -255.074316)
			(xy 370.343136 -255.054844) (xy 370.296978 -255.028195) (xy 370.255307 -254.994964) (xy 370.219055 -254.955893)
			(xy 370.189031 -254.911856) (xy 370.165905 -254.863835) (xy 370.150195 -254.812905) (xy 370.142252 -254.760201)
			(xy 369.912787 -254.760201) (xy 369.910796 -254.786764) (xy 369.898932 -254.83874) (xy 369.879453 -254.888367)
			(xy 369.852795 -254.934537) (xy 369.819553 -254.976217) (xy 369.780469 -255.012477) (xy 369.736418 -255.042507)
			(xy 369.688383 -255.065635) (xy 369.637437 -255.081345) (xy 369.584719 -255.089285) (xy 369.558062 -255.08966)
			(xy 369.557808 -255.08966) (xy 369.527492 -255.088986) (xy 369.467741 -255.078682) (xy 369.410588 -255.058438)
			(xy 369.383818 -255.044194) (xy 369.371299 -255.03768) (xy 369.343864 -255.03112) (xy 369.315681 -255.032329)
			(xy 369.288908 -255.041215) (xy 369.265595 -255.057097) (xy 369.247527 -255.07876) (xy 369.241324 -255.091438)
			(xy 369.231078 -255.113414) (xy 369.205461 -255.154582) (xy 369.19027 -255.17348) (xy 369.18165 -255.184609)
			(xy 369.170316 -255.210366) (xy 369.166447 -255.238239) (xy 369.170337 -255.266109) (xy 369.181691 -255.291856)
			(xy 369.19027 -255.30302) (xy 369.205706 -255.322268) (xy 369.231676 -255.364218) (xy 369.251598 -255.409355)
			(xy 369.265088 -255.456813) (xy 369.271889 -255.505681) (xy 369.272312 -255.53035) (xy 369.271849 -255.556169)
			(xy 369.269206 -255.574271) (xy 370.612406 -255.574271) (xy 370.612406 -255.520973) (xy 370.620349 -255.468269)
			(xy 370.636059 -255.417339) (xy 370.659185 -255.369318) (xy 370.689209 -255.325281) (xy 370.725461 -255.28621)
			(xy 370.767132 -255.252979) (xy 370.81329 -255.22633) (xy 370.862904 -255.206858) (xy 370.914866 -255.194998)
			(xy 370.968016 -255.191015) (xy 371.021166 -255.194998) (xy 371.073128 -255.206858) (xy 371.122742 -255.22633)
			(xy 371.1689 -255.252979) (xy 371.210571 -255.28621) (xy 371.246823 -255.325281) (xy 371.276847 -255.369318)
			(xy 371.299973 -255.417339) (xy 371.315683 -255.468269) (xy 371.323626 -255.520973) (xy 371.324124 -255.547622)
			(xy 371.323626 -255.574271) (xy 371.552206 -255.574271) (xy 371.552206 -255.520973) (xy 371.560149 -255.468269)
			(xy 371.575859 -255.417339) (xy 371.598985 -255.369318) (xy 371.629009 -255.325281) (xy 371.665261 -255.28621)
			(xy 371.706932 -255.252979) (xy 371.75309 -255.22633) (xy 371.802704 -255.206858) (xy 371.854666 -255.194998)
			(xy 371.907816 -255.191015) (xy 371.960966 -255.194998) (xy 372.012928 -255.206858) (xy 372.062542 -255.22633)
			(xy 372.1087 -255.252979) (xy 372.150371 -255.28621) (xy 372.186623 -255.325281) (xy 372.216647 -255.369318)
			(xy 372.239773 -255.417339) (xy 372.255483 -255.468269) (xy 372.263426 -255.520973) (xy 372.263924 -255.547622)
			(xy 372.263426 -255.574271) (xy 372.491752 -255.574271) (xy 372.491752 -255.520973) (xy 372.499695 -255.468269)
			(xy 372.515405 -255.417339) (xy 372.538531 -255.369318) (xy 372.568555 -255.325281) (xy 372.604807 -255.28621)
			(xy 372.646478 -255.252979) (xy 372.692636 -255.22633) (xy 372.74225 -255.206858) (xy 372.794212 -255.194998)
			(xy 372.847362 -255.191015) (xy 372.900512 -255.194998) (xy 372.952474 -255.206858) (xy 373.002088 -255.22633)
			(xy 373.048246 -255.252979) (xy 373.089917 -255.28621) (xy 373.126169 -255.325281) (xy 373.156193 -255.369318)
			(xy 373.179319 -255.417339) (xy 373.195029 -255.468269) (xy 373.202972 -255.520973) (xy 373.20347 -255.547622)
			(xy 373.202972 -255.574271) (xy 373.431806 -255.574271) (xy 373.431806 -255.520973) (xy 373.439749 -255.468269)
			(xy 373.455459 -255.417339) (xy 373.478585 -255.369318) (xy 373.508609 -255.325281) (xy 373.544861 -255.28621)
			(xy 373.586532 -255.252979) (xy 373.63269 -255.22633) (xy 373.682304 -255.206858) (xy 373.734266 -255.194998)
			(xy 373.787416 -255.191015) (xy 373.840566 -255.194998) (xy 373.892528 -255.206858) (xy 373.942142 -255.22633)
			(xy 373.9883 -255.252979) (xy 374.029971 -255.28621) (xy 374.066223 -255.325281) (xy 374.096247 -255.369318)
			(xy 374.119373 -255.417339) (xy 374.135083 -255.468269) (xy 374.143026 -255.520973) (xy 374.143524 -255.547622)
			(xy 374.143026 -255.574271) (xy 374.371352 -255.574271) (xy 374.371352 -255.520973) (xy 374.379295 -255.468269)
			(xy 374.395005 -255.417339) (xy 374.418131 -255.369318) (xy 374.448155 -255.325281) (xy 374.484407 -255.28621)
			(xy 374.526078 -255.252979) (xy 374.572236 -255.22633) (xy 374.62185 -255.206858) (xy 374.673812 -255.194998)
			(xy 374.726962 -255.191015) (xy 374.780112 -255.194998) (xy 374.832074 -255.206858) (xy 374.881688 -255.22633)
			(xy 374.927846 -255.252979) (xy 374.969517 -255.28621) (xy 375.005769 -255.325281) (xy 375.035793 -255.369318)
			(xy 375.058919 -255.417339) (xy 375.074629 -255.468269) (xy 375.082572 -255.520973) (xy 375.08307 -255.547622)
			(xy 375.323103 -255.547622) (xy 375.327133 -255.495124) (xy 375.33913 -255.443856) (xy 375.358813 -255.395021)
			(xy 375.385719 -255.349762) (xy 375.419219 -255.309141) (xy 375.458527 -255.27411) (xy 375.502722 -255.24549)
			(xy 375.550767 -255.223951) (xy 375.601538 -255.209999) (xy 375.653843 -255.203961) (xy 375.706457 -255.205978)
			(xy 375.758147 -255.216002) (xy 375.8077 -255.2338) (xy 375.853956 -255.258953) (xy 375.89583 -255.290872)
			(xy 375.932342 -255.32881) (xy 375.962634 -255.371876) (xy 375.985997 -255.419061) (xy 376.001883 -255.46926)
			(xy 376.00992 -255.521296) (xy 376.010424 -255.547622) (xy 376.00992 -255.573948) (xy 376.00987 -255.574271)
			(xy 376.251206 -255.574271) (xy 376.251206 -255.520973) (xy 376.259149 -255.468269) (xy 376.274859 -255.417339)
			(xy 376.297985 -255.369318) (xy 376.328009 -255.325281) (xy 376.364261 -255.28621) (xy 376.405932 -255.252979)
			(xy 376.45209 -255.22633) (xy 376.501704 -255.206858) (xy 376.553666 -255.194998) (xy 376.606816 -255.191015)
			(xy 376.659966 -255.194998) (xy 376.711928 -255.206858) (xy 376.761542 -255.22633) (xy 376.8077 -255.252979)
			(xy 376.849371 -255.28621) (xy 376.885623 -255.325281) (xy 376.915647 -255.369318) (xy 376.938773 -255.417339)
			(xy 376.954483 -255.468269) (xy 376.962426 -255.520973) (xy 376.962924 -255.547622) (xy 376.962426 -255.574271)
			(xy 377.191006 -255.574271) (xy 377.191006 -255.520973) (xy 377.198949 -255.468269) (xy 377.214659 -255.417339)
			(xy 377.237785 -255.369318) (xy 377.267809 -255.325281) (xy 377.304061 -255.28621) (xy 377.345732 -255.252979)
			(xy 377.39189 -255.22633) (xy 377.441504 -255.206858) (xy 377.493466 -255.194998) (xy 377.546616 -255.191015)
			(xy 377.599766 -255.194998) (xy 377.651728 -255.206858) (xy 377.701342 -255.22633) (xy 377.7475 -255.252979)
			(xy 377.789171 -255.28621) (xy 377.825423 -255.325281) (xy 377.855447 -255.369318) (xy 377.878573 -255.417339)
			(xy 377.894283 -255.468269) (xy 377.902226 -255.520973) (xy 377.902724 -255.547622) (xy 377.902226 -255.574271)
			(xy 378.130806 -255.574271) (xy 378.130806 -255.520973) (xy 378.138749 -255.468269) (xy 378.154459 -255.417339)
			(xy 378.177585 -255.369318) (xy 378.207609 -255.325281) (xy 378.243861 -255.28621) (xy 378.285532 -255.252979)
			(xy 378.33169 -255.22633) (xy 378.381304 -255.206858) (xy 378.433266 -255.194998) (xy 378.486416 -255.191015)
			(xy 378.539566 -255.194998) (xy 378.591528 -255.206858) (xy 378.641142 -255.22633) (xy 378.6873 -255.252979)
			(xy 378.728971 -255.28621) (xy 378.765223 -255.325281) (xy 378.795247 -255.369318) (xy 378.818373 -255.417339)
			(xy 378.834083 -255.468269) (xy 378.842026 -255.520973) (xy 378.842524 -255.547622) (xy 378.842026 -255.574271)
			(xy 379.070606 -255.574271) (xy 379.070606 -255.520973) (xy 379.078549 -255.468269) (xy 379.094259 -255.417339)
			(xy 379.117385 -255.369318) (xy 379.147409 -255.325281) (xy 379.183661 -255.28621) (xy 379.225332 -255.252979)
			(xy 379.27149 -255.22633) (xy 379.321104 -255.206858) (xy 379.373066 -255.194998) (xy 379.426216 -255.191015)
			(xy 379.479366 -255.194998) (xy 379.531328 -255.206858) (xy 379.580942 -255.22633) (xy 379.6271 -255.252979)
			(xy 379.668771 -255.28621) (xy 379.705023 -255.325281) (xy 379.735047 -255.369318) (xy 379.758173 -255.417339)
			(xy 379.773883 -255.468269) (xy 379.781826 -255.520973) (xy 379.782324 -255.547622) (xy 379.781826 -255.574271)
			(xy 380.010406 -255.574271) (xy 380.010406 -255.520973) (xy 380.018349 -255.468269) (xy 380.034059 -255.417339)
			(xy 380.057185 -255.369318) (xy 380.087209 -255.325281) (xy 380.123461 -255.28621) (xy 380.165132 -255.252979)
			(xy 380.21129 -255.22633) (xy 380.260904 -255.206858) (xy 380.312866 -255.194998) (xy 380.366016 -255.191015)
			(xy 380.419166 -255.194998) (xy 380.471128 -255.206858) (xy 380.520742 -255.22633) (xy 380.5669 -255.252979)
			(xy 380.608571 -255.28621) (xy 380.644823 -255.325281) (xy 380.674847 -255.369318) (xy 380.697973 -255.417339)
			(xy 380.713683 -255.468269) (xy 380.721626 -255.520973) (xy 380.722124 -255.547622) (xy 380.721626 -255.574271)
			(xy 380.949952 -255.574271) (xy 380.949952 -255.520973) (xy 380.957895 -255.468269) (xy 380.973605 -255.417339)
			(xy 380.996731 -255.369318) (xy 381.026755 -255.325281) (xy 381.063007 -255.28621) (xy 381.104678 -255.252979)
			(xy 381.150836 -255.22633) (xy 381.20045 -255.206858) (xy 381.252412 -255.194998) (xy 381.305562 -255.191015)
			(xy 381.358712 -255.194998) (xy 381.410674 -255.206858) (xy 381.460288 -255.22633) (xy 381.506446 -255.252979)
			(xy 381.548117 -255.28621) (xy 381.584369 -255.325281) (xy 381.614393 -255.369318) (xy 381.637519 -255.417339)
			(xy 381.653229 -255.468269) (xy 381.661172 -255.520973) (xy 381.66167 -255.547622) (xy 381.661172 -255.574271)
			(xy 381.653229 -255.626975) (xy 381.637519 -255.677905) (xy 381.614393 -255.725926) (xy 381.584369 -255.769963)
			(xy 381.548117 -255.809034) (xy 381.506446 -255.842265) (xy 381.460288 -255.868914) (xy 381.410674 -255.888386)
			(xy 381.358712 -255.900246) (xy 381.305562 -255.90423) (xy 381.252412 -255.900246) (xy 381.20045 -255.888386)
			(xy 381.150836 -255.868914) (xy 381.104678 -255.842265) (xy 381.063007 -255.809034) (xy 381.026755 -255.769963)
			(xy 380.996731 -255.725926) (xy 380.973605 -255.677905) (xy 380.957895 -255.626975) (xy 380.949952 -255.574271)
			(xy 380.721626 -255.574271) (xy 380.713683 -255.626975) (xy 380.697973 -255.677905) (xy 380.674847 -255.725926)
			(xy 380.644823 -255.769963) (xy 380.608571 -255.809034) (xy 380.5669 -255.842265) (xy 380.520742 -255.868914)
			(xy 380.471128 -255.888386) (xy 380.419166 -255.900246) (xy 380.366016 -255.90423) (xy 380.312866 -255.900246)
			(xy 380.260904 -255.888386) (xy 380.21129 -255.868914) (xy 380.165132 -255.842265) (xy 380.123461 -255.809034)
			(xy 380.087209 -255.769963) (xy 380.057185 -255.725926) (xy 380.034059 -255.677905) (xy 380.018349 -255.626975)
			(xy 380.010406 -255.574271) (xy 379.781826 -255.574271) (xy 379.773883 -255.626975) (xy 379.758173 -255.677905)
			(xy 379.735047 -255.725926) (xy 379.705023 -255.769963) (xy 379.668771 -255.809034) (xy 379.6271 -255.842265)
			(xy 379.580942 -255.868914) (xy 379.531328 -255.888386) (xy 379.479366 -255.900246) (xy 379.426216 -255.90423)
			(xy 379.373066 -255.900246) (xy 379.321104 -255.888386) (xy 379.27149 -255.868914) (xy 379.225332 -255.842265)
			(xy 379.183661 -255.809034) (xy 379.147409 -255.769963) (xy 379.117385 -255.725926) (xy 379.094259 -255.677905)
			(xy 379.078549 -255.626975) (xy 379.070606 -255.574271) (xy 378.842026 -255.574271) (xy 378.834083 -255.626975)
			(xy 378.818373 -255.677905) (xy 378.795247 -255.725926) (xy 378.765223 -255.769963) (xy 378.728971 -255.809034)
			(xy 378.6873 -255.842265) (xy 378.641142 -255.868914) (xy 378.591528 -255.888386) (xy 378.539566 -255.900246)
			(xy 378.486416 -255.90423) (xy 378.433266 -255.900246) (xy 378.381304 -255.888386) (xy 378.33169 -255.868914)
			(xy 378.285532 -255.842265) (xy 378.243861 -255.809034) (xy 378.207609 -255.769963) (xy 378.177585 -255.725926)
			(xy 378.154459 -255.677905) (xy 378.138749 -255.626975) (xy 378.130806 -255.574271) (xy 377.902226 -255.574271)
			(xy 377.894283 -255.626975) (xy 377.878573 -255.677905) (xy 377.855447 -255.725926) (xy 377.825423 -255.769963)
			(xy 377.789171 -255.809034) (xy 377.7475 -255.842265) (xy 377.701342 -255.868914) (xy 377.651728 -255.888386)
			(xy 377.599766 -255.900246) (xy 377.546616 -255.90423) (xy 377.493466 -255.900246) (xy 377.441504 -255.888386)
			(xy 377.39189 -255.868914) (xy 377.345732 -255.842265) (xy 377.304061 -255.809034) (xy 377.267809 -255.769963)
			(xy 377.237785 -255.725926) (xy 377.214659 -255.677905) (xy 377.198949 -255.626975) (xy 377.191006 -255.574271)
			(xy 376.962426 -255.574271) (xy 376.954483 -255.626975) (xy 376.938773 -255.677905) (xy 376.915647 -255.725926)
			(xy 376.885623 -255.769963) (xy 376.849371 -255.809034) (xy 376.8077 -255.842265) (xy 376.761542 -255.868914)
			(xy 376.711928 -255.888386) (xy 376.659966 -255.900246) (xy 376.606816 -255.90423) (xy 376.553666 -255.900246)
			(xy 376.501704 -255.888386) (xy 376.45209 -255.868914) (xy 376.405932 -255.842265) (xy 376.364261 -255.809034)
			(xy 376.328009 -255.769963) (xy 376.297985 -255.725926) (xy 376.274859 -255.677905) (xy 376.259149 -255.626975)
			(xy 376.251206 -255.574271) (xy 376.00987 -255.574271) (xy 376.001883 -255.625984) (xy 375.985997 -255.676183)
			(xy 375.962634 -255.723368) (xy 375.932342 -255.766434) (xy 375.89583 -255.804372) (xy 375.853956 -255.836291)
			(xy 375.8077 -255.861444) (xy 375.758147 -255.879242) (xy 375.706457 -255.889266) (xy 375.653843 -255.891283)
			(xy 375.601538 -255.885245) (xy 375.550767 -255.871293) (xy 375.502722 -255.849754) (xy 375.458527 -255.821134)
			(xy 375.419219 -255.786103) (xy 375.385719 -255.745482) (xy 375.358813 -255.700223) (xy 375.33913 -255.651388)
			(xy 375.327133 -255.60012) (xy 375.323103 -255.547622) (xy 375.08307 -255.547622) (xy 375.082572 -255.574271)
			(xy 375.074629 -255.626975) (xy 375.058919 -255.677905) (xy 375.035793 -255.725926) (xy 375.005769 -255.769963)
			(xy 374.969517 -255.809034) (xy 374.927846 -255.842265) (xy 374.881688 -255.868914) (xy 374.832074 -255.888386)
			(xy 374.780112 -255.900246) (xy 374.726962 -255.90423) (xy 374.673812 -255.900246) (xy 374.62185 -255.888386)
			(xy 374.572236 -255.868914) (xy 374.526078 -255.842265) (xy 374.484407 -255.809034) (xy 374.448155 -255.769963)
			(xy 374.418131 -255.725926) (xy 374.395005 -255.677905) (xy 374.379295 -255.626975) (xy 374.371352 -255.574271)
			(xy 374.143026 -255.574271) (xy 374.135083 -255.626975) (xy 374.119373 -255.677905) (xy 374.096247 -255.725926)
			(xy 374.066223 -255.769963) (xy 374.029971 -255.809034) (xy 373.9883 -255.842265) (xy 373.942142 -255.868914)
			(xy 373.892528 -255.888386) (xy 373.840566 -255.900246) (xy 373.787416 -255.90423) (xy 373.734266 -255.900246)
			(xy 373.682304 -255.888386) (xy 373.63269 -255.868914) (xy 373.586532 -255.842265) (xy 373.544861 -255.809034)
			(xy 373.508609 -255.769963) (xy 373.478585 -255.725926) (xy 373.455459 -255.677905) (xy 373.439749 -255.626975)
			(xy 373.431806 -255.574271) (xy 373.202972 -255.574271) (xy 373.195029 -255.626975) (xy 373.179319 -255.677905)
			(xy 373.156193 -255.725926) (xy 373.126169 -255.769963) (xy 373.089917 -255.809034) (xy 373.048246 -255.842265)
			(xy 373.002088 -255.868914) (xy 372.952474 -255.888386) (xy 372.900512 -255.900246) (xy 372.847362 -255.90423)
			(xy 372.794212 -255.900246) (xy 372.74225 -255.888386) (xy 372.692636 -255.868914) (xy 372.646478 -255.842265)
			(xy 372.604807 -255.809034) (xy 372.568555 -255.769963) (xy 372.538531 -255.725926) (xy 372.515405 -255.677905)
			(xy 372.499695 -255.626975) (xy 372.491752 -255.574271) (xy 372.263426 -255.574271) (xy 372.255483 -255.626975)
			(xy 372.239773 -255.677905) (xy 372.216647 -255.725926) (xy 372.186623 -255.769963) (xy 372.150371 -255.809034)
			(xy 372.1087 -255.842265) (xy 372.062542 -255.868914) (xy 372.012928 -255.888386) (xy 371.960966 -255.900246)
			(xy 371.907816 -255.90423) (xy 371.854666 -255.900246) (xy 371.802704 -255.888386) (xy 371.75309 -255.868914)
			(xy 371.706932 -255.842265) (xy 371.665261 -255.809034) (xy 371.629009 -255.769963) (xy 371.598985 -255.725926)
			(xy 371.575859 -255.677905) (xy 371.560149 -255.626975) (xy 371.552206 -255.574271) (xy 371.323626 -255.574271)
			(xy 371.315683 -255.626975) (xy 371.299973 -255.677905) (xy 371.276847 -255.725926) (xy 371.246823 -255.769963)
			(xy 371.210571 -255.809034) (xy 371.1689 -255.842265) (xy 371.122742 -255.868914) (xy 371.073128 -255.888386)
			(xy 371.021166 -255.900246) (xy 370.968016 -255.90423) (xy 370.914866 -255.900246) (xy 370.862904 -255.888386)
			(xy 370.81329 -255.868914) (xy 370.767132 -255.842265) (xy 370.725461 -255.809034) (xy 370.689209 -255.769963)
			(xy 370.659185 -255.725926) (xy 370.636059 -255.677905) (xy 370.620349 -255.626975) (xy 370.612406 -255.574271)
			(xy 369.269206 -255.574271) (xy 369.264388 -255.607266) (xy 369.249629 -255.65675) (xy 369.227882 -255.703586)
			(xy 369.199601 -255.746792) (xy 369.16538 -255.785462) (xy 369.125934 -255.818788) (xy 369.082092 -255.846071)
			(xy 369.03477 -255.86674) (xy 368.98496 -255.880361) (xy 368.959384 -255.883918) (xy 368.91468 -255.889252)
			(xy 368.91468 -256.307844) (xy 368.959638 -256.312924) (xy 368.98831 -256.316806) (xy 369.04396 -256.332629)
			(xy 369.070382 -256.34442) (xy 369.084191 -256.350331) (xy 369.1139 -256.354664) (xy 369.143582 -256.350157)
			(xy 369.170665 -256.3372) (xy 369.192801 -256.316918) (xy 369.208071 -256.291068) (xy 369.212114 -256.276602)
			(xy 369.218842 -256.251133) (xy 369.238777 -256.202374) (xy 369.265679 -256.157084) (xy 369.298961 -256.116254)
			(xy 369.337896 -256.080773) (xy 369.381635 -256.051416) (xy 369.429222 -256.028826) (xy 369.479618 -256.013494)
			(xy 369.531723 -256.005755) (xy 369.558062 -256.00533) (xy 369.584712 -256.0058) (xy 369.637418 -256.013739)
			(xy 369.688351 -256.029445) (xy 369.736375 -256.052568) (xy 369.780416 -256.08259) (xy 369.81949 -256.118841)
			(xy 369.852724 -256.160511) (xy 369.879375 -256.20667) (xy 369.898849 -256.256285) (xy 369.910711 -256.308249)
			(xy 369.914694 -256.3614) (xy 369.912694 -256.388087) (xy 370.142506 -256.388087) (xy 370.142506 -256.334789)
			(xy 370.150449 -256.282085) (xy 370.166159 -256.231155) (xy 370.189285 -256.183134) (xy 370.219309 -256.139097)
			(xy 370.255561 -256.100026) (xy 370.297232 -256.066795) (xy 370.34339 -256.040146) (xy 370.393004 -256.020674)
			(xy 370.444966 -256.008814) (xy 370.498116 -256.004831) (xy 370.551266 -256.008814) (xy 370.603228 -256.020674)
			(xy 370.652842 -256.040146) (xy 370.699 -256.066795) (xy 370.740671 -256.100026) (xy 370.776923 -256.139097)
			(xy 370.806947 -256.183134) (xy 370.830073 -256.231155) (xy 370.845783 -256.282085) (xy 370.853726 -256.334789)
			(xy 370.854224 -256.361438) (xy 370.853726 -256.388087) (xy 371.082052 -256.388087) (xy 371.082052 -256.334789)
			(xy 371.089995 -256.282085) (xy 371.105705 -256.231155) (xy 371.128831 -256.183134) (xy 371.158855 -256.139097)
			(xy 371.195107 -256.100026) (xy 371.236778 -256.066795) (xy 371.282936 -256.040146) (xy 371.33255 -256.020674)
			(xy 371.384512 -256.008814) (xy 371.437662 -256.004831) (xy 371.490812 -256.008814) (xy 371.542774 -256.020674)
			(xy 371.592388 -256.040146) (xy 371.638546 -256.066795) (xy 371.680217 -256.100026) (xy 371.716469 -256.139097)
			(xy 371.746493 -256.183134) (xy 371.769619 -256.231155) (xy 371.785329 -256.282085) (xy 371.793272 -256.334789)
			(xy 371.79377 -256.361438) (xy 371.793272 -256.388087) (xy 372.021852 -256.388087) (xy 372.021852 -256.334789)
			(xy 372.029795 -256.282085) (xy 372.045505 -256.231155) (xy 372.068631 -256.183134) (xy 372.098655 -256.139097)
			(xy 372.134907 -256.100026) (xy 372.176578 -256.066795) (xy 372.222736 -256.040146) (xy 372.27235 -256.020674)
			(xy 372.324312 -256.008814) (xy 372.377462 -256.004831) (xy 372.430612 -256.008814) (xy 372.482574 -256.020674)
			(xy 372.532188 -256.040146) (xy 372.578346 -256.066795) (xy 372.620017 -256.100026) (xy 372.656269 -256.139097)
			(xy 372.686293 -256.183134) (xy 372.709419 -256.231155) (xy 372.725129 -256.282085) (xy 372.733072 -256.334789)
			(xy 372.73357 -256.361438) (xy 372.733072 -256.388087) (xy 372.961652 -256.388087) (xy 372.961652 -256.334789)
			(xy 372.969595 -256.282085) (xy 372.985305 -256.231155) (xy 373.008431 -256.183134) (xy 373.038455 -256.139097)
			(xy 373.074707 -256.100026) (xy 373.116378 -256.066795) (xy 373.162536 -256.040146) (xy 373.21215 -256.020674)
			(xy 373.264112 -256.008814) (xy 373.317262 -256.004831) (xy 373.370412 -256.008814) (xy 373.422374 -256.020674)
			(xy 373.471988 -256.040146) (xy 373.518146 -256.066795) (xy 373.559817 -256.100026) (xy 373.596069 -256.139097)
			(xy 373.626093 -256.183134) (xy 373.649219 -256.231155) (xy 373.664929 -256.282085) (xy 373.672872 -256.334789)
			(xy 373.67337 -256.361438) (xy 373.672872 -256.388087) (xy 373.901452 -256.388087) (xy 373.901452 -256.334789)
			(xy 373.909395 -256.282085) (xy 373.925105 -256.231155) (xy 373.948231 -256.183134) (xy 373.978255 -256.139097)
			(xy 374.014507 -256.100026) (xy 374.056178 -256.066795) (xy 374.102336 -256.040146) (xy 374.15195 -256.020674)
			(xy 374.203912 -256.008814) (xy 374.257062 -256.004831) (xy 374.310212 -256.008814) (xy 374.362174 -256.020674)
			(xy 374.411788 -256.040146) (xy 374.457946 -256.066795) (xy 374.499617 -256.100026) (xy 374.535869 -256.139097)
			(xy 374.565893 -256.183134) (xy 374.589019 -256.231155) (xy 374.604729 -256.282085) (xy 374.612672 -256.334789)
			(xy 374.61317 -256.361438) (xy 374.612672 -256.388087) (xy 374.841252 -256.388087) (xy 374.841252 -256.334789)
			(xy 374.849195 -256.282085) (xy 374.864905 -256.231155) (xy 374.888031 -256.183134) (xy 374.918055 -256.139097)
			(xy 374.954307 -256.100026) (xy 374.995978 -256.066795) (xy 375.042136 -256.040146) (xy 375.09175 -256.020674)
			(xy 375.143712 -256.008814) (xy 375.196862 -256.004831) (xy 375.250012 -256.008814) (xy 375.301974 -256.020674)
			(xy 375.351588 -256.040146) (xy 375.397746 -256.066795) (xy 375.439417 -256.100026) (xy 375.475669 -256.139097)
			(xy 375.505693 -256.183134) (xy 375.528819 -256.231155) (xy 375.544529 -256.282085) (xy 375.552472 -256.334789)
			(xy 375.55297 -256.361438) (xy 375.552472 -256.388087) (xy 375.781052 -256.388087) (xy 375.781052 -256.334789)
			(xy 375.788995 -256.282085) (xy 375.804705 -256.231155) (xy 375.827831 -256.183134) (xy 375.857855 -256.139097)
			(xy 375.894107 -256.100026) (xy 375.935778 -256.066795) (xy 375.981936 -256.040146) (xy 376.03155 -256.020674)
			(xy 376.083512 -256.008814) (xy 376.136662 -256.004831) (xy 376.189812 -256.008814) (xy 376.241774 -256.020674)
			(xy 376.291388 -256.040146) (xy 376.337546 -256.066795) (xy 376.379217 -256.100026) (xy 376.415469 -256.139097)
			(xy 376.445493 -256.183134) (xy 376.468619 -256.231155) (xy 376.484329 -256.282085) (xy 376.492272 -256.334789)
			(xy 376.49277 -256.361438) (xy 376.492272 -256.388087) (xy 376.721106 -256.388087) (xy 376.721106 -256.334789)
			(xy 376.729049 -256.282085) (xy 376.744759 -256.231155) (xy 376.767885 -256.183134) (xy 376.797909 -256.139097)
			(xy 376.834161 -256.100026) (xy 376.875832 -256.066795) (xy 376.92199 -256.040146) (xy 376.971604 -256.020674)
			(xy 377.023566 -256.008814) (xy 377.076716 -256.004831) (xy 377.129866 -256.008814) (xy 377.181828 -256.020674)
			(xy 377.231442 -256.040146) (xy 377.2776 -256.066795) (xy 377.319271 -256.100026) (xy 377.355523 -256.139097)
			(xy 377.385547 -256.183134) (xy 377.408673 -256.231155) (xy 377.424383 -256.282085) (xy 377.432326 -256.334789)
			(xy 377.432824 -256.361438) (xy 377.432326 -256.388087) (xy 377.660652 -256.388087) (xy 377.660652 -256.334789)
			(xy 377.668595 -256.282085) (xy 377.684305 -256.231155) (xy 377.707431 -256.183134) (xy 377.737455 -256.139097)
			(xy 377.773707 -256.100026) (xy 377.815378 -256.066795) (xy 377.861536 -256.040146) (xy 377.91115 -256.020674)
			(xy 377.963112 -256.008814) (xy 378.016262 -256.004831) (xy 378.069412 -256.008814) (xy 378.121374 -256.020674)
			(xy 378.170988 -256.040146) (xy 378.217146 -256.066795) (xy 378.258817 -256.100026) (xy 378.295069 -256.139097)
			(xy 378.325093 -256.183134) (xy 378.348219 -256.231155) (xy 378.363929 -256.282085) (xy 378.371872 -256.334789)
			(xy 378.37237 -256.361438) (xy 378.371872 -256.388087) (xy 378.600452 -256.388087) (xy 378.600452 -256.334789)
			(xy 378.608395 -256.282085) (xy 378.624105 -256.231155) (xy 378.647231 -256.183134) (xy 378.677255 -256.139097)
			(xy 378.713507 -256.100026) (xy 378.755178 -256.066795) (xy 378.801336 -256.040146) (xy 378.85095 -256.020674)
			(xy 378.902912 -256.008814) (xy 378.956062 -256.004831) (xy 379.009212 -256.008814) (xy 379.061174 -256.020674)
			(xy 379.110788 -256.040146) (xy 379.156946 -256.066795) (xy 379.198617 -256.100026) (xy 379.234869 -256.139097)
			(xy 379.264893 -256.183134) (xy 379.288019 -256.231155) (xy 379.303729 -256.282085) (xy 379.311672 -256.334789)
			(xy 379.31217 -256.361438) (xy 379.311672 -256.388087) (xy 379.540252 -256.388087) (xy 379.540252 -256.334789)
			(xy 379.548195 -256.282085) (xy 379.563905 -256.231155) (xy 379.587031 -256.183134) (xy 379.617055 -256.139097)
			(xy 379.653307 -256.100026) (xy 379.694978 -256.066795) (xy 379.741136 -256.040146) (xy 379.79075 -256.020674)
			(xy 379.842712 -256.008814) (xy 379.895862 -256.004831) (xy 379.949012 -256.008814) (xy 380.000974 -256.020674)
			(xy 380.050588 -256.040146) (xy 380.096746 -256.066795) (xy 380.138417 -256.100026) (xy 380.174669 -256.139097)
			(xy 380.204693 -256.183134) (xy 380.227819 -256.231155) (xy 380.243529 -256.282085) (xy 380.251472 -256.334789)
			(xy 380.25197 -256.361438) (xy 380.251472 -256.388087) (xy 380.480052 -256.388087) (xy 380.480052 -256.334789)
			(xy 380.487995 -256.282085) (xy 380.503705 -256.231155) (xy 380.526831 -256.183134) (xy 380.556855 -256.139097)
			(xy 380.593107 -256.100026) (xy 380.634778 -256.066795) (xy 380.680936 -256.040146) (xy 380.73055 -256.020674)
			(xy 380.782512 -256.008814) (xy 380.835662 -256.004831) (xy 380.888812 -256.008814) (xy 380.940774 -256.020674)
			(xy 380.990388 -256.040146) (xy 381.036546 -256.066795) (xy 381.078217 -256.100026) (xy 381.114469 -256.139097)
			(xy 381.144493 -256.183134) (xy 381.167619 -256.231155) (xy 381.183329 -256.282085) (xy 381.191272 -256.334789)
			(xy 381.19177 -256.361438) (xy 381.191272 -256.388087) (xy 381.183329 -256.440791) (xy 381.167619 -256.491721)
			(xy 381.144493 -256.539742) (xy 381.114469 -256.583779) (xy 381.078217 -256.62285) (xy 381.036546 -256.656081)
			(xy 380.990388 -256.68273) (xy 380.940774 -256.702202) (xy 380.888812 -256.714062) (xy 380.835662 -256.718046)
			(xy 380.782512 -256.714062) (xy 380.73055 -256.702202) (xy 380.680936 -256.68273) (xy 380.634778 -256.656081)
			(xy 380.593107 -256.62285) (xy 380.556855 -256.583779) (xy 380.526831 -256.539742) (xy 380.503705 -256.491721)
			(xy 380.487995 -256.440791) (xy 380.480052 -256.388087) (xy 380.251472 -256.388087) (xy 380.243529 -256.440791)
			(xy 380.227819 -256.491721) (xy 380.204693 -256.539742) (xy 380.174669 -256.583779) (xy 380.138417 -256.62285)
			(xy 380.096746 -256.656081) (xy 380.050588 -256.68273) (xy 380.000974 -256.702202) (xy 379.949012 -256.714062)
			(xy 379.895862 -256.718046) (xy 379.842712 -256.714062) (xy 379.79075 -256.702202) (xy 379.741136 -256.68273)
			(xy 379.694978 -256.656081) (xy 379.653307 -256.62285) (xy 379.617055 -256.583779) (xy 379.587031 -256.539742)
			(xy 379.563905 -256.491721) (xy 379.548195 -256.440791) (xy 379.540252 -256.388087) (xy 379.311672 -256.388087)
			(xy 379.303729 -256.440791) (xy 379.288019 -256.491721) (xy 379.264893 -256.539742) (xy 379.234869 -256.583779)
			(xy 379.198617 -256.62285) (xy 379.156946 -256.656081) (xy 379.110788 -256.68273) (xy 379.061174 -256.702202)
			(xy 379.009212 -256.714062) (xy 378.956062 -256.718046) (xy 378.902912 -256.714062) (xy 378.85095 -256.702202)
			(xy 378.801336 -256.68273) (xy 378.755178 -256.656081) (xy 378.713507 -256.62285) (xy 378.677255 -256.583779)
			(xy 378.647231 -256.539742) (xy 378.624105 -256.491721) (xy 378.608395 -256.440791) (xy 378.600452 -256.388087)
			(xy 378.371872 -256.388087) (xy 378.363929 -256.440791) (xy 378.348219 -256.491721) (xy 378.325093 -256.539742)
			(xy 378.295069 -256.583779) (xy 378.258817 -256.62285) (xy 378.217146 -256.656081) (xy 378.170988 -256.68273)
			(xy 378.121374 -256.702202) (xy 378.069412 -256.714062) (xy 378.016262 -256.718046) (xy 377.963112 -256.714062)
			(xy 377.91115 -256.702202) (xy 377.861536 -256.68273) (xy 377.815378 -256.656081) (xy 377.773707 -256.62285)
			(xy 377.737455 -256.583779) (xy 377.707431 -256.539742) (xy 377.684305 -256.491721) (xy 377.668595 -256.440791)
			(xy 377.660652 -256.388087) (xy 377.432326 -256.388087) (xy 377.424383 -256.440791) (xy 377.408673 -256.491721)
			(xy 377.385547 -256.539742) (xy 377.355523 -256.583779) (xy 377.319271 -256.62285) (xy 377.2776 -256.656081)
			(xy 377.231442 -256.68273) (xy 377.181828 -256.702202) (xy 377.129866 -256.714062) (xy 377.076716 -256.718046)
			(xy 377.023566 -256.714062) (xy 376.971604 -256.702202) (xy 376.92199 -256.68273) (xy 376.875832 -256.656081)
			(xy 376.834161 -256.62285) (xy 376.797909 -256.583779) (xy 376.767885 -256.539742) (xy 376.744759 -256.491721)
			(xy 376.729049 -256.440791) (xy 376.721106 -256.388087) (xy 376.492272 -256.388087) (xy 376.484329 -256.440791)
			(xy 376.468619 -256.491721) (xy 376.445493 -256.539742) (xy 376.415469 -256.583779) (xy 376.379217 -256.62285)
			(xy 376.337546 -256.656081) (xy 376.291388 -256.68273) (xy 376.241774 -256.702202) (xy 376.189812 -256.714062)
			(xy 376.136662 -256.718046) (xy 376.083512 -256.714062) (xy 376.03155 -256.702202) (xy 375.981936 -256.68273)
			(xy 375.935778 -256.656081) (xy 375.894107 -256.62285) (xy 375.857855 -256.583779) (xy 375.827831 -256.539742)
			(xy 375.804705 -256.491721) (xy 375.788995 -256.440791) (xy 375.781052 -256.388087) (xy 375.552472 -256.388087)
			(xy 375.544529 -256.440791) (xy 375.528819 -256.491721) (xy 375.505693 -256.539742) (xy 375.475669 -256.583779)
			(xy 375.439417 -256.62285) (xy 375.397746 -256.656081) (xy 375.351588 -256.68273) (xy 375.301974 -256.702202)
			(xy 375.250012 -256.714062) (xy 375.196862 -256.718046) (xy 375.143712 -256.714062) (xy 375.09175 -256.702202)
			(xy 375.042136 -256.68273) (xy 374.995978 -256.656081) (xy 374.954307 -256.62285) (xy 374.918055 -256.583779)
			(xy 374.888031 -256.539742) (xy 374.864905 -256.491721) (xy 374.849195 -256.440791) (xy 374.841252 -256.388087)
			(xy 374.612672 -256.388087) (xy 374.604729 -256.440791) (xy 374.589019 -256.491721) (xy 374.565893 -256.539742)
			(xy 374.535869 -256.583779) (xy 374.499617 -256.62285) (xy 374.457946 -256.656081) (xy 374.411788 -256.68273)
			(xy 374.362174 -256.702202) (xy 374.310212 -256.714062) (xy 374.257062 -256.718046) (xy 374.203912 -256.714062)
			(xy 374.15195 -256.702202) (xy 374.102336 -256.68273) (xy 374.056178 -256.656081) (xy 374.014507 -256.62285)
			(xy 373.978255 -256.583779) (xy 373.948231 -256.539742) (xy 373.925105 -256.491721) (xy 373.909395 -256.440791)
			(xy 373.901452 -256.388087) (xy 373.672872 -256.388087) (xy 373.664929 -256.440791) (xy 373.649219 -256.491721)
			(xy 373.626093 -256.539742) (xy 373.596069 -256.583779) (xy 373.559817 -256.62285) (xy 373.518146 -256.656081)
			(xy 373.471988 -256.68273) (xy 373.422374 -256.702202) (xy 373.370412 -256.714062) (xy 373.317262 -256.718046)
			(xy 373.264112 -256.714062) (xy 373.21215 -256.702202) (xy 373.162536 -256.68273) (xy 373.116378 -256.656081)
			(xy 373.074707 -256.62285) (xy 373.038455 -256.583779) (xy 373.008431 -256.539742) (xy 372.985305 -256.491721)
			(xy 372.969595 -256.440791) (xy 372.961652 -256.388087) (xy 372.733072 -256.388087) (xy 372.725129 -256.440791)
			(xy 372.709419 -256.491721) (xy 372.686293 -256.539742) (xy 372.656269 -256.583779) (xy 372.620017 -256.62285)
			(xy 372.578346 -256.656081) (xy 372.532188 -256.68273) (xy 372.482574 -256.702202) (xy 372.430612 -256.714062)
			(xy 372.377462 -256.718046) (xy 372.324312 -256.714062) (xy 372.27235 -256.702202) (xy 372.222736 -256.68273)
			(xy 372.176578 -256.656081) (xy 372.134907 -256.62285) (xy 372.098655 -256.583779) (xy 372.068631 -256.539742)
			(xy 372.045505 -256.491721) (xy 372.029795 -256.440791) (xy 372.021852 -256.388087) (xy 371.793272 -256.388087)
			(xy 371.785329 -256.440791) (xy 371.769619 -256.491721) (xy 371.746493 -256.539742) (xy 371.716469 -256.583779)
			(xy 371.680217 -256.62285) (xy 371.638546 -256.656081) (xy 371.592388 -256.68273) (xy 371.542774 -256.702202)
			(xy 371.490812 -256.714062) (xy 371.437662 -256.718046) (xy 371.384512 -256.714062) (xy 371.33255 -256.702202)
			(xy 371.282936 -256.68273) (xy 371.236778 -256.656081) (xy 371.195107 -256.62285) (xy 371.158855 -256.583779)
			(xy 371.128831 -256.539742) (xy 371.105705 -256.491721) (xy 371.089995 -256.440791) (xy 371.082052 -256.388087)
			(xy 370.853726 -256.388087) (xy 370.845783 -256.440791) (xy 370.830073 -256.491721) (xy 370.806947 -256.539742)
			(xy 370.776923 -256.583779) (xy 370.740671 -256.62285) (xy 370.699 -256.656081) (xy 370.652842 -256.68273)
			(xy 370.603228 -256.702202) (xy 370.551266 -256.714062) (xy 370.498116 -256.718046) (xy 370.444966 -256.714062)
			(xy 370.393004 -256.702202) (xy 370.34339 -256.68273) (xy 370.297232 -256.656081) (xy 370.255561 -256.62285)
			(xy 370.219309 -256.583779) (xy 370.189285 -256.539742) (xy 370.166159 -256.491721) (xy 370.150449 -256.440791)
			(xy 370.142506 -256.388087) (xy 369.912694 -256.388087) (xy 369.910711 -256.414551) (xy 369.898849 -256.466515)
			(xy 369.879375 -256.51613) (xy 369.852724 -256.562289) (xy 369.81949 -256.603959) (xy 369.780416 -256.64021)
			(xy 369.736375 -256.670232) (xy 369.688351 -256.693355) (xy 369.637418 -256.709061) (xy 369.584712 -256.717)
			(xy 369.558062 -256.717546) (xy 369.557554 -256.717546) (xy 369.531523 -256.717075) (xy 369.480021 -256.709458)
			(xy 369.430178 -256.694422) (xy 369.406424 -256.683764) (xy 369.392614 -256.677852) (xy 369.362904 -256.673519)
			(xy 369.333219 -256.678025) (xy 369.306133 -256.69098) (xy 369.283993 -256.711262) (xy 369.26872 -256.737111)
			(xy 369.264692 -256.751582) (xy 369.257012 -256.780405) (xy 369.233355 -256.835159) (xy 369.200883 -256.88519)
			(xy 369.181126 -256.907538) (xy 369.171325 -256.918984) (xy 369.158277 -256.946128) (xy 369.153717 -256.975898)
			(xy 369.158042 -257.005704) (xy 369.170876 -257.03295) (xy 369.180618 -257.044444) (xy 369.197788 -257.06417)
			(xy 369.226757 -257.107708) (xy 369.249048 -257.155014) (xy 369.263225 -257.201903) (xy 369.672606 -257.201903)
			(xy 369.672606 -257.148605) (xy 369.680549 -257.095901) (xy 369.696259 -257.044971) (xy 369.719385 -256.99695)
			(xy 369.749409 -256.952913) (xy 369.785661 -256.913842) (xy 369.827332 -256.880611) (xy 369.87349 -256.853962)
			(xy 369.923104 -256.83449) (xy 369.975066 -256.82263) (xy 370.028216 -256.818647) (xy 370.081366 -256.82263)
			(xy 370.133328 -256.83449) (xy 370.182942 -256.853962) (xy 370.2291 -256.880611) (xy 370.270771 -256.913842)
			(xy 370.307023 -256.952913) (xy 370.337047 -256.99695) (xy 370.360173 -257.044971) (xy 370.375883 -257.095901)
			(xy 370.383826 -257.148605) (xy 370.384324 -257.175254) (xy 370.383826 -257.201903) (xy 370.612406 -257.201903)
			(xy 370.612406 -257.148605) (xy 370.620349 -257.095901) (xy 370.636059 -257.044971) (xy 370.659185 -256.99695)
			(xy 370.689209 -256.952913) (xy 370.725461 -256.913842) (xy 370.767132 -256.880611) (xy 370.81329 -256.853962)
			(xy 370.862904 -256.83449) (xy 370.914866 -256.82263) (xy 370.968016 -256.818647) (xy 371.021166 -256.82263)
			(xy 371.073128 -256.83449) (xy 371.122742 -256.853962) (xy 371.1689 -256.880611) (xy 371.210571 -256.913842)
			(xy 371.246823 -256.952913) (xy 371.276847 -256.99695) (xy 371.299973 -257.044971) (xy 371.315683 -257.095901)
			(xy 371.323626 -257.148605) (xy 371.324124 -257.175254) (xy 371.323626 -257.201903) (xy 371.552206 -257.201903)
			(xy 371.552206 -257.148605) (xy 371.560149 -257.095901) (xy 371.575859 -257.044971) (xy 371.598985 -256.99695)
			(xy 371.629009 -256.952913) (xy 371.665261 -256.913842) (xy 371.706932 -256.880611) (xy 371.75309 -256.853962)
			(xy 371.802704 -256.83449) (xy 371.854666 -256.82263) (xy 371.907816 -256.818647) (xy 371.960966 -256.82263)
			(xy 372.012928 -256.83449) (xy 372.062542 -256.853962) (xy 372.1087 -256.880611) (xy 372.150371 -256.913842)
			(xy 372.186623 -256.952913) (xy 372.216647 -256.99695) (xy 372.239773 -257.044971) (xy 372.255483 -257.095901)
			(xy 372.263426 -257.148605) (xy 372.263924 -257.175254) (xy 372.263426 -257.201903) (xy 372.491752 -257.201903)
			(xy 372.491752 -257.148605) (xy 372.499695 -257.095901) (xy 372.515405 -257.044971) (xy 372.538531 -256.99695)
			(xy 372.568555 -256.952913) (xy 372.604807 -256.913842) (xy 372.646478 -256.880611) (xy 372.692636 -256.853962)
			(xy 372.74225 -256.83449) (xy 372.794212 -256.82263) (xy 372.847362 -256.818647) (xy 372.900512 -256.82263)
			(xy 372.952474 -256.83449) (xy 373.002088 -256.853962) (xy 373.048246 -256.880611) (xy 373.089917 -256.913842)
			(xy 373.126169 -256.952913) (xy 373.156193 -256.99695) (xy 373.179319 -257.044971) (xy 373.195029 -257.095901)
			(xy 373.202972 -257.148605) (xy 373.20347 -257.175254) (xy 373.202972 -257.201903) (xy 373.431552 -257.201903)
			(xy 373.431552 -257.148605) (xy 373.439495 -257.095901) (xy 373.455205 -257.044971) (xy 373.478331 -256.99695)
			(xy 373.508355 -256.952913) (xy 373.544607 -256.913842) (xy 373.586278 -256.880611) (xy 373.632436 -256.853962)
			(xy 373.68205 -256.83449) (xy 373.734012 -256.82263) (xy 373.787162 -256.818647) (xy 373.840312 -256.82263)
			(xy 373.892274 -256.83449) (xy 373.941888 -256.853962) (xy 373.988046 -256.880611) (xy 374.029717 -256.913842)
			(xy 374.065969 -256.952913) (xy 374.095993 -256.99695) (xy 374.119119 -257.044971) (xy 374.134829 -257.095901)
			(xy 374.142772 -257.148605) (xy 374.14327 -257.175254) (xy 374.142772 -257.201903) (xy 374.371606 -257.201903)
			(xy 374.371606 -257.148605) (xy 374.379549 -257.095901) (xy 374.395259 -257.044971) (xy 374.418385 -256.99695)
			(xy 374.448409 -256.952913) (xy 374.484661 -256.913842) (xy 374.526332 -256.880611) (xy 374.57249 -256.853962)
			(xy 374.622104 -256.83449) (xy 374.674066 -256.82263) (xy 374.727216 -256.818647) (xy 374.780366 -256.82263)
			(xy 374.832328 -256.83449) (xy 374.881942 -256.853962) (xy 374.9281 -256.880611) (xy 374.969771 -256.913842)
			(xy 375.006023 -256.952913) (xy 375.036047 -256.99695) (xy 375.059173 -257.044971) (xy 375.074883 -257.095901)
			(xy 375.082826 -257.148605) (xy 375.083324 -257.175254) (xy 375.082826 -257.201903) (xy 375.311152 -257.201903)
			(xy 375.311152 -257.148605) (xy 375.319095 -257.095901) (xy 375.334805 -257.044971) (xy 375.357931 -256.99695)
			(xy 375.387955 -256.952913) (xy 375.424207 -256.913842) (xy 375.465878 -256.880611) (xy 375.512036 -256.853962)
			(xy 375.56165 -256.83449) (xy 375.613612 -256.82263) (xy 375.666762 -256.818647) (xy 375.719912 -256.82263)
			(xy 375.771874 -256.83449) (xy 375.821488 -256.853962) (xy 375.867646 -256.880611) (xy 375.909317 -256.913842)
			(xy 375.945569 -256.952913) (xy 375.975593 -256.99695) (xy 375.998719 -257.044971) (xy 376.014429 -257.095901)
			(xy 376.022372 -257.148605) (xy 376.02287 -257.175254) (xy 376.022372 -257.201903) (xy 376.251206 -257.201903)
			(xy 376.251206 -257.148605) (xy 376.259149 -257.095901) (xy 376.274859 -257.044971) (xy 376.297985 -256.99695)
			(xy 376.328009 -256.952913) (xy 376.364261 -256.913842) (xy 376.405932 -256.880611) (xy 376.45209 -256.853962)
			(xy 376.501704 -256.83449) (xy 376.553666 -256.82263) (xy 376.606816 -256.818647) (xy 376.659966 -256.82263)
			(xy 376.711928 -256.83449) (xy 376.761542 -256.853962) (xy 376.8077 -256.880611) (xy 376.849371 -256.913842)
			(xy 376.885623 -256.952913) (xy 376.915647 -256.99695) (xy 376.938773 -257.044971) (xy 376.954483 -257.095901)
			(xy 376.962426 -257.148605) (xy 376.962924 -257.175254) (xy 376.962426 -257.201903) (xy 377.191006 -257.201903)
			(xy 377.191006 -257.148605) (xy 377.198949 -257.095901) (xy 377.214659 -257.044971) (xy 377.237785 -256.99695)
			(xy 377.267809 -256.952913) (xy 377.304061 -256.913842) (xy 377.345732 -256.880611) (xy 377.39189 -256.853962)
			(xy 377.441504 -256.83449) (xy 377.493466 -256.82263) (xy 377.546616 -256.818647) (xy 377.599766 -256.82263)
			(xy 377.651728 -256.83449) (xy 377.701342 -256.853962) (xy 377.7475 -256.880611) (xy 377.789171 -256.913842)
			(xy 377.825423 -256.952913) (xy 377.855447 -256.99695) (xy 377.878573 -257.044971) (xy 377.894283 -257.095901)
			(xy 377.902226 -257.148605) (xy 377.902724 -257.175254) (xy 377.902226 -257.201903) (xy 378.130806 -257.201903)
			(xy 378.130806 -257.148605) (xy 378.138749 -257.095901) (xy 378.154459 -257.044971) (xy 378.177585 -256.99695)
			(xy 378.207609 -256.952913) (xy 378.243861 -256.913842) (xy 378.285532 -256.880611) (xy 378.33169 -256.853962)
			(xy 378.381304 -256.83449) (xy 378.433266 -256.82263) (xy 378.486416 -256.818647) (xy 378.539566 -256.82263)
			(xy 378.591528 -256.83449) (xy 378.641142 -256.853962) (xy 378.6873 -256.880611) (xy 378.728971 -256.913842)
			(xy 378.765223 -256.952913) (xy 378.795247 -256.99695) (xy 378.818373 -257.044971) (xy 378.834083 -257.095901)
			(xy 378.842026 -257.148605) (xy 378.842524 -257.175254) (xy 378.842026 -257.201903) (xy 379.070606 -257.201903)
			(xy 379.070606 -257.148605) (xy 379.078549 -257.095901) (xy 379.094259 -257.044971) (xy 379.117385 -256.99695)
			(xy 379.147409 -256.952913) (xy 379.183661 -256.913842) (xy 379.225332 -256.880611) (xy 379.27149 -256.853962)
			(xy 379.321104 -256.83449) (xy 379.373066 -256.82263) (xy 379.426216 -256.818647) (xy 379.479366 -256.82263)
			(xy 379.531328 -256.83449) (xy 379.580942 -256.853962) (xy 379.6271 -256.880611) (xy 379.668771 -256.913842)
			(xy 379.705023 -256.952913) (xy 379.735047 -256.99695) (xy 379.758173 -257.044971) (xy 379.773883 -257.095901)
			(xy 379.781826 -257.148605) (xy 379.782324 -257.175254) (xy 379.781826 -257.201903) (xy 380.010152 -257.201903)
			(xy 380.010152 -257.148605) (xy 380.018095 -257.095901) (xy 380.033805 -257.044971) (xy 380.056931 -256.99695)
			(xy 380.086955 -256.952913) (xy 380.123207 -256.913842) (xy 380.164878 -256.880611) (xy 380.211036 -256.853962)
			(xy 380.26065 -256.83449) (xy 380.312612 -256.82263) (xy 380.365762 -256.818647) (xy 380.418912 -256.82263)
			(xy 380.470874 -256.83449) (xy 380.520488 -256.853962) (xy 380.566646 -256.880611) (xy 380.608317 -256.913842)
			(xy 380.644569 -256.952913) (xy 380.674593 -256.99695) (xy 380.697719 -257.044971) (xy 380.713429 -257.095901)
			(xy 380.721372 -257.148605) (xy 380.72187 -257.175254) (xy 380.721372 -257.201903) (xy 380.950206 -257.201903)
			(xy 380.950206 -257.148605) (xy 380.958149 -257.095901) (xy 380.973859 -257.044971) (xy 380.996985 -256.99695)
			(xy 381.027009 -256.952913) (xy 381.063261 -256.913842) (xy 381.104932 -256.880611) (xy 381.15109 -256.853962)
			(xy 381.200704 -256.83449) (xy 381.252666 -256.82263) (xy 381.305816 -256.818647) (xy 381.358966 -256.82263)
			(xy 381.410928 -256.83449) (xy 381.460542 -256.853962) (xy 381.5067 -256.880611) (xy 381.548371 -256.913842)
			(xy 381.584623 -256.952913) (xy 381.614647 -256.99695) (xy 381.637773 -257.044971) (xy 381.653483 -257.095901)
			(xy 381.661426 -257.148605) (xy 381.661924 -257.175254) (xy 381.661426 -257.201903) (xy 381.653483 -257.254607)
			(xy 381.637773 -257.305537) (xy 381.614647 -257.353558) (xy 381.584623 -257.397595) (xy 381.548371 -257.436666)
			(xy 381.5067 -257.469897) (xy 381.460542 -257.496546) (xy 381.410928 -257.516018) (xy 381.358966 -257.527878)
			(xy 381.305816 -257.531862) (xy 381.252666 -257.527878) (xy 381.200704 -257.516018) (xy 381.15109 -257.496546)
			(xy 381.104932 -257.469897) (xy 381.063261 -257.436666) (xy 381.027009 -257.397595) (xy 380.996985 -257.353558)
			(xy 380.973859 -257.305537) (xy 380.958149 -257.254607) (xy 380.950206 -257.201903) (xy 380.721372 -257.201903)
			(xy 380.713429 -257.254607) (xy 380.697719 -257.305537) (xy 380.674593 -257.353558) (xy 380.644569 -257.397595)
			(xy 380.608317 -257.436666) (xy 380.566646 -257.469897) (xy 380.520488 -257.496546) (xy 380.470874 -257.516018)
			(xy 380.418912 -257.527878) (xy 380.365762 -257.531862) (xy 380.312612 -257.527878) (xy 380.26065 -257.516018)
			(xy 380.211036 -257.496546) (xy 380.164878 -257.469897) (xy 380.123207 -257.436666) (xy 380.086955 -257.397595)
			(xy 380.056931 -257.353558) (xy 380.033805 -257.305537) (xy 380.018095 -257.254607) (xy 380.010152 -257.201903)
			(xy 379.781826 -257.201903) (xy 379.773883 -257.254607) (xy 379.758173 -257.305537) (xy 379.735047 -257.353558)
			(xy 379.705023 -257.397595) (xy 379.668771 -257.436666) (xy 379.6271 -257.469897) (xy 379.580942 -257.496546)
			(xy 379.531328 -257.516018) (xy 379.479366 -257.527878) (xy 379.426216 -257.531862) (xy 379.373066 -257.527878)
			(xy 379.321104 -257.516018) (xy 379.27149 -257.496546) (xy 379.225332 -257.469897) (xy 379.183661 -257.436666)
			(xy 379.147409 -257.397595) (xy 379.117385 -257.353558) (xy 379.094259 -257.305537) (xy 379.078549 -257.254607)
			(xy 379.070606 -257.201903) (xy 378.842026 -257.201903) (xy 378.834083 -257.254607) (xy 378.818373 -257.305537)
			(xy 378.795247 -257.353558) (xy 378.765223 -257.397595) (xy 378.728971 -257.436666) (xy 378.6873 -257.469897)
			(xy 378.641142 -257.496546) (xy 378.591528 -257.516018) (xy 378.539566 -257.527878) (xy 378.486416 -257.531862)
			(xy 378.433266 -257.527878) (xy 378.381304 -257.516018) (xy 378.33169 -257.496546) (xy 378.285532 -257.469897)
			(xy 378.243861 -257.436666) (xy 378.207609 -257.397595) (xy 378.177585 -257.353558) (xy 378.154459 -257.305537)
			(xy 378.138749 -257.254607) (xy 378.130806 -257.201903) (xy 377.902226 -257.201903) (xy 377.894283 -257.254607)
			(xy 377.878573 -257.305537) (xy 377.855447 -257.353558) (xy 377.825423 -257.397595) (xy 377.789171 -257.436666)
			(xy 377.7475 -257.469897) (xy 377.701342 -257.496546) (xy 377.651728 -257.516018) (xy 377.599766 -257.527878)
			(xy 377.546616 -257.531862) (xy 377.493466 -257.527878) (xy 377.441504 -257.516018) (xy 377.39189 -257.496546)
			(xy 377.345732 -257.469897) (xy 377.304061 -257.436666) (xy 377.267809 -257.397595) (xy 377.237785 -257.353558)
			(xy 377.214659 -257.305537) (xy 377.198949 -257.254607) (xy 377.191006 -257.201903) (xy 376.962426 -257.201903)
			(xy 376.954483 -257.254607) (xy 376.938773 -257.305537) (xy 376.915647 -257.353558) (xy 376.885623 -257.397595)
			(xy 376.849371 -257.436666) (xy 376.8077 -257.469897) (xy 376.761542 -257.496546) (xy 376.711928 -257.516018)
			(xy 376.659966 -257.527878) (xy 376.606816 -257.531862) (xy 376.553666 -257.527878) (xy 376.501704 -257.516018)
			(xy 376.45209 -257.496546) (xy 376.405932 -257.469897) (xy 376.364261 -257.436666) (xy 376.328009 -257.397595)
			(xy 376.297985 -257.353558) (xy 376.274859 -257.305537) (xy 376.259149 -257.254607) (xy 376.251206 -257.201903)
			(xy 376.022372 -257.201903) (xy 376.014429 -257.254607) (xy 375.998719 -257.305537) (xy 375.975593 -257.353558)
			(xy 375.945569 -257.397595) (xy 375.909317 -257.436666) (xy 375.867646 -257.469897) (xy 375.821488 -257.496546)
			(xy 375.771874 -257.516018) (xy 375.719912 -257.527878) (xy 375.666762 -257.531862) (xy 375.613612 -257.527878)
			(xy 375.56165 -257.516018) (xy 375.512036 -257.496546) (xy 375.465878 -257.469897) (xy 375.424207 -257.436666)
			(xy 375.387955 -257.397595) (xy 375.357931 -257.353558) (xy 375.334805 -257.305537) (xy 375.319095 -257.254607)
			(xy 375.311152 -257.201903) (xy 375.082826 -257.201903) (xy 375.074883 -257.254607) (xy 375.059173 -257.305537)
			(xy 375.036047 -257.353558) (xy 375.006023 -257.397595) (xy 374.969771 -257.436666) (xy 374.9281 -257.469897)
			(xy 374.881942 -257.496546) (xy 374.832328 -257.516018) (xy 374.780366 -257.527878) (xy 374.727216 -257.531862)
			(xy 374.674066 -257.527878) (xy 374.622104 -257.516018) (xy 374.57249 -257.496546) (xy 374.526332 -257.469897)
			(xy 374.484661 -257.436666) (xy 374.448409 -257.397595) (xy 374.418385 -257.353558) (xy 374.395259 -257.305537)
			(xy 374.379549 -257.254607) (xy 374.371606 -257.201903) (xy 374.142772 -257.201903) (xy 374.134829 -257.254607)
			(xy 374.119119 -257.305537) (xy 374.095993 -257.353558) (xy 374.065969 -257.397595) (xy 374.029717 -257.436666)
			(xy 373.988046 -257.469897) (xy 373.941888 -257.496546) (xy 373.892274 -257.516018) (xy 373.840312 -257.527878)
			(xy 373.787162 -257.531862) (xy 373.734012 -257.527878) (xy 373.68205 -257.516018) (xy 373.632436 -257.496546)
			(xy 373.586278 -257.469897) (xy 373.544607 -257.436666) (xy 373.508355 -257.397595) (xy 373.478331 -257.353558)
			(xy 373.455205 -257.305537) (xy 373.439495 -257.254607) (xy 373.431552 -257.201903) (xy 373.202972 -257.201903)
			(xy 373.195029 -257.254607) (xy 373.179319 -257.305537) (xy 373.156193 -257.353558) (xy 373.126169 -257.397595)
			(xy 373.089917 -257.436666) (xy 373.048246 -257.469897) (xy 373.002088 -257.496546) (xy 372.952474 -257.516018)
			(xy 372.900512 -257.527878) (xy 372.847362 -257.531862) (xy 372.794212 -257.527878) (xy 372.74225 -257.516018)
			(xy 372.692636 -257.496546) (xy 372.646478 -257.469897) (xy 372.604807 -257.436666) (xy 372.568555 -257.397595)
			(xy 372.538531 -257.353558) (xy 372.515405 -257.305537) (xy 372.499695 -257.254607) (xy 372.491752 -257.201903)
			(xy 372.263426 -257.201903) (xy 372.255483 -257.254607) (xy 372.239773 -257.305537) (xy 372.216647 -257.353558)
			(xy 372.186623 -257.397595) (xy 372.150371 -257.436666) (xy 372.1087 -257.469897) (xy 372.062542 -257.496546)
			(xy 372.012928 -257.516018) (xy 371.960966 -257.527878) (xy 371.907816 -257.531862) (xy 371.854666 -257.527878)
			(xy 371.802704 -257.516018) (xy 371.75309 -257.496546) (xy 371.706932 -257.469897) (xy 371.665261 -257.436666)
			(xy 371.629009 -257.397595) (xy 371.598985 -257.353558) (xy 371.575859 -257.305537) (xy 371.560149 -257.254607)
			(xy 371.552206 -257.201903) (xy 371.323626 -257.201903) (xy 371.315683 -257.254607) (xy 371.299973 -257.305537)
			(xy 371.276847 -257.353558) (xy 371.246823 -257.397595) (xy 371.210571 -257.436666) (xy 371.1689 -257.469897)
			(xy 371.122742 -257.496546) (xy 371.073128 -257.516018) (xy 371.021166 -257.527878) (xy 370.968016 -257.531862)
			(xy 370.914866 -257.527878) (xy 370.862904 -257.516018) (xy 370.81329 -257.496546) (xy 370.767132 -257.469897)
			(xy 370.725461 -257.436666) (xy 370.689209 -257.397595) (xy 370.659185 -257.353558) (xy 370.636059 -257.305537)
			(xy 370.620349 -257.254607) (xy 370.612406 -257.201903) (xy 370.383826 -257.201903) (xy 370.375883 -257.254607)
			(xy 370.360173 -257.305537) (xy 370.337047 -257.353558) (xy 370.307023 -257.397595) (xy 370.270771 -257.436666)
			(xy 370.2291 -257.469897) (xy 370.182942 -257.496546) (xy 370.133328 -257.516018) (xy 370.081366 -257.527878)
			(xy 370.028216 -257.531862) (xy 369.975066 -257.527878) (xy 369.923104 -257.516018) (xy 369.87349 -257.496546)
			(xy 369.827332 -257.469897) (xy 369.785661 -257.436666) (xy 369.749409 -257.397595) (xy 369.719385 -257.353558)
			(xy 369.696259 -257.305537) (xy 369.680549 -257.254607) (xy 369.672606 -257.201903) (xy 369.263225 -257.201903)
			(xy 369.264183 -257.205071) (xy 369.271837 -257.256803) (xy 369.272312 -257.28295) (xy 369.271849 -257.308769)
			(xy 369.264388 -257.359866) (xy 369.249629 -257.40935) (xy 369.227882 -257.456186) (xy 369.199601 -257.499392)
			(xy 369.16538 -257.538062) (xy 369.125934 -257.571388) (xy 369.082092 -257.598671) (xy 369.03477 -257.61934)
			(xy 368.98496 -257.632961) (xy 368.959384 -257.636518) (xy 368.91468 -257.641852) (xy 368.91468 -258.092448)
			(xy 368.959384 -258.097782) (xy 368.985665 -258.101459) (xy 369.03681 -258.115608) (xy 369.061238 -258.125976)
			(xy 369.075324 -258.131643) (xy 369.105447 -258.135312) (xy 369.135319 -258.129971) (xy 369.162303 -258.116089)
			(xy 369.184019 -258.094893) (xy 369.19855 -258.068252) (xy 369.204613 -258.038519) (xy 369.203732 -258.02336)
			(xy 369.201954 -257.98907) (xy 369.202462 -257.961987) (xy 369.210669 -257.908446) (xy 369.226889 -257.856765)
			(xy 369.250747 -257.808136) (xy 369.281695 -257.763681) (xy 369.319017 -257.724425) (xy 369.361854 -257.691273)
			(xy 369.409216 -257.66499) (xy 369.460012 -257.646183) (xy 369.513071 -257.635284) (xy 369.567168 -257.632545)
			(xy 369.621056 -257.63803) (xy 369.673492 -257.651612) (xy 369.723267 -257.672977) (xy 369.769232 -257.701634)
			(xy 369.810328 -257.73692) (xy 369.845606 -257.778023) (xy 369.874254 -257.823994) (xy 369.89561 -257.873772)
			(xy 369.909182 -257.926211) (xy 369.914656 -257.9801) (xy 369.912847 -258.015719) (xy 370.142252 -258.015719)
			(xy 370.142252 -257.962421) (xy 370.150195 -257.909717) (xy 370.165905 -257.858787) (xy 370.189031 -257.810766)
			(xy 370.219055 -257.766729) (xy 370.255307 -257.727658) (xy 370.296978 -257.694427) (xy 370.343136 -257.667778)
			(xy 370.39275 -257.648306) (xy 370.444712 -257.636446) (xy 370.497862 -257.632463) (xy 370.551012 -257.636446)
			(xy 370.602974 -257.648306) (xy 370.652588 -257.667778) (xy 370.698746 -257.694427) (xy 370.740417 -257.727658)
			(xy 370.776669 -257.766729) (xy 370.806693 -257.810766) (xy 370.829819 -257.858787) (xy 370.845529 -257.909717)
			(xy 370.853472 -257.962421) (xy 370.85397 -257.98907) (xy 370.853472 -258.015719) (xy 371.082052 -258.015719)
			(xy 371.082052 -257.962421) (xy 371.089995 -257.909717) (xy 371.105705 -257.858787) (xy 371.128831 -257.810766)
			(xy 371.158855 -257.766729) (xy 371.195107 -257.727658) (xy 371.236778 -257.694427) (xy 371.282936 -257.667778)
			(xy 371.33255 -257.648306) (xy 371.384512 -257.636446) (xy 371.437662 -257.632463) (xy 371.490812 -257.636446)
			(xy 371.542774 -257.648306) (xy 371.592388 -257.667778) (xy 371.638546 -257.694427) (xy 371.680217 -257.727658)
			(xy 371.716469 -257.766729) (xy 371.746493 -257.810766) (xy 371.769619 -257.858787) (xy 371.785329 -257.909717)
			(xy 371.793272 -257.962421) (xy 371.79377 -257.98907) (xy 371.793272 -258.015719) (xy 372.021852 -258.015719)
			(xy 372.021852 -257.962421) (xy 372.029795 -257.909717) (xy 372.045505 -257.858787) (xy 372.068631 -257.810766)
			(xy 372.098655 -257.766729) (xy 372.134907 -257.727658) (xy 372.176578 -257.694427) (xy 372.222736 -257.667778)
			(xy 372.27235 -257.648306) (xy 372.324312 -257.636446) (xy 372.377462 -257.632463) (xy 372.430612 -257.636446)
			(xy 372.482574 -257.648306) (xy 372.532188 -257.667778) (xy 372.578346 -257.694427) (xy 372.620017 -257.727658)
			(xy 372.656269 -257.766729) (xy 372.686293 -257.810766) (xy 372.709419 -257.858787) (xy 372.725129 -257.909717)
			(xy 372.733072 -257.962421) (xy 372.73357 -257.98907) (xy 372.733072 -258.015719) (xy 372.961906 -258.015719)
			(xy 372.961906 -257.962421) (xy 372.969849 -257.909717) (xy 372.985559 -257.858787) (xy 373.008685 -257.810766)
			(xy 373.038709 -257.766729) (xy 373.074961 -257.727658) (xy 373.116632 -257.694427) (xy 373.16279 -257.667778)
			(xy 373.212404 -257.648306) (xy 373.264366 -257.636446) (xy 373.317516 -257.632463) (xy 373.370666 -257.636446)
			(xy 373.422628 -257.648306) (xy 373.472242 -257.667778) (xy 373.5184 -257.694427) (xy 373.560071 -257.727658)
			(xy 373.596323 -257.766729) (xy 373.626347 -257.810766) (xy 373.649473 -257.858787) (xy 373.665183 -257.909717)
			(xy 373.673126 -257.962421) (xy 373.673624 -257.98907) (xy 373.673126 -258.015719) (xy 373.901452 -258.015719)
			(xy 373.901452 -257.962421) (xy 373.909395 -257.909717) (xy 373.925105 -257.858787) (xy 373.948231 -257.810766)
			(xy 373.978255 -257.766729) (xy 374.014507 -257.727658) (xy 374.056178 -257.694427) (xy 374.102336 -257.667778)
			(xy 374.15195 -257.648306) (xy 374.203912 -257.636446) (xy 374.257062 -257.632463) (xy 374.310212 -257.636446)
			(xy 374.362174 -257.648306) (xy 374.411788 -257.667778) (xy 374.457946 -257.694427) (xy 374.499617 -257.727658)
			(xy 374.535869 -257.766729) (xy 374.565893 -257.810766) (xy 374.589019 -257.858787) (xy 374.604729 -257.909717)
			(xy 374.612672 -257.962421) (xy 374.61317 -257.98907) (xy 374.612672 -258.015719) (xy 374.841506 -258.015719)
			(xy 374.841506 -257.962421) (xy 374.849449 -257.909717) (xy 374.865159 -257.858787) (xy 374.888285 -257.810766)
			(xy 374.918309 -257.766729) (xy 374.954561 -257.727658) (xy 374.996232 -257.694427) (xy 375.04239 -257.667778)
			(xy 375.092004 -257.648306) (xy 375.143966 -257.636446) (xy 375.197116 -257.632463) (xy 375.250266 -257.636446)
			(xy 375.302228 -257.648306) (xy 375.351842 -257.667778) (xy 375.398 -257.694427) (xy 375.439671 -257.727658)
			(xy 375.475923 -257.766729) (xy 375.505947 -257.810766) (xy 375.529073 -257.858787) (xy 375.544783 -257.909717)
			(xy 375.552726 -257.962421) (xy 375.553224 -257.98907) (xy 375.552726 -258.015719) (xy 375.781052 -258.015719)
			(xy 375.781052 -257.962421) (xy 375.788995 -257.909717) (xy 375.804705 -257.858787) (xy 375.827831 -257.810766)
			(xy 375.857855 -257.766729) (xy 375.894107 -257.727658) (xy 375.935778 -257.694427) (xy 375.981936 -257.667778)
			(xy 376.03155 -257.648306) (xy 376.083512 -257.636446) (xy 376.136662 -257.632463) (xy 376.189812 -257.636446)
			(xy 376.241774 -257.648306) (xy 376.291388 -257.667778) (xy 376.337546 -257.694427) (xy 376.379217 -257.727658)
			(xy 376.415469 -257.766729) (xy 376.445493 -257.810766) (xy 376.468619 -257.858787) (xy 376.484329 -257.909717)
			(xy 376.492272 -257.962421) (xy 376.49277 -257.98907) (xy 376.492272 -258.015719) (xy 376.720852 -258.015719)
			(xy 376.720852 -257.962421) (xy 376.728795 -257.909717) (xy 376.744505 -257.858787) (xy 376.767631 -257.810766)
			(xy 376.797655 -257.766729) (xy 376.833907 -257.727658) (xy 376.875578 -257.694427) (xy 376.921736 -257.667778)
			(xy 376.97135 -257.648306) (xy 377.023312 -257.636446) (xy 377.076462 -257.632463) (xy 377.129612 -257.636446)
			(xy 377.181574 -257.648306) (xy 377.231188 -257.667778) (xy 377.277346 -257.694427) (xy 377.319017 -257.727658)
			(xy 377.355269 -257.766729) (xy 377.385293 -257.810766) (xy 377.408419 -257.858787) (xy 377.424129 -257.909717)
			(xy 377.432072 -257.962421) (xy 377.43257 -257.98907) (xy 377.432072 -258.015719) (xy 377.660652 -258.015719)
			(xy 377.660652 -257.962421) (xy 377.668595 -257.909717) (xy 377.684305 -257.858787) (xy 377.707431 -257.810766)
			(xy 377.737455 -257.766729) (xy 377.773707 -257.727658) (xy 377.815378 -257.694427) (xy 377.861536 -257.667778)
			(xy 377.91115 -257.648306) (xy 377.963112 -257.636446) (xy 378.016262 -257.632463) (xy 378.069412 -257.636446)
			(xy 378.121374 -257.648306) (xy 378.170988 -257.667778) (xy 378.217146 -257.694427) (xy 378.258817 -257.727658)
			(xy 378.295069 -257.766729) (xy 378.325093 -257.810766) (xy 378.348219 -257.858787) (xy 378.363929 -257.909717)
			(xy 378.371872 -257.962421) (xy 378.37237 -257.98907) (xy 378.371872 -258.015719) (xy 378.600452 -258.015719)
			(xy 378.600452 -257.962421) (xy 378.608395 -257.909717) (xy 378.624105 -257.858787) (xy 378.647231 -257.810766)
			(xy 378.677255 -257.766729) (xy 378.713507 -257.727658) (xy 378.755178 -257.694427) (xy 378.801336 -257.667778)
			(xy 378.85095 -257.648306) (xy 378.902912 -257.636446) (xy 378.956062 -257.632463) (xy 379.009212 -257.636446)
			(xy 379.061174 -257.648306) (xy 379.110788 -257.667778) (xy 379.156946 -257.694427) (xy 379.198617 -257.727658)
			(xy 379.234869 -257.766729) (xy 379.264893 -257.810766) (xy 379.288019 -257.858787) (xy 379.303729 -257.909717)
			(xy 379.311672 -257.962421) (xy 379.31217 -257.98907) (xy 379.311672 -258.015719) (xy 379.540506 -258.015719)
			(xy 379.540506 -257.962421) (xy 379.548449 -257.909717) (xy 379.564159 -257.858787) (xy 379.587285 -257.810766)
			(xy 379.617309 -257.766729) (xy 379.653561 -257.727658) (xy 379.695232 -257.694427) (xy 379.74139 -257.667778)
			(xy 379.791004 -257.648306) (xy 379.842966 -257.636446) (xy 379.896116 -257.632463) (xy 379.949266 -257.636446)
			(xy 380.001228 -257.648306) (xy 380.050842 -257.667778) (xy 380.097 -257.694427) (xy 380.138671 -257.727658)
			(xy 380.174923 -257.766729) (xy 380.204947 -257.810766) (xy 380.228073 -257.858787) (xy 380.243783 -257.909717)
			(xy 380.251726 -257.962421) (xy 380.252224 -257.98907) (xy 380.251726 -258.015719) (xy 380.480052 -258.015719)
			(xy 380.480052 -257.962421) (xy 380.487995 -257.909717) (xy 380.503705 -257.858787) (xy 380.526831 -257.810766)
			(xy 380.556855 -257.766729) (xy 380.593107 -257.727658) (xy 380.634778 -257.694427) (xy 380.680936 -257.667778)
			(xy 380.73055 -257.648306) (xy 380.782512 -257.636446) (xy 380.835662 -257.632463) (xy 380.888812 -257.636446)
			(xy 380.940774 -257.648306) (xy 380.990388 -257.667778) (xy 381.036546 -257.694427) (xy 381.078217 -257.727658)
			(xy 381.114469 -257.766729) (xy 381.144493 -257.810766) (xy 381.167619 -257.858787) (xy 381.183329 -257.909717)
			(xy 381.191272 -257.962421) (xy 381.19177 -257.98907) (xy 381.191272 -258.015719) (xy 381.183329 -258.068423)
			(xy 381.167619 -258.119353) (xy 381.144493 -258.167374) (xy 381.114469 -258.211411) (xy 381.078217 -258.250482)
			(xy 381.036546 -258.283713) (xy 380.990388 -258.310362) (xy 380.940774 -258.329834) (xy 380.888812 -258.341694)
			(xy 380.835662 -258.345678) (xy 380.782512 -258.341694) (xy 380.73055 -258.329834) (xy 380.680936 -258.310362)
			(xy 380.634778 -258.283713) (xy 380.593107 -258.250482) (xy 380.556855 -258.211411) (xy 380.526831 -258.167374)
			(xy 380.503705 -258.119353) (xy 380.487995 -258.068423) (xy 380.480052 -258.015719) (xy 380.251726 -258.015719)
			(xy 380.243783 -258.068423) (xy 380.228073 -258.119353) (xy 380.204947 -258.167374) (xy 380.174923 -258.211411)
			(xy 380.138671 -258.250482) (xy 380.097 -258.283713) (xy 380.050842 -258.310362) (xy 380.001228 -258.329834)
			(xy 379.949266 -258.341694) (xy 379.896116 -258.345678) (xy 379.842966 -258.341694) (xy 379.791004 -258.329834)
			(xy 379.74139 -258.310362) (xy 379.695232 -258.283713) (xy 379.653561 -258.250482) (xy 379.617309 -258.211411)
			(xy 379.587285 -258.167374) (xy 379.564159 -258.119353) (xy 379.548449 -258.068423) (xy 379.540506 -258.015719)
			(xy 379.311672 -258.015719) (xy 379.303729 -258.068423) (xy 379.288019 -258.119353) (xy 379.264893 -258.167374)
			(xy 379.234869 -258.211411) (xy 379.198617 -258.250482) (xy 379.156946 -258.283713) (xy 379.110788 -258.310362)
			(xy 379.061174 -258.329834) (xy 379.009212 -258.341694) (xy 378.956062 -258.345678) (xy 378.902912 -258.341694)
			(xy 378.85095 -258.329834) (xy 378.801336 -258.310362) (xy 378.755178 -258.283713) (xy 378.713507 -258.250482)
			(xy 378.677255 -258.211411) (xy 378.647231 -258.167374) (xy 378.624105 -258.119353) (xy 378.608395 -258.068423)
			(xy 378.600452 -258.015719) (xy 378.371872 -258.015719) (xy 378.363929 -258.068423) (xy 378.348219 -258.119353)
			(xy 378.325093 -258.167374) (xy 378.295069 -258.211411) (xy 378.258817 -258.250482) (xy 378.217146 -258.283713)
			(xy 378.170988 -258.310362) (xy 378.121374 -258.329834) (xy 378.069412 -258.341694) (xy 378.016262 -258.345678)
			(xy 377.963112 -258.341694) (xy 377.91115 -258.329834) (xy 377.861536 -258.310362) (xy 377.815378 -258.283713)
			(xy 377.773707 -258.250482) (xy 377.737455 -258.211411) (xy 377.707431 -258.167374) (xy 377.684305 -258.119353)
			(xy 377.668595 -258.068423) (xy 377.660652 -258.015719) (xy 377.432072 -258.015719) (xy 377.424129 -258.068423)
			(xy 377.408419 -258.119353) (xy 377.385293 -258.167374) (xy 377.355269 -258.211411) (xy 377.319017 -258.250482)
			(xy 377.277346 -258.283713) (xy 377.231188 -258.310362) (xy 377.181574 -258.329834) (xy 377.129612 -258.341694)
			(xy 377.076462 -258.345678) (xy 377.023312 -258.341694) (xy 376.97135 -258.329834) (xy 376.921736 -258.310362)
			(xy 376.875578 -258.283713) (xy 376.833907 -258.250482) (xy 376.797655 -258.211411) (xy 376.767631 -258.167374)
			(xy 376.744505 -258.119353) (xy 376.728795 -258.068423) (xy 376.720852 -258.015719) (xy 376.492272 -258.015719)
			(xy 376.484329 -258.068423) (xy 376.468619 -258.119353) (xy 376.445493 -258.167374) (xy 376.415469 -258.211411)
			(xy 376.379217 -258.250482) (xy 376.337546 -258.283713) (xy 376.291388 -258.310362) (xy 376.241774 -258.329834)
			(xy 376.189812 -258.341694) (xy 376.136662 -258.345678) (xy 376.083512 -258.341694) (xy 376.03155 -258.329834)
			(xy 375.981936 -258.310362) (xy 375.935778 -258.283713) (xy 375.894107 -258.250482) (xy 375.857855 -258.211411)
			(xy 375.827831 -258.167374) (xy 375.804705 -258.119353) (xy 375.788995 -258.068423) (xy 375.781052 -258.015719)
			(xy 375.552726 -258.015719) (xy 375.544783 -258.068423) (xy 375.529073 -258.119353) (xy 375.505947 -258.167374)
			(xy 375.475923 -258.211411) (xy 375.439671 -258.250482) (xy 375.398 -258.283713) (xy 375.351842 -258.310362)
			(xy 375.302228 -258.329834) (xy 375.250266 -258.341694) (xy 375.197116 -258.345678) (xy 375.143966 -258.341694)
			(xy 375.092004 -258.329834) (xy 375.04239 -258.310362) (xy 374.996232 -258.283713) (xy 374.954561 -258.250482)
			(xy 374.918309 -258.211411) (xy 374.888285 -258.167374) (xy 374.865159 -258.119353) (xy 374.849449 -258.068423)
			(xy 374.841506 -258.015719) (xy 374.612672 -258.015719) (xy 374.604729 -258.068423) (xy 374.589019 -258.119353)
			(xy 374.565893 -258.167374) (xy 374.535869 -258.211411) (xy 374.499617 -258.250482) (xy 374.457946 -258.283713)
			(xy 374.411788 -258.310362) (xy 374.362174 -258.329834) (xy 374.310212 -258.341694) (xy 374.257062 -258.345678)
			(xy 374.203912 -258.341694) (xy 374.15195 -258.329834) (xy 374.102336 -258.310362) (xy 374.056178 -258.283713)
			(xy 374.014507 -258.250482) (xy 373.978255 -258.211411) (xy 373.948231 -258.167374) (xy 373.925105 -258.119353)
			(xy 373.909395 -258.068423) (xy 373.901452 -258.015719) (xy 373.673126 -258.015719) (xy 373.665183 -258.068423)
			(xy 373.649473 -258.119353) (xy 373.626347 -258.167374) (xy 373.596323 -258.211411) (xy 373.560071 -258.250482)
			(xy 373.5184 -258.283713) (xy 373.472242 -258.310362) (xy 373.422628 -258.329834) (xy 373.370666 -258.341694)
			(xy 373.317516 -258.345678) (xy 373.264366 -258.341694) (xy 373.212404 -258.329834) (xy 373.16279 -258.310362)
			(xy 373.116632 -258.283713) (xy 373.074961 -258.250482) (xy 373.038709 -258.211411) (xy 373.008685 -258.167374)
			(xy 372.985559 -258.119353) (xy 372.969849 -258.068423) (xy 372.961906 -258.015719) (xy 372.733072 -258.015719)
			(xy 372.725129 -258.068423) (xy 372.709419 -258.119353) (xy 372.686293 -258.167374) (xy 372.656269 -258.211411)
			(xy 372.620017 -258.250482) (xy 372.578346 -258.283713) (xy 372.532188 -258.310362) (xy 372.482574 -258.329834)
			(xy 372.430612 -258.341694) (xy 372.377462 -258.345678) (xy 372.324312 -258.341694) (xy 372.27235 -258.329834)
			(xy 372.222736 -258.310362) (xy 372.176578 -258.283713) (xy 372.134907 -258.250482) (xy 372.098655 -258.211411)
			(xy 372.068631 -258.167374) (xy 372.045505 -258.119353) (xy 372.029795 -258.068423) (xy 372.021852 -258.015719)
			(xy 371.793272 -258.015719) (xy 371.785329 -258.068423) (xy 371.769619 -258.119353) (xy 371.746493 -258.167374)
			(xy 371.716469 -258.211411) (xy 371.680217 -258.250482) (xy 371.638546 -258.283713) (xy 371.592388 -258.310362)
			(xy 371.542774 -258.329834) (xy 371.490812 -258.341694) (xy 371.437662 -258.345678) (xy 371.384512 -258.341694)
			(xy 371.33255 -258.329834) (xy 371.282936 -258.310362) (xy 371.236778 -258.283713) (xy 371.195107 -258.250482)
			(xy 371.158855 -258.211411) (xy 371.128831 -258.167374) (xy 371.105705 -258.119353) (xy 371.089995 -258.068423)
			(xy 371.082052 -258.015719) (xy 370.853472 -258.015719) (xy 370.845529 -258.068423) (xy 370.829819 -258.119353)
			(xy 370.806693 -258.167374) (xy 370.776669 -258.211411) (xy 370.740417 -258.250482) (xy 370.698746 -258.283713)
			(xy 370.652588 -258.310362) (xy 370.602974 -258.329834) (xy 370.551012 -258.341694) (xy 370.497862 -258.345678)
			(xy 370.444712 -258.341694) (xy 370.39275 -258.329834) (xy 370.343136 -258.310362) (xy 370.296978 -258.283713)
			(xy 370.255307 -258.250482) (xy 370.219055 -258.211411) (xy 370.189031 -258.167374) (xy 370.165905 -258.119353)
			(xy 370.150195 -258.068423) (xy 370.142252 -258.015719) (xy 369.912847 -258.015719) (xy 369.911908 -258.034197)
			(xy 369.900999 -258.087253) (xy 369.882181 -258.138046) (xy 369.855889 -258.185403) (xy 369.822729 -258.228233)
			(xy 369.783466 -258.265548) (xy 369.739005 -258.296487) (xy 369.690372 -258.320337) (xy 369.638688 -258.336547)
			(xy 369.585145 -258.344743) (xy 369.558062 -258.345178) (xy 369.557554 -258.345178) (xy 369.532739 -258.344726)
			(xy 369.483593 -258.337797) (xy 369.435883 -258.324122) (xy 369.413028 -258.314444) (xy 369.398938 -258.308765)
			(xy 369.368801 -258.305078) (xy 369.338912 -258.31041) (xy 369.311909 -258.324292) (xy 369.290179 -258.345496)
			(xy 369.27564 -258.37215) (xy 369.269577 -258.4019) (xy 369.270534 -258.41706) (xy 369.272312 -258.45135)
			(xy 369.271849 -258.477169) (xy 369.264388 -258.528266) (xy 369.249629 -258.57775) (xy 369.227882 -258.624586)
			(xy 369.199601 -258.667792) (xy 369.16538 -258.706462) (xy 369.125934 -258.739788) (xy 369.082092 -258.767071)
			(xy 369.03477 -258.78774) (xy 368.98496 -258.801361) (xy 368.959384 -258.804918) (xy 368.91468 -258.810252)
			(xy 368.91468 -258.829789) (xy 369.672352 -258.829789) (xy 369.672352 -258.776491) (xy 369.680295 -258.723787)
			(xy 369.696005 -258.672857) (xy 369.719131 -258.624836) (xy 369.749155 -258.580799) (xy 369.785407 -258.541728)
			(xy 369.827078 -258.508497) (xy 369.873236 -258.481848) (xy 369.92285 -258.462376) (xy 369.974812 -258.450516)
			(xy 370.027962 -258.446533) (xy 370.081112 -258.450516) (xy 370.133074 -258.462376) (xy 370.182688 -258.481848)
			(xy 370.228846 -258.508497) (xy 370.270517 -258.541728) (xy 370.306769 -258.580799) (xy 370.336793 -258.624836)
			(xy 370.359919 -258.672857) (xy 370.375629 -258.723787) (xy 370.383572 -258.776491) (xy 370.38407 -258.80314)
			(xy 370.383572 -258.829789) (xy 370.612152 -258.829789) (xy 370.612152 -258.776491) (xy 370.620095 -258.723787)
			(xy 370.635805 -258.672857) (xy 370.658931 -258.624836) (xy 370.688955 -258.580799) (xy 370.725207 -258.541728)
			(xy 370.766878 -258.508497) (xy 370.813036 -258.481848) (xy 370.86265 -258.462376) (xy 370.914612 -258.450516)
			(xy 370.967762 -258.446533) (xy 371.020912 -258.450516) (xy 371.072874 -258.462376) (xy 371.122488 -258.481848)
			(xy 371.168646 -258.508497) (xy 371.210317 -258.541728) (xy 371.246569 -258.580799) (xy 371.276593 -258.624836)
			(xy 371.299719 -258.672857) (xy 371.315429 -258.723787) (xy 371.323372 -258.776491) (xy 371.32387 -258.80314)
			(xy 371.323372 -258.829789) (xy 371.552206 -258.829789) (xy 371.552206 -258.776491) (xy 371.560149 -258.723787)
			(xy 371.575859 -258.672857) (xy 371.598985 -258.624836) (xy 371.629009 -258.580799) (xy 371.665261 -258.541728)
			(xy 371.706932 -258.508497) (xy 371.75309 -258.481848) (xy 371.802704 -258.462376) (xy 371.854666 -258.450516)
			(xy 371.907816 -258.446533) (xy 371.960966 -258.450516) (xy 372.012928 -258.462376) (xy 372.062542 -258.481848)
			(xy 372.1087 -258.508497) (xy 372.150371 -258.541728) (xy 372.186623 -258.580799) (xy 372.216647 -258.624836)
			(xy 372.239773 -258.672857) (xy 372.255483 -258.723787) (xy 372.263426 -258.776491) (xy 372.263924 -258.80314)
			(xy 372.263426 -258.829789) (xy 372.492006 -258.829789) (xy 372.492006 -258.776491) (xy 372.499949 -258.723787)
			(xy 372.515659 -258.672857) (xy 372.538785 -258.624836) (xy 372.568809 -258.580799) (xy 372.605061 -258.541728)
			(xy 372.646732 -258.508497) (xy 372.69289 -258.481848) (xy 372.742504 -258.462376) (xy 372.794466 -258.450516)
			(xy 372.847616 -258.446533) (xy 372.900766 -258.450516) (xy 372.952728 -258.462376) (xy 373.002342 -258.481848)
			(xy 373.0485 -258.508497) (xy 373.090171 -258.541728) (xy 373.126423 -258.580799) (xy 373.156447 -258.624836)
			(xy 373.179573 -258.672857) (xy 373.195283 -258.723787) (xy 373.203226 -258.776491) (xy 373.203724 -258.80314)
			(xy 373.203226 -258.829789) (xy 373.431806 -258.829789) (xy 373.431806 -258.776491) (xy 373.439749 -258.723787)
			(xy 373.455459 -258.672857) (xy 373.478585 -258.624836) (xy 373.508609 -258.580799) (xy 373.544861 -258.541728)
			(xy 373.586532 -258.508497) (xy 373.63269 -258.481848) (xy 373.682304 -258.462376) (xy 373.734266 -258.450516)
			(xy 373.787416 -258.446533) (xy 373.840566 -258.450516) (xy 373.892528 -258.462376) (xy 373.942142 -258.481848)
			(xy 373.9883 -258.508497) (xy 374.029971 -258.541728) (xy 374.066223 -258.580799) (xy 374.096247 -258.624836)
			(xy 374.119373 -258.672857) (xy 374.135083 -258.723787) (xy 374.143026 -258.776491) (xy 374.143524 -258.80314)
			(xy 374.143026 -258.829789) (xy 374.371606 -258.829789) (xy 374.371606 -258.776491) (xy 374.379549 -258.723787)
			(xy 374.395259 -258.672857) (xy 374.418385 -258.624836) (xy 374.448409 -258.580799) (xy 374.484661 -258.541728)
			(xy 374.526332 -258.508497) (xy 374.57249 -258.481848) (xy 374.622104 -258.462376) (xy 374.674066 -258.450516)
			(xy 374.727216 -258.446533) (xy 374.780366 -258.450516) (xy 374.832328 -258.462376) (xy 374.881942 -258.481848)
			(xy 374.9281 -258.508497) (xy 374.969771 -258.541728) (xy 375.006023 -258.580799) (xy 375.036047 -258.624836)
			(xy 375.059173 -258.672857) (xy 375.074883 -258.723787) (xy 375.082826 -258.776491) (xy 375.083324 -258.80314)
			(xy 375.082826 -258.829789) (xy 375.311406 -258.829789) (xy 375.311406 -258.776491) (xy 375.319349 -258.723787)
			(xy 375.335059 -258.672857) (xy 375.358185 -258.624836) (xy 375.388209 -258.580799) (xy 375.424461 -258.541728)
			(xy 375.466132 -258.508497) (xy 375.51229 -258.481848) (xy 375.561904 -258.462376) (xy 375.613866 -258.450516)
			(xy 375.667016 -258.446533) (xy 375.720166 -258.450516) (xy 375.772128 -258.462376) (xy 375.821742 -258.481848)
			(xy 375.8679 -258.508497) (xy 375.909571 -258.541728) (xy 375.945823 -258.580799) (xy 375.975847 -258.624836)
			(xy 375.998973 -258.672857) (xy 376.014683 -258.723787) (xy 376.022626 -258.776491) (xy 376.023124 -258.80314)
			(xy 376.022626 -258.829789) (xy 376.251206 -258.829789) (xy 376.251206 -258.776491) (xy 376.259149 -258.723787)
			(xy 376.274859 -258.672857) (xy 376.297985 -258.624836) (xy 376.328009 -258.580799) (xy 376.364261 -258.541728)
			(xy 376.405932 -258.508497) (xy 376.45209 -258.481848) (xy 376.501704 -258.462376) (xy 376.553666 -258.450516)
			(xy 376.606816 -258.446533) (xy 376.659966 -258.450516) (xy 376.711928 -258.462376) (xy 376.761542 -258.481848)
			(xy 376.8077 -258.508497) (xy 376.849371 -258.541728) (xy 376.885623 -258.580799) (xy 376.915647 -258.624836)
			(xy 376.938773 -258.672857) (xy 376.954483 -258.723787) (xy 376.962426 -258.776491) (xy 376.962924 -258.80314)
			(xy 376.962426 -258.829789) (xy 377.190752 -258.829789) (xy 377.190752 -258.776491) (xy 377.198695 -258.723787)
			(xy 377.214405 -258.672857) (xy 377.237531 -258.624836) (xy 377.267555 -258.580799) (xy 377.303807 -258.541728)
			(xy 377.345478 -258.508497) (xy 377.391636 -258.481848) (xy 377.44125 -258.462376) (xy 377.493212 -258.450516)
			(xy 377.546362 -258.446533) (xy 377.599512 -258.450516) (xy 377.651474 -258.462376) (xy 377.701088 -258.481848)
			(xy 377.747246 -258.508497) (xy 377.788917 -258.541728) (xy 377.825169 -258.580799) (xy 377.855193 -258.624836)
			(xy 377.878319 -258.672857) (xy 377.894029 -258.723787) (xy 377.901972 -258.776491) (xy 377.90247 -258.80314)
			(xy 377.901972 -258.829789) (xy 378.130806 -258.829789) (xy 378.130806 -258.776491) (xy 378.138749 -258.723787)
			(xy 378.154459 -258.672857) (xy 378.177585 -258.624836) (xy 378.207609 -258.580799) (xy 378.243861 -258.541728)
			(xy 378.285532 -258.508497) (xy 378.33169 -258.481848) (xy 378.381304 -258.462376) (xy 378.433266 -258.450516)
			(xy 378.486416 -258.446533) (xy 378.539566 -258.450516) (xy 378.591528 -258.462376) (xy 378.641142 -258.481848)
			(xy 378.6873 -258.508497) (xy 378.728971 -258.541728) (xy 378.765223 -258.580799) (xy 378.795247 -258.624836)
			(xy 378.818373 -258.672857) (xy 378.834083 -258.723787) (xy 378.842026 -258.776491) (xy 378.842524 -258.80314)
			(xy 378.842026 -258.829789) (xy 379.070606 -258.829789) (xy 379.070606 -258.776491) (xy 379.078549 -258.723787)
			(xy 379.094259 -258.672857) (xy 379.117385 -258.624836) (xy 379.147409 -258.580799) (xy 379.183661 -258.541728)
			(xy 379.225332 -258.508497) (xy 379.27149 -258.481848) (xy 379.321104 -258.462376) (xy 379.373066 -258.450516)
			(xy 379.426216 -258.446533) (xy 379.479366 -258.450516) (xy 379.531328 -258.462376) (xy 379.580942 -258.481848)
			(xy 379.6271 -258.508497) (xy 379.668771 -258.541728) (xy 379.705023 -258.580799) (xy 379.735047 -258.624836)
			(xy 379.758173 -258.672857) (xy 379.773883 -258.723787) (xy 379.781826 -258.776491) (xy 379.782324 -258.80314)
			(xy 379.781826 -258.829789) (xy 380.010406 -258.829789) (xy 380.010406 -258.776491) (xy 380.018349 -258.723787)
			(xy 380.034059 -258.672857) (xy 380.057185 -258.624836) (xy 380.087209 -258.580799) (xy 380.123461 -258.541728)
			(xy 380.165132 -258.508497) (xy 380.21129 -258.481848) (xy 380.260904 -258.462376) (xy 380.312866 -258.450516)
			(xy 380.366016 -258.446533) (xy 380.419166 -258.450516) (xy 380.471128 -258.462376) (xy 380.520742 -258.481848)
			(xy 380.5669 -258.508497) (xy 380.608571 -258.541728) (xy 380.644823 -258.580799) (xy 380.674847 -258.624836)
			(xy 380.697973 -258.672857) (xy 380.713683 -258.723787) (xy 380.721626 -258.776491) (xy 380.722124 -258.80314)
			(xy 380.721626 -258.829789) (xy 380.950206 -258.829789) (xy 380.950206 -258.776491) (xy 380.958149 -258.723787)
			(xy 380.973859 -258.672857) (xy 380.996985 -258.624836) (xy 381.027009 -258.580799) (xy 381.063261 -258.541728)
			(xy 381.104932 -258.508497) (xy 381.15109 -258.481848) (xy 381.200704 -258.462376) (xy 381.252666 -258.450516)
			(xy 381.305816 -258.446533) (xy 381.358966 -258.450516) (xy 381.410928 -258.462376) (xy 381.460542 -258.481848)
			(xy 381.5067 -258.508497) (xy 381.548371 -258.541728) (xy 381.584623 -258.580799) (xy 381.614647 -258.624836)
			(xy 381.637773 -258.672857) (xy 381.653483 -258.723787) (xy 381.661426 -258.776491) (xy 381.661924 -258.80314)
			(xy 381.661426 -258.829789) (xy 381.653483 -258.882493) (xy 381.637773 -258.933423) (xy 381.614647 -258.981444)
			(xy 381.584623 -259.025481) (xy 381.548371 -259.064552) (xy 381.5067 -259.097783) (xy 381.460542 -259.124432)
			(xy 381.410928 -259.143904) (xy 381.358966 -259.155764) (xy 381.305816 -259.159748) (xy 381.252666 -259.155764)
			(xy 381.200704 -259.143904) (xy 381.15109 -259.124432) (xy 381.104932 -259.097783) (xy 381.063261 -259.064552)
			(xy 381.027009 -259.025481) (xy 380.996985 -258.981444) (xy 380.973859 -258.933423) (xy 380.958149 -258.882493)
			(xy 380.950206 -258.829789) (xy 380.721626 -258.829789) (xy 380.713683 -258.882493) (xy 380.697973 -258.933423)
			(xy 380.674847 -258.981444) (xy 380.644823 -259.025481) (xy 380.608571 -259.064552) (xy 380.5669 -259.097783)
			(xy 380.520742 -259.124432) (xy 380.471128 -259.143904) (xy 380.419166 -259.155764) (xy 380.366016 -259.159748)
			(xy 380.312866 -259.155764) (xy 380.260904 -259.143904) (xy 380.21129 -259.124432) (xy 380.165132 -259.097783)
			(xy 380.123461 -259.064552) (xy 380.087209 -259.025481) (xy 380.057185 -258.981444) (xy 380.034059 -258.933423)
			(xy 380.018349 -258.882493) (xy 380.010406 -258.829789) (xy 379.781826 -258.829789) (xy 379.773883 -258.882493)
			(xy 379.758173 -258.933423) (xy 379.735047 -258.981444) (xy 379.705023 -259.025481) (xy 379.668771 -259.064552)
			(xy 379.6271 -259.097783) (xy 379.580942 -259.124432) (xy 379.531328 -259.143904) (xy 379.479366 -259.155764)
			(xy 379.426216 -259.159748) (xy 379.373066 -259.155764) (xy 379.321104 -259.143904) (xy 379.27149 -259.124432)
			(xy 379.225332 -259.097783) (xy 379.183661 -259.064552) (xy 379.147409 -259.025481) (xy 379.117385 -258.981444)
			(xy 379.094259 -258.933423) (xy 379.078549 -258.882493) (xy 379.070606 -258.829789) (xy 378.842026 -258.829789)
			(xy 378.834083 -258.882493) (xy 378.818373 -258.933423) (xy 378.795247 -258.981444) (xy 378.765223 -259.025481)
			(xy 378.728971 -259.064552) (xy 378.6873 -259.097783) (xy 378.641142 -259.124432) (xy 378.591528 -259.143904)
			(xy 378.539566 -259.155764) (xy 378.486416 -259.159748) (xy 378.433266 -259.155764) (xy 378.381304 -259.143904)
			(xy 378.33169 -259.124432) (xy 378.285532 -259.097783) (xy 378.243861 -259.064552) (xy 378.207609 -259.025481)
			(xy 378.177585 -258.981444) (xy 378.154459 -258.933423) (xy 378.138749 -258.882493) (xy 378.130806 -258.829789)
			(xy 377.901972 -258.829789) (xy 377.894029 -258.882493) (xy 377.878319 -258.933423) (xy 377.855193 -258.981444)
			(xy 377.825169 -259.025481) (xy 377.788917 -259.064552) (xy 377.747246 -259.097783) (xy 377.701088 -259.124432)
			(xy 377.651474 -259.143904) (xy 377.599512 -259.155764) (xy 377.546362 -259.159748) (xy 377.493212 -259.155764)
			(xy 377.44125 -259.143904) (xy 377.391636 -259.124432) (xy 377.345478 -259.097783) (xy 377.303807 -259.064552)
			(xy 377.267555 -259.025481) (xy 377.237531 -258.981444) (xy 377.214405 -258.933423) (xy 377.198695 -258.882493)
			(xy 377.190752 -258.829789) (xy 376.962426 -258.829789) (xy 376.954483 -258.882493) (xy 376.938773 -258.933423)
			(xy 376.915647 -258.981444) (xy 376.885623 -259.025481) (xy 376.849371 -259.064552) (xy 376.8077 -259.097783)
			(xy 376.761542 -259.124432) (xy 376.711928 -259.143904) (xy 376.659966 -259.155764) (xy 376.606816 -259.159748)
			(xy 376.553666 -259.155764) (xy 376.501704 -259.143904) (xy 376.45209 -259.124432) (xy 376.405932 -259.097783)
			(xy 376.364261 -259.064552) (xy 376.328009 -259.025481) (xy 376.297985 -258.981444) (xy 376.274859 -258.933423)
			(xy 376.259149 -258.882493) (xy 376.251206 -258.829789) (xy 376.022626 -258.829789) (xy 376.014683 -258.882493)
			(xy 375.998973 -258.933423) (xy 375.975847 -258.981444) (xy 375.945823 -259.025481) (xy 375.909571 -259.064552)
			(xy 375.8679 -259.097783) (xy 375.821742 -259.124432) (xy 375.772128 -259.143904) (xy 375.720166 -259.155764)
			(xy 375.667016 -259.159748) (xy 375.613866 -259.155764) (xy 375.561904 -259.143904) (xy 375.51229 -259.124432)
			(xy 375.466132 -259.097783) (xy 375.424461 -259.064552) (xy 375.388209 -259.025481) (xy 375.358185 -258.981444)
			(xy 375.335059 -258.933423) (xy 375.319349 -258.882493) (xy 375.311406 -258.829789) (xy 375.082826 -258.829789)
			(xy 375.074883 -258.882493) (xy 375.059173 -258.933423) (xy 375.036047 -258.981444) (xy 375.006023 -259.025481)
			(xy 374.969771 -259.064552) (xy 374.9281 -259.097783) (xy 374.881942 -259.124432) (xy 374.832328 -259.143904)
			(xy 374.780366 -259.155764) (xy 374.727216 -259.159748) (xy 374.674066 -259.155764) (xy 374.622104 -259.143904)
			(xy 374.57249 -259.124432) (xy 374.526332 -259.097783) (xy 374.484661 -259.064552) (xy 374.448409 -259.025481)
			(xy 374.418385 -258.981444) (xy 374.395259 -258.933423) (xy 374.379549 -258.882493) (xy 374.371606 -258.829789)
			(xy 374.143026 -258.829789) (xy 374.135083 -258.882493) (xy 374.119373 -258.933423) (xy 374.096247 -258.981444)
			(xy 374.066223 -259.025481) (xy 374.029971 -259.064552) (xy 373.9883 -259.097783) (xy 373.942142 -259.124432)
			(xy 373.892528 -259.143904) (xy 373.840566 -259.155764) (xy 373.787416 -259.159748) (xy 373.734266 -259.155764)
			(xy 373.682304 -259.143904) (xy 373.63269 -259.124432) (xy 373.586532 -259.097783) (xy 373.544861 -259.064552)
			(xy 373.508609 -259.025481) (xy 373.478585 -258.981444) (xy 373.455459 -258.933423) (xy 373.439749 -258.882493)
			(xy 373.431806 -258.829789) (xy 373.203226 -258.829789) (xy 373.195283 -258.882493) (xy 373.179573 -258.933423)
			(xy 373.156447 -258.981444) (xy 373.126423 -259.025481) (xy 373.090171 -259.064552) (xy 373.0485 -259.097783)
			(xy 373.002342 -259.124432) (xy 372.952728 -259.143904) (xy 372.900766 -259.155764) (xy 372.847616 -259.159748)
			(xy 372.794466 -259.155764) (xy 372.742504 -259.143904) (xy 372.69289 -259.124432) (xy 372.646732 -259.097783)
			(xy 372.605061 -259.064552) (xy 372.568809 -259.025481) (xy 372.538785 -258.981444) (xy 372.515659 -258.933423)
			(xy 372.499949 -258.882493) (xy 372.492006 -258.829789) (xy 372.263426 -258.829789) (xy 372.255483 -258.882493)
			(xy 372.239773 -258.933423) (xy 372.216647 -258.981444) (xy 372.186623 -259.025481) (xy 372.150371 -259.064552)
			(xy 372.1087 -259.097783) (xy 372.062542 -259.124432) (xy 372.012928 -259.143904) (xy 371.960966 -259.155764)
			(xy 371.907816 -259.159748) (xy 371.854666 -259.155764) (xy 371.802704 -259.143904) (xy 371.75309 -259.124432)
			(xy 371.706932 -259.097783) (xy 371.665261 -259.064552) (xy 371.629009 -259.025481) (xy 371.598985 -258.981444)
			(xy 371.575859 -258.933423) (xy 371.560149 -258.882493) (xy 371.552206 -258.829789) (xy 371.323372 -258.829789)
			(xy 371.315429 -258.882493) (xy 371.299719 -258.933423) (xy 371.276593 -258.981444) (xy 371.246569 -259.025481)
			(xy 371.210317 -259.064552) (xy 371.168646 -259.097783) (xy 371.122488 -259.124432) (xy 371.072874 -259.143904)
			(xy 371.020912 -259.155764) (xy 370.967762 -259.159748) (xy 370.914612 -259.155764) (xy 370.86265 -259.143904)
			(xy 370.813036 -259.124432) (xy 370.766878 -259.097783) (xy 370.725207 -259.064552) (xy 370.688955 -259.025481)
			(xy 370.658931 -258.981444) (xy 370.635805 -258.933423) (xy 370.620095 -258.882493) (xy 370.612152 -258.829789)
			(xy 370.383572 -258.829789) (xy 370.375629 -258.882493) (xy 370.359919 -258.933423) (xy 370.336793 -258.981444)
			(xy 370.306769 -259.025481) (xy 370.270517 -259.064552) (xy 370.228846 -259.097783) (xy 370.182688 -259.124432)
			(xy 370.133074 -259.143904) (xy 370.081112 -259.155764) (xy 370.027962 -259.159748) (xy 369.974812 -259.155764)
			(xy 369.92285 -259.143904) (xy 369.873236 -259.124432) (xy 369.827078 -259.097783) (xy 369.785407 -259.064552)
			(xy 369.749155 -259.025481) (xy 369.719131 -258.981444) (xy 369.696005 -258.933423) (xy 369.680295 -258.882493)
			(xy 369.672352 -258.829789) (xy 368.91468 -258.829789) (xy 368.91468 -259.197348) (xy 368.889788 -259.22224)
			(xy 368.880006 -259.232717) (xy 368.866177 -259.257808) (xy 368.859857 -259.285753) (xy 368.861543 -259.314353)
			(xy 368.871102 -259.341362) (xy 368.887783 -259.364655) (xy 368.910275 -259.382402) (xy 368.936809 -259.393207)
			(xy 368.951002 -259.395214) (xy 368.980127 -259.398875) (xy 369.03671 -259.414486) (xy 369.089973 -259.439148)
			(xy 369.114578 -259.455158) (xy 369.12604 -259.462491) (xy 369.15174 -259.471397) (xy 369.17888 -259.473197)
			(xy 369.205532 -259.467761) (xy 369.2298 -259.455478) (xy 369.24996 -259.437219) (xy 369.25758 -259.425948)
			(xy 369.271667 -259.404614) (xy 369.304983 -259.365839) (xy 369.343499 -259.332223) (xy 369.386425 -259.304459)
			(xy 369.432879 -259.283115) (xy 369.481906 -259.268631) (xy 369.532501 -259.261304) (xy 369.558062 -259.260848)
			(xy 369.584718 -259.261319) (xy 369.637436 -259.269259) (xy 369.688381 -259.284969) (xy 369.736416 -259.308097)
			(xy 369.780467 -259.338126) (xy 369.81955 -259.374385) (xy 369.852791 -259.416065) (xy 369.879449 -259.462234)
			(xy 369.898928 -259.511861) (xy 369.910792 -259.563837) (xy 369.914776 -259.617) (xy 369.912782 -259.643605)
			(xy 370.142252 -259.643605) (xy 370.142252 -259.590307) (xy 370.150195 -259.537603) (xy 370.165905 -259.486673)
			(xy 370.189031 -259.438652) (xy 370.219055 -259.394615) (xy 370.255307 -259.355544) (xy 370.296978 -259.322313)
			(xy 370.343136 -259.295664) (xy 370.39275 -259.276192) (xy 370.444712 -259.264332) (xy 370.497862 -259.260349)
			(xy 370.551012 -259.264332) (xy 370.602974 -259.276192) (xy 370.652588 -259.295664) (xy 370.698746 -259.322313)
			(xy 370.740417 -259.355544) (xy 370.776669 -259.394615) (xy 370.806693 -259.438652) (xy 370.829819 -259.486673)
			(xy 370.845529 -259.537603) (xy 370.853472 -259.590307) (xy 370.85397 -259.616956) (xy 370.853472 -259.643605)
			(xy 371.082052 -259.643605) (xy 371.082052 -259.590307) (xy 371.089995 -259.537603) (xy 371.105705 -259.486673)
			(xy 371.128831 -259.438652) (xy 371.158855 -259.394615) (xy 371.195107 -259.355544) (xy 371.236778 -259.322313)
			(xy 371.282936 -259.295664) (xy 371.33255 -259.276192) (xy 371.384512 -259.264332) (xy 371.437662 -259.260349)
			(xy 371.490812 -259.264332) (xy 371.542774 -259.276192) (xy 371.592388 -259.295664) (xy 371.638546 -259.322313)
			(xy 371.680217 -259.355544) (xy 371.716469 -259.394615) (xy 371.746493 -259.438652) (xy 371.769619 -259.486673)
			(xy 371.785329 -259.537603) (xy 371.793272 -259.590307) (xy 371.79377 -259.616956) (xy 371.793272 -259.643605)
			(xy 372.021852 -259.643605) (xy 372.021852 -259.590307) (xy 372.029795 -259.537603) (xy 372.045505 -259.486673)
			(xy 372.068631 -259.438652) (xy 372.098655 -259.394615) (xy 372.134907 -259.355544) (xy 372.176578 -259.322313)
			(xy 372.222736 -259.295664) (xy 372.27235 -259.276192) (xy 372.324312 -259.264332) (xy 372.377462 -259.260349)
			(xy 372.430612 -259.264332) (xy 372.482574 -259.276192) (xy 372.532188 -259.295664) (xy 372.578346 -259.322313)
			(xy 372.620017 -259.355544) (xy 372.656269 -259.394615) (xy 372.686293 -259.438652) (xy 372.709419 -259.486673)
			(xy 372.725129 -259.537603) (xy 372.733072 -259.590307) (xy 372.73357 -259.616956) (xy 372.733072 -259.643605)
			(xy 372.961652 -259.643605) (xy 372.961652 -259.590307) (xy 372.969595 -259.537603) (xy 372.985305 -259.486673)
			(xy 373.008431 -259.438652) (xy 373.038455 -259.394615) (xy 373.074707 -259.355544) (xy 373.116378 -259.322313)
			(xy 373.162536 -259.295664) (xy 373.21215 -259.276192) (xy 373.264112 -259.264332) (xy 373.317262 -259.260349)
			(xy 373.370412 -259.264332) (xy 373.422374 -259.276192) (xy 373.471988 -259.295664) (xy 373.518146 -259.322313)
			(xy 373.559817 -259.355544) (xy 373.596069 -259.394615) (xy 373.626093 -259.438652) (xy 373.649219 -259.486673)
			(xy 373.664929 -259.537603) (xy 373.672872 -259.590307) (xy 373.67337 -259.616956) (xy 373.672872 -259.643605)
			(xy 373.901452 -259.643605) (xy 373.901452 -259.590307) (xy 373.909395 -259.537603) (xy 373.925105 -259.486673)
			(xy 373.948231 -259.438652) (xy 373.978255 -259.394615) (xy 374.014507 -259.355544) (xy 374.056178 -259.322313)
			(xy 374.102336 -259.295664) (xy 374.15195 -259.276192) (xy 374.203912 -259.264332) (xy 374.257062 -259.260349)
			(xy 374.310212 -259.264332) (xy 374.362174 -259.276192) (xy 374.411788 -259.295664) (xy 374.457946 -259.322313)
			(xy 374.499617 -259.355544) (xy 374.535869 -259.394615) (xy 374.565893 -259.438652) (xy 374.589019 -259.486673)
			(xy 374.604729 -259.537603) (xy 374.612672 -259.590307) (xy 374.61317 -259.616956) (xy 374.612672 -259.643605)
			(xy 374.841252 -259.643605) (xy 374.841252 -259.590307) (xy 374.849195 -259.537603) (xy 374.864905 -259.486673)
			(xy 374.888031 -259.438652) (xy 374.918055 -259.394615) (xy 374.954307 -259.355544) (xy 374.995978 -259.322313)
			(xy 375.042136 -259.295664) (xy 375.09175 -259.276192) (xy 375.143712 -259.264332) (xy 375.196862 -259.260349)
			(xy 375.250012 -259.264332) (xy 375.301974 -259.276192) (xy 375.351588 -259.295664) (xy 375.397746 -259.322313)
			(xy 375.439417 -259.355544) (xy 375.475669 -259.394615) (xy 375.505693 -259.438652) (xy 375.528819 -259.486673)
			(xy 375.544529 -259.537603) (xy 375.552472 -259.590307) (xy 375.55297 -259.616956) (xy 375.552472 -259.643605)
			(xy 375.781052 -259.643605) (xy 375.781052 -259.590307) (xy 375.788995 -259.537603) (xy 375.804705 -259.486673)
			(xy 375.827831 -259.438652) (xy 375.857855 -259.394615) (xy 375.894107 -259.355544) (xy 375.935778 -259.322313)
			(xy 375.981936 -259.295664) (xy 376.03155 -259.276192) (xy 376.083512 -259.264332) (xy 376.136662 -259.260349)
			(xy 376.189812 -259.264332) (xy 376.241774 -259.276192) (xy 376.291388 -259.295664) (xy 376.337546 -259.322313)
			(xy 376.379217 -259.355544) (xy 376.415469 -259.394615) (xy 376.445493 -259.438652) (xy 376.468619 -259.486673)
			(xy 376.484329 -259.537603) (xy 376.492272 -259.590307) (xy 376.49277 -259.616956) (xy 376.492272 -259.643605)
			(xy 376.720852 -259.643605) (xy 376.720852 -259.590307) (xy 376.728795 -259.537603) (xy 376.744505 -259.486673)
			(xy 376.767631 -259.438652) (xy 376.797655 -259.394615) (xy 376.833907 -259.355544) (xy 376.875578 -259.322313)
			(xy 376.921736 -259.295664) (xy 376.97135 -259.276192) (xy 377.023312 -259.264332) (xy 377.076462 -259.260349)
			(xy 377.129612 -259.264332) (xy 377.181574 -259.276192) (xy 377.231188 -259.295664) (xy 377.277346 -259.322313)
			(xy 377.319017 -259.355544) (xy 377.355269 -259.394615) (xy 377.385293 -259.438652) (xy 377.408419 -259.486673)
			(xy 377.424129 -259.537603) (xy 377.432072 -259.590307) (xy 377.43257 -259.616956) (xy 377.432072 -259.643605)
			(xy 377.660652 -259.643605) (xy 377.660652 -259.590307) (xy 377.668595 -259.537603) (xy 377.684305 -259.486673)
			(xy 377.707431 -259.438652) (xy 377.737455 -259.394615) (xy 377.773707 -259.355544) (xy 377.815378 -259.322313)
			(xy 377.861536 -259.295664) (xy 377.91115 -259.276192) (xy 377.963112 -259.264332) (xy 378.016262 -259.260349)
			(xy 378.069412 -259.264332) (xy 378.121374 -259.276192) (xy 378.170988 -259.295664) (xy 378.217146 -259.322313)
			(xy 378.258817 -259.355544) (xy 378.295069 -259.394615) (xy 378.325093 -259.438652) (xy 378.348219 -259.486673)
			(xy 378.363929 -259.537603) (xy 378.371872 -259.590307) (xy 378.37237 -259.616956) (xy 378.371872 -259.643605)
			(xy 378.600452 -259.643605) (xy 378.600452 -259.590307) (xy 378.608395 -259.537603) (xy 378.624105 -259.486673)
			(xy 378.647231 -259.438652) (xy 378.677255 -259.394615) (xy 378.713507 -259.355544) (xy 378.755178 -259.322313)
			(xy 378.801336 -259.295664) (xy 378.85095 -259.276192) (xy 378.902912 -259.264332) (xy 378.956062 -259.260349)
			(xy 379.009212 -259.264332) (xy 379.061174 -259.276192) (xy 379.110788 -259.295664) (xy 379.156946 -259.322313)
			(xy 379.198617 -259.355544) (xy 379.234869 -259.394615) (xy 379.264893 -259.438652) (xy 379.288019 -259.486673)
			(xy 379.303729 -259.537603) (xy 379.311672 -259.590307) (xy 379.31217 -259.616956) (xy 379.311672 -259.643605)
			(xy 379.540252 -259.643605) (xy 379.540252 -259.590307) (xy 379.548195 -259.537603) (xy 379.563905 -259.486673)
			(xy 379.587031 -259.438652) (xy 379.617055 -259.394615) (xy 379.653307 -259.355544) (xy 379.694978 -259.322313)
			(xy 379.741136 -259.295664) (xy 379.79075 -259.276192) (xy 379.842712 -259.264332) (xy 379.895862 -259.260349)
			(xy 379.949012 -259.264332) (xy 380.000974 -259.276192) (xy 380.050588 -259.295664) (xy 380.096746 -259.322313)
			(xy 380.138417 -259.355544) (xy 380.174669 -259.394615) (xy 380.204693 -259.438652) (xy 380.227819 -259.486673)
			(xy 380.243529 -259.537603) (xy 380.251472 -259.590307) (xy 380.25197 -259.616956) (xy 380.251472 -259.643605)
			(xy 380.480052 -259.643605) (xy 380.480052 -259.590307) (xy 380.487995 -259.537603) (xy 380.503705 -259.486673)
			(xy 380.526831 -259.438652) (xy 380.556855 -259.394615) (xy 380.593107 -259.355544) (xy 380.634778 -259.322313)
			(xy 380.680936 -259.295664) (xy 380.73055 -259.276192) (xy 380.782512 -259.264332) (xy 380.835662 -259.260349)
			(xy 380.888812 -259.264332) (xy 380.940774 -259.276192) (xy 380.990388 -259.295664) (xy 381.036546 -259.322313)
			(xy 381.078217 -259.355544) (xy 381.114469 -259.394615) (xy 381.144493 -259.438652) (xy 381.167619 -259.486673)
			(xy 381.183329 -259.537603) (xy 381.191272 -259.590307) (xy 381.19177 -259.616956) (xy 381.191272 -259.643605)
			(xy 381.183329 -259.696309) (xy 381.167619 -259.747239) (xy 381.144493 -259.79526) (xy 381.114469 -259.839297)
			(xy 381.078217 -259.878368) (xy 381.036546 -259.911599) (xy 380.990388 -259.938248) (xy 380.940774 -259.95772)
			(xy 380.888812 -259.96958) (xy 380.835662 -259.973564) (xy 380.782512 -259.96958) (xy 380.73055 -259.95772)
			(xy 380.680936 -259.938248) (xy 380.634778 -259.911599) (xy 380.593107 -259.878368) (xy 380.556855 -259.839297)
			(xy 380.526831 -259.79526) (xy 380.503705 -259.747239) (xy 380.487995 -259.696309) (xy 380.480052 -259.643605)
			(xy 380.251472 -259.643605) (xy 380.243529 -259.696309) (xy 380.227819 -259.747239) (xy 380.204693 -259.79526)
			(xy 380.174669 -259.839297) (xy 380.138417 -259.878368) (xy 380.096746 -259.911599) (xy 380.050588 -259.938248)
			(xy 380.000974 -259.95772) (xy 379.949012 -259.96958) (xy 379.895862 -259.973564) (xy 379.842712 -259.96958)
			(xy 379.79075 -259.95772) (xy 379.741136 -259.938248) (xy 379.694978 -259.911599) (xy 379.653307 -259.878368)
			(xy 379.617055 -259.839297) (xy 379.587031 -259.79526) (xy 379.563905 -259.747239) (xy 379.548195 -259.696309)
			(xy 379.540252 -259.643605) (xy 379.311672 -259.643605) (xy 379.303729 -259.696309) (xy 379.288019 -259.747239)
			(xy 379.264893 -259.79526) (xy 379.234869 -259.839297) (xy 379.198617 -259.878368) (xy 379.156946 -259.911599)
			(xy 379.110788 -259.938248) (xy 379.061174 -259.95772) (xy 379.009212 -259.96958) (xy 378.956062 -259.973564)
			(xy 378.902912 -259.96958) (xy 378.85095 -259.95772) (xy 378.801336 -259.938248) (xy 378.755178 -259.911599)
			(xy 378.713507 -259.878368) (xy 378.677255 -259.839297) (xy 378.647231 -259.79526) (xy 378.624105 -259.747239)
			(xy 378.608395 -259.696309) (xy 378.600452 -259.643605) (xy 378.371872 -259.643605) (xy 378.363929 -259.696309)
			(xy 378.348219 -259.747239) (xy 378.325093 -259.79526) (xy 378.295069 -259.839297) (xy 378.258817 -259.878368)
			(xy 378.217146 -259.911599) (xy 378.170988 -259.938248) (xy 378.121374 -259.95772) (xy 378.069412 -259.96958)
			(xy 378.016262 -259.973564) (xy 377.963112 -259.96958) (xy 377.91115 -259.95772) (xy 377.861536 -259.938248)
			(xy 377.815378 -259.911599) (xy 377.773707 -259.878368) (xy 377.737455 -259.839297) (xy 377.707431 -259.79526)
			(xy 377.684305 -259.747239) (xy 377.668595 -259.696309) (xy 377.660652 -259.643605) (xy 377.432072 -259.643605)
			(xy 377.424129 -259.696309) (xy 377.408419 -259.747239) (xy 377.385293 -259.79526) (xy 377.355269 -259.839297)
			(xy 377.319017 -259.878368) (xy 377.277346 -259.911599) (xy 377.231188 -259.938248) (xy 377.181574 -259.95772)
			(xy 377.129612 -259.96958) (xy 377.076462 -259.973564) (xy 377.023312 -259.96958) (xy 376.97135 -259.95772)
			(xy 376.921736 -259.938248) (xy 376.875578 -259.911599) (xy 376.833907 -259.878368) (xy 376.797655 -259.839297)
			(xy 376.767631 -259.79526) (xy 376.744505 -259.747239) (xy 376.728795 -259.696309) (xy 376.720852 -259.643605)
			(xy 376.492272 -259.643605) (xy 376.484329 -259.696309) (xy 376.468619 -259.747239) (xy 376.445493 -259.79526)
			(xy 376.415469 -259.839297) (xy 376.379217 -259.878368) (xy 376.337546 -259.911599) (xy 376.291388 -259.938248)
			(xy 376.241774 -259.95772) (xy 376.189812 -259.96958) (xy 376.136662 -259.973564) (xy 376.083512 -259.96958)
			(xy 376.03155 -259.95772) (xy 375.981936 -259.938248) (xy 375.935778 -259.911599) (xy 375.894107 -259.878368)
			(xy 375.857855 -259.839297) (xy 375.827831 -259.79526) (xy 375.804705 -259.747239) (xy 375.788995 -259.696309)
			(xy 375.781052 -259.643605) (xy 375.552472 -259.643605) (xy 375.544529 -259.696309) (xy 375.528819 -259.747239)
			(xy 375.505693 -259.79526) (xy 375.475669 -259.839297) (xy 375.439417 -259.878368) (xy 375.397746 -259.911599)
			(xy 375.351588 -259.938248) (xy 375.301974 -259.95772) (xy 375.250012 -259.96958) (xy 375.196862 -259.973564)
			(xy 375.143712 -259.96958) (xy 375.09175 -259.95772) (xy 375.042136 -259.938248) (xy 374.995978 -259.911599)
			(xy 374.954307 -259.878368) (xy 374.918055 -259.839297) (xy 374.888031 -259.79526) (xy 374.864905 -259.747239)
			(xy 374.849195 -259.696309) (xy 374.841252 -259.643605) (xy 374.612672 -259.643605) (xy 374.604729 -259.696309)
			(xy 374.589019 -259.747239) (xy 374.565893 -259.79526) (xy 374.535869 -259.839297) (xy 374.499617 -259.878368)
			(xy 374.457946 -259.911599) (xy 374.411788 -259.938248) (xy 374.362174 -259.95772) (xy 374.310212 -259.96958)
			(xy 374.257062 -259.973564) (xy 374.203912 -259.96958) (xy 374.15195 -259.95772) (xy 374.102336 -259.938248)
			(xy 374.056178 -259.911599) (xy 374.014507 -259.878368) (xy 373.978255 -259.839297) (xy 373.948231 -259.79526)
			(xy 373.925105 -259.747239) (xy 373.909395 -259.696309) (xy 373.901452 -259.643605) (xy 373.672872 -259.643605)
			(xy 373.664929 -259.696309) (xy 373.649219 -259.747239) (xy 373.626093 -259.79526) (xy 373.596069 -259.839297)
			(xy 373.559817 -259.878368) (xy 373.518146 -259.911599) (xy 373.471988 -259.938248) (xy 373.422374 -259.95772)
			(xy 373.370412 -259.96958) (xy 373.317262 -259.973564) (xy 373.264112 -259.96958) (xy 373.21215 -259.95772)
			(xy 373.162536 -259.938248) (xy 373.116378 -259.911599) (xy 373.074707 -259.878368) (xy 373.038455 -259.839297)
			(xy 373.008431 -259.79526) (xy 372.985305 -259.747239) (xy 372.969595 -259.696309) (xy 372.961652 -259.643605)
			(xy 372.733072 -259.643605) (xy 372.725129 -259.696309) (xy 372.709419 -259.747239) (xy 372.686293 -259.79526)
			(xy 372.656269 -259.839297) (xy 372.620017 -259.878368) (xy 372.578346 -259.911599) (xy 372.532188 -259.938248)
			(xy 372.482574 -259.95772) (xy 372.430612 -259.96958) (xy 372.377462 -259.973564) (xy 372.324312 -259.96958)
			(xy 372.27235 -259.95772) (xy 372.222736 -259.938248) (xy 372.176578 -259.911599) (xy 372.134907 -259.878368)
			(xy 372.098655 -259.839297) (xy 372.068631 -259.79526) (xy 372.045505 -259.747239) (xy 372.029795 -259.696309)
			(xy 372.021852 -259.643605) (xy 371.793272 -259.643605) (xy 371.785329 -259.696309) (xy 371.769619 -259.747239)
			(xy 371.746493 -259.79526) (xy 371.716469 -259.839297) (xy 371.680217 -259.878368) (xy 371.638546 -259.911599)
			(xy 371.592388 -259.938248) (xy 371.542774 -259.95772) (xy 371.490812 -259.96958) (xy 371.437662 -259.973564)
			(xy 371.384512 -259.96958) (xy 371.33255 -259.95772) (xy 371.282936 -259.938248) (xy 371.236778 -259.911599)
			(xy 371.195107 -259.878368) (xy 371.158855 -259.839297) (xy 371.128831 -259.79526) (xy 371.105705 -259.747239)
			(xy 371.089995 -259.696309) (xy 371.082052 -259.643605) (xy 370.853472 -259.643605) (xy 370.845529 -259.696309)
			(xy 370.829819 -259.747239) (xy 370.806693 -259.79526) (xy 370.776669 -259.839297) (xy 370.740417 -259.878368)
			(xy 370.698746 -259.911599) (xy 370.652588 -259.938248) (xy 370.602974 -259.95772) (xy 370.551012 -259.96958)
			(xy 370.497862 -259.973564) (xy 370.444712 -259.96958) (xy 370.39275 -259.95772) (xy 370.343136 -259.938248)
			(xy 370.296978 -259.911599) (xy 370.255307 -259.878368) (xy 370.219055 -259.839297) (xy 370.189031 -259.79526)
			(xy 370.165905 -259.747239) (xy 370.150195 -259.696309) (xy 370.142252 -259.643605) (xy 369.912782 -259.643605)
			(xy 369.910792 -259.670163) (xy 369.898928 -259.722139) (xy 369.879449 -259.771766) (xy 369.852791 -259.817935)
			(xy 369.81955 -259.859615) (xy 369.780467 -259.895874) (xy 369.736416 -259.925903) (xy 369.688381 -259.949031)
			(xy 369.637436 -259.964741) (xy 369.584718 -259.972681) (xy 369.558062 -259.973064) (xy 369.557808 -259.973064)
			(xy 369.531144 -259.972595) (xy 369.478412 -259.964647) (xy 369.427458 -259.948914) (xy 369.379426 -259.925747)
			(xy 369.357148 -259.911088) (xy 369.345689 -259.903763) (xy 369.319999 -259.894872) (xy 369.292872 -259.893087)
			(xy 369.266237 -259.898534) (xy 369.24199 -259.910827) (xy 369.221853 -259.929091) (xy 369.214146 -259.940298)
			(xy 369.200058 -259.96163) (xy 369.16674 -260.000404) (xy 369.128224 -260.034018) (xy 369.085298 -260.061782)
			(xy 369.038845 -260.083126) (xy 368.989818 -260.097611) (xy 368.939225 -260.104941) (xy 368.913664 -260.105398)
			(xy 368.887553 -260.104944) (xy 368.835889 -260.097324) (xy 368.785892 -260.082238) (xy 368.738637 -260.060009)
			(xy 368.695135 -260.031115) (xy 368.656322 -259.996176) (xy 368.62303 -259.955941) (xy 368.595973 -259.911274)
			(xy 368.575732 -259.863133) (xy 368.562741 -259.812552) (xy 368.559588 -259.786628) (xy 368.5576 -259.772431)
			(xy 368.546797 -259.745891) (xy 368.529049 -259.723395) (xy 368.505753 -259.706711) (xy 368.47874 -259.697153)
			(xy 368.450136 -259.695471) (xy 368.422189 -259.701798) (xy 368.397098 -259.715636) (xy 368.386614 -259.725414)
			(xy 367.654607 -260.457421) (xy 369.672606 -260.457421) (xy 369.672606 -260.404123) (xy 369.680549 -260.351419)
			(xy 369.696259 -260.300489) (xy 369.719385 -260.252468) (xy 369.749409 -260.208431) (xy 369.785661 -260.16936)
			(xy 369.827332 -260.136129) (xy 369.87349 -260.10948) (xy 369.923104 -260.090008) (xy 369.975066 -260.078148)
			(xy 370.028216 -260.074165) (xy 370.081366 -260.078148) (xy 370.133328 -260.090008) (xy 370.182942 -260.10948)
			(xy 370.2291 -260.136129) (xy 370.270771 -260.16936) (xy 370.307023 -260.208431) (xy 370.337047 -260.252468)
			(xy 370.360173 -260.300489) (xy 370.375883 -260.351419) (xy 370.383826 -260.404123) (xy 370.384324 -260.430772)
			(xy 370.383826 -260.457421) (xy 370.612406 -260.457421) (xy 370.612406 -260.404123) (xy 370.620349 -260.351419)
			(xy 370.636059 -260.300489) (xy 370.659185 -260.252468) (xy 370.689209 -260.208431) (xy 370.725461 -260.16936)
			(xy 370.767132 -260.136129) (xy 370.81329 -260.10948) (xy 370.862904 -260.090008) (xy 370.914866 -260.078148)
			(xy 370.968016 -260.074165) (xy 371.021166 -260.078148) (xy 371.073128 -260.090008) (xy 371.122742 -260.10948)
			(xy 371.1689 -260.136129) (xy 371.210571 -260.16936) (xy 371.246823 -260.208431) (xy 371.276847 -260.252468)
			(xy 371.299973 -260.300489) (xy 371.315683 -260.351419) (xy 371.323626 -260.404123) (xy 371.324124 -260.430772)
			(xy 371.323626 -260.457421) (xy 371.552206 -260.457421) (xy 371.552206 -260.404123) (xy 371.560149 -260.351419)
			(xy 371.575859 -260.300489) (xy 371.598985 -260.252468) (xy 371.629009 -260.208431) (xy 371.665261 -260.16936)
			(xy 371.706932 -260.136129) (xy 371.75309 -260.10948) (xy 371.802704 -260.090008) (xy 371.854666 -260.078148)
			(xy 371.907816 -260.074165) (xy 371.960966 -260.078148) (xy 372.012928 -260.090008) (xy 372.062542 -260.10948)
			(xy 372.1087 -260.136129) (xy 372.150371 -260.16936) (xy 372.186623 -260.208431) (xy 372.216647 -260.252468)
			(xy 372.239773 -260.300489) (xy 372.255483 -260.351419) (xy 372.263426 -260.404123) (xy 372.263924 -260.430772)
			(xy 372.263426 -260.457421) (xy 372.492006 -260.457421) (xy 372.492006 -260.404123) (xy 372.499949 -260.351419)
			(xy 372.515659 -260.300489) (xy 372.538785 -260.252468) (xy 372.568809 -260.208431) (xy 372.605061 -260.16936)
			(xy 372.646732 -260.136129) (xy 372.69289 -260.10948) (xy 372.742504 -260.090008) (xy 372.794466 -260.078148)
			(xy 372.847616 -260.074165) (xy 372.900766 -260.078148) (xy 372.952728 -260.090008) (xy 373.002342 -260.10948)
			(xy 373.0485 -260.136129) (xy 373.090171 -260.16936) (xy 373.126423 -260.208431) (xy 373.156447 -260.252468)
			(xy 373.179573 -260.300489) (xy 373.195283 -260.351419) (xy 373.203226 -260.404123) (xy 373.203724 -260.430772)
			(xy 373.203226 -260.457421) (xy 373.431806 -260.457421) (xy 373.431806 -260.404123) (xy 373.439749 -260.351419)
			(xy 373.455459 -260.300489) (xy 373.478585 -260.252468) (xy 373.508609 -260.208431) (xy 373.544861 -260.16936)
			(xy 373.586532 -260.136129) (xy 373.63269 -260.10948) (xy 373.682304 -260.090008) (xy 373.734266 -260.078148)
			(xy 373.787416 -260.074165) (xy 373.840566 -260.078148) (xy 373.892528 -260.090008) (xy 373.942142 -260.10948)
			(xy 373.9883 -260.136129) (xy 374.029971 -260.16936) (xy 374.066223 -260.208431) (xy 374.096247 -260.252468)
			(xy 374.119373 -260.300489) (xy 374.135083 -260.351419) (xy 374.143026 -260.404123) (xy 374.143524 -260.430772)
			(xy 374.143026 -260.457421) (xy 374.371352 -260.457421) (xy 374.371352 -260.404123) (xy 374.379295 -260.351419)
			(xy 374.395005 -260.300489) (xy 374.418131 -260.252468) (xy 374.448155 -260.208431) (xy 374.484407 -260.16936)
			(xy 374.526078 -260.136129) (xy 374.572236 -260.10948) (xy 374.62185 -260.090008) (xy 374.673812 -260.078148)
			(xy 374.726962 -260.074165) (xy 374.780112 -260.078148) (xy 374.832074 -260.090008) (xy 374.881688 -260.10948)
			(xy 374.927846 -260.136129) (xy 374.969517 -260.16936) (xy 375.005769 -260.208431) (xy 375.035793 -260.252468)
			(xy 375.058919 -260.300489) (xy 375.074629 -260.351419) (xy 375.082572 -260.404123) (xy 375.08307 -260.430772)
			(xy 375.082572 -260.457421) (xy 375.311406 -260.457421) (xy 375.311406 -260.404123) (xy 375.319349 -260.351419)
			(xy 375.335059 -260.300489) (xy 375.358185 -260.252468) (xy 375.388209 -260.208431) (xy 375.424461 -260.16936)
			(xy 375.466132 -260.136129) (xy 375.51229 -260.10948) (xy 375.561904 -260.090008) (xy 375.613866 -260.078148)
			(xy 375.667016 -260.074165) (xy 375.720166 -260.078148) (xy 375.772128 -260.090008) (xy 375.821742 -260.10948)
			(xy 375.8679 -260.136129) (xy 375.909571 -260.16936) (xy 375.945823 -260.208431) (xy 375.975847 -260.252468)
			(xy 375.998973 -260.300489) (xy 376.014683 -260.351419) (xy 376.022626 -260.404123) (xy 376.023124 -260.430772)
			(xy 376.022626 -260.457421) (xy 376.251206 -260.457421) (xy 376.251206 -260.404123) (xy 376.259149 -260.351419)
			(xy 376.274859 -260.300489) (xy 376.297985 -260.252468) (xy 376.328009 -260.208431) (xy 376.364261 -260.16936)
			(xy 376.405932 -260.136129) (xy 376.45209 -260.10948) (xy 376.501704 -260.090008) (xy 376.553666 -260.078148)
			(xy 376.606816 -260.074165) (xy 376.659966 -260.078148) (xy 376.711928 -260.090008) (xy 376.761542 -260.10948)
			(xy 376.8077 -260.136129) (xy 376.849371 -260.16936) (xy 376.885623 -260.208431) (xy 376.915647 -260.252468)
			(xy 376.938773 -260.300489) (xy 376.954483 -260.351419) (xy 376.962426 -260.404123) (xy 376.962924 -260.430772)
			(xy 376.962426 -260.457421) (xy 377.191006 -260.457421) (xy 377.191006 -260.404123) (xy 377.198949 -260.351419)
			(xy 377.214659 -260.300489) (xy 377.237785 -260.252468) (xy 377.267809 -260.208431) (xy 377.304061 -260.16936)
			(xy 377.345732 -260.136129) (xy 377.39189 -260.10948) (xy 377.441504 -260.090008) (xy 377.493466 -260.078148)
			(xy 377.546616 -260.074165) (xy 377.599766 -260.078148) (xy 377.651728 -260.090008) (xy 377.701342 -260.10948)
			(xy 377.7475 -260.136129) (xy 377.789171 -260.16936) (xy 377.825423 -260.208431) (xy 377.855447 -260.252468)
			(xy 377.878573 -260.300489) (xy 377.894283 -260.351419) (xy 377.902226 -260.404123) (xy 377.902724 -260.430772)
			(xy 377.902226 -260.457421) (xy 378.130806 -260.457421) (xy 378.130806 -260.404123) (xy 378.138749 -260.351419)
			(xy 378.154459 -260.300489) (xy 378.177585 -260.252468) (xy 378.207609 -260.208431) (xy 378.243861 -260.16936)
			(xy 378.285532 -260.136129) (xy 378.33169 -260.10948) (xy 378.381304 -260.090008) (xy 378.433266 -260.078148)
			(xy 378.486416 -260.074165) (xy 378.539566 -260.078148) (xy 378.591528 -260.090008) (xy 378.641142 -260.10948)
			(xy 378.6873 -260.136129) (xy 378.728971 -260.16936) (xy 378.765223 -260.208431) (xy 378.795247 -260.252468)
			(xy 378.818373 -260.300489) (xy 378.834083 -260.351419) (xy 378.842026 -260.404123) (xy 378.842524 -260.430772)
			(xy 378.842026 -260.457421) (xy 379.070606 -260.457421) (xy 379.070606 -260.404123) (xy 379.078549 -260.351419)
			(xy 379.094259 -260.300489) (xy 379.117385 -260.252468) (xy 379.147409 -260.208431) (xy 379.183661 -260.16936)
			(xy 379.225332 -260.136129) (xy 379.27149 -260.10948) (xy 379.321104 -260.090008) (xy 379.373066 -260.078148)
			(xy 379.426216 -260.074165) (xy 379.479366 -260.078148) (xy 379.531328 -260.090008) (xy 379.580942 -260.10948)
			(xy 379.6271 -260.136129) (xy 379.668771 -260.16936) (xy 379.705023 -260.208431) (xy 379.735047 -260.252468)
			(xy 379.758173 -260.300489) (xy 379.773883 -260.351419) (xy 379.781826 -260.404123) (xy 379.782324 -260.430772)
			(xy 379.781826 -260.457421) (xy 380.010406 -260.457421) (xy 380.010406 -260.404123) (xy 380.018349 -260.351419)
			(xy 380.034059 -260.300489) (xy 380.057185 -260.252468) (xy 380.087209 -260.208431) (xy 380.123461 -260.16936)
			(xy 380.165132 -260.136129) (xy 380.21129 -260.10948) (xy 380.260904 -260.090008) (xy 380.312866 -260.078148)
			(xy 380.366016 -260.074165) (xy 380.419166 -260.078148) (xy 380.471128 -260.090008) (xy 380.520742 -260.10948)
			(xy 380.5669 -260.136129) (xy 380.608571 -260.16936) (xy 380.644823 -260.208431) (xy 380.674847 -260.252468)
			(xy 380.697973 -260.300489) (xy 380.713683 -260.351419) (xy 380.721626 -260.404123) (xy 380.722124 -260.430772)
			(xy 380.721626 -260.457421) (xy 380.949952 -260.457421) (xy 380.949952 -260.404123) (xy 380.957895 -260.351419)
			(xy 380.973605 -260.300489) (xy 380.996731 -260.252468) (xy 381.026755 -260.208431) (xy 381.063007 -260.16936)
			(xy 381.104678 -260.136129) (xy 381.150836 -260.10948) (xy 381.20045 -260.090008) (xy 381.252412 -260.078148)
			(xy 381.305562 -260.074165) (xy 381.358712 -260.078148) (xy 381.410674 -260.090008) (xy 381.460288 -260.10948)
			(xy 381.506446 -260.136129) (xy 381.548117 -260.16936) (xy 381.584369 -260.208431) (xy 381.614393 -260.252468)
			(xy 381.637519 -260.300489) (xy 381.653229 -260.351419) (xy 381.661172 -260.404123) (xy 381.66167 -260.430772)
			(xy 381.661172 -260.457421) (xy 381.653229 -260.510125) (xy 381.637519 -260.561055) (xy 381.614393 -260.609076)
			(xy 381.584369 -260.653113) (xy 381.548117 -260.692184) (xy 381.506446 -260.725415) (xy 381.460288 -260.752064)
			(xy 381.410674 -260.771536) (xy 381.358712 -260.783396) (xy 381.305562 -260.78738) (xy 381.252412 -260.783396)
			(xy 381.20045 -260.771536) (xy 381.150836 -260.752064) (xy 381.104678 -260.725415) (xy 381.063007 -260.692184)
			(xy 381.026755 -260.653113) (xy 380.996731 -260.609076) (xy 380.973605 -260.561055) (xy 380.957895 -260.510125)
			(xy 380.949952 -260.457421) (xy 380.721626 -260.457421) (xy 380.713683 -260.510125) (xy 380.697973 -260.561055)
			(xy 380.674847 -260.609076) (xy 380.644823 -260.653113) (xy 380.608571 -260.692184) (xy 380.5669 -260.725415)
			(xy 380.520742 -260.752064) (xy 380.471128 -260.771536) (xy 380.419166 -260.783396) (xy 380.366016 -260.78738)
			(xy 380.312866 -260.783396) (xy 380.260904 -260.771536) (xy 380.21129 -260.752064) (xy 380.165132 -260.725415)
			(xy 380.123461 -260.692184) (xy 380.087209 -260.653113) (xy 380.057185 -260.609076) (xy 380.034059 -260.561055)
			(xy 380.018349 -260.510125) (xy 380.010406 -260.457421) (xy 379.781826 -260.457421) (xy 379.773883 -260.510125)
			(xy 379.758173 -260.561055) (xy 379.735047 -260.609076) (xy 379.705023 -260.653113) (xy 379.668771 -260.692184)
			(xy 379.6271 -260.725415) (xy 379.580942 -260.752064) (xy 379.531328 -260.771536) (xy 379.479366 -260.783396)
			(xy 379.426216 -260.78738) (xy 379.373066 -260.783396) (xy 379.321104 -260.771536) (xy 379.27149 -260.752064)
			(xy 379.225332 -260.725415) (xy 379.183661 -260.692184) (xy 379.147409 -260.653113) (xy 379.117385 -260.609076)
			(xy 379.094259 -260.561055) (xy 379.078549 -260.510125) (xy 379.070606 -260.457421) (xy 378.842026 -260.457421)
			(xy 378.834083 -260.510125) (xy 378.818373 -260.561055) (xy 378.795247 -260.609076) (xy 378.765223 -260.653113)
			(xy 378.728971 -260.692184) (xy 378.6873 -260.725415) (xy 378.641142 -260.752064) (xy 378.591528 -260.771536)
			(xy 378.539566 -260.783396) (xy 378.486416 -260.78738) (xy 378.433266 -260.783396) (xy 378.381304 -260.771536)
			(xy 378.33169 -260.752064) (xy 378.285532 -260.725415) (xy 378.243861 -260.692184) (xy 378.207609 -260.653113)
			(xy 378.177585 -260.609076) (xy 378.154459 -260.561055) (xy 378.138749 -260.510125) (xy 378.130806 -260.457421)
			(xy 377.902226 -260.457421) (xy 377.894283 -260.510125) (xy 377.878573 -260.561055) (xy 377.855447 -260.609076)
			(xy 377.825423 -260.653113) (xy 377.789171 -260.692184) (xy 377.7475 -260.725415) (xy 377.701342 -260.752064)
			(xy 377.651728 -260.771536) (xy 377.599766 -260.783396) (xy 377.546616 -260.78738) (xy 377.493466 -260.783396)
			(xy 377.441504 -260.771536) (xy 377.39189 -260.752064) (xy 377.345732 -260.725415) (xy 377.304061 -260.692184)
			(xy 377.267809 -260.653113) (xy 377.237785 -260.609076) (xy 377.214659 -260.561055) (xy 377.198949 -260.510125)
			(xy 377.191006 -260.457421) (xy 376.962426 -260.457421) (xy 376.954483 -260.510125) (xy 376.938773 -260.561055)
			(xy 376.915647 -260.609076) (xy 376.885623 -260.653113) (xy 376.849371 -260.692184) (xy 376.8077 -260.725415)
			(xy 376.761542 -260.752064) (xy 376.711928 -260.771536) (xy 376.659966 -260.783396) (xy 376.606816 -260.78738)
			(xy 376.553666 -260.783396) (xy 376.501704 -260.771536) (xy 376.45209 -260.752064) (xy 376.405932 -260.725415)
			(xy 376.364261 -260.692184) (xy 376.328009 -260.653113) (xy 376.297985 -260.609076) (xy 376.274859 -260.561055)
			(xy 376.259149 -260.510125) (xy 376.251206 -260.457421) (xy 376.022626 -260.457421) (xy 376.014683 -260.510125)
			(xy 375.998973 -260.561055) (xy 375.975847 -260.609076) (xy 375.945823 -260.653113) (xy 375.909571 -260.692184)
			(xy 375.8679 -260.725415) (xy 375.821742 -260.752064) (xy 375.772128 -260.771536) (xy 375.720166 -260.783396)
			(xy 375.667016 -260.78738) (xy 375.613866 -260.783396) (xy 375.561904 -260.771536) (xy 375.51229 -260.752064)
			(xy 375.466132 -260.725415) (xy 375.424461 -260.692184) (xy 375.388209 -260.653113) (xy 375.358185 -260.609076)
			(xy 375.335059 -260.561055) (xy 375.319349 -260.510125) (xy 375.311406 -260.457421) (xy 375.082572 -260.457421)
			(xy 375.074629 -260.510125) (xy 375.058919 -260.561055) (xy 375.035793 -260.609076) (xy 375.005769 -260.653113)
			(xy 374.969517 -260.692184) (xy 374.927846 -260.725415) (xy 374.881688 -260.752064) (xy 374.832074 -260.771536)
			(xy 374.780112 -260.783396) (xy 374.726962 -260.78738) (xy 374.673812 -260.783396) (xy 374.62185 -260.771536)
			(xy 374.572236 -260.752064) (xy 374.526078 -260.725415) (xy 374.484407 -260.692184) (xy 374.448155 -260.653113)
			(xy 374.418131 -260.609076) (xy 374.395005 -260.561055) (xy 374.379295 -260.510125) (xy 374.371352 -260.457421)
			(xy 374.143026 -260.457421) (xy 374.135083 -260.510125) (xy 374.119373 -260.561055) (xy 374.096247 -260.609076)
			(xy 374.066223 -260.653113) (xy 374.029971 -260.692184) (xy 373.9883 -260.725415) (xy 373.942142 -260.752064)
			(xy 373.892528 -260.771536) (xy 373.840566 -260.783396) (xy 373.787416 -260.78738) (xy 373.734266 -260.783396)
			(xy 373.682304 -260.771536) (xy 373.63269 -260.752064) (xy 373.586532 -260.725415) (xy 373.544861 -260.692184)
			(xy 373.508609 -260.653113) (xy 373.478585 -260.609076) (xy 373.455459 -260.561055) (xy 373.439749 -260.510125)
			(xy 373.431806 -260.457421) (xy 373.203226 -260.457421) (xy 373.195283 -260.510125) (xy 373.179573 -260.561055)
			(xy 373.156447 -260.609076) (xy 373.126423 -260.653113) (xy 373.090171 -260.692184) (xy 373.0485 -260.725415)
			(xy 373.002342 -260.752064) (xy 372.952728 -260.771536) (xy 372.900766 -260.783396) (xy 372.847616 -260.78738)
			(xy 372.794466 -260.783396) (xy 372.742504 -260.771536) (xy 372.69289 -260.752064) (xy 372.646732 -260.725415)
			(xy 372.605061 -260.692184) (xy 372.568809 -260.653113) (xy 372.538785 -260.609076) (xy 372.515659 -260.561055)
			(xy 372.499949 -260.510125) (xy 372.492006 -260.457421) (xy 372.263426 -260.457421) (xy 372.255483 -260.510125)
			(xy 372.239773 -260.561055) (xy 372.216647 -260.609076) (xy 372.186623 -260.653113) (xy 372.150371 -260.692184)
			(xy 372.1087 -260.725415) (xy 372.062542 -260.752064) (xy 372.012928 -260.771536) (xy 371.960966 -260.783396)
			(xy 371.907816 -260.78738) (xy 371.854666 -260.783396) (xy 371.802704 -260.771536) (xy 371.75309 -260.752064)
			(xy 371.706932 -260.725415) (xy 371.665261 -260.692184) (xy 371.629009 -260.653113) (xy 371.598985 -260.609076)
			(xy 371.575859 -260.561055) (xy 371.560149 -260.510125) (xy 371.552206 -260.457421) (xy 371.323626 -260.457421)
			(xy 371.315683 -260.510125) (xy 371.299973 -260.561055) (xy 371.276847 -260.609076) (xy 371.246823 -260.653113)
			(xy 371.210571 -260.692184) (xy 371.1689 -260.725415) (xy 371.122742 -260.752064) (xy 371.073128 -260.771536)
			(xy 371.021166 -260.783396) (xy 370.968016 -260.78738) (xy 370.914866 -260.783396) (xy 370.862904 -260.771536)
			(xy 370.81329 -260.752064) (xy 370.767132 -260.725415) (xy 370.725461 -260.692184) (xy 370.689209 -260.653113)
			(xy 370.659185 -260.609076) (xy 370.636059 -260.561055) (xy 370.620349 -260.510125) (xy 370.612406 -260.457421)
			(xy 370.383826 -260.457421) (xy 370.375883 -260.510125) (xy 370.360173 -260.561055) (xy 370.337047 -260.609076)
			(xy 370.307023 -260.653113) (xy 370.270771 -260.692184) (xy 370.2291 -260.725415) (xy 370.182942 -260.752064)
			(xy 370.133328 -260.771536) (xy 370.081366 -260.783396) (xy 370.028216 -260.78738) (xy 369.975066 -260.783396)
			(xy 369.923104 -260.771536) (xy 369.87349 -260.752064) (xy 369.827332 -260.725415) (xy 369.785661 -260.692184)
			(xy 369.749409 -260.653113) (xy 369.719385 -260.609076) (xy 369.696259 -260.561055) (xy 369.680549 -260.510125)
			(xy 369.672606 -260.457421) (xy 367.654607 -260.457421) (xy 367.36528 -260.746748) (xy 367.36528 -261.271491)
			(xy 369.202452 -261.271491) (xy 369.202452 -261.218193) (xy 369.210395 -261.165489) (xy 369.226105 -261.114559)
			(xy 369.249231 -261.066538) (xy 369.279255 -261.022501) (xy 369.315507 -260.98343) (xy 369.357178 -260.950199)
			(xy 369.403336 -260.92355) (xy 369.45295 -260.904078) (xy 369.504912 -260.892218) (xy 369.558062 -260.888235)
			(xy 369.611212 -260.892218) (xy 369.663174 -260.904078) (xy 369.712788 -260.92355) (xy 369.758946 -260.950199)
			(xy 369.800617 -260.98343) (xy 369.836869 -261.022501) (xy 369.866893 -261.066538) (xy 369.890019 -261.114559)
			(xy 369.905729 -261.165489) (xy 369.913672 -261.218193) (xy 369.91417 -261.244842) (xy 369.913672 -261.271491)
			(xy 370.142252 -261.271491) (xy 370.142252 -261.218193) (xy 370.150195 -261.165489) (xy 370.165905 -261.114559)
			(xy 370.189031 -261.066538) (xy 370.219055 -261.022501) (xy 370.255307 -260.98343) (xy 370.296978 -260.950199)
			(xy 370.343136 -260.92355) (xy 370.39275 -260.904078) (xy 370.444712 -260.892218) (xy 370.497862 -260.888235)
			(xy 370.551012 -260.892218) (xy 370.602974 -260.904078) (xy 370.652588 -260.92355) (xy 370.698746 -260.950199)
			(xy 370.740417 -260.98343) (xy 370.776669 -261.022501) (xy 370.806693 -261.066538) (xy 370.829819 -261.114559)
			(xy 370.845529 -261.165489) (xy 370.853472 -261.218193) (xy 370.85397 -261.244842) (xy 370.853472 -261.271491)
			(xy 371.082052 -261.271491) (xy 371.082052 -261.218193) (xy 371.089995 -261.165489) (xy 371.105705 -261.114559)
			(xy 371.128831 -261.066538) (xy 371.158855 -261.022501) (xy 371.195107 -260.98343) (xy 371.236778 -260.950199)
			(xy 371.282936 -260.92355) (xy 371.33255 -260.904078) (xy 371.384512 -260.892218) (xy 371.437662 -260.888235)
			(xy 371.490812 -260.892218) (xy 371.542774 -260.904078) (xy 371.592388 -260.92355) (xy 371.638546 -260.950199)
			(xy 371.680217 -260.98343) (xy 371.716469 -261.022501) (xy 371.746493 -261.066538) (xy 371.769619 -261.114559)
			(xy 371.785329 -261.165489) (xy 371.793272 -261.218193) (xy 371.79377 -261.244842) (xy 371.793272 -261.271491)
			(xy 372.021852 -261.271491) (xy 372.021852 -261.218193) (xy 372.029795 -261.165489) (xy 372.045505 -261.114559)
			(xy 372.068631 -261.066538) (xy 372.098655 -261.022501) (xy 372.134907 -260.98343) (xy 372.176578 -260.950199)
			(xy 372.222736 -260.92355) (xy 372.27235 -260.904078) (xy 372.324312 -260.892218) (xy 372.377462 -260.888235)
			(xy 372.430612 -260.892218) (xy 372.482574 -260.904078) (xy 372.532188 -260.92355) (xy 372.578346 -260.950199)
			(xy 372.620017 -260.98343) (xy 372.656269 -261.022501) (xy 372.686293 -261.066538) (xy 372.709419 -261.114559)
			(xy 372.725129 -261.165489) (xy 372.733072 -261.218193) (xy 372.73357 -261.244842) (xy 372.733072 -261.271491)
			(xy 372.961652 -261.271491) (xy 372.961652 -261.218193) (xy 372.969595 -261.165489) (xy 372.985305 -261.114559)
			(xy 373.008431 -261.066538) (xy 373.038455 -261.022501) (xy 373.074707 -260.98343) (xy 373.116378 -260.950199)
			(xy 373.162536 -260.92355) (xy 373.21215 -260.904078) (xy 373.264112 -260.892218) (xy 373.317262 -260.888235)
			(xy 373.370412 -260.892218) (xy 373.422374 -260.904078) (xy 373.471988 -260.92355) (xy 373.518146 -260.950199)
			(xy 373.559817 -260.98343) (xy 373.596069 -261.022501) (xy 373.626093 -261.066538) (xy 373.649219 -261.114559)
			(xy 373.664929 -261.165489) (xy 373.672872 -261.218193) (xy 373.67337 -261.244842) (xy 373.672872 -261.271491)
			(xy 373.901452 -261.271491) (xy 373.901452 -261.218193) (xy 373.909395 -261.165489) (xy 373.925105 -261.114559)
			(xy 373.948231 -261.066538) (xy 373.978255 -261.022501) (xy 374.014507 -260.98343) (xy 374.056178 -260.950199)
			(xy 374.102336 -260.92355) (xy 374.15195 -260.904078) (xy 374.203912 -260.892218) (xy 374.257062 -260.888235)
			(xy 374.310212 -260.892218) (xy 374.362174 -260.904078) (xy 374.411788 -260.92355) (xy 374.457946 -260.950199)
			(xy 374.499617 -260.98343) (xy 374.535869 -261.022501) (xy 374.565893 -261.066538) (xy 374.589019 -261.114559)
			(xy 374.604729 -261.165489) (xy 374.612672 -261.218193) (xy 374.61317 -261.244842) (xy 374.612672 -261.271491)
			(xy 374.841252 -261.271491) (xy 374.841252 -261.218193) (xy 374.849195 -261.165489) (xy 374.864905 -261.114559)
			(xy 374.888031 -261.066538) (xy 374.918055 -261.022501) (xy 374.954307 -260.98343) (xy 374.995978 -260.950199)
			(xy 375.042136 -260.92355) (xy 375.09175 -260.904078) (xy 375.143712 -260.892218) (xy 375.196862 -260.888235)
			(xy 375.250012 -260.892218) (xy 375.301974 -260.904078) (xy 375.351588 -260.92355) (xy 375.397746 -260.950199)
			(xy 375.439417 -260.98343) (xy 375.475669 -261.022501) (xy 375.505693 -261.066538) (xy 375.528819 -261.114559)
			(xy 375.544529 -261.165489) (xy 375.552472 -261.218193) (xy 375.55297 -261.244842) (xy 375.552472 -261.271491)
			(xy 375.781052 -261.271491) (xy 375.781052 -261.218193) (xy 375.788995 -261.165489) (xy 375.804705 -261.114559)
			(xy 375.827831 -261.066538) (xy 375.857855 -261.022501) (xy 375.894107 -260.98343) (xy 375.935778 -260.950199)
			(xy 375.981936 -260.92355) (xy 376.03155 -260.904078) (xy 376.083512 -260.892218) (xy 376.136662 -260.888235)
			(xy 376.189812 -260.892218) (xy 376.241774 -260.904078) (xy 376.291388 -260.92355) (xy 376.337546 -260.950199)
			(xy 376.379217 -260.98343) (xy 376.415469 -261.022501) (xy 376.445493 -261.066538) (xy 376.468619 -261.114559)
			(xy 376.484329 -261.165489) (xy 376.492272 -261.218193) (xy 376.49277 -261.244842) (xy 376.492272 -261.271491)
			(xy 376.720852 -261.271491) (xy 376.720852 -261.218193) (xy 376.728795 -261.165489) (xy 376.744505 -261.114559)
			(xy 376.767631 -261.066538) (xy 376.797655 -261.022501) (xy 376.833907 -260.98343) (xy 376.875578 -260.950199)
			(xy 376.921736 -260.92355) (xy 376.97135 -260.904078) (xy 377.023312 -260.892218) (xy 377.076462 -260.888235)
			(xy 377.129612 -260.892218) (xy 377.181574 -260.904078) (xy 377.231188 -260.92355) (xy 377.277346 -260.950199)
			(xy 377.319017 -260.98343) (xy 377.355269 -261.022501) (xy 377.385293 -261.066538) (xy 377.408419 -261.114559)
			(xy 377.424129 -261.165489) (xy 377.432072 -261.218193) (xy 377.43257 -261.244842) (xy 377.432072 -261.271491)
			(xy 377.660652 -261.271491) (xy 377.660652 -261.218193) (xy 377.668595 -261.165489) (xy 377.684305 -261.114559)
			(xy 377.707431 -261.066538) (xy 377.737455 -261.022501) (xy 377.773707 -260.98343) (xy 377.815378 -260.950199)
			(xy 377.861536 -260.92355) (xy 377.91115 -260.904078) (xy 377.963112 -260.892218) (xy 378.016262 -260.888235)
			(xy 378.069412 -260.892218) (xy 378.121374 -260.904078) (xy 378.170988 -260.92355) (xy 378.217146 -260.950199)
			(xy 378.258817 -260.98343) (xy 378.295069 -261.022501) (xy 378.325093 -261.066538) (xy 378.348219 -261.114559)
			(xy 378.363929 -261.165489) (xy 378.371872 -261.218193) (xy 378.37237 -261.244842) (xy 378.371872 -261.271491)
			(xy 378.600452 -261.271491) (xy 378.600452 -261.218193) (xy 378.608395 -261.165489) (xy 378.624105 -261.114559)
			(xy 378.647231 -261.066538) (xy 378.677255 -261.022501) (xy 378.713507 -260.98343) (xy 378.755178 -260.950199)
			(xy 378.801336 -260.92355) (xy 378.85095 -260.904078) (xy 378.902912 -260.892218) (xy 378.956062 -260.888235)
			(xy 379.009212 -260.892218) (xy 379.061174 -260.904078) (xy 379.110788 -260.92355) (xy 379.156946 -260.950199)
			(xy 379.198617 -260.98343) (xy 379.234869 -261.022501) (xy 379.264893 -261.066538) (xy 379.288019 -261.114559)
			(xy 379.303729 -261.165489) (xy 379.311672 -261.218193) (xy 379.31217 -261.244842) (xy 379.311672 -261.271491)
			(xy 379.540252 -261.271491) (xy 379.540252 -261.218193) (xy 379.548195 -261.165489) (xy 379.563905 -261.114559)
			(xy 379.587031 -261.066538) (xy 379.617055 -261.022501) (xy 379.653307 -260.98343) (xy 379.694978 -260.950199)
			(xy 379.741136 -260.92355) (xy 379.79075 -260.904078) (xy 379.842712 -260.892218) (xy 379.895862 -260.888235)
			(xy 379.949012 -260.892218) (xy 380.000974 -260.904078) (xy 380.050588 -260.92355) (xy 380.096746 -260.950199)
			(xy 380.138417 -260.98343) (xy 380.174669 -261.022501) (xy 380.204693 -261.066538) (xy 380.227819 -261.114559)
			(xy 380.243529 -261.165489) (xy 380.251472 -261.218193) (xy 380.25197 -261.244842) (xy 380.251472 -261.271491)
			(xy 380.480052 -261.271491) (xy 380.480052 -261.218193) (xy 380.487995 -261.165489) (xy 380.503705 -261.114559)
			(xy 380.526831 -261.066538) (xy 380.556855 -261.022501) (xy 380.593107 -260.98343) (xy 380.634778 -260.950199)
			(xy 380.680936 -260.92355) (xy 380.73055 -260.904078) (xy 380.782512 -260.892218) (xy 380.835662 -260.888235)
			(xy 380.888812 -260.892218) (xy 380.940774 -260.904078) (xy 380.990388 -260.92355) (xy 381.036546 -260.950199)
			(xy 381.078217 -260.98343) (xy 381.114469 -261.022501) (xy 381.144493 -261.066538) (xy 381.167619 -261.114559)
			(xy 381.183329 -261.165489) (xy 381.191272 -261.218193) (xy 381.19177 -261.244842) (xy 381.191272 -261.271491)
			(xy 381.183329 -261.324195) (xy 381.167619 -261.375125) (xy 381.144493 -261.423146) (xy 381.114469 -261.467183)
			(xy 381.078217 -261.506254) (xy 381.036546 -261.539485) (xy 380.990388 -261.566134) (xy 380.940774 -261.585606)
			(xy 380.888812 -261.597466) (xy 380.835662 -261.60145) (xy 380.782512 -261.597466) (xy 380.73055 -261.585606)
			(xy 380.680936 -261.566134) (xy 380.634778 -261.539485) (xy 380.593107 -261.506254) (xy 380.556855 -261.467183)
			(xy 380.526831 -261.423146) (xy 380.503705 -261.375125) (xy 380.487995 -261.324195) (xy 380.480052 -261.271491)
			(xy 380.251472 -261.271491) (xy 380.243529 -261.324195) (xy 380.227819 -261.375125) (xy 380.204693 -261.423146)
			(xy 380.174669 -261.467183) (xy 380.138417 -261.506254) (xy 380.096746 -261.539485) (xy 380.050588 -261.566134)
			(xy 380.000974 -261.585606) (xy 379.949012 -261.597466) (xy 379.895862 -261.60145) (xy 379.842712 -261.597466)
			(xy 379.79075 -261.585606) (xy 379.741136 -261.566134) (xy 379.694978 -261.539485) (xy 379.653307 -261.506254)
			(xy 379.617055 -261.467183) (xy 379.587031 -261.423146) (xy 379.563905 -261.375125) (xy 379.548195 -261.324195)
			(xy 379.540252 -261.271491) (xy 379.311672 -261.271491) (xy 379.303729 -261.324195) (xy 379.288019 -261.375125)
			(xy 379.264893 -261.423146) (xy 379.234869 -261.467183) (xy 379.198617 -261.506254) (xy 379.156946 -261.539485)
			(xy 379.110788 -261.566134) (xy 379.061174 -261.585606) (xy 379.009212 -261.597466) (xy 378.956062 -261.60145)
			(xy 378.902912 -261.597466) (xy 378.85095 -261.585606) (xy 378.801336 -261.566134) (xy 378.755178 -261.539485)
			(xy 378.713507 -261.506254) (xy 378.677255 -261.467183) (xy 378.647231 -261.423146) (xy 378.624105 -261.375125)
			(xy 378.608395 -261.324195) (xy 378.600452 -261.271491) (xy 378.371872 -261.271491) (xy 378.363929 -261.324195)
			(xy 378.348219 -261.375125) (xy 378.325093 -261.423146) (xy 378.295069 -261.467183) (xy 378.258817 -261.506254)
			(xy 378.217146 -261.539485) (xy 378.170988 -261.566134) (xy 378.121374 -261.585606) (xy 378.069412 -261.597466)
			(xy 378.016262 -261.60145) (xy 377.963112 -261.597466) (xy 377.91115 -261.585606) (xy 377.861536 -261.566134)
			(xy 377.815378 -261.539485) (xy 377.773707 -261.506254) (xy 377.737455 -261.467183) (xy 377.707431 -261.423146)
			(xy 377.684305 -261.375125) (xy 377.668595 -261.324195) (xy 377.660652 -261.271491) (xy 377.432072 -261.271491)
			(xy 377.424129 -261.324195) (xy 377.408419 -261.375125) (xy 377.385293 -261.423146) (xy 377.355269 -261.467183)
			(xy 377.319017 -261.506254) (xy 377.277346 -261.539485) (xy 377.231188 -261.566134) (xy 377.181574 -261.585606)
			(xy 377.129612 -261.597466) (xy 377.076462 -261.60145) (xy 377.023312 -261.597466) (xy 376.97135 -261.585606)
			(xy 376.921736 -261.566134) (xy 376.875578 -261.539485) (xy 376.833907 -261.506254) (xy 376.797655 -261.467183)
			(xy 376.767631 -261.423146) (xy 376.744505 -261.375125) (xy 376.728795 -261.324195) (xy 376.720852 -261.271491)
			(xy 376.492272 -261.271491) (xy 376.484329 -261.324195) (xy 376.468619 -261.375125) (xy 376.445493 -261.423146)
			(xy 376.415469 -261.467183) (xy 376.379217 -261.506254) (xy 376.337546 -261.539485) (xy 376.291388 -261.566134)
			(xy 376.241774 -261.585606) (xy 376.189812 -261.597466) (xy 376.136662 -261.60145) (xy 376.083512 -261.597466)
			(xy 376.03155 -261.585606) (xy 375.981936 -261.566134) (xy 375.935778 -261.539485) (xy 375.894107 -261.506254)
			(xy 375.857855 -261.467183) (xy 375.827831 -261.423146) (xy 375.804705 -261.375125) (xy 375.788995 -261.324195)
			(xy 375.781052 -261.271491) (xy 375.552472 -261.271491) (xy 375.544529 -261.324195) (xy 375.528819 -261.375125)
			(xy 375.505693 -261.423146) (xy 375.475669 -261.467183) (xy 375.439417 -261.506254) (xy 375.397746 -261.539485)
			(xy 375.351588 -261.566134) (xy 375.301974 -261.585606) (xy 375.250012 -261.597466) (xy 375.196862 -261.60145)
			(xy 375.143712 -261.597466) (xy 375.09175 -261.585606) (xy 375.042136 -261.566134) (xy 374.995978 -261.539485)
			(xy 374.954307 -261.506254) (xy 374.918055 -261.467183) (xy 374.888031 -261.423146) (xy 374.864905 -261.375125)
			(xy 374.849195 -261.324195) (xy 374.841252 -261.271491) (xy 374.612672 -261.271491) (xy 374.604729 -261.324195)
			(xy 374.589019 -261.375125) (xy 374.565893 -261.423146) (xy 374.535869 -261.467183) (xy 374.499617 -261.506254)
			(xy 374.457946 -261.539485) (xy 374.411788 -261.566134) (xy 374.362174 -261.585606) (xy 374.310212 -261.597466)
			(xy 374.257062 -261.60145) (xy 374.203912 -261.597466) (xy 374.15195 -261.585606) (xy 374.102336 -261.566134)
			(xy 374.056178 -261.539485) (xy 374.014507 -261.506254) (xy 373.978255 -261.467183) (xy 373.948231 -261.423146)
			(xy 373.925105 -261.375125) (xy 373.909395 -261.324195) (xy 373.901452 -261.271491) (xy 373.672872 -261.271491)
			(xy 373.664929 -261.324195) (xy 373.649219 -261.375125) (xy 373.626093 -261.423146) (xy 373.596069 -261.467183)
			(xy 373.559817 -261.506254) (xy 373.518146 -261.539485) (xy 373.471988 -261.566134) (xy 373.422374 -261.585606)
			(xy 373.370412 -261.597466) (xy 373.317262 -261.60145) (xy 373.264112 -261.597466) (xy 373.21215 -261.585606)
			(xy 373.162536 -261.566134) (xy 373.116378 -261.539485) (xy 373.074707 -261.506254) (xy 373.038455 -261.467183)
			(xy 373.008431 -261.423146) (xy 372.985305 -261.375125) (xy 372.969595 -261.324195) (xy 372.961652 -261.271491)
			(xy 372.733072 -261.271491) (xy 372.725129 -261.324195) (xy 372.709419 -261.375125) (xy 372.686293 -261.423146)
			(xy 372.656269 -261.467183) (xy 372.620017 -261.506254) (xy 372.578346 -261.539485) (xy 372.532188 -261.566134)
			(xy 372.482574 -261.585606) (xy 372.430612 -261.597466) (xy 372.377462 -261.60145) (xy 372.324312 -261.597466)
			(xy 372.27235 -261.585606) (xy 372.222736 -261.566134) (xy 372.176578 -261.539485) (xy 372.134907 -261.506254)
			(xy 372.098655 -261.467183) (xy 372.068631 -261.423146) (xy 372.045505 -261.375125) (xy 372.029795 -261.324195)
			(xy 372.021852 -261.271491) (xy 371.793272 -261.271491) (xy 371.785329 -261.324195) (xy 371.769619 -261.375125)
			(xy 371.746493 -261.423146) (xy 371.716469 -261.467183) (xy 371.680217 -261.506254) (xy 371.638546 -261.539485)
			(xy 371.592388 -261.566134) (xy 371.542774 -261.585606) (xy 371.490812 -261.597466) (xy 371.437662 -261.60145)
			(xy 371.384512 -261.597466) (xy 371.33255 -261.585606) (xy 371.282936 -261.566134) (xy 371.236778 -261.539485)
			(xy 371.195107 -261.506254) (xy 371.158855 -261.467183) (xy 371.128831 -261.423146) (xy 371.105705 -261.375125)
			(xy 371.089995 -261.324195) (xy 371.082052 -261.271491) (xy 370.853472 -261.271491) (xy 370.845529 -261.324195)
			(xy 370.829819 -261.375125) (xy 370.806693 -261.423146) (xy 370.776669 -261.467183) (xy 370.740417 -261.506254)
			(xy 370.698746 -261.539485) (xy 370.652588 -261.566134) (xy 370.602974 -261.585606) (xy 370.551012 -261.597466)
			(xy 370.497862 -261.60145) (xy 370.444712 -261.597466) (xy 370.39275 -261.585606) (xy 370.343136 -261.566134)
			(xy 370.296978 -261.539485) (xy 370.255307 -261.506254) (xy 370.219055 -261.467183) (xy 370.189031 -261.423146)
			(xy 370.165905 -261.375125) (xy 370.150195 -261.324195) (xy 370.142252 -261.271491) (xy 369.913672 -261.271491)
			(xy 369.905729 -261.324195) (xy 369.890019 -261.375125) (xy 369.866893 -261.423146) (xy 369.836869 -261.467183)
			(xy 369.800617 -261.506254) (xy 369.758946 -261.539485) (xy 369.712788 -261.566134) (xy 369.663174 -261.585606)
			(xy 369.611212 -261.597466) (xy 369.558062 -261.60145) (xy 369.504912 -261.597466) (xy 369.45295 -261.585606)
			(xy 369.403336 -261.566134) (xy 369.357178 -261.539485) (xy 369.315507 -261.506254) (xy 369.279255 -261.467183)
			(xy 369.249231 -261.423146) (xy 369.226105 -261.375125) (xy 369.210395 -261.324195) (xy 369.202452 -261.271491)
			(xy 367.36528 -261.271491) (xy 367.36528 -262.085307) (xy 369.672606 -262.085307) (xy 369.672606 -262.032009)
			(xy 369.680549 -261.979305) (xy 369.696259 -261.928375) (xy 369.719385 -261.880354) (xy 369.749409 -261.836317)
			(xy 369.785661 -261.797246) (xy 369.827332 -261.764015) (xy 369.87349 -261.737366) (xy 369.923104 -261.717894)
			(xy 369.975066 -261.706034) (xy 370.028216 -261.702051) (xy 370.081366 -261.706034) (xy 370.133328 -261.717894)
			(xy 370.182942 -261.737366) (xy 370.2291 -261.764015) (xy 370.270771 -261.797246) (xy 370.307023 -261.836317)
			(xy 370.337047 -261.880354) (xy 370.360173 -261.928375) (xy 370.375883 -261.979305) (xy 370.383826 -262.032009)
			(xy 370.384324 -262.058658) (xy 370.383826 -262.085307) (xy 370.612152 -262.085307) (xy 370.612152 -262.032009)
			(xy 370.620095 -261.979305) (xy 370.635805 -261.928375) (xy 370.658931 -261.880354) (xy 370.688955 -261.836317)
			(xy 370.725207 -261.797246) (xy 370.766878 -261.764015) (xy 370.813036 -261.737366) (xy 370.86265 -261.717894)
			(xy 370.914612 -261.706034) (xy 370.967762 -261.702051) (xy 371.020912 -261.706034) (xy 371.072874 -261.717894)
			(xy 371.122488 -261.737366) (xy 371.168646 -261.764015) (xy 371.210317 -261.797246) (xy 371.246569 -261.836317)
			(xy 371.276593 -261.880354) (xy 371.299719 -261.928375) (xy 371.315429 -261.979305) (xy 371.323372 -262.032009)
			(xy 371.32387 -262.058658) (xy 371.323372 -262.085307) (xy 371.552206 -262.085307) (xy 371.552206 -262.032009)
			(xy 371.560149 -261.979305) (xy 371.575859 -261.928375) (xy 371.598985 -261.880354) (xy 371.629009 -261.836317)
			(xy 371.665261 -261.797246) (xy 371.706932 -261.764015) (xy 371.75309 -261.737366) (xy 371.802704 -261.717894)
			(xy 371.854666 -261.706034) (xy 371.907816 -261.702051) (xy 371.960966 -261.706034) (xy 372.012928 -261.717894)
			(xy 372.062542 -261.737366) (xy 372.1087 -261.764015) (xy 372.150371 -261.797246) (xy 372.186623 -261.836317)
			(xy 372.216647 -261.880354) (xy 372.239773 -261.928375) (xy 372.255483 -261.979305) (xy 372.263426 -262.032009)
			(xy 372.263924 -262.058658) (xy 372.263426 -262.085307) (xy 372.492006 -262.085307) (xy 372.492006 -262.032009)
			(xy 372.499949 -261.979305) (xy 372.515659 -261.928375) (xy 372.538785 -261.880354) (xy 372.568809 -261.836317)
			(xy 372.605061 -261.797246) (xy 372.646732 -261.764015) (xy 372.69289 -261.737366) (xy 372.742504 -261.717894)
			(xy 372.794466 -261.706034) (xy 372.847616 -261.702051) (xy 372.900766 -261.706034) (xy 372.952728 -261.717894)
			(xy 373.002342 -261.737366) (xy 373.0485 -261.764015) (xy 373.090171 -261.797246) (xy 373.126423 -261.836317)
			(xy 373.156447 -261.880354) (xy 373.179573 -261.928375) (xy 373.195283 -261.979305) (xy 373.203226 -262.032009)
			(xy 373.203724 -262.058658) (xy 373.203226 -262.085307) (xy 373.431552 -262.085307) (xy 373.431552 -262.032009)
			(xy 373.439495 -261.979305) (xy 373.455205 -261.928375) (xy 373.478331 -261.880354) (xy 373.508355 -261.836317)
			(xy 373.544607 -261.797246) (xy 373.586278 -261.764015) (xy 373.632436 -261.737366) (xy 373.68205 -261.717894)
			(xy 373.734012 -261.706034) (xy 373.787162 -261.702051) (xy 373.840312 -261.706034) (xy 373.892274 -261.717894)
			(xy 373.941888 -261.737366) (xy 373.988046 -261.764015) (xy 374.029717 -261.797246) (xy 374.065969 -261.836317)
			(xy 374.095993 -261.880354) (xy 374.119119 -261.928375) (xy 374.134829 -261.979305) (xy 374.142772 -262.032009)
			(xy 374.14327 -262.058658) (xy 374.142772 -262.085307) (xy 374.371606 -262.085307) (xy 374.371606 -262.032009)
			(xy 374.379549 -261.979305) (xy 374.395259 -261.928375) (xy 374.418385 -261.880354) (xy 374.448409 -261.836317)
			(xy 374.484661 -261.797246) (xy 374.526332 -261.764015) (xy 374.57249 -261.737366) (xy 374.622104 -261.717894)
			(xy 374.674066 -261.706034) (xy 374.727216 -261.702051) (xy 374.780366 -261.706034) (xy 374.832328 -261.717894)
			(xy 374.881942 -261.737366) (xy 374.9281 -261.764015) (xy 374.969771 -261.797246) (xy 375.006023 -261.836317)
			(xy 375.036047 -261.880354) (xy 375.059173 -261.928375) (xy 375.074883 -261.979305) (xy 375.082826 -262.032009)
			(xy 375.083324 -262.058658) (xy 375.082826 -262.085307) (xy 375.311406 -262.085307) (xy 375.311406 -262.032009)
			(xy 375.319349 -261.979305) (xy 375.335059 -261.928375) (xy 375.358185 -261.880354) (xy 375.388209 -261.836317)
			(xy 375.424461 -261.797246) (xy 375.466132 -261.764015) (xy 375.51229 -261.737366) (xy 375.561904 -261.717894)
			(xy 375.613866 -261.706034) (xy 375.667016 -261.702051) (xy 375.720166 -261.706034) (xy 375.772128 -261.717894)
			(xy 375.821742 -261.737366) (xy 375.8679 -261.764015) (xy 375.909571 -261.797246) (xy 375.945823 -261.836317)
			(xy 375.975847 -261.880354) (xy 375.998973 -261.928375) (xy 376.014683 -261.979305) (xy 376.022626 -262.032009)
			(xy 376.023124 -262.058658) (xy 376.022626 -262.085307) (xy 376.251206 -262.085307) (xy 376.251206 -262.032009)
			(xy 376.259149 -261.979305) (xy 376.274859 -261.928375) (xy 376.297985 -261.880354) (xy 376.328009 -261.836317)
			(xy 376.364261 -261.797246) (xy 376.405932 -261.764015) (xy 376.45209 -261.737366) (xy 376.501704 -261.717894)
			(xy 376.553666 -261.706034) (xy 376.606816 -261.702051) (xy 376.659966 -261.706034) (xy 376.711928 -261.717894)
			(xy 376.761542 -261.737366) (xy 376.8077 -261.764015) (xy 376.849371 -261.797246) (xy 376.885623 -261.836317)
			(xy 376.915647 -261.880354) (xy 376.938773 -261.928375) (xy 376.954483 -261.979305) (xy 376.962426 -262.032009)
			(xy 376.962924 -262.058658) (xy 376.962426 -262.085307) (xy 377.191006 -262.085307) (xy 377.191006 -262.032009)
			(xy 377.198949 -261.979305) (xy 377.214659 -261.928375) (xy 377.237785 -261.880354) (xy 377.267809 -261.836317)
			(xy 377.304061 -261.797246) (xy 377.345732 -261.764015) (xy 377.39189 -261.737366) (xy 377.441504 -261.717894)
			(xy 377.493466 -261.706034) (xy 377.546616 -261.702051) (xy 377.599766 -261.706034) (xy 377.651728 -261.717894)
			(xy 377.701342 -261.737366) (xy 377.7475 -261.764015) (xy 377.789171 -261.797246) (xy 377.825423 -261.836317)
			(xy 377.855447 -261.880354) (xy 377.878573 -261.928375) (xy 377.894283 -261.979305) (xy 377.902226 -262.032009)
			(xy 377.902724 -262.058658) (xy 377.902226 -262.085307) (xy 378.130806 -262.085307) (xy 378.130806 -262.032009)
			(xy 378.138749 -261.979305) (xy 378.154459 -261.928375) (xy 378.177585 -261.880354) (xy 378.207609 -261.836317)
			(xy 378.243861 -261.797246) (xy 378.285532 -261.764015) (xy 378.33169 -261.737366) (xy 378.381304 -261.717894)
			(xy 378.433266 -261.706034) (xy 378.486416 -261.702051) (xy 378.539566 -261.706034) (xy 378.591528 -261.717894)
			(xy 378.641142 -261.737366) (xy 378.6873 -261.764015) (xy 378.728971 -261.797246) (xy 378.765223 -261.836317)
			(xy 378.795247 -261.880354) (xy 378.818373 -261.928375) (xy 378.834083 -261.979305) (xy 378.842026 -262.032009)
			(xy 378.842524 -262.058658) (xy 378.842026 -262.085307) (xy 379.070606 -262.085307) (xy 379.070606 -262.032009)
			(xy 379.078549 -261.979305) (xy 379.094259 -261.928375) (xy 379.117385 -261.880354) (xy 379.147409 -261.836317)
			(xy 379.183661 -261.797246) (xy 379.225332 -261.764015) (xy 379.27149 -261.737366) (xy 379.321104 -261.717894)
			(xy 379.373066 -261.706034) (xy 379.426216 -261.702051) (xy 379.479366 -261.706034) (xy 379.531328 -261.717894)
			(xy 379.580942 -261.737366) (xy 379.6271 -261.764015) (xy 379.668771 -261.797246) (xy 379.705023 -261.836317)
			(xy 379.735047 -261.880354) (xy 379.758173 -261.928375) (xy 379.773883 -261.979305) (xy 379.781826 -262.032009)
			(xy 379.782324 -262.058658) (xy 379.781826 -262.085307) (xy 380.010152 -262.085307) (xy 380.010152 -262.032009)
			(xy 380.018095 -261.979305) (xy 380.033805 -261.928375) (xy 380.056931 -261.880354) (xy 380.086955 -261.836317)
			(xy 380.123207 -261.797246) (xy 380.164878 -261.764015) (xy 380.211036 -261.737366) (xy 380.26065 -261.717894)
			(xy 380.312612 -261.706034) (xy 380.365762 -261.702051) (xy 380.418912 -261.706034) (xy 380.470874 -261.717894)
			(xy 380.520488 -261.737366) (xy 380.566646 -261.764015) (xy 380.608317 -261.797246) (xy 380.644569 -261.836317)
			(xy 380.674593 -261.880354) (xy 380.697719 -261.928375) (xy 380.713429 -261.979305) (xy 380.721372 -262.032009)
			(xy 380.72187 -262.058658) (xy 380.721372 -262.085307) (xy 380.950206 -262.085307) (xy 380.950206 -262.032009)
			(xy 380.958149 -261.979305) (xy 380.973859 -261.928375) (xy 380.996985 -261.880354) (xy 381.027009 -261.836317)
			(xy 381.063261 -261.797246) (xy 381.104932 -261.764015) (xy 381.15109 -261.737366) (xy 381.200704 -261.717894)
			(xy 381.252666 -261.706034) (xy 381.305816 -261.702051) (xy 381.358966 -261.706034) (xy 381.410928 -261.717894)
			(xy 381.460542 -261.737366) (xy 381.5067 -261.764015) (xy 381.548371 -261.797246) (xy 381.584623 -261.836317)
			(xy 381.614647 -261.880354) (xy 381.637773 -261.928375) (xy 381.653483 -261.979305) (xy 381.661426 -262.032009)
			(xy 381.661924 -262.058658) (xy 381.661426 -262.085307) (xy 381.653483 -262.138011) (xy 381.637773 -262.188941)
			(xy 381.614647 -262.236962) (xy 381.584623 -262.280999) (xy 381.548371 -262.32007) (xy 381.5067 -262.353301)
			(xy 381.460542 -262.37995) (xy 381.410928 -262.399422) (xy 381.358966 -262.411282) (xy 381.305816 -262.415266)
			(xy 381.252666 -262.411282) (xy 381.200704 -262.399422) (xy 381.15109 -262.37995) (xy 381.104932 -262.353301)
			(xy 381.063261 -262.32007) (xy 381.027009 -262.280999) (xy 380.996985 -262.236962) (xy 380.973859 -262.188941)
			(xy 380.958149 -262.138011) (xy 380.950206 -262.085307) (xy 380.721372 -262.085307) (xy 380.713429 -262.138011)
			(xy 380.697719 -262.188941) (xy 380.674593 -262.236962) (xy 380.644569 -262.280999) (xy 380.608317 -262.32007)
			(xy 380.566646 -262.353301) (xy 380.520488 -262.37995) (xy 380.470874 -262.399422) (xy 380.418912 -262.411282)
			(xy 380.365762 -262.415266) (xy 380.312612 -262.411282) (xy 380.26065 -262.399422) (xy 380.211036 -262.37995)
			(xy 380.164878 -262.353301) (xy 380.123207 -262.32007) (xy 380.086955 -262.280999) (xy 380.056931 -262.236962)
			(xy 380.033805 -262.188941) (xy 380.018095 -262.138011) (xy 380.010152 -262.085307) (xy 379.781826 -262.085307)
			(xy 379.773883 -262.138011) (xy 379.758173 -262.188941) (xy 379.735047 -262.236962) (xy 379.705023 -262.280999)
			(xy 379.668771 -262.32007) (xy 379.6271 -262.353301) (xy 379.580942 -262.37995) (xy 379.531328 -262.399422)
			(xy 379.479366 -262.411282) (xy 379.426216 -262.415266) (xy 379.373066 -262.411282) (xy 379.321104 -262.399422)
			(xy 379.27149 -262.37995) (xy 379.225332 -262.353301) (xy 379.183661 -262.32007) (xy 379.147409 -262.280999)
			(xy 379.117385 -262.236962) (xy 379.094259 -262.188941) (xy 379.078549 -262.138011) (xy 379.070606 -262.085307)
			(xy 378.842026 -262.085307) (xy 378.834083 -262.138011) (xy 378.818373 -262.188941) (xy 378.795247 -262.236962)
			(xy 378.765223 -262.280999) (xy 378.728971 -262.32007) (xy 378.6873 -262.353301) (xy 378.641142 -262.37995)
			(xy 378.591528 -262.399422) (xy 378.539566 -262.411282) (xy 378.486416 -262.415266) (xy 378.433266 -262.411282)
			(xy 378.381304 -262.399422) (xy 378.33169 -262.37995) (xy 378.285532 -262.353301) (xy 378.243861 -262.32007)
			(xy 378.207609 -262.280999) (xy 378.177585 -262.236962) (xy 378.154459 -262.188941) (xy 378.138749 -262.138011)
			(xy 378.130806 -262.085307) (xy 377.902226 -262.085307) (xy 377.894283 -262.138011) (xy 377.878573 -262.188941)
			(xy 377.855447 -262.236962) (xy 377.825423 -262.280999) (xy 377.789171 -262.32007) (xy 377.7475 -262.353301)
			(xy 377.701342 -262.37995) (xy 377.651728 -262.399422) (xy 377.599766 -262.411282) (xy 377.546616 -262.415266)
			(xy 377.493466 -262.411282) (xy 377.441504 -262.399422) (xy 377.39189 -262.37995) (xy 377.345732 -262.353301)
			(xy 377.304061 -262.32007) (xy 377.267809 -262.280999) (xy 377.237785 -262.236962) (xy 377.214659 -262.188941)
			(xy 377.198949 -262.138011) (xy 377.191006 -262.085307) (xy 376.962426 -262.085307) (xy 376.954483 -262.138011)
			(xy 376.938773 -262.188941) (xy 376.915647 -262.236962) (xy 376.885623 -262.280999) (xy 376.849371 -262.32007)
			(xy 376.8077 -262.353301) (xy 376.761542 -262.37995) (xy 376.711928 -262.399422) (xy 376.659966 -262.411282)
			(xy 376.606816 -262.415266) (xy 376.553666 -262.411282) (xy 376.501704 -262.399422) (xy 376.45209 -262.37995)
			(xy 376.405932 -262.353301) (xy 376.364261 -262.32007) (xy 376.328009 -262.280999) (xy 376.297985 -262.236962)
			(xy 376.274859 -262.188941) (xy 376.259149 -262.138011) (xy 376.251206 -262.085307) (xy 376.022626 -262.085307)
			(xy 376.014683 -262.138011) (xy 375.998973 -262.188941) (xy 375.975847 -262.236962) (xy 375.945823 -262.280999)
			(xy 375.909571 -262.32007) (xy 375.8679 -262.353301) (xy 375.821742 -262.37995) (xy 375.772128 -262.399422)
			(xy 375.720166 -262.411282) (xy 375.667016 -262.415266) (xy 375.613866 -262.411282) (xy 375.561904 -262.399422)
			(xy 375.51229 -262.37995) (xy 375.466132 -262.353301) (xy 375.424461 -262.32007) (xy 375.388209 -262.280999)
			(xy 375.358185 -262.236962) (xy 375.335059 -262.188941) (xy 375.319349 -262.138011) (xy 375.311406 -262.085307)
			(xy 375.082826 -262.085307) (xy 375.074883 -262.138011) (xy 375.059173 -262.188941) (xy 375.036047 -262.236962)
			(xy 375.006023 -262.280999) (xy 374.969771 -262.32007) (xy 374.9281 -262.353301) (xy 374.881942 -262.37995)
			(xy 374.832328 -262.399422) (xy 374.780366 -262.411282) (xy 374.727216 -262.415266) (xy 374.674066 -262.411282)
			(xy 374.622104 -262.399422) (xy 374.57249 -262.37995) (xy 374.526332 -262.353301) (xy 374.484661 -262.32007)
			(xy 374.448409 -262.280999) (xy 374.418385 -262.236962) (xy 374.395259 -262.188941) (xy 374.379549 -262.138011)
			(xy 374.371606 -262.085307) (xy 374.142772 -262.085307) (xy 374.134829 -262.138011) (xy 374.119119 -262.188941)
			(xy 374.095993 -262.236962) (xy 374.065969 -262.280999) (xy 374.029717 -262.32007) (xy 373.988046 -262.353301)
			(xy 373.941888 -262.37995) (xy 373.892274 -262.399422) (xy 373.840312 -262.411282) (xy 373.787162 -262.415266)
			(xy 373.734012 -262.411282) (xy 373.68205 -262.399422) (xy 373.632436 -262.37995) (xy 373.586278 -262.353301)
			(xy 373.544607 -262.32007) (xy 373.508355 -262.280999) (xy 373.478331 -262.236962) (xy 373.455205 -262.188941)
			(xy 373.439495 -262.138011) (xy 373.431552 -262.085307) (xy 373.203226 -262.085307) (xy 373.195283 -262.138011)
			(xy 373.179573 -262.188941) (xy 373.156447 -262.236962) (xy 373.126423 -262.280999) (xy 373.090171 -262.32007)
			(xy 373.0485 -262.353301) (xy 373.002342 -262.37995) (xy 372.952728 -262.399422) (xy 372.900766 -262.411282)
			(xy 372.847616 -262.415266) (xy 372.794466 -262.411282) (xy 372.742504 -262.399422) (xy 372.69289 -262.37995)
			(xy 372.646732 -262.353301) (xy 372.605061 -262.32007) (xy 372.568809 -262.280999) (xy 372.538785 -262.236962)
			(xy 372.515659 -262.188941) (xy 372.499949 -262.138011) (xy 372.492006 -262.085307) (xy 372.263426 -262.085307)
			(xy 372.255483 -262.138011) (xy 372.239773 -262.188941) (xy 372.216647 -262.236962) (xy 372.186623 -262.280999)
			(xy 372.150371 -262.32007) (xy 372.1087 -262.353301) (xy 372.062542 -262.37995) (xy 372.012928 -262.399422)
			(xy 371.960966 -262.411282) (xy 371.907816 -262.415266) (xy 371.854666 -262.411282) (xy 371.802704 -262.399422)
			(xy 371.75309 -262.37995) (xy 371.706932 -262.353301) (xy 371.665261 -262.32007) (xy 371.629009 -262.280999)
			(xy 371.598985 -262.236962) (xy 371.575859 -262.188941) (xy 371.560149 -262.138011) (xy 371.552206 -262.085307)
			(xy 371.323372 -262.085307) (xy 371.315429 -262.138011) (xy 371.299719 -262.188941) (xy 371.276593 -262.236962)
			(xy 371.246569 -262.280999) (xy 371.210317 -262.32007) (xy 371.168646 -262.353301) (xy 371.122488 -262.37995)
			(xy 371.072874 -262.399422) (xy 371.020912 -262.411282) (xy 370.967762 -262.415266) (xy 370.914612 -262.411282)
			(xy 370.86265 -262.399422) (xy 370.813036 -262.37995) (xy 370.766878 -262.353301) (xy 370.725207 -262.32007)
			(xy 370.688955 -262.280999) (xy 370.658931 -262.236962) (xy 370.635805 -262.188941) (xy 370.620095 -262.138011)
			(xy 370.612152 -262.085307) (xy 370.383826 -262.085307) (xy 370.375883 -262.138011) (xy 370.360173 -262.188941)
			(xy 370.337047 -262.236962) (xy 370.307023 -262.280999) (xy 370.270771 -262.32007) (xy 370.2291 -262.353301)
			(xy 370.182942 -262.37995) (xy 370.133328 -262.399422) (xy 370.081366 -262.411282) (xy 370.028216 -262.415266)
			(xy 369.975066 -262.411282) (xy 369.923104 -262.399422) (xy 369.87349 -262.37995) (xy 369.827332 -262.353301)
			(xy 369.785661 -262.32007) (xy 369.749409 -262.280999) (xy 369.719385 -262.236962) (xy 369.696259 -262.188941)
			(xy 369.680549 -262.138011) (xy 369.672606 -262.085307) (xy 367.36528 -262.085307) (xy 367.36528 -262.856218)
			(xy 367.365759 -262.870556) (xy 367.373714 -262.898105) (xy 367.389021 -262.922353) (xy 367.410469 -262.941385)
			(xy 367.436365 -262.953698) (xy 367.464665 -262.95832) (xy 367.493134 -262.954886) (xy 367.506504 -262.94969)
			(xy 367.528603 -262.940736) (xy 367.574594 -262.928155) (xy 367.621855 -262.921835) (xy 367.645696 -262.921496)
			(xy 367.671299 -262.92192) (xy 367.721981 -262.929224) (xy 367.77109 -262.943722) (xy 367.79454 -262.954008)
			(xy 367.807568 -262.959495) (xy 367.835492 -262.963817) (xy 367.863531 -262.960321) (xy 367.88954 -262.949276)
			(xy 367.911527 -262.931527) (xy 367.920016 -262.920226) (xy 367.936839 -262.897365) (xy 367.976522 -262.856789)
			(xy 368.022139 -262.82302) (xy 368.072534 -262.796913) (xy 368.126432 -262.779129) (xy 368.182468 -262.770119)
			(xy 368.210846 -262.769604) (xy 368.237492 -262.770105) (xy 368.290188 -262.778054) (xy 368.341112 -262.793767)
			(xy 368.389124 -262.816895) (xy 368.433154 -262.846919) (xy 368.472218 -262.88317) (xy 368.484939 -262.899123)
			(xy 369.202452 -262.899123) (xy 369.202452 -262.845825) (xy 369.210395 -262.793121) (xy 369.226105 -262.742191)
			(xy 369.249231 -262.69417) (xy 369.279255 -262.650133) (xy 369.315507 -262.611062) (xy 369.357178 -262.577831)
			(xy 369.403336 -262.551182) (xy 369.45295 -262.53171) (xy 369.504912 -262.51985) (xy 369.558062 -262.515867)
			(xy 369.611212 -262.51985) (xy 369.663174 -262.53171) (xy 369.712788 -262.551182) (xy 369.758946 -262.577831)
			(xy 369.800617 -262.611062) (xy 369.836869 -262.650133) (xy 369.866893 -262.69417) (xy 369.890019 -262.742191)
			(xy 369.905729 -262.793121) (xy 369.913672 -262.845825) (xy 369.91417 -262.872474) (xy 369.913672 -262.899123)
			(xy 370.142506 -262.899123) (xy 370.142506 -262.845825) (xy 370.150449 -262.793121) (xy 370.166159 -262.742191)
			(xy 370.189285 -262.69417) (xy 370.219309 -262.650133) (xy 370.255561 -262.611062) (xy 370.297232 -262.577831)
			(xy 370.34339 -262.551182) (xy 370.393004 -262.53171) (xy 370.444966 -262.51985) (xy 370.498116 -262.515867)
			(xy 370.551266 -262.51985) (xy 370.603228 -262.53171) (xy 370.652842 -262.551182) (xy 370.699 -262.577831)
			(xy 370.740671 -262.611062) (xy 370.776923 -262.650133) (xy 370.806947 -262.69417) (xy 370.830073 -262.742191)
			(xy 370.845783 -262.793121) (xy 370.853726 -262.845825) (xy 370.854224 -262.872474) (xy 370.853726 -262.899123)
			(xy 371.082052 -262.899123) (xy 371.082052 -262.845825) (xy 371.089995 -262.793121) (xy 371.105705 -262.742191)
			(xy 371.128831 -262.69417) (xy 371.158855 -262.650133) (xy 371.195107 -262.611062) (xy 371.236778 -262.577831)
			(xy 371.282936 -262.551182) (xy 371.33255 -262.53171) (xy 371.384512 -262.51985) (xy 371.437662 -262.515867)
			(xy 371.490812 -262.51985) (xy 371.542774 -262.53171) (xy 371.592388 -262.551182) (xy 371.638546 -262.577831)
			(xy 371.680217 -262.611062) (xy 371.716469 -262.650133) (xy 371.746493 -262.69417) (xy 371.769619 -262.742191)
			(xy 371.785329 -262.793121) (xy 371.793272 -262.845825) (xy 371.79377 -262.872474) (xy 371.793272 -262.899123)
			(xy 372.021852 -262.899123) (xy 372.021852 -262.845825) (xy 372.029795 -262.793121) (xy 372.045505 -262.742191)
			(xy 372.068631 -262.69417) (xy 372.098655 -262.650133) (xy 372.134907 -262.611062) (xy 372.176578 -262.577831)
			(xy 372.222736 -262.551182) (xy 372.27235 -262.53171) (xy 372.324312 -262.51985) (xy 372.377462 -262.515867)
			(xy 372.430612 -262.51985) (xy 372.482574 -262.53171) (xy 372.532188 -262.551182) (xy 372.578346 -262.577831)
			(xy 372.620017 -262.611062) (xy 372.656269 -262.650133) (xy 372.686293 -262.69417) (xy 372.709419 -262.742191)
			(xy 372.725129 -262.793121) (xy 372.733072 -262.845825) (xy 372.73357 -262.872474) (xy 372.733072 -262.899123)
			(xy 372.961906 -262.899123) (xy 372.961906 -262.845825) (xy 372.969849 -262.793121) (xy 372.985559 -262.742191)
			(xy 373.008685 -262.69417) (xy 373.038709 -262.650133) (xy 373.074961 -262.611062) (xy 373.116632 -262.577831)
			(xy 373.16279 -262.551182) (xy 373.212404 -262.53171) (xy 373.264366 -262.51985) (xy 373.317516 -262.515867)
			(xy 373.370666 -262.51985) (xy 373.422628 -262.53171) (xy 373.472242 -262.551182) (xy 373.5184 -262.577831)
			(xy 373.560071 -262.611062) (xy 373.596323 -262.650133) (xy 373.626347 -262.69417) (xy 373.649473 -262.742191)
			(xy 373.665183 -262.793121) (xy 373.673126 -262.845825) (xy 373.673624 -262.872474) (xy 373.673126 -262.899123)
			(xy 373.901452 -262.899123) (xy 373.901452 -262.845825) (xy 373.909395 -262.793121) (xy 373.925105 -262.742191)
			(xy 373.948231 -262.69417) (xy 373.978255 -262.650133) (xy 374.014507 -262.611062) (xy 374.056178 -262.577831)
			(xy 374.102336 -262.551182) (xy 374.15195 -262.53171) (xy 374.203912 -262.51985) (xy 374.257062 -262.515867)
			(xy 374.310212 -262.51985) (xy 374.362174 -262.53171) (xy 374.411788 -262.551182) (xy 374.457946 -262.577831)
			(xy 374.499617 -262.611062) (xy 374.535869 -262.650133) (xy 374.565893 -262.69417) (xy 374.589019 -262.742191)
			(xy 374.604729 -262.793121) (xy 374.612672 -262.845825) (xy 374.61317 -262.872474) (xy 374.612672 -262.899123)
			(xy 374.841252 -262.899123) (xy 374.841252 -262.845825) (xy 374.849195 -262.793121) (xy 374.864905 -262.742191)
			(xy 374.888031 -262.69417) (xy 374.918055 -262.650133) (xy 374.954307 -262.611062) (xy 374.995978 -262.577831)
			(xy 375.042136 -262.551182) (xy 375.09175 -262.53171) (xy 375.143712 -262.51985) (xy 375.196862 -262.515867)
			(xy 375.250012 -262.51985) (xy 375.301974 -262.53171) (xy 375.351588 -262.551182) (xy 375.397746 -262.577831)
			(xy 375.439417 -262.611062) (xy 375.475669 -262.650133) (xy 375.505693 -262.69417) (xy 375.528819 -262.742191)
			(xy 375.544529 -262.793121) (xy 375.552472 -262.845825) (xy 375.55297 -262.872474) (xy 375.552472 -262.899123)
			(xy 375.781052 -262.899123) (xy 375.781052 -262.845825) (xy 375.788995 -262.793121) (xy 375.804705 -262.742191)
			(xy 375.827831 -262.69417) (xy 375.857855 -262.650133) (xy 375.894107 -262.611062) (xy 375.935778 -262.577831)
			(xy 375.981936 -262.551182) (xy 376.03155 -262.53171) (xy 376.083512 -262.51985) (xy 376.136662 -262.515867)
			(xy 376.189812 -262.51985) (xy 376.241774 -262.53171) (xy 376.291388 -262.551182) (xy 376.337546 -262.577831)
			(xy 376.379217 -262.611062) (xy 376.415469 -262.650133) (xy 376.445493 -262.69417) (xy 376.468619 -262.742191)
			(xy 376.484329 -262.793121) (xy 376.492272 -262.845825) (xy 376.49277 -262.872474) (xy 376.492272 -262.899123)
			(xy 376.720852 -262.899123) (xy 376.720852 -262.845825) (xy 376.728795 -262.793121) (xy 376.744505 -262.742191)
			(xy 376.767631 -262.69417) (xy 376.797655 -262.650133) (xy 376.833907 -262.611062) (xy 376.875578 -262.577831)
			(xy 376.921736 -262.551182) (xy 376.97135 -262.53171) (xy 377.023312 -262.51985) (xy 377.076462 -262.515867)
			(xy 377.129612 -262.51985) (xy 377.181574 -262.53171) (xy 377.231188 -262.551182) (xy 377.277346 -262.577831)
			(xy 377.319017 -262.611062) (xy 377.355269 -262.650133) (xy 377.385293 -262.69417) (xy 377.408419 -262.742191)
			(xy 377.424129 -262.793121) (xy 377.432072 -262.845825) (xy 377.43257 -262.872474) (xy 377.432072 -262.899123)
			(xy 377.660652 -262.899123) (xy 377.660652 -262.845825) (xy 377.668595 -262.793121) (xy 377.684305 -262.742191)
			(xy 377.707431 -262.69417) (xy 377.737455 -262.650133) (xy 377.773707 -262.611062) (xy 377.815378 -262.577831)
			(xy 377.861536 -262.551182) (xy 377.91115 -262.53171) (xy 377.963112 -262.51985) (xy 378.016262 -262.515867)
			(xy 378.069412 -262.51985) (xy 378.121374 -262.53171) (xy 378.170988 -262.551182) (xy 378.217146 -262.577831)
			(xy 378.258817 -262.611062) (xy 378.295069 -262.650133) (xy 378.325093 -262.69417) (xy 378.348219 -262.742191)
			(xy 378.363929 -262.793121) (xy 378.371872 -262.845825) (xy 378.37237 -262.872474) (xy 378.371872 -262.899123)
			(xy 378.600452 -262.899123) (xy 378.600452 -262.845825) (xy 378.608395 -262.793121) (xy 378.624105 -262.742191)
			(xy 378.647231 -262.69417) (xy 378.677255 -262.650133) (xy 378.713507 -262.611062) (xy 378.755178 -262.577831)
			(xy 378.801336 -262.551182) (xy 378.85095 -262.53171) (xy 378.902912 -262.51985) (xy 378.956062 -262.515867)
			(xy 379.009212 -262.51985) (xy 379.061174 -262.53171) (xy 379.110788 -262.551182) (xy 379.156946 -262.577831)
			(xy 379.198617 -262.611062) (xy 379.234869 -262.650133) (xy 379.264893 -262.69417) (xy 379.288019 -262.742191)
			(xy 379.303729 -262.793121) (xy 379.311672 -262.845825) (xy 379.31217 -262.872474) (xy 379.311672 -262.899123)
			(xy 379.540506 -262.899123) (xy 379.540506 -262.845825) (xy 379.548449 -262.793121) (xy 379.564159 -262.742191)
			(xy 379.587285 -262.69417) (xy 379.617309 -262.650133) (xy 379.653561 -262.611062) (xy 379.695232 -262.577831)
			(xy 379.74139 -262.551182) (xy 379.791004 -262.53171) (xy 379.842966 -262.51985) (xy 379.896116 -262.515867)
			(xy 379.949266 -262.51985) (xy 380.001228 -262.53171) (xy 380.050842 -262.551182) (xy 380.097 -262.577831)
			(xy 380.138671 -262.611062) (xy 380.174923 -262.650133) (xy 380.204947 -262.69417) (xy 380.228073 -262.742191)
			(xy 380.243783 -262.793121) (xy 380.251726 -262.845825) (xy 380.252224 -262.872474) (xy 380.251726 -262.899123)
			(xy 380.480052 -262.899123) (xy 380.480052 -262.845825) (xy 380.487995 -262.793121) (xy 380.503705 -262.742191)
			(xy 380.526831 -262.69417) (xy 380.556855 -262.650133) (xy 380.593107 -262.611062) (xy 380.634778 -262.577831)
			(xy 380.680936 -262.551182) (xy 380.73055 -262.53171) (xy 380.782512 -262.51985) (xy 380.835662 -262.515867)
			(xy 380.888812 -262.51985) (xy 380.940774 -262.53171) (xy 380.990388 -262.551182) (xy 381.036546 -262.577831)
			(xy 381.078217 -262.611062) (xy 381.114469 -262.650133) (xy 381.144493 -262.69417) (xy 381.167619 -262.742191)
			(xy 381.183329 -262.793121) (xy 381.191272 -262.845825) (xy 381.19177 -262.872474) (xy 381.191272 -262.899123)
			(xy 381.183329 -262.951827) (xy 381.167619 -263.002757) (xy 381.144493 -263.050778) (xy 381.114469 -263.094815)
			(xy 381.078217 -263.133886) (xy 381.036546 -263.167117) (xy 380.990388 -263.193766) (xy 380.940774 -263.213238)
			(xy 380.888812 -263.225098) (xy 380.835662 -263.229082) (xy 380.782512 -263.225098) (xy 380.73055 -263.213238)
			(xy 380.680936 -263.193766) (xy 380.634778 -263.167117) (xy 380.593107 -263.133886) (xy 380.556855 -263.094815)
			(xy 380.526831 -263.050778) (xy 380.503705 -263.002757) (xy 380.487995 -262.951827) (xy 380.480052 -262.899123)
			(xy 380.251726 -262.899123) (xy 380.243783 -262.951827) (xy 380.228073 -263.002757) (xy 380.204947 -263.050778)
			(xy 380.174923 -263.094815) (xy 380.138671 -263.133886) (xy 380.097 -263.167117) (xy 380.050842 -263.193766)
			(xy 380.001228 -263.213238) (xy 379.949266 -263.225098) (xy 379.896116 -263.229082) (xy 379.842966 -263.225098)
			(xy 379.791004 -263.213238) (xy 379.74139 -263.193766) (xy 379.695232 -263.167117) (xy 379.653561 -263.133886)
			(xy 379.617309 -263.094815) (xy 379.587285 -263.050778) (xy 379.564159 -263.002757) (xy 379.548449 -262.951827)
			(xy 379.540506 -262.899123) (xy 379.311672 -262.899123) (xy 379.303729 -262.951827) (xy 379.288019 -263.002757)
			(xy 379.264893 -263.050778) (xy 379.234869 -263.094815) (xy 379.198617 -263.133886) (xy 379.156946 -263.167117)
			(xy 379.110788 -263.193766) (xy 379.061174 -263.213238) (xy 379.009212 -263.225098) (xy 378.956062 -263.229082)
			(xy 378.902912 -263.225098) (xy 378.85095 -263.213238) (xy 378.801336 -263.193766) (xy 378.755178 -263.167117)
			(xy 378.713507 -263.133886) (xy 378.677255 -263.094815) (xy 378.647231 -263.050778) (xy 378.624105 -263.002757)
			(xy 378.608395 -262.951827) (xy 378.600452 -262.899123) (xy 378.371872 -262.899123) (xy 378.363929 -262.951827)
			(xy 378.348219 -263.002757) (xy 378.325093 -263.050778) (xy 378.295069 -263.094815) (xy 378.258817 -263.133886)
			(xy 378.217146 -263.167117) (xy 378.170988 -263.193766) (xy 378.121374 -263.213238) (xy 378.069412 -263.225098)
			(xy 378.016262 -263.229082) (xy 377.963112 -263.225098) (xy 377.91115 -263.213238) (xy 377.861536 -263.193766)
			(xy 377.815378 -263.167117) (xy 377.773707 -263.133886) (xy 377.737455 -263.094815) (xy 377.707431 -263.050778)
			(xy 377.684305 -263.002757) (xy 377.668595 -262.951827) (xy 377.660652 -262.899123) (xy 377.432072 -262.899123)
			(xy 377.424129 -262.951827) (xy 377.408419 -263.002757) (xy 377.385293 -263.050778) (xy 377.355269 -263.094815)
			(xy 377.319017 -263.133886) (xy 377.277346 -263.167117) (xy 377.231188 -263.193766) (xy 377.181574 -263.213238)
			(xy 377.129612 -263.225098) (xy 377.076462 -263.229082) (xy 377.023312 -263.225098) (xy 376.97135 -263.213238)
			(xy 376.921736 -263.193766) (xy 376.875578 -263.167117) (xy 376.833907 -263.133886) (xy 376.797655 -263.094815)
			(xy 376.767631 -263.050778) (xy 376.744505 -263.002757) (xy 376.728795 -262.951827) (xy 376.720852 -262.899123)
			(xy 376.492272 -262.899123) (xy 376.484329 -262.951827) (xy 376.468619 -263.002757) (xy 376.445493 -263.050778)
			(xy 376.415469 -263.094815) (xy 376.379217 -263.133886) (xy 376.337546 -263.167117) (xy 376.291388 -263.193766)
			(xy 376.241774 -263.213238) (xy 376.189812 -263.225098) (xy 376.136662 -263.229082) (xy 376.083512 -263.225098)
			(xy 376.03155 -263.213238) (xy 375.981936 -263.193766) (xy 375.935778 -263.167117) (xy 375.894107 -263.133886)
			(xy 375.857855 -263.094815) (xy 375.827831 -263.050778) (xy 375.804705 -263.002757) (xy 375.788995 -262.951827)
			(xy 375.781052 -262.899123) (xy 375.552472 -262.899123) (xy 375.544529 -262.951827) (xy 375.528819 -263.002757)
			(xy 375.505693 -263.050778) (xy 375.475669 -263.094815) (xy 375.439417 -263.133886) (xy 375.397746 -263.167117)
			(xy 375.351588 -263.193766) (xy 375.301974 -263.213238) (xy 375.250012 -263.225098) (xy 375.196862 -263.229082)
			(xy 375.143712 -263.225098) (xy 375.09175 -263.213238) (xy 375.042136 -263.193766) (xy 374.995978 -263.167117)
			(xy 374.954307 -263.133886) (xy 374.918055 -263.094815) (xy 374.888031 -263.050778) (xy 374.864905 -263.002757)
			(xy 374.849195 -262.951827) (xy 374.841252 -262.899123) (xy 374.612672 -262.899123) (xy 374.604729 -262.951827)
			(xy 374.589019 -263.002757) (xy 374.565893 -263.050778) (xy 374.535869 -263.094815) (xy 374.499617 -263.133886)
			(xy 374.457946 -263.167117) (xy 374.411788 -263.193766) (xy 374.362174 -263.213238) (xy 374.310212 -263.225098)
			(xy 374.257062 -263.229082) (xy 374.203912 -263.225098) (xy 374.15195 -263.213238) (xy 374.102336 -263.193766)
			(xy 374.056178 -263.167117) (xy 374.014507 -263.133886) (xy 373.978255 -263.094815) (xy 373.948231 -263.050778)
			(xy 373.925105 -263.002757) (xy 373.909395 -262.951827) (xy 373.901452 -262.899123) (xy 373.673126 -262.899123)
			(xy 373.665183 -262.951827) (xy 373.649473 -263.002757) (xy 373.626347 -263.050778) (xy 373.596323 -263.094815)
			(xy 373.560071 -263.133886) (xy 373.5184 -263.167117) (xy 373.472242 -263.193766) (xy 373.422628 -263.213238)
			(xy 373.370666 -263.225098) (xy 373.317516 -263.229082) (xy 373.264366 -263.225098) (xy 373.212404 -263.213238)
			(xy 373.16279 -263.193766) (xy 373.116632 -263.167117) (xy 373.074961 -263.133886) (xy 373.038709 -263.094815)
			(xy 373.008685 -263.050778) (xy 372.985559 -263.002757) (xy 372.969849 -262.951827) (xy 372.961906 -262.899123)
			(xy 372.733072 -262.899123) (xy 372.725129 -262.951827) (xy 372.709419 -263.002757) (xy 372.686293 -263.050778)
			(xy 372.656269 -263.094815) (xy 372.620017 -263.133886) (xy 372.578346 -263.167117) (xy 372.532188 -263.193766)
			(xy 372.482574 -263.213238) (xy 372.430612 -263.225098) (xy 372.377462 -263.229082) (xy 372.324312 -263.225098)
			(xy 372.27235 -263.213238) (xy 372.222736 -263.193766) (xy 372.176578 -263.167117) (xy 372.134907 -263.133886)
			(xy 372.098655 -263.094815) (xy 372.068631 -263.050778) (xy 372.045505 -263.002757) (xy 372.029795 -262.951827)
			(xy 372.021852 -262.899123) (xy 371.793272 -262.899123) (xy 371.785329 -262.951827) (xy 371.769619 -263.002757)
			(xy 371.746493 -263.050778) (xy 371.716469 -263.094815) (xy 371.680217 -263.133886) (xy 371.638546 -263.167117)
			(xy 371.592388 -263.193766) (xy 371.542774 -263.213238) (xy 371.490812 -263.225098) (xy 371.437662 -263.229082)
			(xy 371.384512 -263.225098) (xy 371.33255 -263.213238) (xy 371.282936 -263.193766) (xy 371.236778 -263.167117)
			(xy 371.195107 -263.133886) (xy 371.158855 -263.094815) (xy 371.128831 -263.050778) (xy 371.105705 -263.002757)
			(xy 371.089995 -262.951827) (xy 371.082052 -262.899123) (xy 370.853726 -262.899123) (xy 370.845783 -262.951827)
			(xy 370.830073 -263.002757) (xy 370.806947 -263.050778) (xy 370.776923 -263.094815) (xy 370.740671 -263.133886)
			(xy 370.699 -263.167117) (xy 370.652842 -263.193766) (xy 370.603228 -263.213238) (xy 370.551266 -263.225098)
			(xy 370.498116 -263.229082) (xy 370.444966 -263.225098) (xy 370.393004 -263.213238) (xy 370.34339 -263.193766)
			(xy 370.297232 -263.167117) (xy 370.255561 -263.133886) (xy 370.219309 -263.094815) (xy 370.189285 -263.050778)
			(xy 370.166159 -263.002757) (xy 370.150449 -262.951827) (xy 370.142506 -262.899123) (xy 369.913672 -262.899123)
			(xy 369.905729 -262.951827) (xy 369.890019 -263.002757) (xy 369.866893 -263.050778) (xy 369.836869 -263.094815)
			(xy 369.800617 -263.133886) (xy 369.758946 -263.167117) (xy 369.712788 -263.193766) (xy 369.663174 -263.213238)
			(xy 369.611212 -263.225098) (xy 369.558062 -263.229082) (xy 369.504912 -263.225098) (xy 369.45295 -263.213238)
			(xy 369.403336 -263.193766) (xy 369.357178 -263.167117) (xy 369.315507 -263.133886) (xy 369.279255 -263.094815)
			(xy 369.249231 -263.050778) (xy 369.226105 -263.002757) (xy 369.210395 -262.951827) (xy 369.202452 -262.899123)
			(xy 368.484939 -262.899123) (xy 368.505443 -262.924837) (xy 368.532087 -262.970991) (xy 368.551556 -263.0206)
			(xy 368.563413 -263.072557) (xy 368.567396 -263.1257) (xy 368.563413 -263.178843) (xy 368.551556 -263.2308)
			(xy 368.532087 -263.280409) (xy 368.505443 -263.326563) (xy 368.472218 -263.36823) (xy 368.433154 -263.404481)
			(xy 368.389124 -263.434505) (xy 368.341112 -263.457633) (xy 368.290188 -263.473346) (xy 368.237492 -263.481295)
			(xy 368.210846 -263.48182) (xy 368.210592 -263.48182) (xy 368.185031 -263.481383) (xy 368.134434 -263.474074)
			(xy 368.085406 -263.459593) (xy 368.062002 -263.449308) (xy 368.048977 -263.44383) (xy 368.021061 -263.439522)
			(xy 367.993034 -263.443029) (xy 367.96704 -263.454081) (xy 367.94507 -263.471834) (xy 367.936526 -263.48309)
			(xy 367.919701 -263.505946) (xy 367.880015 -263.546515) (xy 367.834397 -263.580275) (xy 367.784002 -263.606372)
			(xy 367.730105 -263.624146) (xy 367.674072 -263.633147) (xy 367.645696 -263.633712) (xy 367.645188 -263.633712)
			(xy 367.621435 -263.633299) (xy 367.574354 -263.626952) (xy 367.528533 -263.614412) (xy 367.506504 -263.605518)
			(xy 367.493121 -263.600383) (xy 367.464673 -263.596985) (xy 367.436399 -263.601621) (xy 367.410525 -263.613927)
			(xy 367.389088 -263.632935) (xy 367.373773 -263.65715) (xy 367.365785 -263.684665) (xy 367.36528 -263.69899)
			(xy 367.36528 -263.713193) (xy 369.672606 -263.713193) (xy 369.672606 -263.659895) (xy 369.680549 -263.607191)
			(xy 369.696259 -263.556261) (xy 369.719385 -263.50824) (xy 369.749409 -263.464203) (xy 369.785661 -263.425132)
			(xy 369.827332 -263.391901) (xy 369.87349 -263.365252) (xy 369.923104 -263.34578) (xy 369.975066 -263.33392)
			(xy 370.028216 -263.329937) (xy 370.081366 -263.33392) (xy 370.133328 -263.34578) (xy 370.182942 -263.365252)
			(xy 370.2291 -263.391901) (xy 370.270771 -263.425132) (xy 370.307023 -263.464203) (xy 370.337047 -263.50824)
			(xy 370.360173 -263.556261) (xy 370.375883 -263.607191) (xy 370.383826 -263.659895) (xy 370.384324 -263.686544)
			(xy 370.383826 -263.713193) (xy 370.612152 -263.713193) (xy 370.612152 -263.659895) (xy 370.620095 -263.607191)
			(xy 370.635805 -263.556261) (xy 370.658931 -263.50824) (xy 370.688955 -263.464203) (xy 370.725207 -263.425132)
			(xy 370.766878 -263.391901) (xy 370.813036 -263.365252) (xy 370.86265 -263.34578) (xy 370.914612 -263.33392)
			(xy 370.967762 -263.329937) (xy 371.020912 -263.33392) (xy 371.072874 -263.34578) (xy 371.122488 -263.365252)
			(xy 371.168646 -263.391901) (xy 371.210317 -263.425132) (xy 371.246569 -263.464203) (xy 371.276593 -263.50824)
			(xy 371.299719 -263.556261) (xy 371.315429 -263.607191) (xy 371.323372 -263.659895) (xy 371.32387 -263.686544)
			(xy 371.323372 -263.713193) (xy 371.552206 -263.713193) (xy 371.552206 -263.659895) (xy 371.560149 -263.607191)
			(xy 371.575859 -263.556261) (xy 371.598985 -263.50824) (xy 371.629009 -263.464203) (xy 371.665261 -263.425132)
			(xy 371.706932 -263.391901) (xy 371.75309 -263.365252) (xy 371.802704 -263.34578) (xy 371.854666 -263.33392)
			(xy 371.907816 -263.329937) (xy 371.960966 -263.33392) (xy 372.012928 -263.34578) (xy 372.062542 -263.365252)
			(xy 372.1087 -263.391901) (xy 372.150371 -263.425132) (xy 372.186623 -263.464203) (xy 372.216647 -263.50824)
			(xy 372.239773 -263.556261) (xy 372.255483 -263.607191) (xy 372.263426 -263.659895) (xy 372.263924 -263.686544)
			(xy 372.263426 -263.713193) (xy 372.492006 -263.713193) (xy 372.492006 -263.659895) (xy 372.499949 -263.607191)
			(xy 372.515659 -263.556261) (xy 372.538785 -263.50824) (xy 372.568809 -263.464203) (xy 372.605061 -263.425132)
			(xy 372.646732 -263.391901) (xy 372.69289 -263.365252) (xy 372.742504 -263.34578) (xy 372.794466 -263.33392)
			(xy 372.847616 -263.329937) (xy 372.900766 -263.33392) (xy 372.952728 -263.34578) (xy 373.002342 -263.365252)
			(xy 373.0485 -263.391901) (xy 373.090171 -263.425132) (xy 373.126423 -263.464203) (xy 373.156447 -263.50824)
			(xy 373.179573 -263.556261) (xy 373.195283 -263.607191) (xy 373.203226 -263.659895) (xy 373.203724 -263.686544)
			(xy 373.203226 -263.713193) (xy 373.431806 -263.713193) (xy 373.431806 -263.659895) (xy 373.439749 -263.607191)
			(xy 373.455459 -263.556261) (xy 373.478585 -263.50824) (xy 373.508609 -263.464203) (xy 373.544861 -263.425132)
			(xy 373.586532 -263.391901) (xy 373.63269 -263.365252) (xy 373.682304 -263.34578) (xy 373.734266 -263.33392)
			(xy 373.787416 -263.329937) (xy 373.840566 -263.33392) (xy 373.892528 -263.34578) (xy 373.942142 -263.365252)
			(xy 373.9883 -263.391901) (xy 374.029971 -263.425132) (xy 374.066223 -263.464203) (xy 374.096247 -263.50824)
			(xy 374.119373 -263.556261) (xy 374.135083 -263.607191) (xy 374.143026 -263.659895) (xy 374.143524 -263.686544)
			(xy 374.143026 -263.713193) (xy 374.371606 -263.713193) (xy 374.371606 -263.659895) (xy 374.379549 -263.607191)
			(xy 374.395259 -263.556261) (xy 374.418385 -263.50824) (xy 374.448409 -263.464203) (xy 374.484661 -263.425132)
			(xy 374.526332 -263.391901) (xy 374.57249 -263.365252) (xy 374.622104 -263.34578) (xy 374.674066 -263.33392)
			(xy 374.727216 -263.329937) (xy 374.780366 -263.33392) (xy 374.832328 -263.34578) (xy 374.881942 -263.365252)
			(xy 374.9281 -263.391901) (xy 374.969771 -263.425132) (xy 375.006023 -263.464203) (xy 375.036047 -263.50824)
			(xy 375.059173 -263.556261) (xy 375.074883 -263.607191) (xy 375.082826 -263.659895) (xy 375.083324 -263.686544)
			(xy 375.082826 -263.713193) (xy 375.311406 -263.713193) (xy 375.311406 -263.659895) (xy 375.319349 -263.607191)
			(xy 375.335059 -263.556261) (xy 375.358185 -263.50824) (xy 375.388209 -263.464203) (xy 375.424461 -263.425132)
			(xy 375.466132 -263.391901) (xy 375.51229 -263.365252) (xy 375.561904 -263.34578) (xy 375.613866 -263.33392)
			(xy 375.667016 -263.329937) (xy 375.720166 -263.33392) (xy 375.772128 -263.34578) (xy 375.821742 -263.365252)
			(xy 375.8679 -263.391901) (xy 375.909571 -263.425132) (xy 375.945823 -263.464203) (xy 375.975847 -263.50824)
			(xy 375.998973 -263.556261) (xy 376.014683 -263.607191) (xy 376.022626 -263.659895) (xy 376.023124 -263.686544)
			(xy 376.022626 -263.713193) (xy 376.251206 -263.713193) (xy 376.251206 -263.659895) (xy 376.259149 -263.607191)
			(xy 376.274859 -263.556261) (xy 376.297985 -263.50824) (xy 376.328009 -263.464203) (xy 376.364261 -263.425132)
			(xy 376.405932 -263.391901) (xy 376.45209 -263.365252) (xy 376.501704 -263.34578) (xy 376.553666 -263.33392)
			(xy 376.606816 -263.329937) (xy 376.659966 -263.33392) (xy 376.711928 -263.34578) (xy 376.761542 -263.365252)
			(xy 376.8077 -263.391901) (xy 376.849371 -263.425132) (xy 376.885623 -263.464203) (xy 376.915647 -263.50824)
			(xy 376.938773 -263.556261) (xy 376.954483 -263.607191) (xy 376.962426 -263.659895) (xy 376.962924 -263.686544)
			(xy 376.962426 -263.713193) (xy 377.190752 -263.713193) (xy 377.190752 -263.659895) (xy 377.198695 -263.607191)
			(xy 377.214405 -263.556261) (xy 377.237531 -263.50824) (xy 377.267555 -263.464203) (xy 377.303807 -263.425132)
			(xy 377.345478 -263.391901) (xy 377.391636 -263.365252) (xy 377.44125 -263.34578) (xy 377.493212 -263.33392)
			(xy 377.546362 -263.329937) (xy 377.599512 -263.33392) (xy 377.651474 -263.34578) (xy 377.701088 -263.365252)
			(xy 377.747246 -263.391901) (xy 377.788917 -263.425132) (xy 377.825169 -263.464203) (xy 377.855193 -263.50824)
			(xy 377.878319 -263.556261) (xy 377.894029 -263.607191) (xy 377.901972 -263.659895) (xy 377.90247 -263.686544)
			(xy 377.901972 -263.713193) (xy 378.130806 -263.713193) (xy 378.130806 -263.659895) (xy 378.138749 -263.607191)
			(xy 378.154459 -263.556261) (xy 378.177585 -263.50824) (xy 378.207609 -263.464203) (xy 378.243861 -263.425132)
			(xy 378.285532 -263.391901) (xy 378.33169 -263.365252) (xy 378.381304 -263.34578) (xy 378.433266 -263.33392)
			(xy 378.486416 -263.329937) (xy 378.539566 -263.33392) (xy 378.591528 -263.34578) (xy 378.641142 -263.365252)
			(xy 378.6873 -263.391901) (xy 378.728971 -263.425132) (xy 378.765223 -263.464203) (xy 378.795247 -263.50824)
			(xy 378.818373 -263.556261) (xy 378.834083 -263.607191) (xy 378.842026 -263.659895) (xy 378.842524 -263.686544)
			(xy 378.842026 -263.713193) (xy 379.070606 -263.713193) (xy 379.070606 -263.659895) (xy 379.078549 -263.607191)
			(xy 379.094259 -263.556261) (xy 379.117385 -263.50824) (xy 379.147409 -263.464203) (xy 379.183661 -263.425132)
			(xy 379.225332 -263.391901) (xy 379.27149 -263.365252) (xy 379.321104 -263.34578) (xy 379.373066 -263.33392)
			(xy 379.426216 -263.329937) (xy 379.479366 -263.33392) (xy 379.531328 -263.34578) (xy 379.580942 -263.365252)
			(xy 379.6271 -263.391901) (xy 379.668771 -263.425132) (xy 379.705023 -263.464203) (xy 379.735047 -263.50824)
			(xy 379.758173 -263.556261) (xy 379.773883 -263.607191) (xy 379.781826 -263.659895) (xy 379.782324 -263.686544)
			(xy 379.781826 -263.713193) (xy 380.010406 -263.713193) (xy 380.010406 -263.659895) (xy 380.018349 -263.607191)
			(xy 380.034059 -263.556261) (xy 380.057185 -263.50824) (xy 380.087209 -263.464203) (xy 380.123461 -263.425132)
			(xy 380.165132 -263.391901) (xy 380.21129 -263.365252) (xy 380.260904 -263.34578) (xy 380.312866 -263.33392)
			(xy 380.366016 -263.329937) (xy 380.419166 -263.33392) (xy 380.471128 -263.34578) (xy 380.520742 -263.365252)
			(xy 380.5669 -263.391901) (xy 380.608571 -263.425132) (xy 380.644823 -263.464203) (xy 380.674847 -263.50824)
			(xy 380.697973 -263.556261) (xy 380.713683 -263.607191) (xy 380.721626 -263.659895) (xy 380.722124 -263.686544)
			(xy 380.721626 -263.713193) (xy 380.950206 -263.713193) (xy 380.950206 -263.659895) (xy 380.958149 -263.607191)
			(xy 380.973859 -263.556261) (xy 380.996985 -263.50824) (xy 381.027009 -263.464203) (xy 381.063261 -263.425132)
			(xy 381.104932 -263.391901) (xy 381.15109 -263.365252) (xy 381.200704 -263.34578) (xy 381.252666 -263.33392)
			(xy 381.305816 -263.329937) (xy 381.358966 -263.33392) (xy 381.410928 -263.34578) (xy 381.460542 -263.365252)
			(xy 381.5067 -263.391901) (xy 381.548371 -263.425132) (xy 381.584623 -263.464203) (xy 381.614647 -263.50824)
			(xy 381.637773 -263.556261) (xy 381.653483 -263.607191) (xy 381.661426 -263.659895) (xy 381.661924 -263.686544)
			(xy 381.661426 -263.713193) (xy 381.653483 -263.765897) (xy 381.637773 -263.816827) (xy 381.614647 -263.864848)
			(xy 381.584623 -263.908885) (xy 381.548371 -263.947956) (xy 381.5067 -263.981187) (xy 381.460542 -264.007836)
			(xy 381.410928 -264.027308) (xy 381.358966 -264.039168) (xy 381.305816 -264.043152) (xy 381.252666 -264.039168)
			(xy 381.200704 -264.027308) (xy 381.15109 -264.007836) (xy 381.104932 -263.981187) (xy 381.063261 -263.947956)
			(xy 381.027009 -263.908885) (xy 380.996985 -263.864848) (xy 380.973859 -263.816827) (xy 380.958149 -263.765897)
			(xy 380.950206 -263.713193) (xy 380.721626 -263.713193) (xy 380.713683 -263.765897) (xy 380.697973 -263.816827)
			(xy 380.674847 -263.864848) (xy 380.644823 -263.908885) (xy 380.608571 -263.947956) (xy 380.5669 -263.981187)
			(xy 380.520742 -264.007836) (xy 380.471128 -264.027308) (xy 380.419166 -264.039168) (xy 380.366016 -264.043152)
			(xy 380.312866 -264.039168) (xy 380.260904 -264.027308) (xy 380.21129 -264.007836) (xy 380.165132 -263.981187)
			(xy 380.123461 -263.947956) (xy 380.087209 -263.908885) (xy 380.057185 -263.864848) (xy 380.034059 -263.816827)
			(xy 380.018349 -263.765897) (xy 380.010406 -263.713193) (xy 379.781826 -263.713193) (xy 379.773883 -263.765897)
			(xy 379.758173 -263.816827) (xy 379.735047 -263.864848) (xy 379.705023 -263.908885) (xy 379.668771 -263.947956)
			(xy 379.6271 -263.981187) (xy 379.580942 -264.007836) (xy 379.531328 -264.027308) (xy 379.479366 -264.039168)
			(xy 379.426216 -264.043152) (xy 379.373066 -264.039168) (xy 379.321104 -264.027308) (xy 379.27149 -264.007836)
			(xy 379.225332 -263.981187) (xy 379.183661 -263.947956) (xy 379.147409 -263.908885) (xy 379.117385 -263.864848)
			(xy 379.094259 -263.816827) (xy 379.078549 -263.765897) (xy 379.070606 -263.713193) (xy 378.842026 -263.713193)
			(xy 378.834083 -263.765897) (xy 378.818373 -263.816827) (xy 378.795247 -263.864848) (xy 378.765223 -263.908885)
			(xy 378.728971 -263.947956) (xy 378.6873 -263.981187) (xy 378.641142 -264.007836) (xy 378.591528 -264.027308)
			(xy 378.539566 -264.039168) (xy 378.486416 -264.043152) (xy 378.433266 -264.039168) (xy 378.381304 -264.027308)
			(xy 378.33169 -264.007836) (xy 378.285532 -263.981187) (xy 378.243861 -263.947956) (xy 378.207609 -263.908885)
			(xy 378.177585 -263.864848) (xy 378.154459 -263.816827) (xy 378.138749 -263.765897) (xy 378.130806 -263.713193)
			(xy 377.901972 -263.713193) (xy 377.894029 -263.765897) (xy 377.878319 -263.816827) (xy 377.855193 -263.864848)
			(xy 377.825169 -263.908885) (xy 377.788917 -263.947956) (xy 377.747246 -263.981187) (xy 377.701088 -264.007836)
			(xy 377.651474 -264.027308) (xy 377.599512 -264.039168) (xy 377.546362 -264.043152) (xy 377.493212 -264.039168)
			(xy 377.44125 -264.027308) (xy 377.391636 -264.007836) (xy 377.345478 -263.981187) (xy 377.303807 -263.947956)
			(xy 377.267555 -263.908885) (xy 377.237531 -263.864848) (xy 377.214405 -263.816827) (xy 377.198695 -263.765897)
			(xy 377.190752 -263.713193) (xy 376.962426 -263.713193) (xy 376.954483 -263.765897) (xy 376.938773 -263.816827)
			(xy 376.915647 -263.864848) (xy 376.885623 -263.908885) (xy 376.849371 -263.947956) (xy 376.8077 -263.981187)
			(xy 376.761542 -264.007836) (xy 376.711928 -264.027308) (xy 376.659966 -264.039168) (xy 376.606816 -264.043152)
			(xy 376.553666 -264.039168) (xy 376.501704 -264.027308) (xy 376.45209 -264.007836) (xy 376.405932 -263.981187)
			(xy 376.364261 -263.947956) (xy 376.328009 -263.908885) (xy 376.297985 -263.864848) (xy 376.274859 -263.816827)
			(xy 376.259149 -263.765897) (xy 376.251206 -263.713193) (xy 376.022626 -263.713193) (xy 376.014683 -263.765897)
			(xy 375.998973 -263.816827) (xy 375.975847 -263.864848) (xy 375.945823 -263.908885) (xy 375.909571 -263.947956)
			(xy 375.8679 -263.981187) (xy 375.821742 -264.007836) (xy 375.772128 -264.027308) (xy 375.720166 -264.039168)
			(xy 375.667016 -264.043152) (xy 375.613866 -264.039168) (xy 375.561904 -264.027308) (xy 375.51229 -264.007836)
			(xy 375.466132 -263.981187) (xy 375.424461 -263.947956) (xy 375.388209 -263.908885) (xy 375.358185 -263.864848)
			(xy 375.335059 -263.816827) (xy 375.319349 -263.765897) (xy 375.311406 -263.713193) (xy 375.082826 -263.713193)
			(xy 375.074883 -263.765897) (xy 375.059173 -263.816827) (xy 375.036047 -263.864848) (xy 375.006023 -263.908885)
			(xy 374.969771 -263.947956) (xy 374.9281 -263.981187) (xy 374.881942 -264.007836) (xy 374.832328 -264.027308)
			(xy 374.780366 -264.039168) (xy 374.727216 -264.043152) (xy 374.674066 -264.039168) (xy 374.622104 -264.027308)
			(xy 374.57249 -264.007836) (xy 374.526332 -263.981187) (xy 374.484661 -263.947956) (xy 374.448409 -263.908885)
			(xy 374.418385 -263.864848) (xy 374.395259 -263.816827) (xy 374.379549 -263.765897) (xy 374.371606 -263.713193)
			(xy 374.143026 -263.713193) (xy 374.135083 -263.765897) (xy 374.119373 -263.816827) (xy 374.096247 -263.864848)
			(xy 374.066223 -263.908885) (xy 374.029971 -263.947956) (xy 373.9883 -263.981187) (xy 373.942142 -264.007836)
			(xy 373.892528 -264.027308) (xy 373.840566 -264.039168) (xy 373.787416 -264.043152) (xy 373.734266 -264.039168)
			(xy 373.682304 -264.027308) (xy 373.63269 -264.007836) (xy 373.586532 -263.981187) (xy 373.544861 -263.947956)
			(xy 373.508609 -263.908885) (xy 373.478585 -263.864848) (xy 373.455459 -263.816827) (xy 373.439749 -263.765897)
			(xy 373.431806 -263.713193) (xy 373.203226 -263.713193) (xy 373.195283 -263.765897) (xy 373.179573 -263.816827)
			(xy 373.156447 -263.864848) (xy 373.126423 -263.908885) (xy 373.090171 -263.947956) (xy 373.0485 -263.981187)
			(xy 373.002342 -264.007836) (xy 372.952728 -264.027308) (xy 372.900766 -264.039168) (xy 372.847616 -264.043152)
			(xy 372.794466 -264.039168) (xy 372.742504 -264.027308) (xy 372.69289 -264.007836) (xy 372.646732 -263.981187)
			(xy 372.605061 -263.947956) (xy 372.568809 -263.908885) (xy 372.538785 -263.864848) (xy 372.515659 -263.816827)
			(xy 372.499949 -263.765897) (xy 372.492006 -263.713193) (xy 372.263426 -263.713193) (xy 372.255483 -263.765897)
			(xy 372.239773 -263.816827) (xy 372.216647 -263.864848) (xy 372.186623 -263.908885) (xy 372.150371 -263.947956)
			(xy 372.1087 -263.981187) (xy 372.062542 -264.007836) (xy 372.012928 -264.027308) (xy 371.960966 -264.039168)
			(xy 371.907816 -264.043152) (xy 371.854666 -264.039168) (xy 371.802704 -264.027308) (xy 371.75309 -264.007836)
			(xy 371.706932 -263.981187) (xy 371.665261 -263.947956) (xy 371.629009 -263.908885) (xy 371.598985 -263.864848)
			(xy 371.575859 -263.816827) (xy 371.560149 -263.765897) (xy 371.552206 -263.713193) (xy 371.323372 -263.713193)
			(xy 371.315429 -263.765897) (xy 371.299719 -263.816827) (xy 371.276593 -263.864848) (xy 371.246569 -263.908885)
			(xy 371.210317 -263.947956) (xy 371.168646 -263.981187) (xy 371.122488 -264.007836) (xy 371.072874 -264.027308)
			(xy 371.020912 -264.039168) (xy 370.967762 -264.043152) (xy 370.914612 -264.039168) (xy 370.86265 -264.027308)
			(xy 370.813036 -264.007836) (xy 370.766878 -263.981187) (xy 370.725207 -263.947956) (xy 370.688955 -263.908885)
			(xy 370.658931 -263.864848) (xy 370.635805 -263.816827) (xy 370.620095 -263.765897) (xy 370.612152 -263.713193)
			(xy 370.383826 -263.713193) (xy 370.375883 -263.765897) (xy 370.360173 -263.816827) (xy 370.337047 -263.864848)
			(xy 370.307023 -263.908885) (xy 370.270771 -263.947956) (xy 370.2291 -263.981187) (xy 370.182942 -264.007836)
			(xy 370.133328 -264.027308) (xy 370.081366 -264.039168) (xy 370.028216 -264.043152) (xy 369.975066 -264.039168)
			(xy 369.923104 -264.027308) (xy 369.87349 -264.007836) (xy 369.827332 -263.981187) (xy 369.785661 -263.947956)
			(xy 369.749409 -263.908885) (xy 369.719385 -263.864848) (xy 369.696259 -263.816827) (xy 369.680549 -263.765897)
			(xy 369.672606 -263.713193) (xy 367.36528 -263.713193) (xy 367.36528 -264.094722) (xy 367.365844 -264.109622)
			(xy 367.374524 -264.138132) (xy 367.391054 -264.162931) (xy 367.414031 -264.181913) (xy 367.441503 -264.193466)
			(xy 367.471139 -264.196611) (xy 367.500425 -264.19108) (xy 367.51387 -264.184638) (xy 367.539435 -264.171953)
			(xy 367.593597 -264.153978) (xy 367.649929 -264.144847) (xy 367.678462 -264.144252) (xy 367.705118 -264.144723)
			(xy 367.757835 -264.152663) (xy 367.80878 -264.168373) (xy 367.856814 -264.1915) (xy 367.900864 -264.221529)
			(xy 367.939947 -264.257788) (xy 367.973188 -264.299468) (xy 367.999846 -264.345636) (xy 368.019324 -264.395262)
			(xy 368.031188 -264.447237) (xy 368.035172 -264.5004) (xy 368.033178 -264.527009) (xy 368.262652 -264.527009)
			(xy 368.262652 -264.473711) (xy 368.270595 -264.421007) (xy 368.286305 -264.370077) (xy 368.309431 -264.322056)
			(xy 368.339455 -264.278019) (xy 368.375707 -264.238948) (xy 368.417378 -264.205717) (xy 368.463536 -264.179068)
			(xy 368.51315 -264.159596) (xy 368.565112 -264.147736) (xy 368.618262 -264.143753) (xy 368.671412 -264.147736)
			(xy 368.723374 -264.159596) (xy 368.772988 -264.179068) (xy 368.819146 -264.205717) (xy 368.860817 -264.238948)
			(xy 368.897069 -264.278019) (xy 368.927093 -264.322056) (xy 368.950219 -264.370077) (xy 368.965929 -264.421007)
			(xy 368.973872 -264.473711) (xy 368.97437 -264.50036) (xy 368.973872 -264.527009) (xy 369.202452 -264.527009)
			(xy 369.202452 -264.473711) (xy 369.210395 -264.421007) (xy 369.226105 -264.370077) (xy 369.249231 -264.322056)
			(xy 369.279255 -264.278019) (xy 369.315507 -264.238948) (xy 369.357178 -264.205717) (xy 369.403336 -264.179068)
			(xy 369.45295 -264.159596) (xy 369.504912 -264.147736) (xy 369.558062 -264.143753) (xy 369.611212 -264.147736)
			(xy 369.663174 -264.159596) (xy 369.712788 -264.179068) (xy 369.758946 -264.205717) (xy 369.800617 -264.238948)
			(xy 369.836869 -264.278019) (xy 369.866893 -264.322056) (xy 369.890019 -264.370077) (xy 369.905729 -264.421007)
			(xy 369.913672 -264.473711) (xy 369.91417 -264.50036) (xy 369.913672 -264.527009) (xy 370.142252 -264.527009)
			(xy 370.142252 -264.473711) (xy 370.150195 -264.421007) (xy 370.165905 -264.370077) (xy 370.189031 -264.322056)
			(xy 370.219055 -264.278019) (xy 370.255307 -264.238948) (xy 370.296978 -264.205717) (xy 370.343136 -264.179068)
			(xy 370.39275 -264.159596) (xy 370.444712 -264.147736) (xy 370.497862 -264.143753) (xy 370.551012 -264.147736)
			(xy 370.602974 -264.159596) (xy 370.652588 -264.179068) (xy 370.698746 -264.205717) (xy 370.740417 -264.238948)
			(xy 370.776669 -264.278019) (xy 370.806693 -264.322056) (xy 370.829819 -264.370077) (xy 370.845529 -264.421007)
			(xy 370.853472 -264.473711) (xy 370.85397 -264.50036) (xy 370.853472 -264.527009) (xy 371.082052 -264.527009)
			(xy 371.082052 -264.473711) (xy 371.089995 -264.421007) (xy 371.105705 -264.370077) (xy 371.128831 -264.322056)
			(xy 371.158855 -264.278019) (xy 371.195107 -264.238948) (xy 371.236778 -264.205717) (xy 371.282936 -264.179068)
			(xy 371.33255 -264.159596) (xy 371.384512 -264.147736) (xy 371.437662 -264.143753) (xy 371.490812 -264.147736)
			(xy 371.542774 -264.159596) (xy 371.592388 -264.179068) (xy 371.638546 -264.205717) (xy 371.680217 -264.238948)
			(xy 371.716469 -264.278019) (xy 371.746493 -264.322056) (xy 371.769619 -264.370077) (xy 371.785329 -264.421007)
			(xy 371.793272 -264.473711) (xy 371.79377 -264.50036) (xy 371.793272 -264.527009) (xy 372.021852 -264.527009)
			(xy 372.021852 -264.473711) (xy 372.029795 -264.421007) (xy 372.045505 -264.370077) (xy 372.068631 -264.322056)
			(xy 372.098655 -264.278019) (xy 372.134907 -264.238948) (xy 372.176578 -264.205717) (xy 372.222736 -264.179068)
			(xy 372.27235 -264.159596) (xy 372.324312 -264.147736) (xy 372.377462 -264.143753) (xy 372.430612 -264.147736)
			(xy 372.482574 -264.159596) (xy 372.532188 -264.179068) (xy 372.578346 -264.205717) (xy 372.620017 -264.238948)
			(xy 372.656269 -264.278019) (xy 372.686293 -264.322056) (xy 372.709419 -264.370077) (xy 372.725129 -264.421007)
			(xy 372.733072 -264.473711) (xy 372.73357 -264.50036) (xy 372.733072 -264.527009) (xy 372.961652 -264.527009)
			(xy 372.961652 -264.473711) (xy 372.969595 -264.421007) (xy 372.985305 -264.370077) (xy 373.008431 -264.322056)
			(xy 373.038455 -264.278019) (xy 373.074707 -264.238948) (xy 373.116378 -264.205717) (xy 373.162536 -264.179068)
			(xy 373.21215 -264.159596) (xy 373.264112 -264.147736) (xy 373.317262 -264.143753) (xy 373.370412 -264.147736)
			(xy 373.422374 -264.159596) (xy 373.471988 -264.179068) (xy 373.518146 -264.205717) (xy 373.559817 -264.238948)
			(xy 373.596069 -264.278019) (xy 373.626093 -264.322056) (xy 373.649219 -264.370077) (xy 373.664929 -264.421007)
			(xy 373.672872 -264.473711) (xy 373.67337 -264.50036) (xy 373.672872 -264.527009) (xy 373.901706 -264.527009)
			(xy 373.901706 -264.473711) (xy 373.909649 -264.421007) (xy 373.925359 -264.370077) (xy 373.948485 -264.322056)
			(xy 373.978509 -264.278019) (xy 374.014761 -264.238948) (xy 374.056432 -264.205717) (xy 374.10259 -264.179068)
			(xy 374.152204 -264.159596) (xy 374.204166 -264.147736) (xy 374.257316 -264.143753) (xy 374.310466 -264.147736)
			(xy 374.362428 -264.159596) (xy 374.412042 -264.179068) (xy 374.4582 -264.205717) (xy 374.499871 -264.238948)
			(xy 374.536123 -264.278019) (xy 374.566147 -264.322056) (xy 374.589273 -264.370077) (xy 374.604983 -264.421007)
			(xy 374.612926 -264.473711) (xy 374.613424 -264.50036) (xy 374.612926 -264.527009) (xy 374.841252 -264.527009)
			(xy 374.841252 -264.473711) (xy 374.849195 -264.421007) (xy 374.864905 -264.370077) (xy 374.888031 -264.322056)
			(xy 374.918055 -264.278019) (xy 374.954307 -264.238948) (xy 374.995978 -264.205717) (xy 375.042136 -264.179068)
			(xy 375.09175 -264.159596) (xy 375.143712 -264.147736) (xy 375.196862 -264.143753) (xy 375.250012 -264.147736)
			(xy 375.301974 -264.159596) (xy 375.351588 -264.179068) (xy 375.397746 -264.205717) (xy 375.439417 -264.238948)
			(xy 375.475669 -264.278019) (xy 375.505693 -264.322056) (xy 375.528819 -264.370077) (xy 375.544529 -264.421007)
			(xy 375.552472 -264.473711) (xy 375.55297 -264.50036) (xy 375.552472 -264.527009) (xy 375.781052 -264.527009)
			(xy 375.781052 -264.473711) (xy 375.788995 -264.421007) (xy 375.804705 -264.370077) (xy 375.827831 -264.322056)
			(xy 375.857855 -264.278019) (xy 375.894107 -264.238948) (xy 375.935778 -264.205717) (xy 375.981936 -264.179068)
			(xy 376.03155 -264.159596) (xy 376.083512 -264.147736) (xy 376.136662 -264.143753) (xy 376.189812 -264.147736)
			(xy 376.241774 -264.159596) (xy 376.291388 -264.179068) (xy 376.337546 -264.205717) (xy 376.379217 -264.238948)
			(xy 376.415469 -264.278019) (xy 376.445493 -264.322056) (xy 376.468619 -264.370077) (xy 376.484329 -264.421007)
			(xy 376.492272 -264.473711) (xy 376.49277 -264.50036) (xy 376.492272 -264.527009) (xy 376.720852 -264.527009)
			(xy 376.720852 -264.473711) (xy 376.728795 -264.421007) (xy 376.744505 -264.370077) (xy 376.767631 -264.322056)
			(xy 376.797655 -264.278019) (xy 376.833907 -264.238948) (xy 376.875578 -264.205717) (xy 376.921736 -264.179068)
			(xy 376.97135 -264.159596) (xy 377.023312 -264.147736) (xy 377.076462 -264.143753) (xy 377.129612 -264.147736)
			(xy 377.181574 -264.159596) (xy 377.231188 -264.179068) (xy 377.277346 -264.205717) (xy 377.319017 -264.238948)
			(xy 377.355269 -264.278019) (xy 377.385293 -264.322056) (xy 377.408419 -264.370077) (xy 377.424129 -264.421007)
			(xy 377.432072 -264.473711) (xy 377.43257 -264.50036) (xy 377.432072 -264.527009) (xy 377.660652 -264.527009)
			(xy 377.660652 -264.473711) (xy 377.668595 -264.421007) (xy 377.684305 -264.370077) (xy 377.707431 -264.322056)
			(xy 377.737455 -264.278019) (xy 377.773707 -264.238948) (xy 377.815378 -264.205717) (xy 377.861536 -264.179068)
			(xy 377.91115 -264.159596) (xy 377.963112 -264.147736) (xy 378.016262 -264.143753) (xy 378.069412 -264.147736)
			(xy 378.121374 -264.159596) (xy 378.170988 -264.179068) (xy 378.217146 -264.205717) (xy 378.258817 -264.238948)
			(xy 378.295069 -264.278019) (xy 378.325093 -264.322056) (xy 378.348219 -264.370077) (xy 378.363929 -264.421007)
			(xy 378.371872 -264.473711) (xy 378.37237 -264.50036) (xy 378.371872 -264.527009) (xy 378.600452 -264.527009)
			(xy 378.600452 -264.473711) (xy 378.608395 -264.421007) (xy 378.624105 -264.370077) (xy 378.647231 -264.322056)
			(xy 378.677255 -264.278019) (xy 378.713507 -264.238948) (xy 378.755178 -264.205717) (xy 378.801336 -264.179068)
			(xy 378.85095 -264.159596) (xy 378.902912 -264.147736) (xy 378.956062 -264.143753) (xy 379.009212 -264.147736)
			(xy 379.061174 -264.159596) (xy 379.110788 -264.179068) (xy 379.156946 -264.205717) (xy 379.198617 -264.238948)
			(xy 379.234869 -264.278019) (xy 379.264893 -264.322056) (xy 379.288019 -264.370077) (xy 379.303729 -264.421007)
			(xy 379.311672 -264.473711) (xy 379.31217 -264.50036) (xy 379.311672 -264.527009) (xy 379.540252 -264.527009)
			(xy 379.540252 -264.473711) (xy 379.548195 -264.421007) (xy 379.563905 -264.370077) (xy 379.587031 -264.322056)
			(xy 379.617055 -264.278019) (xy 379.653307 -264.238948) (xy 379.694978 -264.205717) (xy 379.741136 -264.179068)
			(xy 379.79075 -264.159596) (xy 379.842712 -264.147736) (xy 379.895862 -264.143753) (xy 379.949012 -264.147736)
			(xy 380.000974 -264.159596) (xy 380.050588 -264.179068) (xy 380.096746 -264.205717) (xy 380.138417 -264.238948)
			(xy 380.174669 -264.278019) (xy 380.204693 -264.322056) (xy 380.227819 -264.370077) (xy 380.243529 -264.421007)
			(xy 380.251472 -264.473711) (xy 380.25197 -264.50036) (xy 380.251472 -264.527009) (xy 380.480306 -264.527009)
			(xy 380.480306 -264.473711) (xy 380.488249 -264.421007) (xy 380.503959 -264.370077) (xy 380.527085 -264.322056)
			(xy 380.557109 -264.278019) (xy 380.593361 -264.238948) (xy 380.635032 -264.205717) (xy 380.68119 -264.179068)
			(xy 380.730804 -264.159596) (xy 380.782766 -264.147736) (xy 380.835916 -264.143753) (xy 380.889066 -264.147736)
			(xy 380.941028 -264.159596) (xy 380.990642 -264.179068) (xy 381.0368 -264.205717) (xy 381.078471 -264.238948)
			(xy 381.114723 -264.278019) (xy 381.144747 -264.322056) (xy 381.167873 -264.370077) (xy 381.183583 -264.421007)
			(xy 381.191526 -264.473711) (xy 381.192024 -264.50036) (xy 381.191526 -264.527009) (xy 381.183583 -264.579713)
			(xy 381.167873 -264.630643) (xy 381.144747 -264.678664) (xy 381.114723 -264.722701) (xy 381.078471 -264.761772)
			(xy 381.0368 -264.795003) (xy 380.990642 -264.821652) (xy 380.941028 -264.841124) (xy 380.889066 -264.852984)
			(xy 380.835916 -264.856968) (xy 380.782766 -264.852984) (xy 380.730804 -264.841124) (xy 380.68119 -264.821652)
			(xy 380.635032 -264.795003) (xy 380.593361 -264.761772) (xy 380.557109 -264.722701) (xy 380.527085 -264.678664)
			(xy 380.503959 -264.630643) (xy 380.488249 -264.579713) (xy 380.480306 -264.527009) (xy 380.251472 -264.527009)
			(xy 380.243529 -264.579713) (xy 380.227819 -264.630643) (xy 380.204693 -264.678664) (xy 380.174669 -264.722701)
			(xy 380.138417 -264.761772) (xy 380.096746 -264.795003) (xy 380.050588 -264.821652) (xy 380.000974 -264.841124)
			(xy 379.949012 -264.852984) (xy 379.895862 -264.856968) (xy 379.842712 -264.852984) (xy 379.79075 -264.841124)
			(xy 379.741136 -264.821652) (xy 379.694978 -264.795003) (xy 379.653307 -264.761772) (xy 379.617055 -264.722701)
			(xy 379.587031 -264.678664) (xy 379.563905 -264.630643) (xy 379.548195 -264.579713) (xy 379.540252 -264.527009)
			(xy 379.311672 -264.527009) (xy 379.303729 -264.579713) (xy 379.288019 -264.630643) (xy 379.264893 -264.678664)
			(xy 379.234869 -264.722701) (xy 379.198617 -264.761772) (xy 379.156946 -264.795003) (xy 379.110788 -264.821652)
			(xy 379.061174 -264.841124) (xy 379.009212 -264.852984) (xy 378.956062 -264.856968) (xy 378.902912 -264.852984)
			(xy 378.85095 -264.841124) (xy 378.801336 -264.821652) (xy 378.755178 -264.795003) (xy 378.713507 -264.761772)
			(xy 378.677255 -264.722701) (xy 378.647231 -264.678664) (xy 378.624105 -264.630643) (xy 378.608395 -264.579713)
			(xy 378.600452 -264.527009) (xy 378.371872 -264.527009) (xy 378.363929 -264.579713) (xy 378.348219 -264.630643)
			(xy 378.325093 -264.678664) (xy 378.295069 -264.722701) (xy 378.258817 -264.761772) (xy 378.217146 -264.795003)
			(xy 378.170988 -264.821652) (xy 378.121374 -264.841124) (xy 378.069412 -264.852984) (xy 378.016262 -264.856968)
			(xy 377.963112 -264.852984) (xy 377.91115 -264.841124) (xy 377.861536 -264.821652) (xy 377.815378 -264.795003)
			(xy 377.773707 -264.761772) (xy 377.737455 -264.722701) (xy 377.707431 -264.678664) (xy 377.684305 -264.630643)
			(xy 377.668595 -264.579713) (xy 377.660652 -264.527009) (xy 377.432072 -264.527009) (xy 377.424129 -264.579713)
			(xy 377.408419 -264.630643) (xy 377.385293 -264.678664) (xy 377.355269 -264.722701) (xy 377.319017 -264.761772)
			(xy 377.277346 -264.795003) (xy 377.231188 -264.821652) (xy 377.181574 -264.841124) (xy 377.129612 -264.852984)
			(xy 377.076462 -264.856968) (xy 377.023312 -264.852984) (xy 376.97135 -264.841124) (xy 376.921736 -264.821652)
			(xy 376.875578 -264.795003) (xy 376.833907 -264.761772) (xy 376.797655 -264.722701) (xy 376.767631 -264.678664)
			(xy 376.744505 -264.630643) (xy 376.728795 -264.579713) (xy 376.720852 -264.527009) (xy 376.492272 -264.527009)
			(xy 376.484329 -264.579713) (xy 376.468619 -264.630643) (xy 376.445493 -264.678664) (xy 376.415469 -264.722701)
			(xy 376.379217 -264.761772) (xy 376.337546 -264.795003) (xy 376.291388 -264.821652) (xy 376.241774 -264.841124)
			(xy 376.189812 -264.852984) (xy 376.136662 -264.856968) (xy 376.083512 -264.852984) (xy 376.03155 -264.841124)
			(xy 375.981936 -264.821652) (xy 375.935778 -264.795003) (xy 375.894107 -264.761772) (xy 375.857855 -264.722701)
			(xy 375.827831 -264.678664) (xy 375.804705 -264.630643) (xy 375.788995 -264.579713) (xy 375.781052 -264.527009)
			(xy 375.552472 -264.527009) (xy 375.544529 -264.579713) (xy 375.528819 -264.630643) (xy 375.505693 -264.678664)
			(xy 375.475669 -264.722701) (xy 375.439417 -264.761772) (xy 375.397746 -264.795003) (xy 375.351588 -264.821652)
			(xy 375.301974 -264.841124) (xy 375.250012 -264.852984) (xy 375.196862 -264.856968) (xy 375.143712 -264.852984)
			(xy 375.09175 -264.841124) (xy 375.042136 -264.821652) (xy 374.995978 -264.795003) (xy 374.954307 -264.761772)
			(xy 374.918055 -264.722701) (xy 374.888031 -264.678664) (xy 374.864905 -264.630643) (xy 374.849195 -264.579713)
			(xy 374.841252 -264.527009) (xy 374.612926 -264.527009) (xy 374.604983 -264.579713) (xy 374.589273 -264.630643)
			(xy 374.566147 -264.678664) (xy 374.536123 -264.722701) (xy 374.499871 -264.761772) (xy 374.4582 -264.795003)
			(xy 374.412042 -264.821652) (xy 374.362428 -264.841124) (xy 374.310466 -264.852984) (xy 374.257316 -264.856968)
			(xy 374.204166 -264.852984) (xy 374.152204 -264.841124) (xy 374.10259 -264.821652) (xy 374.056432 -264.795003)
			(xy 374.014761 -264.761772) (xy 373.978509 -264.722701) (xy 373.948485 -264.678664) (xy 373.925359 -264.630643)
			(xy 373.909649 -264.579713) (xy 373.901706 -264.527009) (xy 373.672872 -264.527009) (xy 373.664929 -264.579713)
			(xy 373.649219 -264.630643) (xy 373.626093 -264.678664) (xy 373.596069 -264.722701) (xy 373.559817 -264.761772)
			(xy 373.518146 -264.795003) (xy 373.471988 -264.821652) (xy 373.422374 -264.841124) (xy 373.370412 -264.852984)
			(xy 373.317262 -264.856968) (xy 373.264112 -264.852984) (xy 373.21215 -264.841124) (xy 373.162536 -264.821652)
			(xy 373.116378 -264.795003) (xy 373.074707 -264.761772) (xy 373.038455 -264.722701) (xy 373.008431 -264.678664)
			(xy 372.985305 -264.630643) (xy 372.969595 -264.579713) (xy 372.961652 -264.527009) (xy 372.733072 -264.527009)
			(xy 372.725129 -264.579713) (xy 372.709419 -264.630643) (xy 372.686293 -264.678664) (xy 372.656269 -264.722701)
			(xy 372.620017 -264.761772) (xy 372.578346 -264.795003) (xy 372.532188 -264.821652) (xy 372.482574 -264.841124)
			(xy 372.430612 -264.852984) (xy 372.377462 -264.856968) (xy 372.324312 -264.852984) (xy 372.27235 -264.841124)
			(xy 372.222736 -264.821652) (xy 372.176578 -264.795003) (xy 372.134907 -264.761772) (xy 372.098655 -264.722701)
			(xy 372.068631 -264.678664) (xy 372.045505 -264.630643) (xy 372.029795 -264.579713) (xy 372.021852 -264.527009)
			(xy 371.793272 -264.527009) (xy 371.785329 -264.579713) (xy 371.769619 -264.630643) (xy 371.746493 -264.678664)
			(xy 371.716469 -264.722701) (xy 371.680217 -264.761772) (xy 371.638546 -264.795003) (xy 371.592388 -264.821652)
			(xy 371.542774 -264.841124) (xy 371.490812 -264.852984) (xy 371.437662 -264.856968) (xy 371.384512 -264.852984)
			(xy 371.33255 -264.841124) (xy 371.282936 -264.821652) (xy 371.236778 -264.795003) (xy 371.195107 -264.761772)
			(xy 371.158855 -264.722701) (xy 371.128831 -264.678664) (xy 371.105705 -264.630643) (xy 371.089995 -264.579713)
			(xy 371.082052 -264.527009) (xy 370.853472 -264.527009) (xy 370.845529 -264.579713) (xy 370.829819 -264.630643)
			(xy 370.806693 -264.678664) (xy 370.776669 -264.722701) (xy 370.740417 -264.761772) (xy 370.698746 -264.795003)
			(xy 370.652588 -264.821652) (xy 370.602974 -264.841124) (xy 370.551012 -264.852984) (xy 370.497862 -264.856968)
			(xy 370.444712 -264.852984) (xy 370.39275 -264.841124) (xy 370.343136 -264.821652) (xy 370.296978 -264.795003)
			(xy 370.255307 -264.761772) (xy 370.219055 -264.722701) (xy 370.189031 -264.678664) (xy 370.165905 -264.630643)
			(xy 370.150195 -264.579713) (xy 370.142252 -264.527009) (xy 369.913672 -264.527009) (xy 369.905729 -264.579713)
			(xy 369.890019 -264.630643) (xy 369.866893 -264.678664) (xy 369.836869 -264.722701) (xy 369.800617 -264.761772)
			(xy 369.758946 -264.795003) (xy 369.712788 -264.821652) (xy 369.663174 -264.841124) (xy 369.611212 -264.852984)
			(xy 369.558062 -264.856968) (xy 369.504912 -264.852984) (xy 369.45295 -264.841124) (xy 369.403336 -264.821652)
			(xy 369.357178 -264.795003) (xy 369.315507 -264.761772) (xy 369.279255 -264.722701) (xy 369.249231 -264.678664)
			(xy 369.226105 -264.630643) (xy 369.210395 -264.579713) (xy 369.202452 -264.527009) (xy 368.973872 -264.527009)
			(xy 368.965929 -264.579713) (xy 368.950219 -264.630643) (xy 368.927093 -264.678664) (xy 368.897069 -264.722701)
			(xy 368.860817 -264.761772) (xy 368.819146 -264.795003) (xy 368.772988 -264.821652) (xy 368.723374 -264.841124)
			(xy 368.671412 -264.852984) (xy 368.618262 -264.856968) (xy 368.565112 -264.852984) (xy 368.51315 -264.841124)
			(xy 368.463536 -264.821652) (xy 368.417378 -264.795003) (xy 368.375707 -264.761772) (xy 368.339455 -264.722701)
			(xy 368.309431 -264.678664) (xy 368.286305 -264.630643) (xy 368.270595 -264.579713) (xy 368.262652 -264.527009)
			(xy 368.033178 -264.527009) (xy 368.031188 -264.553563) (xy 368.019324 -264.605538) (xy 367.999846 -264.655164)
			(xy 367.973188 -264.701332) (xy 367.939947 -264.743012) (xy 367.900864 -264.779271) (xy 367.856814 -264.8093)
			(xy 367.80878 -264.832427) (xy 367.757835 -264.848137) (xy 367.705118 -264.856077) (xy 367.678462 -264.856468)
			(xy 367.649924 -264.855912) (xy 367.593581 -264.846808) (xy 367.539419 -264.828808) (xy 367.51387 -264.816082)
			(xy 367.500412 -264.809653) (xy 367.471123 -264.804089) (xy 367.441476 -264.807215) (xy 367.413991 -264.818764)
			(xy 367.391009 -264.837753) (xy 367.374485 -264.862566) (xy 367.365825 -264.891093) (xy 367.36528 -264.905998)
			(xy 367.36528 -264.99439) (xy 367.388881 -265.006459) (xy 367.432536 -265.036527) (xy 367.471248 -265.072736)
			(xy 367.504161 -265.114287) (xy 367.530548 -265.16026) (xy 367.549824 -265.209638) (xy 367.561564 -265.261329)
			(xy 367.565507 -265.314189) (xy 367.563522 -265.340825) (xy 367.793006 -265.340825) (xy 367.793006 -265.287527)
			(xy 367.800949 -265.234823) (xy 367.816659 -265.183893) (xy 367.839785 -265.135872) (xy 367.869809 -265.091835)
			(xy 367.906061 -265.052764) (xy 367.947732 -265.019533) (xy 367.99389 -264.992884) (xy 368.043504 -264.973412)
			(xy 368.095466 -264.961552) (xy 368.148616 -264.957569) (xy 368.201766 -264.961552) (xy 368.253728 -264.973412)
			(xy 368.303342 -264.992884) (xy 368.3495 -265.019533) (xy 368.391171 -265.052764) (xy 368.427423 -265.091835)
			(xy 368.457447 -265.135872) (xy 368.480573 -265.183893) (xy 368.496283 -265.234823) (xy 368.504226 -265.287527)
			(xy 368.504724 -265.314176) (xy 368.504226 -265.340825) (xy 369.672606 -265.340825) (xy 369.672606 -265.287527)
			(xy 369.680549 -265.234823) (xy 369.696259 -265.183893) (xy 369.719385 -265.135872) (xy 369.749409 -265.091835)
			(xy 369.785661 -265.052764) (xy 369.827332 -265.019533) (xy 369.87349 -264.992884) (xy 369.923104 -264.973412)
			(xy 369.975066 -264.961552) (xy 370.028216 -264.957569) (xy 370.081366 -264.961552) (xy 370.133328 -264.973412)
			(xy 370.182942 -264.992884) (xy 370.2291 -265.019533) (xy 370.270771 -265.052764) (xy 370.307023 -265.091835)
			(xy 370.337047 -265.135872) (xy 370.360173 -265.183893) (xy 370.375883 -265.234823) (xy 370.383826 -265.287527)
			(xy 370.384324 -265.314176) (xy 370.383826 -265.340825) (xy 370.612406 -265.340825) (xy 370.612406 -265.287527)
			(xy 370.620349 -265.234823) (xy 370.636059 -265.183893) (xy 370.659185 -265.135872) (xy 370.689209 -265.091835)
			(xy 370.725461 -265.052764) (xy 370.767132 -265.019533) (xy 370.81329 -264.992884) (xy 370.862904 -264.973412)
			(xy 370.914866 -264.961552) (xy 370.968016 -264.957569) (xy 371.021166 -264.961552) (xy 371.073128 -264.973412)
			(xy 371.122742 -264.992884) (xy 371.1689 -265.019533) (xy 371.210571 -265.052764) (xy 371.246823 -265.091835)
			(xy 371.276847 -265.135872) (xy 371.299973 -265.183893) (xy 371.315683 -265.234823) (xy 371.323626 -265.287527)
			(xy 371.324124 -265.314176) (xy 371.323626 -265.340825) (xy 371.552206 -265.340825) (xy 371.552206 -265.287527)
			(xy 371.560149 -265.234823) (xy 371.575859 -265.183893) (xy 371.598985 -265.135872) (xy 371.629009 -265.091835)
			(xy 371.665261 -265.052764) (xy 371.706932 -265.019533) (xy 371.75309 -264.992884) (xy 371.802704 -264.973412)
			(xy 371.854666 -264.961552) (xy 371.907816 -264.957569) (xy 371.960966 -264.961552) (xy 372.012928 -264.973412)
			(xy 372.062542 -264.992884) (xy 372.1087 -265.019533) (xy 372.150371 -265.052764) (xy 372.186623 -265.091835)
			(xy 372.216647 -265.135872) (xy 372.239773 -265.183893) (xy 372.255483 -265.234823) (xy 372.263426 -265.287527)
			(xy 372.263924 -265.314176) (xy 372.263426 -265.340825) (xy 372.492006 -265.340825) (xy 372.492006 -265.287527)
			(xy 372.499949 -265.234823) (xy 372.515659 -265.183893) (xy 372.538785 -265.135872) (xy 372.568809 -265.091835)
			(xy 372.605061 -265.052764) (xy 372.646732 -265.019533) (xy 372.69289 -264.992884) (xy 372.742504 -264.973412)
			(xy 372.794466 -264.961552) (xy 372.847616 -264.957569) (xy 372.900766 -264.961552) (xy 372.952728 -264.973412)
			(xy 373.002342 -264.992884) (xy 373.0485 -265.019533) (xy 373.090171 -265.052764) (xy 373.126423 -265.091835)
			(xy 373.156447 -265.135872) (xy 373.179573 -265.183893) (xy 373.195283 -265.234823) (xy 373.203226 -265.287527)
			(xy 373.203724 -265.314176) (xy 373.203226 -265.340825) (xy 373.431806 -265.340825) (xy 373.431806 -265.287527)
			(xy 373.439749 -265.234823) (xy 373.455459 -265.183893) (xy 373.478585 -265.135872) (xy 373.508609 -265.091835)
			(xy 373.544861 -265.052764) (xy 373.586532 -265.019533) (xy 373.63269 -264.992884) (xy 373.682304 -264.973412)
			(xy 373.734266 -264.961552) (xy 373.787416 -264.957569) (xy 373.840566 -264.961552) (xy 373.892528 -264.973412)
			(xy 373.942142 -264.992884) (xy 373.9883 -265.019533) (xy 374.029971 -265.052764) (xy 374.066223 -265.091835)
			(xy 374.096247 -265.135872) (xy 374.119373 -265.183893) (xy 374.135083 -265.234823) (xy 374.143026 -265.287527)
			(xy 374.143524 -265.314176) (xy 374.143026 -265.340825) (xy 374.371352 -265.340825) (xy 374.371352 -265.287527)
			(xy 374.379295 -265.234823) (xy 374.395005 -265.183893) (xy 374.418131 -265.135872) (xy 374.448155 -265.091835)
			(xy 374.484407 -265.052764) (xy 374.526078 -265.019533) (xy 374.572236 -264.992884) (xy 374.62185 -264.973412)
			(xy 374.673812 -264.961552) (xy 374.726962 -264.957569) (xy 374.780112 -264.961552) (xy 374.832074 -264.973412)
			(xy 374.881688 -264.992884) (xy 374.927846 -265.019533) (xy 374.969517 -265.052764) (xy 375.005769 -265.091835)
			(xy 375.035793 -265.135872) (xy 375.058919 -265.183893) (xy 375.074629 -265.234823) (xy 375.082572 -265.287527)
			(xy 375.08307 -265.314176) (xy 375.082572 -265.340825) (xy 375.311406 -265.340825) (xy 375.311406 -265.287527)
			(xy 375.319349 -265.234823) (xy 375.335059 -265.183893) (xy 375.358185 -265.135872) (xy 375.388209 -265.091835)
			(xy 375.424461 -265.052764) (xy 375.466132 -265.019533) (xy 375.51229 -264.992884) (xy 375.561904 -264.973412)
			(xy 375.613866 -264.961552) (xy 375.667016 -264.957569) (xy 375.720166 -264.961552) (xy 375.772128 -264.973412)
			(xy 375.821742 -264.992884) (xy 375.8679 -265.019533) (xy 375.909571 -265.052764) (xy 375.945823 -265.091835)
			(xy 375.975847 -265.135872) (xy 375.998973 -265.183893) (xy 376.014683 -265.234823) (xy 376.022626 -265.287527)
			(xy 376.023124 -265.314176) (xy 376.022626 -265.340825) (xy 376.251206 -265.340825) (xy 376.251206 -265.287527)
			(xy 376.259149 -265.234823) (xy 376.274859 -265.183893) (xy 376.297985 -265.135872) (xy 376.328009 -265.091835)
			(xy 376.364261 -265.052764) (xy 376.405932 -265.019533) (xy 376.45209 -264.992884) (xy 376.501704 -264.973412)
			(xy 376.553666 -264.961552) (xy 376.606816 -264.957569) (xy 376.659966 -264.961552) (xy 376.711928 -264.973412)
			(xy 376.761542 -264.992884) (xy 376.8077 -265.019533) (xy 376.849371 -265.052764) (xy 376.885623 -265.091835)
			(xy 376.915647 -265.135872) (xy 376.938773 -265.183893) (xy 376.954483 -265.234823) (xy 376.962426 -265.287527)
			(xy 376.962924 -265.314176) (xy 376.962426 -265.340825) (xy 377.191006 -265.340825) (xy 377.191006 -265.287527)
			(xy 377.198949 -265.234823) (xy 377.214659 -265.183893) (xy 377.237785 -265.135872) (xy 377.267809 -265.091835)
			(xy 377.304061 -265.052764) (xy 377.345732 -265.019533) (xy 377.39189 -264.992884) (xy 377.441504 -264.973412)
			(xy 377.493466 -264.961552) (xy 377.546616 -264.957569) (xy 377.599766 -264.961552) (xy 377.651728 -264.973412)
			(xy 377.701342 -264.992884) (xy 377.7475 -265.019533) (xy 377.789171 -265.052764) (xy 377.825423 -265.091835)
			(xy 377.855447 -265.135872) (xy 377.878573 -265.183893) (xy 377.894283 -265.234823) (xy 377.902226 -265.287527)
			(xy 377.902724 -265.314176) (xy 377.902226 -265.340825) (xy 378.130806 -265.340825) (xy 378.130806 -265.287527)
			(xy 378.138749 -265.234823) (xy 378.154459 -265.183893) (xy 378.177585 -265.135872) (xy 378.207609 -265.091835)
			(xy 378.243861 -265.052764) (xy 378.285532 -265.019533) (xy 378.33169 -264.992884) (xy 378.381304 -264.973412)
			(xy 378.433266 -264.961552) (xy 378.486416 -264.957569) (xy 378.539566 -264.961552) (xy 378.591528 -264.973412)
			(xy 378.641142 -264.992884) (xy 378.6873 -265.019533) (xy 378.728971 -265.052764) (xy 378.765223 -265.091835)
			(xy 378.795247 -265.135872) (xy 378.818373 -265.183893) (xy 378.834083 -265.234823) (xy 378.842026 -265.287527)
			(xy 378.842524 -265.314176) (xy 378.842026 -265.340825) (xy 379.070606 -265.340825) (xy 379.070606 -265.287527)
			(xy 379.078549 -265.234823) (xy 379.094259 -265.183893) (xy 379.117385 -265.135872) (xy 379.147409 -265.091835)
			(xy 379.183661 -265.052764) (xy 379.225332 -265.019533) (xy 379.27149 -264.992884) (xy 379.321104 -264.973412)
			(xy 379.373066 -264.961552) (xy 379.426216 -264.957569) (xy 379.479366 -264.961552) (xy 379.531328 -264.973412)
			(xy 379.580942 -264.992884) (xy 379.6271 -265.019533) (xy 379.668771 -265.052764) (xy 379.705023 -265.091835)
			(xy 379.735047 -265.135872) (xy 379.758173 -265.183893) (xy 379.773883 -265.234823) (xy 379.781826 -265.287527)
			(xy 379.782324 -265.314176) (xy 379.781826 -265.340825) (xy 380.010406 -265.340825) (xy 380.010406 -265.287527)
			(xy 380.018349 -265.234823) (xy 380.034059 -265.183893) (xy 380.057185 -265.135872) (xy 380.087209 -265.091835)
			(xy 380.123461 -265.052764) (xy 380.165132 -265.019533) (xy 380.21129 -264.992884) (xy 380.260904 -264.973412)
			(xy 380.312866 -264.961552) (xy 380.366016 -264.957569) (xy 380.419166 -264.961552) (xy 380.471128 -264.973412)
			(xy 380.520742 -264.992884) (xy 380.5669 -265.019533) (xy 380.608571 -265.052764) (xy 380.644823 -265.091835)
			(xy 380.674847 -265.135872) (xy 380.697973 -265.183893) (xy 380.713683 -265.234823) (xy 380.721626 -265.287527)
			(xy 380.722124 -265.314176) (xy 380.721626 -265.340825) (xy 380.949952 -265.340825) (xy 380.949952 -265.287527)
			(xy 380.957895 -265.234823) (xy 380.973605 -265.183893) (xy 380.996731 -265.135872) (xy 381.026755 -265.091835)
			(xy 381.063007 -265.052764) (xy 381.104678 -265.019533) (xy 381.150836 -264.992884) (xy 381.20045 -264.973412)
			(xy 381.252412 -264.961552) (xy 381.305562 -264.957569) (xy 381.358712 -264.961552) (xy 381.410674 -264.973412)
			(xy 381.460288 -264.992884) (xy 381.506446 -265.019533) (xy 381.548117 -265.052764) (xy 381.584369 -265.091835)
			(xy 381.614393 -265.135872) (xy 381.637519 -265.183893) (xy 381.653229 -265.234823) (xy 381.661172 -265.287527)
			(xy 381.66167 -265.314176) (xy 381.661172 -265.340825) (xy 381.653229 -265.393529) (xy 381.637519 -265.444459)
			(xy 381.614393 -265.49248) (xy 381.584369 -265.536517) (xy 381.548117 -265.575588) (xy 381.506446 -265.608819)
			(xy 381.460288 -265.635468) (xy 381.410674 -265.65494) (xy 381.358712 -265.6668) (xy 381.305562 -265.670784)
			(xy 381.252412 -265.6668) (xy 381.20045 -265.65494) (xy 381.150836 -265.635468) (xy 381.104678 -265.608819)
			(xy 381.063007 -265.575588) (xy 381.026755 -265.536517) (xy 380.996731 -265.49248) (xy 380.973605 -265.444459)
			(xy 380.957895 -265.393529) (xy 380.949952 -265.340825) (xy 380.721626 -265.340825) (xy 380.713683 -265.393529)
			(xy 380.697973 -265.444459) (xy 380.674847 -265.49248) (xy 380.644823 -265.536517) (xy 380.608571 -265.575588)
			(xy 380.5669 -265.608819) (xy 380.520742 -265.635468) (xy 380.471128 -265.65494) (xy 380.419166 -265.6668)
			(xy 380.366016 -265.670784) (xy 380.312866 -265.6668) (xy 380.260904 -265.65494) (xy 380.21129 -265.635468)
			(xy 380.165132 -265.608819) (xy 380.123461 -265.575588) (xy 380.087209 -265.536517) (xy 380.057185 -265.49248)
			(xy 380.034059 -265.444459) (xy 380.018349 -265.393529) (xy 380.010406 -265.340825) (xy 379.781826 -265.340825)
			(xy 379.773883 -265.393529) (xy 379.758173 -265.444459) (xy 379.735047 -265.49248) (xy 379.705023 -265.536517)
			(xy 379.668771 -265.575588) (xy 379.6271 -265.608819) (xy 379.580942 -265.635468) (xy 379.531328 -265.65494)
			(xy 379.479366 -265.6668) (xy 379.426216 -265.670784) (xy 379.373066 -265.6668) (xy 379.321104 -265.65494)
			(xy 379.27149 -265.635468) (xy 379.225332 -265.608819) (xy 379.183661 -265.575588) (xy 379.147409 -265.536517)
			(xy 379.117385 -265.49248) (xy 379.094259 -265.444459) (xy 379.078549 -265.393529) (xy 379.070606 -265.340825)
			(xy 378.842026 -265.340825) (xy 378.834083 -265.393529) (xy 378.818373 -265.444459) (xy 378.795247 -265.49248)
			(xy 378.765223 -265.536517) (xy 378.728971 -265.575588) (xy 378.6873 -265.608819) (xy 378.641142 -265.635468)
			(xy 378.591528 -265.65494) (xy 378.539566 -265.6668) (xy 378.486416 -265.670784) (xy 378.433266 -265.6668)
			(xy 378.381304 -265.65494) (xy 378.33169 -265.635468) (xy 378.285532 -265.608819) (xy 378.243861 -265.575588)
			(xy 378.207609 -265.536517) (xy 378.177585 -265.49248) (xy 378.154459 -265.444459) (xy 378.138749 -265.393529)
			(xy 378.130806 -265.340825) (xy 377.902226 -265.340825) (xy 377.894283 -265.393529) (xy 377.878573 -265.444459)
			(xy 377.855447 -265.49248) (xy 377.825423 -265.536517) (xy 377.789171 -265.575588) (xy 377.7475 -265.608819)
			(xy 377.701342 -265.635468) (xy 377.651728 -265.65494) (xy 377.599766 -265.6668) (xy 377.546616 -265.670784)
			(xy 377.493466 -265.6668) (xy 377.441504 -265.65494) (xy 377.39189 -265.635468) (xy 377.345732 -265.608819)
			(xy 377.304061 -265.575588) (xy 377.267809 -265.536517) (xy 377.237785 -265.49248) (xy 377.214659 -265.444459)
			(xy 377.198949 -265.393529) (xy 377.191006 -265.340825) (xy 376.962426 -265.340825) (xy 376.954483 -265.393529)
			(xy 376.938773 -265.444459) (xy 376.915647 -265.49248) (xy 376.885623 -265.536517) (xy 376.849371 -265.575588)
			(xy 376.8077 -265.608819) (xy 376.761542 -265.635468) (xy 376.711928 -265.65494) (xy 376.659966 -265.6668)
			(xy 376.606816 -265.670784) (xy 376.553666 -265.6668) (xy 376.501704 -265.65494) (xy 376.45209 -265.635468)
			(xy 376.405932 -265.608819) (xy 376.364261 -265.575588) (xy 376.328009 -265.536517) (xy 376.297985 -265.49248)
			(xy 376.274859 -265.444459) (xy 376.259149 -265.393529) (xy 376.251206 -265.340825) (xy 376.022626 -265.340825)
			(xy 376.014683 -265.393529) (xy 375.998973 -265.444459) (xy 375.975847 -265.49248) (xy 375.945823 -265.536517)
			(xy 375.909571 -265.575588) (xy 375.8679 -265.608819) (xy 375.821742 -265.635468) (xy 375.772128 -265.65494)
			(xy 375.720166 -265.6668) (xy 375.667016 -265.670784) (xy 375.613866 -265.6668) (xy 375.561904 -265.65494)
			(xy 375.51229 -265.635468) (xy 375.466132 -265.608819) (xy 375.424461 -265.575588) (xy 375.388209 -265.536517)
			(xy 375.358185 -265.49248) (xy 375.335059 -265.444459) (xy 375.319349 -265.393529) (xy 375.311406 -265.340825)
			(xy 375.082572 -265.340825) (xy 375.074629 -265.393529) (xy 375.058919 -265.444459) (xy 375.035793 -265.49248)
			(xy 375.005769 -265.536517) (xy 374.969517 -265.575588) (xy 374.927846 -265.608819) (xy 374.881688 -265.635468)
			(xy 374.832074 -265.65494) (xy 374.780112 -265.6668) (xy 374.726962 -265.670784) (xy 374.673812 -265.6668)
			(xy 374.62185 -265.65494) (xy 374.572236 -265.635468) (xy 374.526078 -265.608819) (xy 374.484407 -265.575588)
			(xy 374.448155 -265.536517) (xy 374.418131 -265.49248) (xy 374.395005 -265.444459) (xy 374.379295 -265.393529)
			(xy 374.371352 -265.340825) (xy 374.143026 -265.340825) (xy 374.135083 -265.393529) (xy 374.119373 -265.444459)
			(xy 374.096247 -265.49248) (xy 374.066223 -265.536517) (xy 374.029971 -265.575588) (xy 373.9883 -265.608819)
			(xy 373.942142 -265.635468) (xy 373.892528 -265.65494) (xy 373.840566 -265.6668) (xy 373.787416 -265.670784)
			(xy 373.734266 -265.6668) (xy 373.682304 -265.65494) (xy 373.63269 -265.635468) (xy 373.586532 -265.608819)
			(xy 373.544861 -265.575588) (xy 373.508609 -265.536517) (xy 373.478585 -265.49248) (xy 373.455459 -265.444459)
			(xy 373.439749 -265.393529) (xy 373.431806 -265.340825) (xy 373.203226 -265.340825) (xy 373.195283 -265.393529)
			(xy 373.179573 -265.444459) (xy 373.156447 -265.49248) (xy 373.126423 -265.536517) (xy 373.090171 -265.575588)
			(xy 373.0485 -265.608819) (xy 373.002342 -265.635468) (xy 372.952728 -265.65494) (xy 372.900766 -265.6668)
			(xy 372.847616 -265.670784) (xy 372.794466 -265.6668) (xy 372.742504 -265.65494) (xy 372.69289 -265.635468)
			(xy 372.646732 -265.608819) (xy 372.605061 -265.575588) (xy 372.568809 -265.536517) (xy 372.538785 -265.49248)
			(xy 372.515659 -265.444459) (xy 372.499949 -265.393529) (xy 372.492006 -265.340825) (xy 372.263426 -265.340825)
			(xy 372.255483 -265.393529) (xy 372.239773 -265.444459) (xy 372.216647 -265.49248) (xy 372.186623 -265.536517)
			(xy 372.150371 -265.575588) (xy 372.1087 -265.608819) (xy 372.062542 -265.635468) (xy 372.012928 -265.65494)
			(xy 371.960966 -265.6668) (xy 371.907816 -265.670784) (xy 371.854666 -265.6668) (xy 371.802704 -265.65494)
			(xy 371.75309 -265.635468) (xy 371.706932 -265.608819) (xy 371.665261 -265.575588) (xy 371.629009 -265.536517)
			(xy 371.598985 -265.49248) (xy 371.575859 -265.444459) (xy 371.560149 -265.393529) (xy 371.552206 -265.340825)
			(xy 371.323626 -265.340825) (xy 371.315683 -265.393529) (xy 371.299973 -265.444459) (xy 371.276847 -265.49248)
			(xy 371.246823 -265.536517) (xy 371.210571 -265.575588) (xy 371.1689 -265.608819) (xy 371.122742 -265.635468)
			(xy 371.073128 -265.65494) (xy 371.021166 -265.6668) (xy 370.968016 -265.670784) (xy 370.914866 -265.6668)
			(xy 370.862904 -265.65494) (xy 370.81329 -265.635468) (xy 370.767132 -265.608819) (xy 370.725461 -265.575588)
			(xy 370.689209 -265.536517) (xy 370.659185 -265.49248) (xy 370.636059 -265.444459) (xy 370.620349 -265.393529)
			(xy 370.612406 -265.340825) (xy 370.383826 -265.340825) (xy 370.375883 -265.393529) (xy 370.360173 -265.444459)
			(xy 370.337047 -265.49248) (xy 370.307023 -265.536517) (xy 370.270771 -265.575588) (xy 370.2291 -265.608819)
			(xy 370.182942 -265.635468) (xy 370.133328 -265.65494) (xy 370.081366 -265.6668) (xy 370.028216 -265.670784)
			(xy 369.975066 -265.6668) (xy 369.923104 -265.65494) (xy 369.87349 -265.635468) (xy 369.827332 -265.608819)
			(xy 369.785661 -265.575588) (xy 369.749409 -265.536517) (xy 369.719385 -265.49248) (xy 369.696259 -265.444459)
			(xy 369.680549 -265.393529) (xy 369.672606 -265.340825) (xy 368.504226 -265.340825) (xy 368.496283 -265.393529)
			(xy 368.480573 -265.444459) (xy 368.457447 -265.49248) (xy 368.427423 -265.536517) (xy 368.391171 -265.575588)
			(xy 368.3495 -265.608819) (xy 368.303342 -265.635468) (xy 368.253728 -265.65494) (xy 368.201766 -265.6668)
			(xy 368.148616 -265.670784) (xy 368.095466 -265.6668) (xy 368.043504 -265.65494) (xy 367.99389 -265.635468)
			(xy 367.947732 -265.608819) (xy 367.906061 -265.575588) (xy 367.869809 -265.536517) (xy 367.839785 -265.49248)
			(xy 367.816659 -265.444459) (xy 367.800949 -265.393529) (xy 367.793006 -265.340825) (xy 367.563522 -265.340825)
			(xy 367.561567 -265.36705) (xy 367.54983 -265.418742) (xy 367.530557 -265.468121) (xy 367.504173 -265.514095)
			(xy 367.471262 -265.555648) (xy 367.432552 -265.59186) (xy 367.3889 -265.621931) (xy 367.36528 -265.633962)
			(xy 367.36528 -265.722608) (xy 367.365842 -265.737509) (xy 367.37452 -265.766024) (xy 367.39105 -265.790826)
			(xy 367.414027 -265.809811) (xy 367.441502 -265.821366) (xy 367.471141 -265.824511) (xy 367.500429 -265.818979)
			(xy 367.51387 -265.812524) (xy 367.539435 -265.79984) (xy 367.593597 -265.781865) (xy 367.649929 -265.772735)
			(xy 367.678462 -265.772138) (xy 367.705112 -265.772608) (xy 367.757816 -265.780547) (xy 367.808749 -265.796253)
			(xy 367.856771 -265.819375) (xy 367.900811 -265.849396) (xy 367.939884 -265.885647) (xy 367.973117 -265.927316)
			(xy 367.999768 -265.973473) (xy 368.019242 -266.023088) (xy 368.031103 -266.07505) (xy 368.035086 -266.1282)
			(xy 368.033086 -266.154895) (xy 368.262652 -266.154895) (xy 368.262652 -266.101597) (xy 368.270595 -266.048893)
			(xy 368.286305 -265.997963) (xy 368.309431 -265.949942) (xy 368.339455 -265.905905) (xy 368.375707 -265.866834)
			(xy 368.417378 -265.833603) (xy 368.463536 -265.806954) (xy 368.51315 -265.787482) (xy 368.565112 -265.775622)
			(xy 368.618262 -265.771639) (xy 368.671412 -265.775622) (xy 368.723374 -265.787482) (xy 368.772988 -265.806954)
			(xy 368.819146 -265.833603) (xy 368.860817 -265.866834) (xy 368.897069 -265.905905) (xy 368.927093 -265.949942)
			(xy 368.950219 -265.997963) (xy 368.965929 -266.048893) (xy 368.973872 -266.101597) (xy 368.97437 -266.128246)
			(xy 368.973872 -266.154895) (xy 370.142252 -266.154895) (xy 370.142252 -266.101597) (xy 370.150195 -266.048893)
			(xy 370.165905 -265.997963) (xy 370.189031 -265.949942) (xy 370.219055 -265.905905) (xy 370.255307 -265.866834)
			(xy 370.296978 -265.833603) (xy 370.343136 -265.806954) (xy 370.39275 -265.787482) (xy 370.444712 -265.775622)
			(xy 370.497862 -265.771639) (xy 370.551012 -265.775622) (xy 370.602974 -265.787482) (xy 370.652588 -265.806954)
			(xy 370.698746 -265.833603) (xy 370.740417 -265.866834) (xy 370.776669 -265.905905) (xy 370.806693 -265.949942)
			(xy 370.829819 -265.997963) (xy 370.845529 -266.048893) (xy 370.853472 -266.101597) (xy 370.85397 -266.128246)
			(xy 370.853472 -266.154895) (xy 371.082052 -266.154895) (xy 371.082052 -266.101597) (xy 371.089995 -266.048893)
			(xy 371.105705 -265.997963) (xy 371.128831 -265.949942) (xy 371.158855 -265.905905) (xy 371.195107 -265.866834)
			(xy 371.236778 -265.833603) (xy 371.282936 -265.806954) (xy 371.33255 -265.787482) (xy 371.384512 -265.775622)
			(xy 371.437662 -265.771639) (xy 371.490812 -265.775622) (xy 371.542774 -265.787482) (xy 371.592388 -265.806954)
			(xy 371.638546 -265.833603) (xy 371.680217 -265.866834) (xy 371.716469 -265.905905) (xy 371.746493 -265.949942)
			(xy 371.769619 -265.997963) (xy 371.785329 -266.048893) (xy 371.793272 -266.101597) (xy 371.79377 -266.128246)
			(xy 371.793272 -266.154895) (xy 372.021852 -266.154895) (xy 372.021852 -266.101597) (xy 372.029795 -266.048893)
			(xy 372.045505 -265.997963) (xy 372.068631 -265.949942) (xy 372.098655 -265.905905) (xy 372.134907 -265.866834)
			(xy 372.176578 -265.833603) (xy 372.222736 -265.806954) (xy 372.27235 -265.787482) (xy 372.324312 -265.775622)
			(xy 372.377462 -265.771639) (xy 372.430612 -265.775622) (xy 372.482574 -265.787482) (xy 372.532188 -265.806954)
			(xy 372.578346 -265.833603) (xy 372.620017 -265.866834) (xy 372.656269 -265.905905) (xy 372.686293 -265.949942)
			(xy 372.709419 -265.997963) (xy 372.725129 -266.048893) (xy 372.733072 -266.101597) (xy 372.73357 -266.128246)
			(xy 372.733072 -266.154895) (xy 372.961652 -266.154895) (xy 372.961652 -266.101597) (xy 372.969595 -266.048893)
			(xy 372.985305 -265.997963) (xy 373.008431 -265.949942) (xy 373.038455 -265.905905) (xy 373.074707 -265.866834)
			(xy 373.116378 -265.833603) (xy 373.162536 -265.806954) (xy 373.21215 -265.787482) (xy 373.264112 -265.775622)
			(xy 373.317262 -265.771639) (xy 373.370412 -265.775622) (xy 373.422374 -265.787482) (xy 373.471988 -265.806954)
			(xy 373.518146 -265.833603) (xy 373.559817 -265.866834) (xy 373.596069 -265.905905) (xy 373.626093 -265.949942)
			(xy 373.649219 -265.997963) (xy 373.664929 -266.048893) (xy 373.672872 -266.101597) (xy 373.67337 -266.128246)
			(xy 373.672872 -266.154895) (xy 373.901452 -266.154895) (xy 373.901452 -266.101597) (xy 373.909395 -266.048893)
			(xy 373.925105 -265.997963) (xy 373.948231 -265.949942) (xy 373.978255 -265.905905) (xy 374.014507 -265.866834)
			(xy 374.056178 -265.833603) (xy 374.102336 -265.806954) (xy 374.15195 -265.787482) (xy 374.203912 -265.775622)
			(xy 374.257062 -265.771639) (xy 374.310212 -265.775622) (xy 374.362174 -265.787482) (xy 374.411788 -265.806954)
			(xy 374.457946 -265.833603) (xy 374.499617 -265.866834) (xy 374.535869 -265.905905) (xy 374.565893 -265.949942)
			(xy 374.589019 -265.997963) (xy 374.604729 -266.048893) (xy 374.612672 -266.101597) (xy 374.61317 -266.128246)
			(xy 374.612672 -266.154895) (xy 374.841252 -266.154895) (xy 374.841252 -266.101597) (xy 374.849195 -266.048893)
			(xy 374.864905 -265.997963) (xy 374.888031 -265.949942) (xy 374.918055 -265.905905) (xy 374.954307 -265.866834)
			(xy 374.995978 -265.833603) (xy 375.042136 -265.806954) (xy 375.09175 -265.787482) (xy 375.143712 -265.775622)
			(xy 375.196862 -265.771639) (xy 375.250012 -265.775622) (xy 375.301974 -265.787482) (xy 375.351588 -265.806954)
			(xy 375.397746 -265.833603) (xy 375.439417 -265.866834) (xy 375.475669 -265.905905) (xy 375.505693 -265.949942)
			(xy 375.528819 -265.997963) (xy 375.544529 -266.048893) (xy 375.552472 -266.101597) (xy 375.55297 -266.128246)
			(xy 375.552472 -266.154895) (xy 375.781052 -266.154895) (xy 375.781052 -266.101597) (xy 375.788995 -266.048893)
			(xy 375.804705 -265.997963) (xy 375.827831 -265.949942) (xy 375.857855 -265.905905) (xy 375.894107 -265.866834)
			(xy 375.935778 -265.833603) (xy 375.981936 -265.806954) (xy 376.03155 -265.787482) (xy 376.083512 -265.775622)
			(xy 376.136662 -265.771639) (xy 376.189812 -265.775622) (xy 376.241774 -265.787482) (xy 376.291388 -265.806954)
			(xy 376.337546 -265.833603) (xy 376.379217 -265.866834) (xy 376.415469 -265.905905) (xy 376.445493 -265.949942)
			(xy 376.468619 -265.997963) (xy 376.484329 -266.048893) (xy 376.492272 -266.101597) (xy 376.49277 -266.128246)
			(xy 376.492272 -266.154895) (xy 376.720852 -266.154895) (xy 376.720852 -266.101597) (xy 376.728795 -266.048893)
			(xy 376.744505 -265.997963) (xy 376.767631 -265.949942) (xy 376.797655 -265.905905) (xy 376.833907 -265.866834)
			(xy 376.875578 -265.833603) (xy 376.921736 -265.806954) (xy 376.97135 -265.787482) (xy 377.023312 -265.775622)
			(xy 377.076462 -265.771639) (xy 377.129612 -265.775622) (xy 377.181574 -265.787482) (xy 377.231188 -265.806954)
			(xy 377.277346 -265.833603) (xy 377.319017 -265.866834) (xy 377.355269 -265.905905) (xy 377.385293 -265.949942)
			(xy 377.408419 -265.997963) (xy 377.424129 -266.048893) (xy 377.432072 -266.101597) (xy 377.43257 -266.128246)
			(xy 377.432072 -266.154895) (xy 377.660652 -266.154895) (xy 377.660652 -266.101597) (xy 377.668595 -266.048893)
			(xy 377.684305 -265.997963) (xy 377.707431 -265.949942) (xy 377.737455 -265.905905) (xy 377.773707 -265.866834)
			(xy 377.815378 -265.833603) (xy 377.861536 -265.806954) (xy 377.91115 -265.787482) (xy 377.963112 -265.775622)
			(xy 378.016262 -265.771639) (xy 378.069412 -265.775622) (xy 378.121374 -265.787482) (xy 378.170988 -265.806954)
			(xy 378.217146 -265.833603) (xy 378.258817 -265.866834) (xy 378.295069 -265.905905) (xy 378.325093 -265.949942)
			(xy 378.348219 -265.997963) (xy 378.363929 -266.048893) (xy 378.371872 -266.101597) (xy 378.37237 -266.128246)
			(xy 378.371872 -266.154895) (xy 378.600452 -266.154895) (xy 378.600452 -266.101597) (xy 378.608395 -266.048893)
			(xy 378.624105 -265.997963) (xy 378.647231 -265.949942) (xy 378.677255 -265.905905) (xy 378.713507 -265.866834)
			(xy 378.755178 -265.833603) (xy 378.801336 -265.806954) (xy 378.85095 -265.787482) (xy 378.902912 -265.775622)
			(xy 378.956062 -265.771639) (xy 379.009212 -265.775622) (xy 379.061174 -265.787482) (xy 379.110788 -265.806954)
			(xy 379.156946 -265.833603) (xy 379.198617 -265.866834) (xy 379.234869 -265.905905) (xy 379.264893 -265.949942)
			(xy 379.288019 -265.997963) (xy 379.303729 -266.048893) (xy 379.311672 -266.101597) (xy 379.31217 -266.128246)
			(xy 379.311672 -266.154895) (xy 379.540252 -266.154895) (xy 379.540252 -266.101597) (xy 379.548195 -266.048893)
			(xy 379.563905 -265.997963) (xy 379.587031 -265.949942) (xy 379.617055 -265.905905) (xy 379.653307 -265.866834)
			(xy 379.694978 -265.833603) (xy 379.741136 -265.806954) (xy 379.79075 -265.787482) (xy 379.842712 -265.775622)
			(xy 379.895862 -265.771639) (xy 379.949012 -265.775622) (xy 380.000974 -265.787482) (xy 380.050588 -265.806954)
			(xy 380.096746 -265.833603) (xy 380.138417 -265.866834) (xy 380.174669 -265.905905) (xy 380.204693 -265.949942)
			(xy 380.227819 -265.997963) (xy 380.243529 -266.048893) (xy 380.251472 -266.101597) (xy 380.25197 -266.128246)
			(xy 380.251472 -266.154895) (xy 380.480052 -266.154895) (xy 380.480052 -266.101597) (xy 380.487995 -266.048893)
			(xy 380.503705 -265.997963) (xy 380.526831 -265.949942) (xy 380.556855 -265.905905) (xy 380.593107 -265.866834)
			(xy 380.634778 -265.833603) (xy 380.680936 -265.806954) (xy 380.73055 -265.787482) (xy 380.782512 -265.775622)
			(xy 380.835662 -265.771639) (xy 380.888812 -265.775622) (xy 380.940774 -265.787482) (xy 380.990388 -265.806954)
			(xy 381.036546 -265.833603) (xy 381.078217 -265.866834) (xy 381.114469 -265.905905) (xy 381.144493 -265.949942)
			(xy 381.167619 -265.997963) (xy 381.183329 -266.048893) (xy 381.191272 -266.101597) (xy 381.19177 -266.128246)
			(xy 381.191272 -266.154895) (xy 381.183329 -266.207599) (xy 381.167619 -266.258529) (xy 381.144493 -266.30655)
			(xy 381.114469 -266.350587) (xy 381.078217 -266.389658) (xy 381.036546 -266.422889) (xy 380.990388 -266.449538)
			(xy 380.940774 -266.46901) (xy 380.888812 -266.48087) (xy 380.835662 -266.484854) (xy 380.782512 -266.48087)
			(xy 380.73055 -266.46901) (xy 380.680936 -266.449538) (xy 380.634778 -266.422889) (xy 380.593107 -266.389658)
			(xy 380.556855 -266.350587) (xy 380.526831 -266.30655) (xy 380.503705 -266.258529) (xy 380.487995 -266.207599)
			(xy 380.480052 -266.154895) (xy 380.251472 -266.154895) (xy 380.243529 -266.207599) (xy 380.227819 -266.258529)
			(xy 380.204693 -266.30655) (xy 380.174669 -266.350587) (xy 380.138417 -266.389658) (xy 380.096746 -266.422889)
			(xy 380.050588 -266.449538) (xy 380.000974 -266.46901) (xy 379.949012 -266.48087) (xy 379.895862 -266.484854)
			(xy 379.842712 -266.48087) (xy 379.79075 -266.46901) (xy 379.741136 -266.449538) (xy 379.694978 -266.422889)
			(xy 379.653307 -266.389658) (xy 379.617055 -266.350587) (xy 379.587031 -266.30655) (xy 379.563905 -266.258529)
			(xy 379.548195 -266.207599) (xy 379.540252 -266.154895) (xy 379.311672 -266.154895) (xy 379.303729 -266.207599)
			(xy 379.288019 -266.258529) (xy 379.264893 -266.30655) (xy 379.234869 -266.350587) (xy 379.198617 -266.389658)
			(xy 379.156946 -266.422889) (xy 379.110788 -266.449538) (xy 379.061174 -266.46901) (xy 379.009212 -266.48087)
			(xy 378.956062 -266.484854) (xy 378.902912 -266.48087) (xy 378.85095 -266.46901) (xy 378.801336 -266.449538)
			(xy 378.755178 -266.422889) (xy 378.713507 -266.389658) (xy 378.677255 -266.350587) (xy 378.647231 -266.30655)
			(xy 378.624105 -266.258529) (xy 378.608395 -266.207599) (xy 378.600452 -266.154895) (xy 378.371872 -266.154895)
			(xy 378.363929 -266.207599) (xy 378.348219 -266.258529) (xy 378.325093 -266.30655) (xy 378.295069 -266.350587)
			(xy 378.258817 -266.389658) (xy 378.217146 -266.422889) (xy 378.170988 -266.449538) (xy 378.121374 -266.46901)
			(xy 378.069412 -266.48087) (xy 378.016262 -266.484854) (xy 377.963112 -266.48087) (xy 377.91115 -266.46901)
			(xy 377.861536 -266.449538) (xy 377.815378 -266.422889) (xy 377.773707 -266.389658) (xy 377.737455 -266.350587)
			(xy 377.707431 -266.30655) (xy 377.684305 -266.258529) (xy 377.668595 -266.207599) (xy 377.660652 -266.154895)
			(xy 377.432072 -266.154895) (xy 377.424129 -266.207599) (xy 377.408419 -266.258529) (xy 377.385293 -266.30655)
			(xy 377.355269 -266.350587) (xy 377.319017 -266.389658) (xy 377.277346 -266.422889) (xy 377.231188 -266.449538)
			(xy 377.181574 -266.46901) (xy 377.129612 -266.48087) (xy 377.076462 -266.484854) (xy 377.023312 -266.48087)
			(xy 376.97135 -266.46901) (xy 376.921736 -266.449538) (xy 376.875578 -266.422889) (xy 376.833907 -266.389658)
			(xy 376.797655 -266.350587) (xy 376.767631 -266.30655) (xy 376.744505 -266.258529) (xy 376.728795 -266.207599)
			(xy 376.720852 -266.154895) (xy 376.492272 -266.154895) (xy 376.484329 -266.207599) (xy 376.468619 -266.258529)
			(xy 376.445493 -266.30655) (xy 376.415469 -266.350587) (xy 376.379217 -266.389658) (xy 376.337546 -266.422889)
			(xy 376.291388 -266.449538) (xy 376.241774 -266.46901) (xy 376.189812 -266.48087) (xy 376.136662 -266.484854)
			(xy 376.083512 -266.48087) (xy 376.03155 -266.46901) (xy 375.981936 -266.449538) (xy 375.935778 -266.422889)
			(xy 375.894107 -266.389658) (xy 375.857855 -266.350587) (xy 375.827831 -266.30655) (xy 375.804705 -266.258529)
			(xy 375.788995 -266.207599) (xy 375.781052 -266.154895) (xy 375.552472 -266.154895) (xy 375.544529 -266.207599)
			(xy 375.528819 -266.258529) (xy 375.505693 -266.30655) (xy 375.475669 -266.350587) (xy 375.439417 -266.389658)
			(xy 375.397746 -266.422889) (xy 375.351588 -266.449538) (xy 375.301974 -266.46901) (xy 375.250012 -266.48087)
			(xy 375.196862 -266.484854) (xy 375.143712 -266.48087) (xy 375.09175 -266.46901) (xy 375.042136 -266.449538)
			(xy 374.995978 -266.422889) (xy 374.954307 -266.389658) (xy 374.918055 -266.350587) (xy 374.888031 -266.30655)
			(xy 374.864905 -266.258529) (xy 374.849195 -266.207599) (xy 374.841252 -266.154895) (xy 374.612672 -266.154895)
			(xy 374.604729 -266.207599) (xy 374.589019 -266.258529) (xy 374.565893 -266.30655) (xy 374.535869 -266.350587)
			(xy 374.499617 -266.389658) (xy 374.457946 -266.422889) (xy 374.411788 -266.449538) (xy 374.362174 -266.46901)
			(xy 374.310212 -266.48087) (xy 374.257062 -266.484854) (xy 374.203912 -266.48087) (xy 374.15195 -266.46901)
			(xy 374.102336 -266.449538) (xy 374.056178 -266.422889) (xy 374.014507 -266.389658) (xy 373.978255 -266.350587)
			(xy 373.948231 -266.30655) (xy 373.925105 -266.258529) (xy 373.909395 -266.207599) (xy 373.901452 -266.154895)
			(xy 373.672872 -266.154895) (xy 373.664929 -266.207599) (xy 373.649219 -266.258529) (xy 373.626093 -266.30655)
			(xy 373.596069 -266.350587) (xy 373.559817 -266.389658) (xy 373.518146 -266.422889) (xy 373.471988 -266.449538)
			(xy 373.422374 -266.46901) (xy 373.370412 -266.48087) (xy 373.317262 -266.484854) (xy 373.264112 -266.48087)
			(xy 373.21215 -266.46901) (xy 373.162536 -266.449538) (xy 373.116378 -266.422889) (xy 373.074707 -266.389658)
			(xy 373.038455 -266.350587) (xy 373.008431 -266.30655) (xy 372.985305 -266.258529) (xy 372.969595 -266.207599)
			(xy 372.961652 -266.154895) (xy 372.733072 -266.154895) (xy 372.725129 -266.207599) (xy 372.709419 -266.258529)
			(xy 372.686293 -266.30655) (xy 372.656269 -266.350587) (xy 372.620017 -266.389658) (xy 372.578346 -266.422889)
			(xy 372.532188 -266.449538) (xy 372.482574 -266.46901) (xy 372.430612 -266.48087) (xy 372.377462 -266.484854)
			(xy 372.324312 -266.48087) (xy 372.27235 -266.46901) (xy 372.222736 -266.449538) (xy 372.176578 -266.422889)
			(xy 372.134907 -266.389658) (xy 372.098655 -266.350587) (xy 372.068631 -266.30655) (xy 372.045505 -266.258529)
			(xy 372.029795 -266.207599) (xy 372.021852 -266.154895) (xy 371.793272 -266.154895) (xy 371.785329 -266.207599)
			(xy 371.769619 -266.258529) (xy 371.746493 -266.30655) (xy 371.716469 -266.350587) (xy 371.680217 -266.389658)
			(xy 371.638546 -266.422889) (xy 371.592388 -266.449538) (xy 371.542774 -266.46901) (xy 371.490812 -266.48087)
			(xy 371.437662 -266.484854) (xy 371.384512 -266.48087) (xy 371.33255 -266.46901) (xy 371.282936 -266.449538)
			(xy 371.236778 -266.422889) (xy 371.195107 -266.389658) (xy 371.158855 -266.350587) (xy 371.128831 -266.30655)
			(xy 371.105705 -266.258529) (xy 371.089995 -266.207599) (xy 371.082052 -266.154895) (xy 370.853472 -266.154895)
			(xy 370.845529 -266.207599) (xy 370.829819 -266.258529) (xy 370.806693 -266.30655) (xy 370.776669 -266.350587)
			(xy 370.740417 -266.389658) (xy 370.698746 -266.422889) (xy 370.652588 -266.449538) (xy 370.602974 -266.46901)
			(xy 370.551012 -266.48087) (xy 370.497862 -266.484854) (xy 370.444712 -266.48087) (xy 370.39275 -266.46901)
			(xy 370.343136 -266.449538) (xy 370.296978 -266.422889) (xy 370.255307 -266.389658) (xy 370.219055 -266.350587)
			(xy 370.189031 -266.30655) (xy 370.165905 -266.258529) (xy 370.150195 -266.207599) (xy 370.142252 -266.154895)
			(xy 368.973872 -266.154895) (xy 368.965929 -266.207599) (xy 368.950219 -266.258529) (xy 368.927093 -266.30655)
			(xy 368.897069 -266.350587) (xy 368.860817 -266.389658) (xy 368.819146 -266.422889) (xy 368.772988 -266.449538)
			(xy 368.723374 -266.46901) (xy 368.671412 -266.48087) (xy 368.618262 -266.484854) (xy 368.565112 -266.48087)
			(xy 368.51315 -266.46901) (xy 368.463536 -266.449538) (xy 368.417378 -266.422889) (xy 368.375707 -266.389658)
			(xy 368.339455 -266.350587) (xy 368.309431 -266.30655) (xy 368.286305 -266.258529) (xy 368.270595 -266.207599)
			(xy 368.262652 -266.154895) (xy 368.033086 -266.154895) (xy 368.031103 -266.18135) (xy 368.019242 -266.233312)
			(xy 367.999768 -266.282927) (xy 367.973117 -266.329084) (xy 367.939884 -266.370753) (xy 367.900811 -266.407004)
			(xy 367.856771 -266.437025) (xy 367.808749 -266.460147) (xy 367.757816 -266.475853) (xy 367.705112 -266.483792)
			(xy 367.678462 -266.484354) (xy 367.649723 -266.483801) (xy 367.592991 -266.474562) (xy 367.53848 -266.45633)
			(xy 367.487606 -266.429578) (xy 367.441689 -266.395002) (xy 367.421414 -266.374626) (xy 367.411764 -266.365153)
			(xy 367.388602 -266.351215) (xy 367.362594 -266.343844) (xy 367.335564 -266.343556) (xy 367.309405 -266.350371)
			(xy 367.285951 -266.363812) (xy 367.276126 -266.373102) (xy 366.680771 -266.968457) (xy 369.672606 -266.968457)
			(xy 369.672606 -266.915159) (xy 369.680549 -266.862455) (xy 369.696259 -266.811525) (xy 369.719385 -266.763504)
			(xy 369.749409 -266.719467) (xy 369.785661 -266.680396) (xy 369.827332 -266.647165) (xy 369.87349 -266.620516)
			(xy 369.923104 -266.601044) (xy 369.975066 -266.589184) (xy 370.028216 -266.585201) (xy 370.081366 -266.589184)
			(xy 370.133328 -266.601044) (xy 370.182942 -266.620516) (xy 370.2291 -266.647165) (xy 370.270771 -266.680396)
			(xy 370.307023 -266.719467) (xy 370.337047 -266.763504) (xy 370.360173 -266.811525) (xy 370.375883 -266.862455)
			(xy 370.383826 -266.915159) (xy 370.384324 -266.941808) (xy 370.383826 -266.968457) (xy 370.612406 -266.968457)
			(xy 370.612406 -266.915159) (xy 370.620349 -266.862455) (xy 370.636059 -266.811525) (xy 370.659185 -266.763504)
			(xy 370.689209 -266.719467) (xy 370.725461 -266.680396) (xy 370.767132 -266.647165) (xy 370.81329 -266.620516)
			(xy 370.862904 -266.601044) (xy 370.914866 -266.589184) (xy 370.968016 -266.585201) (xy 371.021166 -266.589184)
			(xy 371.073128 -266.601044) (xy 371.122742 -266.620516) (xy 371.1689 -266.647165) (xy 371.210571 -266.680396)
			(xy 371.246823 -266.719467) (xy 371.276847 -266.763504) (xy 371.299973 -266.811525) (xy 371.315683 -266.862455)
			(xy 371.323626 -266.915159) (xy 371.324124 -266.941808) (xy 371.323626 -266.968457) (xy 371.552206 -266.968457)
			(xy 371.552206 -266.915159) (xy 371.560149 -266.862455) (xy 371.575859 -266.811525) (xy 371.598985 -266.763504)
			(xy 371.629009 -266.719467) (xy 371.665261 -266.680396) (xy 371.706932 -266.647165) (xy 371.75309 -266.620516)
			(xy 371.802704 -266.601044) (xy 371.854666 -266.589184) (xy 371.907816 -266.585201) (xy 371.960966 -266.589184)
			(xy 372.012928 -266.601044) (xy 372.062542 -266.620516) (xy 372.1087 -266.647165) (xy 372.150371 -266.680396)
			(xy 372.186623 -266.719467) (xy 372.216647 -266.763504) (xy 372.239773 -266.811525) (xy 372.255483 -266.862455)
			(xy 372.263426 -266.915159) (xy 372.263924 -266.941808) (xy 372.263426 -266.968457) (xy 372.492006 -266.968457)
			(xy 372.492006 -266.915159) (xy 372.499949 -266.862455) (xy 372.515659 -266.811525) (xy 372.538785 -266.763504)
			(xy 372.568809 -266.719467) (xy 372.605061 -266.680396) (xy 372.646732 -266.647165) (xy 372.69289 -266.620516)
			(xy 372.742504 -266.601044) (xy 372.794466 -266.589184) (xy 372.847616 -266.585201) (xy 372.900766 -266.589184)
			(xy 372.952728 -266.601044) (xy 373.002342 -266.620516) (xy 373.0485 -266.647165) (xy 373.090171 -266.680396)
			(xy 373.126423 -266.719467) (xy 373.156447 -266.763504) (xy 373.179573 -266.811525) (xy 373.195283 -266.862455)
			(xy 373.203226 -266.915159) (xy 373.203724 -266.941808) (xy 373.203226 -266.968457) (xy 373.431552 -266.968457)
			(xy 373.431552 -266.915159) (xy 373.439495 -266.862455) (xy 373.455205 -266.811525) (xy 373.478331 -266.763504)
			(xy 373.508355 -266.719467) (xy 373.544607 -266.680396) (xy 373.586278 -266.647165) (xy 373.632436 -266.620516)
			(xy 373.68205 -266.601044) (xy 373.734012 -266.589184) (xy 373.787162 -266.585201) (xy 373.840312 -266.589184)
			(xy 373.892274 -266.601044) (xy 373.941888 -266.620516) (xy 373.988046 -266.647165) (xy 374.029717 -266.680396)
			(xy 374.065969 -266.719467) (xy 374.095993 -266.763504) (xy 374.119119 -266.811525) (xy 374.134829 -266.862455)
			(xy 374.142772 -266.915159) (xy 374.14327 -266.941808) (xy 374.142772 -266.968457) (xy 374.371606 -266.968457)
			(xy 374.371606 -266.915159) (xy 374.379549 -266.862455) (xy 374.395259 -266.811525) (xy 374.418385 -266.763504)
			(xy 374.448409 -266.719467) (xy 374.484661 -266.680396) (xy 374.526332 -266.647165) (xy 374.57249 -266.620516)
			(xy 374.622104 -266.601044) (xy 374.674066 -266.589184) (xy 374.727216 -266.585201) (xy 374.780366 -266.589184)
			(xy 374.832328 -266.601044) (xy 374.881942 -266.620516) (xy 374.9281 -266.647165) (xy 374.969771 -266.680396)
			(xy 375.006023 -266.719467) (xy 375.036047 -266.763504) (xy 375.059173 -266.811525) (xy 375.074883 -266.862455)
			(xy 375.082826 -266.915159) (xy 375.083324 -266.941808) (xy 375.082826 -266.968457) (xy 375.311406 -266.968457)
			(xy 375.311406 -266.915159) (xy 375.319349 -266.862455) (xy 375.335059 -266.811525) (xy 375.358185 -266.763504)
			(xy 375.388209 -266.719467) (xy 375.424461 -266.680396) (xy 375.466132 -266.647165) (xy 375.51229 -266.620516)
			(xy 375.561904 -266.601044) (xy 375.613866 -266.589184) (xy 375.667016 -266.585201) (xy 375.720166 -266.589184)
			(xy 375.772128 -266.601044) (xy 375.821742 -266.620516) (xy 375.8679 -266.647165) (xy 375.909571 -266.680396)
			(xy 375.945823 -266.719467) (xy 375.975847 -266.763504) (xy 375.998973 -266.811525) (xy 376.014683 -266.862455)
			(xy 376.022626 -266.915159) (xy 376.023124 -266.941808) (xy 376.022626 -266.968457) (xy 376.251206 -266.968457)
			(xy 376.251206 -266.915159) (xy 376.259149 -266.862455) (xy 376.274859 -266.811525) (xy 376.297985 -266.763504)
			(xy 376.328009 -266.719467) (xy 376.364261 -266.680396) (xy 376.405932 -266.647165) (xy 376.45209 -266.620516)
			(xy 376.501704 -266.601044) (xy 376.553666 -266.589184) (xy 376.606816 -266.585201) (xy 376.659966 -266.589184)
			(xy 376.711928 -266.601044) (xy 376.761542 -266.620516) (xy 376.8077 -266.647165) (xy 376.849371 -266.680396)
			(xy 376.885623 -266.719467) (xy 376.915647 -266.763504) (xy 376.938773 -266.811525) (xy 376.954483 -266.862455)
			(xy 376.962426 -266.915159) (xy 376.962924 -266.941808) (xy 376.962426 -266.968457) (xy 377.191006 -266.968457)
			(xy 377.191006 -266.915159) (xy 377.198949 -266.862455) (xy 377.214659 -266.811525) (xy 377.237785 -266.763504)
			(xy 377.267809 -266.719467) (xy 377.304061 -266.680396) (xy 377.345732 -266.647165) (xy 377.39189 -266.620516)
			(xy 377.441504 -266.601044) (xy 377.493466 -266.589184) (xy 377.546616 -266.585201) (xy 377.599766 -266.589184)
			(xy 377.651728 -266.601044) (xy 377.701342 -266.620516) (xy 377.7475 -266.647165) (xy 377.789171 -266.680396)
			(xy 377.825423 -266.719467) (xy 377.855447 -266.763504) (xy 377.878573 -266.811525) (xy 377.894283 -266.862455)
			(xy 377.902226 -266.915159) (xy 377.902724 -266.941808) (xy 377.902226 -266.968457) (xy 378.130806 -266.968457)
			(xy 378.130806 -266.915159) (xy 378.138749 -266.862455) (xy 378.154459 -266.811525) (xy 378.177585 -266.763504)
			(xy 378.207609 -266.719467) (xy 378.243861 -266.680396) (xy 378.285532 -266.647165) (xy 378.33169 -266.620516)
			(xy 378.381304 -266.601044) (xy 378.433266 -266.589184) (xy 378.486416 -266.585201) (xy 378.539566 -266.589184)
			(xy 378.591528 -266.601044) (xy 378.641142 -266.620516) (xy 378.6873 -266.647165) (xy 378.728971 -266.680396)
			(xy 378.765223 -266.719467) (xy 378.795247 -266.763504) (xy 378.818373 -266.811525) (xy 378.834083 -266.862455)
			(xy 378.842026 -266.915159) (xy 378.842524 -266.941808) (xy 378.842026 -266.968457) (xy 379.070606 -266.968457)
			(xy 379.070606 -266.915159) (xy 379.078549 -266.862455) (xy 379.094259 -266.811525) (xy 379.117385 -266.763504)
			(xy 379.147409 -266.719467) (xy 379.183661 -266.680396) (xy 379.225332 -266.647165) (xy 379.27149 -266.620516)
			(xy 379.321104 -266.601044) (xy 379.373066 -266.589184) (xy 379.426216 -266.585201) (xy 379.479366 -266.589184)
			(xy 379.531328 -266.601044) (xy 379.580942 -266.620516) (xy 379.6271 -266.647165) (xy 379.668771 -266.680396)
			(xy 379.705023 -266.719467) (xy 379.735047 -266.763504) (xy 379.758173 -266.811525) (xy 379.773883 -266.862455)
			(xy 379.781826 -266.915159) (xy 379.782324 -266.941808) (xy 379.781826 -266.968457) (xy 380.010152 -266.968457)
			(xy 380.010152 -266.915159) (xy 380.018095 -266.862455) (xy 380.033805 -266.811525) (xy 380.056931 -266.763504)
			(xy 380.086955 -266.719467) (xy 380.123207 -266.680396) (xy 380.164878 -266.647165) (xy 380.211036 -266.620516)
			(xy 380.26065 -266.601044) (xy 380.312612 -266.589184) (xy 380.365762 -266.585201) (xy 380.418912 -266.589184)
			(xy 380.470874 -266.601044) (xy 380.520488 -266.620516) (xy 380.566646 -266.647165) (xy 380.608317 -266.680396)
			(xy 380.644569 -266.719467) (xy 380.674593 -266.763504) (xy 380.697719 -266.811525) (xy 380.713429 -266.862455)
			(xy 380.721372 -266.915159) (xy 380.72187 -266.941808) (xy 380.721372 -266.968457) (xy 380.949952 -266.968457)
			(xy 380.949952 -266.915159) (xy 380.957895 -266.862455) (xy 380.973605 -266.811525) (xy 380.996731 -266.763504)
			(xy 381.026755 -266.719467) (xy 381.063007 -266.680396) (xy 381.104678 -266.647165) (xy 381.150836 -266.620516)
			(xy 381.20045 -266.601044) (xy 381.252412 -266.589184) (xy 381.305562 -266.585201) (xy 381.358712 -266.589184)
			(xy 381.410674 -266.601044) (xy 381.460288 -266.620516) (xy 381.506446 -266.647165) (xy 381.548117 -266.680396)
			(xy 381.584369 -266.719467) (xy 381.614393 -266.763504) (xy 381.637519 -266.811525) (xy 381.653229 -266.862455)
			(xy 381.661172 -266.915159) (xy 381.66167 -266.941808) (xy 381.661172 -266.968457) (xy 381.653229 -267.021161)
			(xy 381.637519 -267.072091) (xy 381.614393 -267.120112) (xy 381.584369 -267.164149) (xy 381.548117 -267.20322)
			(xy 381.506446 -267.236451) (xy 381.460288 -267.2631) (xy 381.410674 -267.282572) (xy 381.358712 -267.294432)
			(xy 381.305562 -267.298416) (xy 381.252412 -267.294432) (xy 381.20045 -267.282572) (xy 381.150836 -267.2631)
			(xy 381.104678 -267.236451) (xy 381.063007 -267.20322) (xy 381.026755 -267.164149) (xy 380.996731 -267.120112)
			(xy 380.973605 -267.072091) (xy 380.957895 -267.021161) (xy 380.949952 -266.968457) (xy 380.721372 -266.968457)
			(xy 380.713429 -267.021161) (xy 380.697719 -267.072091) (xy 380.674593 -267.120112) (xy 380.644569 -267.164149)
			(xy 380.608317 -267.20322) (xy 380.566646 -267.236451) (xy 380.520488 -267.2631) (xy 380.470874 -267.282572)
			(xy 380.418912 -267.294432) (xy 380.365762 -267.298416) (xy 380.312612 -267.294432) (xy 380.26065 -267.282572)
			(xy 380.211036 -267.2631) (xy 380.164878 -267.236451) (xy 380.123207 -267.20322) (xy 380.086955 -267.164149)
			(xy 380.056931 -267.120112) (xy 380.033805 -267.072091) (xy 380.018095 -267.021161) (xy 380.010152 -266.968457)
			(xy 379.781826 -266.968457) (xy 379.773883 -267.021161) (xy 379.758173 -267.072091) (xy 379.735047 -267.120112)
			(xy 379.705023 -267.164149) (xy 379.668771 -267.20322) (xy 379.6271 -267.236451) (xy 379.580942 -267.2631)
			(xy 379.531328 -267.282572) (xy 379.479366 -267.294432) (xy 379.426216 -267.298416) (xy 379.373066 -267.294432)
			(xy 379.321104 -267.282572) (xy 379.27149 -267.2631) (xy 379.225332 -267.236451) (xy 379.183661 -267.20322)
			(xy 379.147409 -267.164149) (xy 379.117385 -267.120112) (xy 379.094259 -267.072091) (xy 379.078549 -267.021161)
			(xy 379.070606 -266.968457) (xy 378.842026 -266.968457) (xy 378.834083 -267.021161) (xy 378.818373 -267.072091)
			(xy 378.795247 -267.120112) (xy 378.765223 -267.164149) (xy 378.728971 -267.20322) (xy 378.6873 -267.236451)
			(xy 378.641142 -267.2631) (xy 378.591528 -267.282572) (xy 378.539566 -267.294432) (xy 378.486416 -267.298416)
			(xy 378.433266 -267.294432) (xy 378.381304 -267.282572) (xy 378.33169 -267.2631) (xy 378.285532 -267.236451)
			(xy 378.243861 -267.20322) (xy 378.207609 -267.164149) (xy 378.177585 -267.120112) (xy 378.154459 -267.072091)
			(xy 378.138749 -267.021161) (xy 378.130806 -266.968457) (xy 377.902226 -266.968457) (xy 377.894283 -267.021161)
			(xy 377.878573 -267.072091) (xy 377.855447 -267.120112) (xy 377.825423 -267.164149) (xy 377.789171 -267.20322)
			(xy 377.7475 -267.236451) (xy 377.701342 -267.2631) (xy 377.651728 -267.282572) (xy 377.599766 -267.294432)
			(xy 377.546616 -267.298416) (xy 377.493466 -267.294432) (xy 377.441504 -267.282572) (xy 377.39189 -267.2631)
			(xy 377.345732 -267.236451) (xy 377.304061 -267.20322) (xy 377.267809 -267.164149) (xy 377.237785 -267.120112)
			(xy 377.214659 -267.072091) (xy 377.198949 -267.021161) (xy 377.191006 -266.968457) (xy 376.962426 -266.968457)
			(xy 376.954483 -267.021161) (xy 376.938773 -267.072091) (xy 376.915647 -267.120112) (xy 376.885623 -267.164149)
			(xy 376.849371 -267.20322) (xy 376.8077 -267.236451) (xy 376.761542 -267.2631) (xy 376.711928 -267.282572)
			(xy 376.659966 -267.294432) (xy 376.606816 -267.298416) (xy 376.553666 -267.294432) (xy 376.501704 -267.282572)
			(xy 376.45209 -267.2631) (xy 376.405932 -267.236451) (xy 376.364261 -267.20322) (xy 376.328009 -267.164149)
			(xy 376.297985 -267.120112) (xy 376.274859 -267.072091) (xy 376.259149 -267.021161) (xy 376.251206 -266.968457)
			(xy 376.022626 -266.968457) (xy 376.014683 -267.021161) (xy 375.998973 -267.072091) (xy 375.975847 -267.120112)
			(xy 375.945823 -267.164149) (xy 375.909571 -267.20322) (xy 375.8679 -267.236451) (xy 375.821742 -267.2631)
			(xy 375.772128 -267.282572) (xy 375.720166 -267.294432) (xy 375.667016 -267.298416) (xy 375.613866 -267.294432)
			(xy 375.561904 -267.282572) (xy 375.51229 -267.2631) (xy 375.466132 -267.236451) (xy 375.424461 -267.20322)
			(xy 375.388209 -267.164149) (xy 375.358185 -267.120112) (xy 375.335059 -267.072091) (xy 375.319349 -267.021161)
			(xy 375.311406 -266.968457) (xy 375.082826 -266.968457) (xy 375.074883 -267.021161) (xy 375.059173 -267.072091)
			(xy 375.036047 -267.120112) (xy 375.006023 -267.164149) (xy 374.969771 -267.20322) (xy 374.9281 -267.236451)
			(xy 374.881942 -267.2631) (xy 374.832328 -267.282572) (xy 374.780366 -267.294432) (xy 374.727216 -267.298416)
			(xy 374.674066 -267.294432) (xy 374.622104 -267.282572) (xy 374.57249 -267.2631) (xy 374.526332 -267.236451)
			(xy 374.484661 -267.20322) (xy 374.448409 -267.164149) (xy 374.418385 -267.120112) (xy 374.395259 -267.072091)
			(xy 374.379549 -267.021161) (xy 374.371606 -266.968457) (xy 374.142772 -266.968457) (xy 374.134829 -267.021161)
			(xy 374.119119 -267.072091) (xy 374.095993 -267.120112) (xy 374.065969 -267.164149) (xy 374.029717 -267.20322)
			(xy 373.988046 -267.236451) (xy 373.941888 -267.2631) (xy 373.892274 -267.282572) (xy 373.840312 -267.294432)
			(xy 373.787162 -267.298416) (xy 373.734012 -267.294432) (xy 373.68205 -267.282572) (xy 373.632436 -267.2631)
			(xy 373.586278 -267.236451) (xy 373.544607 -267.20322) (xy 373.508355 -267.164149) (xy 373.478331 -267.120112)
			(xy 373.455205 -267.072091) (xy 373.439495 -267.021161) (xy 373.431552 -266.968457) (xy 373.203226 -266.968457)
			(xy 373.195283 -267.021161) (xy 373.179573 -267.072091) (xy 373.156447 -267.120112) (xy 373.126423 -267.164149)
			(xy 373.090171 -267.20322) (xy 373.0485 -267.236451) (xy 373.002342 -267.2631) (xy 372.952728 -267.282572)
			(xy 372.900766 -267.294432) (xy 372.847616 -267.298416) (xy 372.794466 -267.294432) (xy 372.742504 -267.282572)
			(xy 372.69289 -267.2631) (xy 372.646732 -267.236451) (xy 372.605061 -267.20322) (xy 372.568809 -267.164149)
			(xy 372.538785 -267.120112) (xy 372.515659 -267.072091) (xy 372.499949 -267.021161) (xy 372.492006 -266.968457)
			(xy 372.263426 -266.968457) (xy 372.255483 -267.021161) (xy 372.239773 -267.072091) (xy 372.216647 -267.120112)
			(xy 372.186623 -267.164149) (xy 372.150371 -267.20322) (xy 372.1087 -267.236451) (xy 372.062542 -267.2631)
			(xy 372.012928 -267.282572) (xy 371.960966 -267.294432) (xy 371.907816 -267.298416) (xy 371.854666 -267.294432)
			(xy 371.802704 -267.282572) (xy 371.75309 -267.2631) (xy 371.706932 -267.236451) (xy 371.665261 -267.20322)
			(xy 371.629009 -267.164149) (xy 371.598985 -267.120112) (xy 371.575859 -267.072091) (xy 371.560149 -267.021161)
			(xy 371.552206 -266.968457) (xy 371.323626 -266.968457) (xy 371.315683 -267.021161) (xy 371.299973 -267.072091)
			(xy 371.276847 -267.120112) (xy 371.246823 -267.164149) (xy 371.210571 -267.20322) (xy 371.1689 -267.236451)
			(xy 371.122742 -267.2631) (xy 371.073128 -267.282572) (xy 371.021166 -267.294432) (xy 370.968016 -267.298416)
			(xy 370.914866 -267.294432) (xy 370.862904 -267.282572) (xy 370.81329 -267.2631) (xy 370.767132 -267.236451)
			(xy 370.725461 -267.20322) (xy 370.689209 -267.164149) (xy 370.659185 -267.120112) (xy 370.636059 -267.072091)
			(xy 370.620349 -267.021161) (xy 370.612406 -266.968457) (xy 370.383826 -266.968457) (xy 370.375883 -267.021161)
			(xy 370.360173 -267.072091) (xy 370.337047 -267.120112) (xy 370.307023 -267.164149) (xy 370.270771 -267.20322)
			(xy 370.2291 -267.236451) (xy 370.182942 -267.2631) (xy 370.133328 -267.282572) (xy 370.081366 -267.294432)
			(xy 370.028216 -267.298416) (xy 369.975066 -267.294432) (xy 369.923104 -267.282572) (xy 369.87349 -267.2631)
			(xy 369.827332 -267.236451) (xy 369.785661 -267.20322) (xy 369.749409 -267.164149) (xy 369.719385 -267.120112)
			(xy 369.696259 -267.072091) (xy 369.680549 -267.021161) (xy 369.672606 -266.968457) (xy 366.680771 -266.968457)
			(xy 366.611662 -267.037566) (xy 366.608106 -267.04925) (xy 366.598941 -267.076326) (xy 366.573211 -267.127365)
			(xy 366.539659 -267.173639) (xy 366.499146 -267.21396) (xy 366.47628 -267.231114) (xy 366.47628 -267.782527)
			(xy 367.322852 -267.782527) (xy 367.322852 -267.729229) (xy 367.330795 -267.676525) (xy 367.346505 -267.625595)
			(xy 367.369631 -267.577574) (xy 367.399655 -267.533537) (xy 367.435907 -267.494466) (xy 367.477578 -267.461235)
			(xy 367.523736 -267.434586) (xy 367.57335 -267.415114) (xy 367.625312 -267.403254) (xy 367.678462 -267.399271)
			(xy 367.731612 -267.403254) (xy 367.783574 -267.415114) (xy 367.833188 -267.434586) (xy 367.879346 -267.461235)
			(xy 367.921017 -267.494466) (xy 367.957269 -267.533537) (xy 367.987293 -267.577574) (xy 368.010419 -267.625595)
			(xy 368.026129 -267.676525) (xy 368.034072 -267.729229) (xy 368.03457 -267.755878) (xy 368.034072 -267.782527)
			(xy 371.082052 -267.782527) (xy 371.082052 -267.729229) (xy 371.089995 -267.676525) (xy 371.105705 -267.625595)
			(xy 371.128831 -267.577574) (xy 371.158855 -267.533537) (xy 371.195107 -267.494466) (xy 371.236778 -267.461235)
			(xy 371.282936 -267.434586) (xy 371.33255 -267.415114) (xy 371.384512 -267.403254) (xy 371.437662 -267.399271)
			(xy 371.490812 -267.403254) (xy 371.542774 -267.415114) (xy 371.592388 -267.434586) (xy 371.638546 -267.461235)
			(xy 371.680217 -267.494466) (xy 371.716469 -267.533537) (xy 371.746493 -267.577574) (xy 371.769619 -267.625595)
			(xy 371.785329 -267.676525) (xy 371.793272 -267.729229) (xy 371.79377 -267.755878) (xy 371.793272 -267.782527)
			(xy 372.021852 -267.782527) (xy 372.021852 -267.729229) (xy 372.029795 -267.676525) (xy 372.045505 -267.625595)
			(xy 372.068631 -267.577574) (xy 372.098655 -267.533537) (xy 372.134907 -267.494466) (xy 372.176578 -267.461235)
			(xy 372.222736 -267.434586) (xy 372.27235 -267.415114) (xy 372.324312 -267.403254) (xy 372.377462 -267.399271)
			(xy 372.430612 -267.403254) (xy 372.482574 -267.415114) (xy 372.532188 -267.434586) (xy 372.578346 -267.461235)
			(xy 372.620017 -267.494466) (xy 372.656269 -267.533537) (xy 372.686293 -267.577574) (xy 372.709419 -267.625595)
			(xy 372.725129 -267.676525) (xy 372.733072 -267.729229) (xy 372.73357 -267.755878) (xy 372.733072 -267.782527)
			(xy 372.961652 -267.782527) (xy 372.961652 -267.729229) (xy 372.969595 -267.676525) (xy 372.985305 -267.625595)
			(xy 373.008431 -267.577574) (xy 373.038455 -267.533537) (xy 373.074707 -267.494466) (xy 373.116378 -267.461235)
			(xy 373.162536 -267.434586) (xy 373.21215 -267.415114) (xy 373.264112 -267.403254) (xy 373.317262 -267.399271)
			(xy 373.370412 -267.403254) (xy 373.422374 -267.415114) (xy 373.471988 -267.434586) (xy 373.518146 -267.461235)
			(xy 373.559817 -267.494466) (xy 373.596069 -267.533537) (xy 373.626093 -267.577574) (xy 373.649219 -267.625595)
			(xy 373.664929 -267.676525) (xy 373.672872 -267.729229) (xy 373.67337 -267.755878) (xy 373.672872 -267.782527)
			(xy 373.901452 -267.782527) (xy 373.901452 -267.729229) (xy 373.909395 -267.676525) (xy 373.925105 -267.625595)
			(xy 373.948231 -267.577574) (xy 373.978255 -267.533537) (xy 374.014507 -267.494466) (xy 374.056178 -267.461235)
			(xy 374.102336 -267.434586) (xy 374.15195 -267.415114) (xy 374.203912 -267.403254) (xy 374.257062 -267.399271)
			(xy 374.310212 -267.403254) (xy 374.362174 -267.415114) (xy 374.411788 -267.434586) (xy 374.457946 -267.461235)
			(xy 374.499617 -267.494466) (xy 374.535869 -267.533537) (xy 374.565893 -267.577574) (xy 374.589019 -267.625595)
			(xy 374.604729 -267.676525) (xy 374.612672 -267.729229) (xy 374.61317 -267.755878) (xy 374.612672 -267.782527)
			(xy 374.841252 -267.782527) (xy 374.841252 -267.729229) (xy 374.849195 -267.676525) (xy 374.864905 -267.625595)
			(xy 374.888031 -267.577574) (xy 374.918055 -267.533537) (xy 374.954307 -267.494466) (xy 374.995978 -267.461235)
			(xy 375.042136 -267.434586) (xy 375.09175 -267.415114) (xy 375.143712 -267.403254) (xy 375.196862 -267.399271)
			(xy 375.250012 -267.403254) (xy 375.301974 -267.415114) (xy 375.351588 -267.434586) (xy 375.397746 -267.461235)
			(xy 375.439417 -267.494466) (xy 375.475669 -267.533537) (xy 375.505693 -267.577574) (xy 375.528819 -267.625595)
			(xy 375.544529 -267.676525) (xy 375.552472 -267.729229) (xy 375.55297 -267.755878) (xy 375.552472 -267.782527)
			(xy 375.781052 -267.782527) (xy 375.781052 -267.729229) (xy 375.788995 -267.676525) (xy 375.804705 -267.625595)
			(xy 375.827831 -267.577574) (xy 375.857855 -267.533537) (xy 375.894107 -267.494466) (xy 375.935778 -267.461235)
			(xy 375.981936 -267.434586) (xy 376.03155 -267.415114) (xy 376.083512 -267.403254) (xy 376.136662 -267.399271)
			(xy 376.189812 -267.403254) (xy 376.241774 -267.415114) (xy 376.291388 -267.434586) (xy 376.337546 -267.461235)
			(xy 376.379217 -267.494466) (xy 376.415469 -267.533537) (xy 376.445493 -267.577574) (xy 376.468619 -267.625595)
			(xy 376.484329 -267.676525) (xy 376.492272 -267.729229) (xy 376.49277 -267.755878) (xy 376.492272 -267.782527)
			(xy 376.720852 -267.782527) (xy 376.720852 -267.729229) (xy 376.728795 -267.676525) (xy 376.744505 -267.625595)
			(xy 376.767631 -267.577574) (xy 376.797655 -267.533537) (xy 376.833907 -267.494466) (xy 376.875578 -267.461235)
			(xy 376.921736 -267.434586) (xy 376.97135 -267.415114) (xy 377.023312 -267.403254) (xy 377.076462 -267.399271)
			(xy 377.129612 -267.403254) (xy 377.181574 -267.415114) (xy 377.231188 -267.434586) (xy 377.277346 -267.461235)
			(xy 377.319017 -267.494466) (xy 377.355269 -267.533537) (xy 377.385293 -267.577574) (xy 377.408419 -267.625595)
			(xy 377.424129 -267.676525) (xy 377.432072 -267.729229) (xy 377.43257 -267.755878) (xy 377.432072 -267.782527)
			(xy 377.660652 -267.782527) (xy 377.660652 -267.729229) (xy 377.668595 -267.676525) (xy 377.684305 -267.625595)
			(xy 377.707431 -267.577574) (xy 377.737455 -267.533537) (xy 377.773707 -267.494466) (xy 377.815378 -267.461235)
			(xy 377.861536 -267.434586) (xy 377.91115 -267.415114) (xy 377.963112 -267.403254) (xy 378.016262 -267.399271)
			(xy 378.069412 -267.403254) (xy 378.121374 -267.415114) (xy 378.170988 -267.434586) (xy 378.217146 -267.461235)
			(xy 378.258817 -267.494466) (xy 378.295069 -267.533537) (xy 378.325093 -267.577574) (xy 378.348219 -267.625595)
			(xy 378.363929 -267.676525) (xy 378.371872 -267.729229) (xy 378.37237 -267.755878) (xy 378.371872 -267.782527)
			(xy 378.600452 -267.782527) (xy 378.600452 -267.729229) (xy 378.608395 -267.676525) (xy 378.624105 -267.625595)
			(xy 378.647231 -267.577574) (xy 378.677255 -267.533537) (xy 378.713507 -267.494466) (xy 378.755178 -267.461235)
			(xy 378.801336 -267.434586) (xy 378.85095 -267.415114) (xy 378.902912 -267.403254) (xy 378.956062 -267.399271)
			(xy 379.009212 -267.403254) (xy 379.061174 -267.415114) (xy 379.110788 -267.434586) (xy 379.156946 -267.461235)
			(xy 379.198617 -267.494466) (xy 379.234869 -267.533537) (xy 379.264893 -267.577574) (xy 379.288019 -267.625595)
			(xy 379.303729 -267.676525) (xy 379.311672 -267.729229) (xy 379.31217 -267.755878) (xy 379.311672 -267.782527)
			(xy 379.540506 -267.782527) (xy 379.540506 -267.729229) (xy 379.548449 -267.676525) (xy 379.564159 -267.625595)
			(xy 379.587285 -267.577574) (xy 379.617309 -267.533537) (xy 379.653561 -267.494466) (xy 379.695232 -267.461235)
			(xy 379.74139 -267.434586) (xy 379.791004 -267.415114) (xy 379.842966 -267.403254) (xy 379.896116 -267.399271)
			(xy 379.949266 -267.403254) (xy 380.001228 -267.415114) (xy 380.050842 -267.434586) (xy 380.097 -267.461235)
			(xy 380.138671 -267.494466) (xy 380.174923 -267.533537) (xy 380.204947 -267.577574) (xy 380.228073 -267.625595)
			(xy 380.243783 -267.676525) (xy 380.251726 -267.729229) (xy 380.252224 -267.755878) (xy 380.251726 -267.782527)
			(xy 380.480052 -267.782527) (xy 380.480052 -267.729229) (xy 380.487995 -267.676525) (xy 380.503705 -267.625595)
			(xy 380.526831 -267.577574) (xy 380.556855 -267.533537) (xy 380.593107 -267.494466) (xy 380.634778 -267.461235)
			(xy 380.680936 -267.434586) (xy 380.73055 -267.415114) (xy 380.782512 -267.403254) (xy 380.835662 -267.399271)
			(xy 380.888812 -267.403254) (xy 380.940774 -267.415114) (xy 380.990388 -267.434586) (xy 381.036546 -267.461235)
			(xy 381.078217 -267.494466) (xy 381.114469 -267.533537) (xy 381.144493 -267.577574) (xy 381.167619 -267.625595)
			(xy 381.183329 -267.676525) (xy 381.191272 -267.729229) (xy 381.19177 -267.755878) (xy 381.191272 -267.782527)
			(xy 381.183329 -267.835231) (xy 381.167619 -267.886161) (xy 381.144493 -267.934182) (xy 381.114469 -267.978219)
			(xy 381.078217 -268.01729) (xy 381.036546 -268.050521) (xy 380.990388 -268.07717) (xy 380.940774 -268.096642)
			(xy 380.888812 -268.108502) (xy 380.835662 -268.112486) (xy 380.782512 -268.108502) (xy 380.73055 -268.096642)
			(xy 380.680936 -268.07717) (xy 380.634778 -268.050521) (xy 380.593107 -268.01729) (xy 380.556855 -267.978219)
			(xy 380.526831 -267.934182) (xy 380.503705 -267.886161) (xy 380.487995 -267.835231) (xy 380.480052 -267.782527)
			(xy 380.251726 -267.782527) (xy 380.243783 -267.835231) (xy 380.228073 -267.886161) (xy 380.204947 -267.934182)
			(xy 380.174923 -267.978219) (xy 380.138671 -268.01729) (xy 380.097 -268.050521) (xy 380.050842 -268.07717)
			(xy 380.001228 -268.096642) (xy 379.949266 -268.108502) (xy 379.896116 -268.112486) (xy 379.842966 -268.108502)
			(xy 379.791004 -268.096642) (xy 379.74139 -268.07717) (xy 379.695232 -268.050521) (xy 379.653561 -268.01729)
			(xy 379.617309 -267.978219) (xy 379.587285 -267.934182) (xy 379.564159 -267.886161) (xy 379.548449 -267.835231)
			(xy 379.540506 -267.782527) (xy 379.311672 -267.782527) (xy 379.303729 -267.835231) (xy 379.288019 -267.886161)
			(xy 379.264893 -267.934182) (xy 379.234869 -267.978219) (xy 379.198617 -268.01729) (xy 379.156946 -268.050521)
			(xy 379.110788 -268.07717) (xy 379.061174 -268.096642) (xy 379.009212 -268.108502) (xy 378.956062 -268.112486)
			(xy 378.902912 -268.108502) (xy 378.85095 -268.096642) (xy 378.801336 -268.07717) (xy 378.755178 -268.050521)
			(xy 378.713507 -268.01729) (xy 378.677255 -267.978219) (xy 378.647231 -267.934182) (xy 378.624105 -267.886161)
			(xy 378.608395 -267.835231) (xy 378.600452 -267.782527) (xy 378.371872 -267.782527) (xy 378.363929 -267.835231)
			(xy 378.348219 -267.886161) (xy 378.325093 -267.934182) (xy 378.295069 -267.978219) (xy 378.258817 -268.01729)
			(xy 378.217146 -268.050521) (xy 378.170988 -268.07717) (xy 378.121374 -268.096642) (xy 378.069412 -268.108502)
			(xy 378.016262 -268.112486) (xy 377.963112 -268.108502) (xy 377.91115 -268.096642) (xy 377.861536 -268.07717)
			(xy 377.815378 -268.050521) (xy 377.773707 -268.01729) (xy 377.737455 -267.978219) (xy 377.707431 -267.934182)
			(xy 377.684305 -267.886161) (xy 377.668595 -267.835231) (xy 377.660652 -267.782527) (xy 377.432072 -267.782527)
			(xy 377.424129 -267.835231) (xy 377.408419 -267.886161) (xy 377.385293 -267.934182) (xy 377.355269 -267.978219)
			(xy 377.319017 -268.01729) (xy 377.277346 -268.050521) (xy 377.231188 -268.07717) (xy 377.181574 -268.096642)
			(xy 377.129612 -268.108502) (xy 377.076462 -268.112486) (xy 377.023312 -268.108502) (xy 376.97135 -268.096642)
			(xy 376.921736 -268.07717) (xy 376.875578 -268.050521) (xy 376.833907 -268.01729) (xy 376.797655 -267.978219)
			(xy 376.767631 -267.934182) (xy 376.744505 -267.886161) (xy 376.728795 -267.835231) (xy 376.720852 -267.782527)
			(xy 376.492272 -267.782527) (xy 376.484329 -267.835231) (xy 376.468619 -267.886161) (xy 376.445493 -267.934182)
			(xy 376.415469 -267.978219) (xy 376.379217 -268.01729) (xy 376.337546 -268.050521) (xy 376.291388 -268.07717)
			(xy 376.241774 -268.096642) (xy 376.189812 -268.108502) (xy 376.136662 -268.112486) (xy 376.083512 -268.108502)
			(xy 376.03155 -268.096642) (xy 375.981936 -268.07717) (xy 375.935778 -268.050521) (xy 375.894107 -268.01729)
			(xy 375.857855 -267.978219) (xy 375.827831 -267.934182) (xy 375.804705 -267.886161) (xy 375.788995 -267.835231)
			(xy 375.781052 -267.782527) (xy 375.552472 -267.782527) (xy 375.544529 -267.835231) (xy 375.528819 -267.886161)
			(xy 375.505693 -267.934182) (xy 375.475669 -267.978219) (xy 375.439417 -268.01729) (xy 375.397746 -268.050521)
			(xy 375.351588 -268.07717) (xy 375.301974 -268.096642) (xy 375.250012 -268.108502) (xy 375.196862 -268.112486)
			(xy 375.143712 -268.108502) (xy 375.09175 -268.096642) (xy 375.042136 -268.07717) (xy 374.995978 -268.050521)
			(xy 374.954307 -268.01729) (xy 374.918055 -267.978219) (xy 374.888031 -267.934182) (xy 374.864905 -267.886161)
			(xy 374.849195 -267.835231) (xy 374.841252 -267.782527) (xy 374.612672 -267.782527) (xy 374.604729 -267.835231)
			(xy 374.589019 -267.886161) (xy 374.565893 -267.934182) (xy 374.535869 -267.978219) (xy 374.499617 -268.01729)
			(xy 374.457946 -268.050521) (xy 374.411788 -268.07717) (xy 374.362174 -268.096642) (xy 374.310212 -268.108502)
			(xy 374.257062 -268.112486) (xy 374.203912 -268.108502) (xy 374.15195 -268.096642) (xy 374.102336 -268.07717)
			(xy 374.056178 -268.050521) (xy 374.014507 -268.01729) (xy 373.978255 -267.978219) (xy 373.948231 -267.934182)
			(xy 373.925105 -267.886161) (xy 373.909395 -267.835231) (xy 373.901452 -267.782527) (xy 373.672872 -267.782527)
			(xy 373.664929 -267.835231) (xy 373.649219 -267.886161) (xy 373.626093 -267.934182) (xy 373.596069 -267.978219)
			(xy 373.559817 -268.01729) (xy 373.518146 -268.050521) (xy 373.471988 -268.07717) (xy 373.422374 -268.096642)
			(xy 373.370412 -268.108502) (xy 373.317262 -268.112486) (xy 373.264112 -268.108502) (xy 373.21215 -268.096642)
			(xy 373.162536 -268.07717) (xy 373.116378 -268.050521) (xy 373.074707 -268.01729) (xy 373.038455 -267.978219)
			(xy 373.008431 -267.934182) (xy 372.985305 -267.886161) (xy 372.969595 -267.835231) (xy 372.961652 -267.782527)
			(xy 372.733072 -267.782527) (xy 372.725129 -267.835231) (xy 372.709419 -267.886161) (xy 372.686293 -267.934182)
			(xy 372.656269 -267.978219) (xy 372.620017 -268.01729) (xy 372.578346 -268.050521) (xy 372.532188 -268.07717)
			(xy 372.482574 -268.096642) (xy 372.430612 -268.108502) (xy 372.377462 -268.112486) (xy 372.324312 -268.108502)
			(xy 372.27235 -268.096642) (xy 372.222736 -268.07717) (xy 372.176578 -268.050521) (xy 372.134907 -268.01729)
			(xy 372.098655 -267.978219) (xy 372.068631 -267.934182) (xy 372.045505 -267.886161) (xy 372.029795 -267.835231)
			(xy 372.021852 -267.782527) (xy 371.793272 -267.782527) (xy 371.785329 -267.835231) (xy 371.769619 -267.886161)
			(xy 371.746493 -267.934182) (xy 371.716469 -267.978219) (xy 371.680217 -268.01729) (xy 371.638546 -268.050521)
			(xy 371.592388 -268.07717) (xy 371.542774 -268.096642) (xy 371.490812 -268.108502) (xy 371.437662 -268.112486)
			(xy 371.384512 -268.108502) (xy 371.33255 -268.096642) (xy 371.282936 -268.07717) (xy 371.236778 -268.050521)
			(xy 371.195107 -268.01729) (xy 371.158855 -267.978219) (xy 371.128831 -267.934182) (xy 371.105705 -267.886161)
			(xy 371.089995 -267.835231) (xy 371.082052 -267.782527) (xy 368.034072 -267.782527) (xy 368.026129 -267.835231)
			(xy 368.010419 -267.886161) (xy 367.987293 -267.934182) (xy 367.957269 -267.978219) (xy 367.921017 -268.01729)
			(xy 367.879346 -268.050521) (xy 367.833188 -268.07717) (xy 367.783574 -268.096642) (xy 367.731612 -268.108502)
			(xy 367.678462 -268.112486) (xy 367.625312 -268.108502) (xy 367.57335 -268.096642) (xy 367.523736 -268.07717)
			(xy 367.477578 -268.050521) (xy 367.435907 -268.01729) (xy 367.399655 -267.978219) (xy 367.369631 -267.934182)
			(xy 367.346505 -267.886161) (xy 367.330795 -267.835231) (xy 367.322852 -267.782527) (xy 366.47628 -267.782527)
			(xy 366.47628 -268.280134) (xy 366.497163 -268.295666) (xy 366.534622 -268.331796) (xy 366.566422 -268.372994)
			(xy 366.591887 -268.418382) (xy 366.610474 -268.466993) (xy 366.621787 -268.517792) (xy 366.625585 -268.569697)
			(xy 366.623636 -268.596343) (xy 370.612152 -268.596343) (xy 370.612152 -268.543045) (xy 370.620095 -268.490341)
			(xy 370.635805 -268.439411) (xy 370.658931 -268.39139) (xy 370.688955 -268.347353) (xy 370.725207 -268.308282)
			(xy 370.766878 -268.275051) (xy 370.813036 -268.248402) (xy 370.86265 -268.22893) (xy 370.914612 -268.21707)
			(xy 370.967762 -268.213087) (xy 371.020912 -268.21707) (xy 371.072874 -268.22893) (xy 371.122488 -268.248402)
			(xy 371.168646 -268.275051) (xy 371.210317 -268.308282) (xy 371.246569 -268.347353) (xy 371.276593 -268.39139)
			(xy 371.299719 -268.439411) (xy 371.315429 -268.490341) (xy 371.323372 -268.543045) (xy 371.32387 -268.569694)
			(xy 371.323372 -268.596343) (xy 371.552206 -268.596343) (xy 371.552206 -268.543045) (xy 371.560149 -268.490341)
			(xy 371.575859 -268.439411) (xy 371.598985 -268.39139) (xy 371.629009 -268.347353) (xy 371.665261 -268.308282)
			(xy 371.706932 -268.275051) (xy 371.75309 -268.248402) (xy 371.802704 -268.22893) (xy 371.854666 -268.21707)
			(xy 371.907816 -268.213087) (xy 371.960966 -268.21707) (xy 372.012928 -268.22893) (xy 372.062542 -268.248402)
			(xy 372.1087 -268.275051) (xy 372.150371 -268.308282) (xy 372.186623 -268.347353) (xy 372.216647 -268.39139)
			(xy 372.239773 -268.439411) (xy 372.255483 -268.490341) (xy 372.263426 -268.543045) (xy 372.263924 -268.569694)
			(xy 372.263426 -268.596343) (xy 372.492006 -268.596343) (xy 372.492006 -268.543045) (xy 372.499949 -268.490341)
			(xy 372.515659 -268.439411) (xy 372.538785 -268.39139) (xy 372.568809 -268.347353) (xy 372.605061 -268.308282)
			(xy 372.646732 -268.275051) (xy 372.69289 -268.248402) (xy 372.742504 -268.22893) (xy 372.794466 -268.21707)
			(xy 372.847616 -268.213087) (xy 372.900766 -268.21707) (xy 372.952728 -268.22893) (xy 373.002342 -268.248402)
			(xy 373.0485 -268.275051) (xy 373.090171 -268.308282) (xy 373.126423 -268.347353) (xy 373.156447 -268.39139)
			(xy 373.179573 -268.439411) (xy 373.195283 -268.490341) (xy 373.203226 -268.543045) (xy 373.203724 -268.569694)
			(xy 373.203226 -268.596343) (xy 373.431806 -268.596343) (xy 373.431806 -268.543045) (xy 373.439749 -268.490341)
			(xy 373.455459 -268.439411) (xy 373.478585 -268.39139) (xy 373.508609 -268.347353) (xy 373.544861 -268.308282)
			(xy 373.586532 -268.275051) (xy 373.63269 -268.248402) (xy 373.682304 -268.22893) (xy 373.734266 -268.21707)
			(xy 373.787416 -268.213087) (xy 373.840566 -268.21707) (xy 373.892528 -268.22893) (xy 373.942142 -268.248402)
			(xy 373.9883 -268.275051) (xy 374.029971 -268.308282) (xy 374.066223 -268.347353) (xy 374.096247 -268.39139)
			(xy 374.119373 -268.439411) (xy 374.135083 -268.490341) (xy 374.143026 -268.543045) (xy 374.143524 -268.569694)
			(xy 374.143026 -268.596343) (xy 374.371606 -268.596343) (xy 374.371606 -268.543045) (xy 374.379549 -268.490341)
			(xy 374.395259 -268.439411) (xy 374.418385 -268.39139) (xy 374.448409 -268.347353) (xy 374.484661 -268.308282)
			(xy 374.526332 -268.275051) (xy 374.57249 -268.248402) (xy 374.622104 -268.22893) (xy 374.674066 -268.21707)
			(xy 374.727216 -268.213087) (xy 374.780366 -268.21707) (xy 374.832328 -268.22893) (xy 374.881942 -268.248402)
			(xy 374.9281 -268.275051) (xy 374.969771 -268.308282) (xy 375.006023 -268.347353) (xy 375.036047 -268.39139)
			(xy 375.059173 -268.439411) (xy 375.074883 -268.490341) (xy 375.082826 -268.543045) (xy 375.083324 -268.569694)
			(xy 375.082826 -268.596343) (xy 375.311406 -268.596343) (xy 375.311406 -268.543045) (xy 375.319349 -268.490341)
			(xy 375.335059 -268.439411) (xy 375.358185 -268.39139) (xy 375.388209 -268.347353) (xy 375.424461 -268.308282)
			(xy 375.466132 -268.275051) (xy 375.51229 -268.248402) (xy 375.561904 -268.22893) (xy 375.613866 -268.21707)
			(xy 375.667016 -268.213087) (xy 375.720166 -268.21707) (xy 375.772128 -268.22893) (xy 375.821742 -268.248402)
			(xy 375.8679 -268.275051) (xy 375.909571 -268.308282) (xy 375.945823 -268.347353) (xy 375.975847 -268.39139)
			(xy 375.998973 -268.439411) (xy 376.014683 -268.490341) (xy 376.022626 -268.543045) (xy 376.023124 -268.569694)
			(xy 376.022626 -268.596343) (xy 376.251206 -268.596343) (xy 376.251206 -268.543045) (xy 376.259149 -268.490341)
			(xy 376.274859 -268.439411) (xy 376.297985 -268.39139) (xy 376.328009 -268.347353) (xy 376.364261 -268.308282)
			(xy 376.405932 -268.275051) (xy 376.45209 -268.248402) (xy 376.501704 -268.22893) (xy 376.553666 -268.21707)
			(xy 376.606816 -268.213087) (xy 376.659966 -268.21707) (xy 376.711928 -268.22893) (xy 376.761542 -268.248402)
			(xy 376.8077 -268.275051) (xy 376.849371 -268.308282) (xy 376.885623 -268.347353) (xy 376.915647 -268.39139)
			(xy 376.938773 -268.439411) (xy 376.954483 -268.490341) (xy 376.962426 -268.543045) (xy 376.962924 -268.569694)
			(xy 376.962426 -268.596343) (xy 377.191006 -268.596343) (xy 377.191006 -268.543045) (xy 377.198949 -268.490341)
			(xy 377.214659 -268.439411) (xy 377.237785 -268.39139) (xy 377.267809 -268.347353) (xy 377.304061 -268.308282)
			(xy 377.345732 -268.275051) (xy 377.39189 -268.248402) (xy 377.441504 -268.22893) (xy 377.493466 -268.21707)
			(xy 377.546616 -268.213087) (xy 377.599766 -268.21707) (xy 377.651728 -268.22893) (xy 377.701342 -268.248402)
			(xy 377.7475 -268.275051) (xy 377.789171 -268.308282) (xy 377.825423 -268.347353) (xy 377.855447 -268.39139)
			(xy 377.878573 -268.439411) (xy 377.894283 -268.490341) (xy 377.902226 -268.543045) (xy 377.902724 -268.569694)
			(xy 377.902226 -268.596343) (xy 378.130806 -268.596343) (xy 378.130806 -268.543045) (xy 378.138749 -268.490341)
			(xy 378.154459 -268.439411) (xy 378.177585 -268.39139) (xy 378.207609 -268.347353) (xy 378.243861 -268.308282)
			(xy 378.285532 -268.275051) (xy 378.33169 -268.248402) (xy 378.381304 -268.22893) (xy 378.433266 -268.21707)
			(xy 378.486416 -268.213087) (xy 378.539566 -268.21707) (xy 378.591528 -268.22893) (xy 378.641142 -268.248402)
			(xy 378.6873 -268.275051) (xy 378.728971 -268.308282) (xy 378.765223 -268.347353) (xy 378.795247 -268.39139)
			(xy 378.818373 -268.439411) (xy 378.834083 -268.490341) (xy 378.842026 -268.543045) (xy 378.842524 -268.569694)
			(xy 378.842026 -268.596343) (xy 379.070606 -268.596343) (xy 379.070606 -268.543045) (xy 379.078549 -268.490341)
			(xy 379.094259 -268.439411) (xy 379.117385 -268.39139) (xy 379.147409 -268.347353) (xy 379.183661 -268.308282)
			(xy 379.225332 -268.275051) (xy 379.27149 -268.248402) (xy 379.321104 -268.22893) (xy 379.373066 -268.21707)
			(xy 379.426216 -268.213087) (xy 379.479366 -268.21707) (xy 379.531328 -268.22893) (xy 379.580942 -268.248402)
			(xy 379.6271 -268.275051) (xy 379.668771 -268.308282) (xy 379.705023 -268.347353) (xy 379.735047 -268.39139)
			(xy 379.758173 -268.439411) (xy 379.773883 -268.490341) (xy 379.781826 -268.543045) (xy 379.782324 -268.569694)
			(xy 379.781826 -268.596343) (xy 380.010406 -268.596343) (xy 380.010406 -268.543045) (xy 380.018349 -268.490341)
			(xy 380.034059 -268.439411) (xy 380.057185 -268.39139) (xy 380.087209 -268.347353) (xy 380.123461 -268.308282)
			(xy 380.165132 -268.275051) (xy 380.21129 -268.248402) (xy 380.260904 -268.22893) (xy 380.312866 -268.21707)
			(xy 380.366016 -268.213087) (xy 380.419166 -268.21707) (xy 380.471128 -268.22893) (xy 380.520742 -268.248402)
			(xy 380.5669 -268.275051) (xy 380.608571 -268.308282) (xy 380.644823 -268.347353) (xy 380.674847 -268.39139)
			(xy 380.697973 -268.439411) (xy 380.713683 -268.490341) (xy 380.721626 -268.543045) (xy 380.722124 -268.569694)
			(xy 380.721626 -268.596343) (xy 380.950206 -268.596343) (xy 380.950206 -268.543045) (xy 380.958149 -268.490341)
			(xy 380.973859 -268.439411) (xy 380.996985 -268.39139) (xy 381.027009 -268.347353) (xy 381.063261 -268.308282)
			(xy 381.104932 -268.275051) (xy 381.15109 -268.248402) (xy 381.200704 -268.22893) (xy 381.252666 -268.21707)
			(xy 381.305816 -268.213087) (xy 381.358966 -268.21707) (xy 381.410928 -268.22893) (xy 381.460542 -268.248402)
			(xy 381.5067 -268.275051) (xy 381.548371 -268.308282) (xy 381.584623 -268.347353) (xy 381.614647 -268.39139)
			(xy 381.637773 -268.439411) (xy 381.653483 -268.490341) (xy 381.661426 -268.543045) (xy 381.661924 -268.569694)
			(xy 381.661426 -268.596343) (xy 381.653483 -268.649047) (xy 381.637773 -268.699977) (xy 381.614647 -268.747998)
			(xy 381.584623 -268.792035) (xy 381.548371 -268.831106) (xy 381.5067 -268.864337) (xy 381.460542 -268.890986)
			(xy 381.410928 -268.910458) (xy 381.358966 -268.922318) (xy 381.305816 -268.926302) (xy 381.252666 -268.922318)
			(xy 381.200704 -268.910458) (xy 381.15109 -268.890986) (xy 381.104932 -268.864337) (xy 381.063261 -268.831106)
			(xy 381.027009 -268.792035) (xy 380.996985 -268.747998) (xy 380.973859 -268.699977) (xy 380.958149 -268.649047)
			(xy 380.950206 -268.596343) (xy 380.721626 -268.596343) (xy 380.713683 -268.649047) (xy 380.697973 -268.699977)
			(xy 380.674847 -268.747998) (xy 380.644823 -268.792035) (xy 380.608571 -268.831106) (xy 380.5669 -268.864337)
			(xy 380.520742 -268.890986) (xy 380.471128 -268.910458) (xy 380.419166 -268.922318) (xy 380.366016 -268.926302)
			(xy 380.312866 -268.922318) (xy 380.260904 -268.910458) (xy 380.21129 -268.890986) (xy 380.165132 -268.864337)
			(xy 380.123461 -268.831106) (xy 380.087209 -268.792035) (xy 380.057185 -268.747998) (xy 380.034059 -268.699977)
			(xy 380.018349 -268.649047) (xy 380.010406 -268.596343) (xy 379.781826 -268.596343) (xy 379.773883 -268.649047)
			(xy 379.758173 -268.699977) (xy 379.735047 -268.747998) (xy 379.705023 -268.792035) (xy 379.668771 -268.831106)
			(xy 379.6271 -268.864337) (xy 379.580942 -268.890986) (xy 379.531328 -268.910458) (xy 379.479366 -268.922318)
			(xy 379.426216 -268.926302) (xy 379.373066 -268.922318) (xy 379.321104 -268.910458) (xy 379.27149 -268.890986)
			(xy 379.225332 -268.864337) (xy 379.183661 -268.831106) (xy 379.147409 -268.792035) (xy 379.117385 -268.747998)
			(xy 379.094259 -268.699977) (xy 379.078549 -268.649047) (xy 379.070606 -268.596343) (xy 378.842026 -268.596343)
			(xy 378.834083 -268.649047) (xy 378.818373 -268.699977) (xy 378.795247 -268.747998) (xy 378.765223 -268.792035)
			(xy 378.728971 -268.831106) (xy 378.6873 -268.864337) (xy 378.641142 -268.890986) (xy 378.591528 -268.910458)
			(xy 378.539566 -268.922318) (xy 378.486416 -268.926302) (xy 378.433266 -268.922318) (xy 378.381304 -268.910458)
			(xy 378.33169 -268.890986) (xy 378.285532 -268.864337) (xy 378.243861 -268.831106) (xy 378.207609 -268.792035)
			(xy 378.177585 -268.747998) (xy 378.154459 -268.699977) (xy 378.138749 -268.649047) (xy 378.130806 -268.596343)
			(xy 377.902226 -268.596343) (xy 377.894283 -268.649047) (xy 377.878573 -268.699977) (xy 377.855447 -268.747998)
			(xy 377.825423 -268.792035) (xy 377.789171 -268.831106) (xy 377.7475 -268.864337) (xy 377.701342 -268.890986)
			(xy 377.651728 -268.910458) (xy 377.599766 -268.922318) (xy 377.546616 -268.926302) (xy 377.493466 -268.922318)
			(xy 377.441504 -268.910458) (xy 377.39189 -268.890986) (xy 377.345732 -268.864337) (xy 377.304061 -268.831106)
			(xy 377.267809 -268.792035) (xy 377.237785 -268.747998) (xy 377.214659 -268.699977) (xy 377.198949 -268.649047)
			(xy 377.191006 -268.596343) (xy 376.962426 -268.596343) (xy 376.954483 -268.649047) (xy 376.938773 -268.699977)
			(xy 376.915647 -268.747998) (xy 376.885623 -268.792035) (xy 376.849371 -268.831106) (xy 376.8077 -268.864337)
			(xy 376.761542 -268.890986) (xy 376.711928 -268.910458) (xy 376.659966 -268.922318) (xy 376.606816 -268.926302)
			(xy 376.553666 -268.922318) (xy 376.501704 -268.910458) (xy 376.45209 -268.890986) (xy 376.405932 -268.864337)
			(xy 376.364261 -268.831106) (xy 376.328009 -268.792035) (xy 376.297985 -268.747998) (xy 376.274859 -268.699977)
			(xy 376.259149 -268.649047) (xy 376.251206 -268.596343) (xy 376.022626 -268.596343) (xy 376.014683 -268.649047)
			(xy 375.998973 -268.699977) (xy 375.975847 -268.747998) (xy 375.945823 -268.792035) (xy 375.909571 -268.831106)
			(xy 375.8679 -268.864337) (xy 375.821742 -268.890986) (xy 375.772128 -268.910458) (xy 375.720166 -268.922318)
			(xy 375.667016 -268.926302) (xy 375.613866 -268.922318) (xy 375.561904 -268.910458) (xy 375.51229 -268.890986)
			(xy 375.466132 -268.864337) (xy 375.424461 -268.831106) (xy 375.388209 -268.792035) (xy 375.358185 -268.747998)
			(xy 375.335059 -268.699977) (xy 375.319349 -268.649047) (xy 375.311406 -268.596343) (xy 375.082826 -268.596343)
			(xy 375.074883 -268.649047) (xy 375.059173 -268.699977) (xy 375.036047 -268.747998) (xy 375.006023 -268.792035)
			(xy 374.969771 -268.831106) (xy 374.9281 -268.864337) (xy 374.881942 -268.890986) (xy 374.832328 -268.910458)
			(xy 374.780366 -268.922318) (xy 374.727216 -268.926302) (xy 374.674066 -268.922318) (xy 374.622104 -268.910458)
			(xy 374.57249 -268.890986) (xy 374.526332 -268.864337) (xy 374.484661 -268.831106) (xy 374.448409 -268.792035)
			(xy 374.418385 -268.747998) (xy 374.395259 -268.699977) (xy 374.379549 -268.649047) (xy 374.371606 -268.596343)
			(xy 374.143026 -268.596343) (xy 374.135083 -268.649047) (xy 374.119373 -268.699977) (xy 374.096247 -268.747998)
			(xy 374.066223 -268.792035) (xy 374.029971 -268.831106) (xy 373.9883 -268.864337) (xy 373.942142 -268.890986)
			(xy 373.892528 -268.910458) (xy 373.840566 -268.922318) (xy 373.787416 -268.926302) (xy 373.734266 -268.922318)
			(xy 373.682304 -268.910458) (xy 373.63269 -268.890986) (xy 373.586532 -268.864337) (xy 373.544861 -268.831106)
			(xy 373.508609 -268.792035) (xy 373.478585 -268.747998) (xy 373.455459 -268.699977) (xy 373.439749 -268.649047)
			(xy 373.431806 -268.596343) (xy 373.203226 -268.596343) (xy 373.195283 -268.649047) (xy 373.179573 -268.699977)
			(xy 373.156447 -268.747998) (xy 373.126423 -268.792035) (xy 373.090171 -268.831106) (xy 373.0485 -268.864337)
			(xy 373.002342 -268.890986) (xy 372.952728 -268.910458) (xy 372.900766 -268.922318) (xy 372.847616 -268.926302)
			(xy 372.794466 -268.922318) (xy 372.742504 -268.910458) (xy 372.69289 -268.890986) (xy 372.646732 -268.864337)
			(xy 372.605061 -268.831106) (xy 372.568809 -268.792035) (xy 372.538785 -268.747998) (xy 372.515659 -268.699977)
			(xy 372.499949 -268.649047) (xy 372.492006 -268.596343) (xy 372.263426 -268.596343) (xy 372.255483 -268.649047)
			(xy 372.239773 -268.699977) (xy 372.216647 -268.747998) (xy 372.186623 -268.792035) (xy 372.150371 -268.831106)
			(xy 372.1087 -268.864337) (xy 372.062542 -268.890986) (xy 372.012928 -268.910458) (xy 371.960966 -268.922318)
			(xy 371.907816 -268.926302) (xy 371.854666 -268.922318) (xy 371.802704 -268.910458) (xy 371.75309 -268.890986)
			(xy 371.706932 -268.864337) (xy 371.665261 -268.831106) (xy 371.629009 -268.792035) (xy 371.598985 -268.747998)
			(xy 371.575859 -268.699977) (xy 371.560149 -268.649047) (xy 371.552206 -268.596343) (xy 371.323372 -268.596343)
			(xy 371.315429 -268.649047) (xy 371.299719 -268.699977) (xy 371.276593 -268.747998) (xy 371.246569 -268.792035)
			(xy 371.210317 -268.831106) (xy 371.168646 -268.864337) (xy 371.122488 -268.890986) (xy 371.072874 -268.910458)
			(xy 371.020912 -268.922318) (xy 370.967762 -268.926302) (xy 370.914612 -268.922318) (xy 370.86265 -268.910458)
			(xy 370.813036 -268.890986) (xy 370.766878 -268.864337) (xy 370.725207 -268.831106) (xy 370.688955 -268.792035)
			(xy 370.658931 -268.747998) (xy 370.635805 -268.699977) (xy 370.620095 -268.649047) (xy 370.612152 -268.596343)
			(xy 366.623636 -268.596343) (xy 366.621788 -268.621601) (xy 366.610476 -268.6724) (xy 366.59189 -268.721012)
			(xy 366.566426 -268.7664) (xy 366.534626 -268.807599) (xy 366.497169 -268.843729) (xy 366.47628 -268.859254)
			(xy 366.47628 -269.410159) (xy 368.262652 -269.410159) (xy 368.262652 -269.356861) (xy 368.270595 -269.304157)
			(xy 368.286305 -269.253227) (xy 368.309431 -269.205206) (xy 368.339455 -269.161169) (xy 368.375707 -269.122098)
			(xy 368.417378 -269.088867) (xy 368.463536 -269.062218) (xy 368.51315 -269.042746) (xy 368.565112 -269.030886)
			(xy 368.618262 -269.026903) (xy 368.671412 -269.030886) (xy 368.723374 -269.042746) (xy 368.772988 -269.062218)
			(xy 368.819146 -269.088867) (xy 368.860817 -269.122098) (xy 368.897069 -269.161169) (xy 368.927093 -269.205206)
			(xy 368.950219 -269.253227) (xy 368.965929 -269.304157) (xy 368.973872 -269.356861) (xy 368.97437 -269.38351)
			(xy 368.973872 -269.410159) (xy 370.142252 -269.410159) (xy 370.142252 -269.356861) (xy 370.150195 -269.304157)
			(xy 370.165905 -269.253227) (xy 370.189031 -269.205206) (xy 370.219055 -269.161169) (xy 370.255307 -269.122098)
			(xy 370.296978 -269.088867) (xy 370.343136 -269.062218) (xy 370.39275 -269.042746) (xy 370.444712 -269.030886)
			(xy 370.497862 -269.026903) (xy 370.551012 -269.030886) (xy 370.602974 -269.042746) (xy 370.652588 -269.062218)
			(xy 370.698746 -269.088867) (xy 370.740417 -269.122098) (xy 370.776669 -269.161169) (xy 370.806693 -269.205206)
			(xy 370.829819 -269.253227) (xy 370.845529 -269.304157) (xy 370.853472 -269.356861) (xy 370.85397 -269.38351)
			(xy 370.853472 -269.410159) (xy 371.082052 -269.410159) (xy 371.082052 -269.356861) (xy 371.089995 -269.304157)
			(xy 371.105705 -269.253227) (xy 371.128831 -269.205206) (xy 371.158855 -269.161169) (xy 371.195107 -269.122098)
			(xy 371.236778 -269.088867) (xy 371.282936 -269.062218) (xy 371.33255 -269.042746) (xy 371.384512 -269.030886)
			(xy 371.437662 -269.026903) (xy 371.490812 -269.030886) (xy 371.542774 -269.042746) (xy 371.592388 -269.062218)
			(xy 371.638546 -269.088867) (xy 371.680217 -269.122098) (xy 371.716469 -269.161169) (xy 371.746493 -269.205206)
			(xy 371.769619 -269.253227) (xy 371.785329 -269.304157) (xy 371.793272 -269.356861) (xy 371.79377 -269.38351)
			(xy 371.793272 -269.410159) (xy 372.021852 -269.410159) (xy 372.021852 -269.356861) (xy 372.029795 -269.304157)
			(xy 372.045505 -269.253227) (xy 372.068631 -269.205206) (xy 372.098655 -269.161169) (xy 372.134907 -269.122098)
			(xy 372.176578 -269.088867) (xy 372.222736 -269.062218) (xy 372.27235 -269.042746) (xy 372.324312 -269.030886)
			(xy 372.377462 -269.026903) (xy 372.430612 -269.030886) (xy 372.482574 -269.042746) (xy 372.532188 -269.062218)
			(xy 372.578346 -269.088867) (xy 372.620017 -269.122098) (xy 372.656269 -269.161169) (xy 372.686293 -269.205206)
			(xy 372.709419 -269.253227) (xy 372.725129 -269.304157) (xy 372.733072 -269.356861) (xy 372.73357 -269.38351)
			(xy 372.733072 -269.410159) (xy 372.961652 -269.410159) (xy 372.961652 -269.356861) (xy 372.969595 -269.304157)
			(xy 372.985305 -269.253227) (xy 373.008431 -269.205206) (xy 373.038455 -269.161169) (xy 373.074707 -269.122098)
			(xy 373.116378 -269.088867) (xy 373.162536 -269.062218) (xy 373.21215 -269.042746) (xy 373.264112 -269.030886)
			(xy 373.317262 -269.026903) (xy 373.370412 -269.030886) (xy 373.422374 -269.042746) (xy 373.471988 -269.062218)
			(xy 373.518146 -269.088867) (xy 373.559817 -269.122098) (xy 373.596069 -269.161169) (xy 373.626093 -269.205206)
			(xy 373.649219 -269.253227) (xy 373.664929 -269.304157) (xy 373.672872 -269.356861) (xy 373.67337 -269.38351)
			(xy 373.672872 -269.410159) (xy 373.901452 -269.410159) (xy 373.901452 -269.356861) (xy 373.909395 -269.304157)
			(xy 373.925105 -269.253227) (xy 373.948231 -269.205206) (xy 373.978255 -269.161169) (xy 374.014507 -269.122098)
			(xy 374.056178 -269.088867) (xy 374.102336 -269.062218) (xy 374.15195 -269.042746) (xy 374.203912 -269.030886)
			(xy 374.257062 -269.026903) (xy 374.310212 -269.030886) (xy 374.362174 -269.042746) (xy 374.411788 -269.062218)
			(xy 374.457946 -269.088867) (xy 374.499617 -269.122098) (xy 374.535869 -269.161169) (xy 374.565893 -269.205206)
			(xy 374.589019 -269.253227) (xy 374.604729 -269.304157) (xy 374.612672 -269.356861) (xy 374.61317 -269.38351)
			(xy 374.612672 -269.410159) (xy 374.841252 -269.410159) (xy 374.841252 -269.356861) (xy 374.849195 -269.304157)
			(xy 374.864905 -269.253227) (xy 374.888031 -269.205206) (xy 374.918055 -269.161169) (xy 374.954307 -269.122098)
			(xy 374.995978 -269.088867) (xy 375.042136 -269.062218) (xy 375.09175 -269.042746) (xy 375.143712 -269.030886)
			(xy 375.196862 -269.026903) (xy 375.250012 -269.030886) (xy 375.301974 -269.042746) (xy 375.351588 -269.062218)
			(xy 375.397746 -269.088867) (xy 375.439417 -269.122098) (xy 375.475669 -269.161169) (xy 375.505693 -269.205206)
			(xy 375.528819 -269.253227) (xy 375.544529 -269.304157) (xy 375.552472 -269.356861) (xy 375.55297 -269.38351)
			(xy 375.552472 -269.410159) (xy 375.781052 -269.410159) (xy 375.781052 -269.356861) (xy 375.788995 -269.304157)
			(xy 375.804705 -269.253227) (xy 375.827831 -269.205206) (xy 375.857855 -269.161169) (xy 375.894107 -269.122098)
			(xy 375.935778 -269.088867) (xy 375.981936 -269.062218) (xy 376.03155 -269.042746) (xy 376.083512 -269.030886)
			(xy 376.136662 -269.026903) (xy 376.189812 -269.030886) (xy 376.241774 -269.042746) (xy 376.291388 -269.062218)
			(xy 376.337546 -269.088867) (xy 376.379217 -269.122098) (xy 376.415469 -269.161169) (xy 376.445493 -269.205206)
			(xy 376.468619 -269.253227) (xy 376.484329 -269.304157) (xy 376.492272 -269.356861) (xy 376.49277 -269.38351)
			(xy 376.492272 -269.410159) (xy 376.720852 -269.410159) (xy 376.720852 -269.356861) (xy 376.728795 -269.304157)
			(xy 376.744505 -269.253227) (xy 376.767631 -269.205206) (xy 376.797655 -269.161169) (xy 376.833907 -269.122098)
			(xy 376.875578 -269.088867) (xy 376.921736 -269.062218) (xy 376.97135 -269.042746) (xy 377.023312 -269.030886)
			(xy 377.076462 -269.026903) (xy 377.129612 -269.030886) (xy 377.181574 -269.042746) (xy 377.231188 -269.062218)
			(xy 377.277346 -269.088867) (xy 377.319017 -269.122098) (xy 377.355269 -269.161169) (xy 377.385293 -269.205206)
			(xy 377.408419 -269.253227) (xy 377.424129 -269.304157) (xy 377.432072 -269.356861) (xy 377.43257 -269.38351)
			(xy 377.432072 -269.410159) (xy 377.660652 -269.410159) (xy 377.660652 -269.356861) (xy 377.668595 -269.304157)
			(xy 377.684305 -269.253227) (xy 377.707431 -269.205206) (xy 377.737455 -269.161169) (xy 377.773707 -269.122098)
			(xy 377.815378 -269.088867) (xy 377.861536 -269.062218) (xy 377.91115 -269.042746) (xy 377.963112 -269.030886)
			(xy 378.016262 -269.026903) (xy 378.069412 -269.030886) (xy 378.121374 -269.042746) (xy 378.170988 -269.062218)
			(xy 378.217146 -269.088867) (xy 378.258817 -269.122098) (xy 378.295069 -269.161169) (xy 378.325093 -269.205206)
			(xy 378.348219 -269.253227) (xy 378.363929 -269.304157) (xy 378.371872 -269.356861) (xy 378.37237 -269.38351)
			(xy 378.371872 -269.410159) (xy 378.600452 -269.410159) (xy 378.600452 -269.356861) (xy 378.608395 -269.304157)
			(xy 378.624105 -269.253227) (xy 378.647231 -269.205206) (xy 378.677255 -269.161169) (xy 378.713507 -269.122098)
			(xy 378.755178 -269.088867) (xy 378.801336 -269.062218) (xy 378.85095 -269.042746) (xy 378.902912 -269.030886)
			(xy 378.956062 -269.026903) (xy 379.009212 -269.030886) (xy 379.061174 -269.042746) (xy 379.110788 -269.062218)
			(xy 379.156946 -269.088867) (xy 379.198617 -269.122098) (xy 379.234869 -269.161169) (xy 379.264893 -269.205206)
			(xy 379.288019 -269.253227) (xy 379.303729 -269.304157) (xy 379.311672 -269.356861) (xy 379.31217 -269.38351)
			(xy 379.311672 -269.410159) (xy 379.540252 -269.410159) (xy 379.540252 -269.356861) (xy 379.548195 -269.304157)
			(xy 379.563905 -269.253227) (xy 379.587031 -269.205206) (xy 379.617055 -269.161169) (xy 379.653307 -269.122098)
			(xy 379.694978 -269.088867) (xy 379.741136 -269.062218) (xy 379.79075 -269.042746) (xy 379.842712 -269.030886)
			(xy 379.895862 -269.026903) (xy 379.949012 -269.030886) (xy 380.000974 -269.042746) (xy 380.050588 -269.062218)
			(xy 380.096746 -269.088867) (xy 380.138417 -269.122098) (xy 380.174669 -269.161169) (xy 380.204693 -269.205206)
			(xy 380.227819 -269.253227) (xy 380.243529 -269.304157) (xy 380.251472 -269.356861) (xy 380.25197 -269.38351)
			(xy 380.251472 -269.410159) (xy 380.480306 -269.410159) (xy 380.480306 -269.356861) (xy 380.488249 -269.304157)
			(xy 380.503959 -269.253227) (xy 380.527085 -269.205206) (xy 380.557109 -269.161169) (xy 380.593361 -269.122098)
			(xy 380.635032 -269.088867) (xy 380.68119 -269.062218) (xy 380.730804 -269.042746) (xy 380.782766 -269.030886)
			(xy 380.835916 -269.026903) (xy 380.889066 -269.030886) (xy 380.941028 -269.042746) (xy 380.990642 -269.062218)
			(xy 381.0368 -269.088867) (xy 381.078471 -269.122098) (xy 381.114723 -269.161169) (xy 381.144747 -269.205206)
			(xy 381.167873 -269.253227) (xy 381.183583 -269.304157) (xy 381.191526 -269.356861) (xy 381.192024 -269.38351)
			(xy 381.191526 -269.410159) (xy 381.183583 -269.462863) (xy 381.167873 -269.513793) (xy 381.144747 -269.561814)
			(xy 381.114723 -269.605851) (xy 381.078471 -269.644922) (xy 381.0368 -269.678153) (xy 380.990642 -269.704802)
			(xy 380.941028 -269.724274) (xy 380.889066 -269.736134) (xy 380.835916 -269.740118) (xy 380.782766 -269.736134)
			(xy 380.730804 -269.724274) (xy 380.68119 -269.704802) (xy 380.635032 -269.678153) (xy 380.593361 -269.644922)
			(xy 380.557109 -269.605851) (xy 380.527085 -269.561814) (xy 380.503959 -269.513793) (xy 380.488249 -269.462863)
			(xy 380.480306 -269.410159) (xy 380.251472 -269.410159) (xy 380.243529 -269.462863) (xy 380.227819 -269.513793)
			(xy 380.204693 -269.561814) (xy 380.174669 -269.605851) (xy 380.138417 -269.644922) (xy 380.096746 -269.678153)
			(xy 380.050588 -269.704802) (xy 380.000974 -269.724274) (xy 379.949012 -269.736134) (xy 379.895862 -269.740118)
			(xy 379.842712 -269.736134) (xy 379.79075 -269.724274) (xy 379.741136 -269.704802) (xy 379.694978 -269.678153)
			(xy 379.653307 -269.644922) (xy 379.617055 -269.605851) (xy 379.587031 -269.561814) (xy 379.563905 -269.513793)
			(xy 379.548195 -269.462863) (xy 379.540252 -269.410159) (xy 379.311672 -269.410159) (xy 379.303729 -269.462863)
			(xy 379.288019 -269.513793) (xy 379.264893 -269.561814) (xy 379.234869 -269.605851) (xy 379.198617 -269.644922)
			(xy 379.156946 -269.678153) (xy 379.110788 -269.704802) (xy 379.061174 -269.724274) (xy 379.009212 -269.736134)
			(xy 378.956062 -269.740118) (xy 378.902912 -269.736134) (xy 378.85095 -269.724274) (xy 378.801336 -269.704802)
			(xy 378.755178 -269.678153) (xy 378.713507 -269.644922) (xy 378.677255 -269.605851) (xy 378.647231 -269.561814)
			(xy 378.624105 -269.513793) (xy 378.608395 -269.462863) (xy 378.600452 -269.410159) (xy 378.371872 -269.410159)
			(xy 378.363929 -269.462863) (xy 378.348219 -269.513793) (xy 378.325093 -269.561814) (xy 378.295069 -269.605851)
			(xy 378.258817 -269.644922) (xy 378.217146 -269.678153) (xy 378.170988 -269.704802) (xy 378.121374 -269.724274)
			(xy 378.069412 -269.736134) (xy 378.016262 -269.740118) (xy 377.963112 -269.736134) (xy 377.91115 -269.724274)
			(xy 377.861536 -269.704802) (xy 377.815378 -269.678153) (xy 377.773707 -269.644922) (xy 377.737455 -269.605851)
			(xy 377.707431 -269.561814) (xy 377.684305 -269.513793) (xy 377.668595 -269.462863) (xy 377.660652 -269.410159)
			(xy 377.432072 -269.410159) (xy 377.424129 -269.462863) (xy 377.408419 -269.513793) (xy 377.385293 -269.561814)
			(xy 377.355269 -269.605851) (xy 377.319017 -269.644922) (xy 377.277346 -269.678153) (xy 377.231188 -269.704802)
			(xy 377.181574 -269.724274) (xy 377.129612 -269.736134) (xy 377.076462 -269.740118) (xy 377.023312 -269.736134)
			(xy 376.97135 -269.724274) (xy 376.921736 -269.704802) (xy 376.875578 -269.678153) (xy 376.833907 -269.644922)
			(xy 376.797655 -269.605851) (xy 376.767631 -269.561814) (xy 376.744505 -269.513793) (xy 376.728795 -269.462863)
			(xy 376.720852 -269.410159) (xy 376.492272 -269.410159) (xy 376.484329 -269.462863) (xy 376.468619 -269.513793)
			(xy 376.445493 -269.561814) (xy 376.415469 -269.605851) (xy 376.379217 -269.644922) (xy 376.337546 -269.678153)
			(xy 376.291388 -269.704802) (xy 376.241774 -269.724274) (xy 376.189812 -269.736134) (xy 376.136662 -269.740118)
			(xy 376.083512 -269.736134) (xy 376.03155 -269.724274) (xy 375.981936 -269.704802) (xy 375.935778 -269.678153)
			(xy 375.894107 -269.644922) (xy 375.857855 -269.605851) (xy 375.827831 -269.561814) (xy 375.804705 -269.513793)
			(xy 375.788995 -269.462863) (xy 375.781052 -269.410159) (xy 375.552472 -269.410159) (xy 375.544529 -269.462863)
			(xy 375.528819 -269.513793) (xy 375.505693 -269.561814) (xy 375.475669 -269.605851) (xy 375.439417 -269.644922)
			(xy 375.397746 -269.678153) (xy 375.351588 -269.704802) (xy 375.301974 -269.724274) (xy 375.250012 -269.736134)
			(xy 375.196862 -269.740118) (xy 375.143712 -269.736134) (xy 375.09175 -269.724274) (xy 375.042136 -269.704802)
			(xy 374.995978 -269.678153) (xy 374.954307 -269.644922) (xy 374.918055 -269.605851) (xy 374.888031 -269.561814)
			(xy 374.864905 -269.513793) (xy 374.849195 -269.462863) (xy 374.841252 -269.410159) (xy 374.612672 -269.410159)
			(xy 374.604729 -269.462863) (xy 374.589019 -269.513793) (xy 374.565893 -269.561814) (xy 374.535869 -269.605851)
			(xy 374.499617 -269.644922) (xy 374.457946 -269.678153) (xy 374.411788 -269.704802) (xy 374.362174 -269.724274)
			(xy 374.310212 -269.736134) (xy 374.257062 -269.740118) (xy 374.203912 -269.736134) (xy 374.15195 -269.724274)
			(xy 374.102336 -269.704802) (xy 374.056178 -269.678153) (xy 374.014507 -269.644922) (xy 373.978255 -269.605851)
			(xy 373.948231 -269.561814) (xy 373.925105 -269.513793) (xy 373.909395 -269.462863) (xy 373.901452 -269.410159)
			(xy 373.672872 -269.410159) (xy 373.664929 -269.462863) (xy 373.649219 -269.513793) (xy 373.626093 -269.561814)
			(xy 373.596069 -269.605851) (xy 373.559817 -269.644922) (xy 373.518146 -269.678153) (xy 373.471988 -269.704802)
			(xy 373.422374 -269.724274) (xy 373.370412 -269.736134) (xy 373.317262 -269.740118) (xy 373.264112 -269.736134)
			(xy 373.21215 -269.724274) (xy 373.162536 -269.704802) (xy 373.116378 -269.678153) (xy 373.074707 -269.644922)
			(xy 373.038455 -269.605851) (xy 373.008431 -269.561814) (xy 372.985305 -269.513793) (xy 372.969595 -269.462863)
			(xy 372.961652 -269.410159) (xy 372.733072 -269.410159) (xy 372.725129 -269.462863) (xy 372.709419 -269.513793)
			(xy 372.686293 -269.561814) (xy 372.656269 -269.605851) (xy 372.620017 -269.644922) (xy 372.578346 -269.678153)
			(xy 372.532188 -269.704802) (xy 372.482574 -269.724274) (xy 372.430612 -269.736134) (xy 372.377462 -269.740118)
			(xy 372.324312 -269.736134) (xy 372.27235 -269.724274) (xy 372.222736 -269.704802) (xy 372.176578 -269.678153)
			(xy 372.134907 -269.644922) (xy 372.098655 -269.605851) (xy 372.068631 -269.561814) (xy 372.045505 -269.513793)
			(xy 372.029795 -269.462863) (xy 372.021852 -269.410159) (xy 371.793272 -269.410159) (xy 371.785329 -269.462863)
			(xy 371.769619 -269.513793) (xy 371.746493 -269.561814) (xy 371.716469 -269.605851) (xy 371.680217 -269.644922)
			(xy 371.638546 -269.678153) (xy 371.592388 -269.704802) (xy 371.542774 -269.724274) (xy 371.490812 -269.736134)
			(xy 371.437662 -269.740118) (xy 371.384512 -269.736134) (xy 371.33255 -269.724274) (xy 371.282936 -269.704802)
			(xy 371.236778 -269.678153) (xy 371.195107 -269.644922) (xy 371.158855 -269.605851) (xy 371.128831 -269.561814)
			(xy 371.105705 -269.513793) (xy 371.089995 -269.462863) (xy 371.082052 -269.410159) (xy 370.853472 -269.410159)
			(xy 370.845529 -269.462863) (xy 370.829819 -269.513793) (xy 370.806693 -269.561814) (xy 370.776669 -269.605851)
			(xy 370.740417 -269.644922) (xy 370.698746 -269.678153) (xy 370.652588 -269.704802) (xy 370.602974 -269.724274)
			(xy 370.551012 -269.736134) (xy 370.497862 -269.740118) (xy 370.444712 -269.736134) (xy 370.39275 -269.724274)
			(xy 370.343136 -269.704802) (xy 370.296978 -269.678153) (xy 370.255307 -269.644922) (xy 370.219055 -269.605851)
			(xy 370.189031 -269.561814) (xy 370.165905 -269.513793) (xy 370.150195 -269.462863) (xy 370.142252 -269.410159)
			(xy 368.973872 -269.410159) (xy 368.965929 -269.462863) (xy 368.950219 -269.513793) (xy 368.927093 -269.561814)
			(xy 368.897069 -269.605851) (xy 368.860817 -269.644922) (xy 368.819146 -269.678153) (xy 368.772988 -269.704802)
			(xy 368.723374 -269.724274) (xy 368.671412 -269.736134) (xy 368.618262 -269.740118) (xy 368.565112 -269.736134)
			(xy 368.51315 -269.724274) (xy 368.463536 -269.704802) (xy 368.417378 -269.678153) (xy 368.375707 -269.644922)
			(xy 368.339455 -269.605851) (xy 368.309431 -269.561814) (xy 368.286305 -269.513793) (xy 368.270595 -269.462863)
			(xy 368.262652 -269.410159) (xy 366.47628 -269.410159) (xy 366.47628 -269.90802) (xy 366.498894 -269.924867)
			(xy 366.539001 -269.964503) (xy 366.572361 -270.009965) (xy 366.598139 -270.060116) (xy 366.615693 -270.113703)
			(xy 366.624582 -270.169386) (xy 366.625124 -270.19758) (xy 366.624678 -270.222916) (xy 366.62449 -270.224229)
			(xy 370.612406 -270.224229) (xy 370.612406 -270.170931) (xy 370.620349 -270.118227) (xy 370.636059 -270.067297)
			(xy 370.659185 -270.019276) (xy 370.689209 -269.975239) (xy 370.725461 -269.936168) (xy 370.767132 -269.902937)
			(xy 370.81329 -269.876288) (xy 370.862904 -269.856816) (xy 370.914866 -269.844956) (xy 370.968016 -269.840973)
			(xy 371.021166 -269.844956) (xy 371.073128 -269.856816) (xy 371.122742 -269.876288) (xy 371.1689 -269.902937)
			(xy 371.210571 -269.936168) (xy 371.246823 -269.975239) (xy 371.276847 -270.019276) (xy 371.299973 -270.067297)
			(xy 371.315683 -270.118227) (xy 371.323626 -270.170931) (xy 371.324124 -270.19758) (xy 371.323626 -270.224229)
			(xy 371.552206 -270.224229) (xy 371.552206 -270.170931) (xy 371.560149 -270.118227) (xy 371.575859 -270.067297)
			(xy 371.598985 -270.019276) (xy 371.629009 -269.975239) (xy 371.665261 -269.936168) (xy 371.706932 -269.902937)
			(xy 371.75309 -269.876288) (xy 371.802704 -269.856816) (xy 371.854666 -269.844956) (xy 371.907816 -269.840973)
			(xy 371.960966 -269.844956) (xy 372.012928 -269.856816) (xy 372.062542 -269.876288) (xy 372.1087 -269.902937)
			(xy 372.150371 -269.936168) (xy 372.186623 -269.975239) (xy 372.216647 -270.019276) (xy 372.239773 -270.067297)
			(xy 372.255483 -270.118227) (xy 372.263426 -270.170931) (xy 372.263924 -270.19758) (xy 372.263426 -270.224229)
			(xy 372.492006 -270.224229) (xy 372.492006 -270.170931) (xy 372.499949 -270.118227) (xy 372.515659 -270.067297)
			(xy 372.538785 -270.019276) (xy 372.568809 -269.975239) (xy 372.605061 -269.936168) (xy 372.646732 -269.902937)
			(xy 372.69289 -269.876288) (xy 372.742504 -269.856816) (xy 372.794466 -269.844956) (xy 372.847616 -269.840973)
			(xy 372.900766 -269.844956) (xy 372.952728 -269.856816) (xy 373.002342 -269.876288) (xy 373.0485 -269.902937)
			(xy 373.090171 -269.936168) (xy 373.126423 -269.975239) (xy 373.156447 -270.019276) (xy 373.179573 -270.067297)
			(xy 373.195283 -270.118227) (xy 373.203226 -270.170931) (xy 373.203724 -270.19758) (xy 373.203226 -270.224229)
			(xy 373.431806 -270.224229) (xy 373.431806 -270.170931) (xy 373.439749 -270.118227) (xy 373.455459 -270.067297)
			(xy 373.478585 -270.019276) (xy 373.508609 -269.975239) (xy 373.544861 -269.936168) (xy 373.586532 -269.902937)
			(xy 373.63269 -269.876288) (xy 373.682304 -269.856816) (xy 373.734266 -269.844956) (xy 373.787416 -269.840973)
			(xy 373.840566 -269.844956) (xy 373.892528 -269.856816) (xy 373.942142 -269.876288) (xy 373.9883 -269.902937)
			(xy 374.029971 -269.936168) (xy 374.066223 -269.975239) (xy 374.096247 -270.019276) (xy 374.119373 -270.067297)
			(xy 374.135083 -270.118227) (xy 374.143026 -270.170931) (xy 374.143524 -270.19758) (xy 374.143026 -270.224229)
			(xy 374.371606 -270.224229) (xy 374.371606 -270.170931) (xy 374.379549 -270.118227) (xy 374.395259 -270.067297)
			(xy 374.418385 -270.019276) (xy 374.448409 -269.975239) (xy 374.484661 -269.936168) (xy 374.526332 -269.902937)
			(xy 374.57249 -269.876288) (xy 374.622104 -269.856816) (xy 374.674066 -269.844956) (xy 374.727216 -269.840973)
			(xy 374.780366 -269.844956) (xy 374.832328 -269.856816) (xy 374.881942 -269.876288) (xy 374.9281 -269.902937)
			(xy 374.969771 -269.936168) (xy 375.006023 -269.975239) (xy 375.036047 -270.019276) (xy 375.059173 -270.067297)
			(xy 375.074883 -270.118227) (xy 375.082826 -270.170931) (xy 375.083324 -270.19758) (xy 375.082826 -270.224229)
			(xy 375.311406 -270.224229) (xy 375.311406 -270.170931) (xy 375.319349 -270.118227) (xy 375.335059 -270.067297)
			(xy 375.358185 -270.019276) (xy 375.388209 -269.975239) (xy 375.424461 -269.936168) (xy 375.466132 -269.902937)
			(xy 375.51229 -269.876288) (xy 375.561904 -269.856816) (xy 375.613866 -269.844956) (xy 375.667016 -269.840973)
			(xy 375.720166 -269.844956) (xy 375.772128 -269.856816) (xy 375.821742 -269.876288) (xy 375.8679 -269.902937)
			(xy 375.909571 -269.936168) (xy 375.945823 -269.975239) (xy 375.975847 -270.019276) (xy 375.998973 -270.067297)
			(xy 376.014683 -270.118227) (xy 376.022626 -270.170931) (xy 376.023124 -270.19758) (xy 376.022626 -270.224229)
			(xy 376.251206 -270.224229) (xy 376.251206 -270.170931) (xy 376.259149 -270.118227) (xy 376.274859 -270.067297)
			(xy 376.297985 -270.019276) (xy 376.328009 -269.975239) (xy 376.364261 -269.936168) (xy 376.405932 -269.902937)
			(xy 376.45209 -269.876288) (xy 376.501704 -269.856816) (xy 376.553666 -269.844956) (xy 376.606816 -269.840973)
			(xy 376.659966 -269.844956) (xy 376.711928 -269.856816) (xy 376.761542 -269.876288) (xy 376.8077 -269.902937)
			(xy 376.849371 -269.936168) (xy 376.885623 -269.975239) (xy 376.915647 -270.019276) (xy 376.938773 -270.067297)
			(xy 376.954483 -270.118227) (xy 376.962426 -270.170931) (xy 376.962924 -270.19758) (xy 376.962426 -270.224229)
			(xy 377.191006 -270.224229) (xy 377.191006 -270.170931) (xy 377.198949 -270.118227) (xy 377.214659 -270.067297)
			(xy 377.237785 -270.019276) (xy 377.267809 -269.975239) (xy 377.304061 -269.936168) (xy 377.345732 -269.902937)
			(xy 377.39189 -269.876288) (xy 377.441504 -269.856816) (xy 377.493466 -269.844956) (xy 377.546616 -269.840973)
			(xy 377.599766 -269.844956) (xy 377.651728 -269.856816) (xy 377.701342 -269.876288) (xy 377.7475 -269.902937)
			(xy 377.789171 -269.936168) (xy 377.825423 -269.975239) (xy 377.855447 -270.019276) (xy 377.878573 -270.067297)
			(xy 377.894283 -270.118227) (xy 377.902226 -270.170931) (xy 377.902724 -270.19758) (xy 377.902226 -270.224229)
			(xy 378.130806 -270.224229) (xy 378.130806 -270.170931) (xy 378.138749 -270.118227) (xy 378.154459 -270.067297)
			(xy 378.177585 -270.019276) (xy 378.207609 -269.975239) (xy 378.243861 -269.936168) (xy 378.285532 -269.902937)
			(xy 378.33169 -269.876288) (xy 378.381304 -269.856816) (xy 378.433266 -269.844956) (xy 378.486416 -269.840973)
			(xy 378.539566 -269.844956) (xy 378.591528 -269.856816) (xy 378.641142 -269.876288) (xy 378.6873 -269.902937)
			(xy 378.728971 -269.936168) (xy 378.765223 -269.975239) (xy 378.795247 -270.019276) (xy 378.818373 -270.067297)
			(xy 378.834083 -270.118227) (xy 378.842026 -270.170931) (xy 378.842524 -270.19758) (xy 378.842026 -270.224229)
			(xy 379.070606 -270.224229) (xy 379.070606 -270.170931) (xy 379.078549 -270.118227) (xy 379.094259 -270.067297)
			(xy 379.117385 -270.019276) (xy 379.147409 -269.975239) (xy 379.183661 -269.936168) (xy 379.225332 -269.902937)
			(xy 379.27149 -269.876288) (xy 379.321104 -269.856816) (xy 379.373066 -269.844956) (xy 379.426216 -269.840973)
			(xy 379.479366 -269.844956) (xy 379.531328 -269.856816) (xy 379.580942 -269.876288) (xy 379.6271 -269.902937)
			(xy 379.668771 -269.936168) (xy 379.705023 -269.975239) (xy 379.735047 -270.019276) (xy 379.758173 -270.067297)
			(xy 379.773883 -270.118227) (xy 379.781826 -270.170931) (xy 379.782324 -270.19758) (xy 379.781826 -270.224229)
			(xy 380.010406 -270.224229) (xy 380.010406 -270.170931) (xy 380.018349 -270.118227) (xy 380.034059 -270.067297)
			(xy 380.057185 -270.019276) (xy 380.087209 -269.975239) (xy 380.123461 -269.936168) (xy 380.165132 -269.902937)
			(xy 380.21129 -269.876288) (xy 380.260904 -269.856816) (xy 380.312866 -269.844956) (xy 380.366016 -269.840973)
			(xy 380.419166 -269.844956) (xy 380.471128 -269.856816) (xy 380.520742 -269.876288) (xy 380.5669 -269.902937)
			(xy 380.608571 -269.936168) (xy 380.644823 -269.975239) (xy 380.674847 -270.019276) (xy 380.697973 -270.067297)
			(xy 380.713683 -270.118227) (xy 380.721626 -270.170931) (xy 380.722124 -270.19758) (xy 380.721626 -270.224229)
			(xy 380.713683 -270.276933) (xy 380.697973 -270.327863) (xy 380.674847 -270.375884) (xy 380.644823 -270.419921)
			(xy 380.608571 -270.458992) (xy 380.5669 -270.492223) (xy 380.520742 -270.518872) (xy 380.471128 -270.538344)
			(xy 380.419166 -270.550204) (xy 380.366016 -270.554188) (xy 380.312866 -270.550204) (xy 380.260904 -270.538344)
			(xy 380.21129 -270.518872) (xy 380.165132 -270.492223) (xy 380.123461 -270.458992) (xy 380.087209 -270.419921)
			(xy 380.057185 -270.375884) (xy 380.034059 -270.327863) (xy 380.018349 -270.276933) (xy 380.010406 -270.224229)
			(xy 379.781826 -270.224229) (xy 379.773883 -270.276933) (xy 379.758173 -270.327863) (xy 379.735047 -270.375884)
			(xy 379.705023 -270.419921) (xy 379.668771 -270.458992) (xy 379.6271 -270.492223) (xy 379.580942 -270.518872)
			(xy 379.531328 -270.538344) (xy 379.479366 -270.550204) (xy 379.426216 -270.554188) (xy 379.373066 -270.550204)
			(xy 379.321104 -270.538344) (xy 379.27149 -270.518872) (xy 379.225332 -270.492223) (xy 379.183661 -270.458992)
			(xy 379.147409 -270.419921) (xy 379.117385 -270.375884) (xy 379.094259 -270.327863) (xy 379.078549 -270.276933)
			(xy 379.070606 -270.224229) (xy 378.842026 -270.224229) (xy 378.834083 -270.276933) (xy 378.818373 -270.327863)
			(xy 378.795247 -270.375884) (xy 378.765223 -270.419921) (xy 378.728971 -270.458992) (xy 378.6873 -270.492223)
			(xy 378.641142 -270.518872) (xy 378.591528 -270.538344) (xy 378.539566 -270.550204) (xy 378.486416 -270.554188)
			(xy 378.433266 -270.550204) (xy 378.381304 -270.538344) (xy 378.33169 -270.518872) (xy 378.285532 -270.492223)
			(xy 378.243861 -270.458992) (xy 378.207609 -270.419921) (xy 378.177585 -270.375884) (xy 378.154459 -270.327863)
			(xy 378.138749 -270.276933) (xy 378.130806 -270.224229) (xy 377.902226 -270.224229) (xy 377.894283 -270.276933)
			(xy 377.878573 -270.327863) (xy 377.855447 -270.375884) (xy 377.825423 -270.419921) (xy 377.789171 -270.458992)
			(xy 377.7475 -270.492223) (xy 377.701342 -270.518872) (xy 377.651728 -270.538344) (xy 377.599766 -270.550204)
			(xy 377.546616 -270.554188) (xy 377.493466 -270.550204) (xy 377.441504 -270.538344) (xy 377.39189 -270.518872)
			(xy 377.345732 -270.492223) (xy 377.304061 -270.458992) (xy 377.267809 -270.419921) (xy 377.237785 -270.375884)
			(xy 377.214659 -270.327863) (xy 377.198949 -270.276933) (xy 377.191006 -270.224229) (xy 376.962426 -270.224229)
			(xy 376.954483 -270.276933) (xy 376.938773 -270.327863) (xy 376.915647 -270.375884) (xy 376.885623 -270.419921)
			(xy 376.849371 -270.458992) (xy 376.8077 -270.492223) (xy 376.761542 -270.518872) (xy 376.711928 -270.538344)
			(xy 376.659966 -270.550204) (xy 376.606816 -270.554188) (xy 376.553666 -270.550204) (xy 376.501704 -270.538344)
			(xy 376.45209 -270.518872) (xy 376.405932 -270.492223) (xy 376.364261 -270.458992) (xy 376.328009 -270.419921)
			(xy 376.297985 -270.375884) (xy 376.274859 -270.327863) (xy 376.259149 -270.276933) (xy 376.251206 -270.224229)
			(xy 376.022626 -270.224229) (xy 376.014683 -270.276933) (xy 375.998973 -270.327863) (xy 375.975847 -270.375884)
			(xy 375.945823 -270.419921) (xy 375.909571 -270.458992) (xy 375.8679 -270.492223) (xy 375.821742 -270.518872)
			(xy 375.772128 -270.538344) (xy 375.720166 -270.550204) (xy 375.667016 -270.554188) (xy 375.613866 -270.550204)
			(xy 375.561904 -270.538344) (xy 375.51229 -270.518872) (xy 375.466132 -270.492223) (xy 375.424461 -270.458992)
			(xy 375.388209 -270.419921) (xy 375.358185 -270.375884) (xy 375.335059 -270.327863) (xy 375.319349 -270.276933)
			(xy 375.311406 -270.224229) (xy 375.082826 -270.224229) (xy 375.074883 -270.276933) (xy 375.059173 -270.327863)
			(xy 375.036047 -270.375884) (xy 375.006023 -270.419921) (xy 374.969771 -270.458992) (xy 374.9281 -270.492223)
			(xy 374.881942 -270.518872) (xy 374.832328 -270.538344) (xy 374.780366 -270.550204) (xy 374.727216 -270.554188)
			(xy 374.674066 -270.550204) (xy 374.622104 -270.538344) (xy 374.57249 -270.518872) (xy 374.526332 -270.492223)
			(xy 374.484661 -270.458992) (xy 374.448409 -270.419921) (xy 374.418385 -270.375884) (xy 374.395259 -270.327863)
			(xy 374.379549 -270.276933) (xy 374.371606 -270.224229) (xy 374.143026 -270.224229) (xy 374.135083 -270.276933)
			(xy 374.119373 -270.327863) (xy 374.096247 -270.375884) (xy 374.066223 -270.419921) (xy 374.029971 -270.458992)
			(xy 373.9883 -270.492223) (xy 373.942142 -270.518872) (xy 373.892528 -270.538344) (xy 373.840566 -270.550204)
			(xy 373.787416 -270.554188) (xy 373.734266 -270.550204) (xy 373.682304 -270.538344) (xy 373.63269 -270.518872)
			(xy 373.586532 -270.492223) (xy 373.544861 -270.458992) (xy 373.508609 -270.419921) (xy 373.478585 -270.375884)
			(xy 373.455459 -270.327863) (xy 373.439749 -270.276933) (xy 373.431806 -270.224229) (xy 373.203226 -270.224229)
			(xy 373.195283 -270.276933) (xy 373.179573 -270.327863) (xy 373.156447 -270.375884) (xy 373.126423 -270.419921)
			(xy 373.090171 -270.458992) (xy 373.0485 -270.492223) (xy 373.002342 -270.518872) (xy 372.952728 -270.538344)
			(xy 372.900766 -270.550204) (xy 372.847616 -270.554188) (xy 372.794466 -270.550204) (xy 372.742504 -270.538344)
			(xy 372.69289 -270.518872) (xy 372.646732 -270.492223) (xy 372.605061 -270.458992) (xy 372.568809 -270.419921)
			(xy 372.538785 -270.375884) (xy 372.515659 -270.327863) (xy 372.499949 -270.276933) (xy 372.492006 -270.224229)
			(xy 372.263426 -270.224229) (xy 372.255483 -270.276933) (xy 372.239773 -270.327863) (xy 372.216647 -270.375884)
			(xy 372.186623 -270.419921) (xy 372.150371 -270.458992) (xy 372.1087 -270.492223) (xy 372.062542 -270.518872)
			(xy 372.012928 -270.538344) (xy 371.960966 -270.550204) (xy 371.907816 -270.554188) (xy 371.854666 -270.550204)
			(xy 371.802704 -270.538344) (xy 371.75309 -270.518872) (xy 371.706932 -270.492223) (xy 371.665261 -270.458992)
			(xy 371.629009 -270.419921) (xy 371.598985 -270.375884) (xy 371.575859 -270.327863) (xy 371.560149 -270.276933)
			(xy 371.552206 -270.224229) (xy 371.323626 -270.224229) (xy 371.315683 -270.276933) (xy 371.299973 -270.327863)
			(xy 371.276847 -270.375884) (xy 371.246823 -270.419921) (xy 371.210571 -270.458992) (xy 371.1689 -270.492223)
			(xy 371.122742 -270.518872) (xy 371.073128 -270.538344) (xy 371.021166 -270.550204) (xy 370.968016 -270.554188)
			(xy 370.914866 -270.550204) (xy 370.862904 -270.538344) (xy 370.81329 -270.518872) (xy 370.767132 -270.492223)
			(xy 370.725461 -270.458992) (xy 370.689209 -270.419921) (xy 370.659185 -270.375884) (xy 370.636059 -270.327863)
			(xy 370.620349 -270.276933) (xy 370.612406 -270.224229) (xy 366.62449 -270.224229) (xy 366.617494 -270.273076)
			(xy 366.603269 -270.321711) (xy 366.58229 -270.367836) (xy 366.554981 -270.410519) (xy 366.538764 -270.42999)
			(xy 366.52921 -270.441844) (xy 366.517013 -270.469727) (xy 366.513586 -270.499967) (xy 366.519236 -270.529872)
			(xy 366.533458 -270.556778) (xy 366.543844 -270.567912) (xy 366.643158 -270.667226) (xy 366.669828 -270.661892)
			(xy 366.686864 -270.658769) (xy 366.721343 -270.655458) (xy 366.738662 -270.655288) (xy 366.766392 -270.655822)
			(xy 366.821179 -270.664432) (xy 366.873968 -270.681433) (xy 366.923483 -270.706414) (xy 366.968524 -270.738772)
			(xy 367.008004 -270.777722) (xy 367.040965 -270.822324) (xy 367.066612 -270.871497) (xy 367.075974 -270.897604)
			(xy 367.087658 -270.932148) (xy 367.329466 -270.932148) (xy 367.34115 -270.897604) (xy 367.349911 -270.873012)
			(xy 367.373613 -270.8265) (xy 367.403854 -270.78395) (xy 367.439988 -270.746273) (xy 367.481237 -270.714278)
			(xy 367.526717 -270.688653) (xy 367.575453 -270.669946) (xy 367.626399 -270.658558) (xy 367.678462 -270.654735)
			(xy 367.730525 -270.658558) (xy 367.781471 -270.669946) (xy 367.830207 -270.688653) (xy 367.875687 -270.714278)
			(xy 367.916936 -270.746273) (xy 367.95307 -270.78395) (xy 367.983311 -270.8265) (xy 368.007013 -270.873012)
			(xy 368.015774 -270.897604) (xy 368.027458 -270.932148) (xy 368.269266 -270.932148) (xy 368.28095 -270.897604)
			(xy 368.289711 -270.873012) (xy 368.313413 -270.8265) (xy 368.343654 -270.78395) (xy 368.379788 -270.746273)
			(xy 368.421037 -270.714278) (xy 368.466517 -270.688653) (xy 368.515253 -270.669946) (xy 368.566199 -270.658558)
			(xy 368.618262 -270.654735) (xy 368.670325 -270.658558) (xy 368.721271 -270.669946) (xy 368.770007 -270.688653)
			(xy 368.815487 -270.714278) (xy 368.856736 -270.746273) (xy 368.89287 -270.78395) (xy 368.923111 -270.8265)
			(xy 368.946813 -270.873012) (xy 368.955574 -270.897604) (xy 368.967258 -270.932148) (xy 369.209066 -270.932148)
			(xy 369.22075 -270.897604) (xy 369.229511 -270.873012) (xy 369.253213 -270.8265) (xy 369.283454 -270.78395)
			(xy 369.319588 -270.746273) (xy 369.360837 -270.714278) (xy 369.406317 -270.688653) (xy 369.455053 -270.669946)
			(xy 369.505999 -270.658558) (xy 369.558062 -270.654735) (xy 369.610125 -270.658558) (xy 369.661071 -270.669946)
			(xy 369.709807 -270.688653) (xy 369.755287 -270.714278) (xy 369.796536 -270.746273) (xy 369.83267 -270.78395)
			(xy 369.862911 -270.8265) (xy 369.886613 -270.873012) (xy 369.895374 -270.897604) (xy 369.907058 -270.932148)
			(xy 370.14912 -270.932148) (xy 370.160804 -270.897604) (xy 370.169565 -270.873012) (xy 370.193267 -270.8265)
			(xy 370.223508 -270.78395) (xy 370.259642 -270.746273) (xy 370.300891 -270.714278) (xy 370.346371 -270.688653)
			(xy 370.395107 -270.669946) (xy 370.446053 -270.658558) (xy 370.498116 -270.654735) (xy 370.550179 -270.658558)
			(xy 370.601125 -270.669946) (xy 370.649861 -270.688653) (xy 370.695341 -270.714278) (xy 370.73659 -270.746273)
			(xy 370.772724 -270.78395) (xy 370.802965 -270.8265) (xy 370.826667 -270.873012) (xy 370.835428 -270.897604)
			(xy 370.847112 -270.932148) (xy 371.088666 -270.932148) (xy 371.10035 -270.897604) (xy 371.109111 -270.873012)
			(xy 371.132813 -270.8265) (xy 371.163054 -270.78395) (xy 371.199188 -270.746273) (xy 371.240437 -270.714278)
			(xy 371.285917 -270.688653) (xy 371.334653 -270.669946) (xy 371.385599 -270.658558) (xy 371.437662 -270.654735)
			(xy 371.489725 -270.658558) (xy 371.540671 -270.669946) (xy 371.589407 -270.688653) (xy 371.634887 -270.714278)
			(xy 371.676136 -270.746273) (xy 371.71227 -270.78395) (xy 371.742511 -270.8265) (xy 371.766213 -270.873012)
			(xy 371.774974 -270.897604) (xy 371.786658 -270.932148) (xy 372.028466 -270.932148) (xy 372.04015 -270.897604)
			(xy 372.048911 -270.873012) (xy 372.072613 -270.8265) (xy 372.102854 -270.78395) (xy 372.138988 -270.746273)
			(xy 372.180237 -270.714278) (xy 372.225717 -270.688653) (xy 372.274453 -270.669946) (xy 372.325399 -270.658558)
			(xy 372.377462 -270.654735) (xy 372.429525 -270.658558) (xy 372.480471 -270.669946) (xy 372.529207 -270.688653)
			(xy 372.574687 -270.714278) (xy 372.615936 -270.746273) (xy 372.65207 -270.78395) (xy 372.682311 -270.8265)
			(xy 372.706013 -270.873012) (xy 372.714774 -270.897604) (xy 372.726458 -270.932148) (xy 372.968266 -270.932148)
			(xy 372.97995 -270.897604) (xy 372.988711 -270.873012) (xy 373.012413 -270.8265) (xy 373.042654 -270.78395)
			(xy 373.078788 -270.746273) (xy 373.120037 -270.714278) (xy 373.165517 -270.688653) (xy 373.214253 -270.669946)
			(xy 373.265199 -270.658558) (xy 373.317262 -270.654735) (xy 373.369325 -270.658558) (xy 373.420271 -270.669946)
			(xy 373.469007 -270.688653) (xy 373.514487 -270.714278) (xy 373.555736 -270.746273) (xy 373.59187 -270.78395)
			(xy 373.622111 -270.8265) (xy 373.645813 -270.873012) (xy 373.654574 -270.897604) (xy 373.666258 -270.932148)
			(xy 373.908066 -270.932148) (xy 373.91975 -270.897604) (xy 373.928511 -270.873012) (xy 373.952213 -270.8265)
			(xy 373.982454 -270.78395) (xy 374.018588 -270.746273) (xy 374.059837 -270.714278) (xy 374.105317 -270.688653)
			(xy 374.154053 -270.669946) (xy 374.204999 -270.658558) (xy 374.257062 -270.654735) (xy 374.309125 -270.658558)
			(xy 374.360071 -270.669946) (xy 374.408807 -270.688653) (xy 374.454287 -270.714278) (xy 374.495536 -270.746273)
			(xy 374.53167 -270.78395) (xy 374.561911 -270.8265) (xy 374.585613 -270.873012) (xy 374.594374 -270.897604)
			(xy 374.606058 -270.932148) (xy 374.847866 -270.932148) (xy 374.85955 -270.897604) (xy 374.868311 -270.873012)
			(xy 374.892013 -270.8265) (xy 374.922254 -270.78395) (xy 374.958388 -270.746273) (xy 374.999637 -270.714278)
			(xy 375.045117 -270.688653) (xy 375.093853 -270.669946) (xy 375.144799 -270.658558) (xy 375.196862 -270.654735)
			(xy 375.248925 -270.658558) (xy 375.299871 -270.669946) (xy 375.348607 -270.688653) (xy 375.394087 -270.714278)
			(xy 375.435336 -270.746273) (xy 375.47147 -270.78395) (xy 375.501711 -270.8265) (xy 375.525413 -270.873012)
			(xy 375.534174 -270.897604) (xy 375.545858 -270.932148) (xy 375.787666 -270.932148) (xy 375.79935 -270.897604)
			(xy 375.808111 -270.873012) (xy 375.831813 -270.8265) (xy 375.862054 -270.78395) (xy 375.898188 -270.746273)
			(xy 375.939437 -270.714278) (xy 375.984917 -270.688653) (xy 376.033653 -270.669946) (xy 376.084599 -270.658558)
			(xy 376.136662 -270.654735) (xy 376.188725 -270.658558) (xy 376.239671 -270.669946) (xy 376.288407 -270.688653)
			(xy 376.333887 -270.714278) (xy 376.375136 -270.746273) (xy 376.41127 -270.78395) (xy 376.441511 -270.8265)
			(xy 376.465213 -270.873012) (xy 376.473974 -270.897604) (xy 376.485658 -270.932148) (xy 376.727466 -270.932148)
			(xy 376.73915 -270.897604) (xy 376.747911 -270.873012) (xy 376.771613 -270.8265) (xy 376.801854 -270.78395)
			(xy 376.837988 -270.746273) (xy 376.879237 -270.714278) (xy 376.924717 -270.688653) (xy 376.973453 -270.669946)
			(xy 377.024399 -270.658558) (xy 377.076462 -270.654735) (xy 377.128525 -270.658558) (xy 377.179471 -270.669946)
			(xy 377.228207 -270.688653) (xy 377.273687 -270.714278) (xy 377.314936 -270.746273) (xy 377.35107 -270.78395)
			(xy 377.381311 -270.8265) (xy 377.405013 -270.873012) (xy 377.413774 -270.897604) (xy 377.425458 -270.932148)
			(xy 377.667266 -270.932148) (xy 377.67895 -270.897604) (xy 377.687711 -270.873012) (xy 377.711413 -270.8265)
			(xy 377.741654 -270.78395) (xy 377.777788 -270.746273) (xy 377.819037 -270.714278) (xy 377.864517 -270.688653)
			(xy 377.913253 -270.669946) (xy 377.964199 -270.658558) (xy 378.016262 -270.654735) (xy 378.068325 -270.658558)
			(xy 378.119271 -270.669946) (xy 378.168007 -270.688653) (xy 378.213487 -270.714278) (xy 378.254736 -270.746273)
			(xy 378.29087 -270.78395) (xy 378.321111 -270.8265) (xy 378.344813 -270.873012) (xy 378.353574 -270.897604)
			(xy 378.365258 -270.932148) (xy 378.607066 -270.932148) (xy 378.61875 -270.897604) (xy 378.627511 -270.873012)
			(xy 378.651213 -270.8265) (xy 378.681454 -270.78395) (xy 378.717588 -270.746273) (xy 378.758837 -270.714278)
			(xy 378.804317 -270.688653) (xy 378.853053 -270.669946) (xy 378.903999 -270.658558) (xy 378.956062 -270.654735)
			(xy 379.008125 -270.658558) (xy 379.059071 -270.669946) (xy 379.107807 -270.688653) (xy 379.153287 -270.714278)
			(xy 379.194536 -270.746273) (xy 379.23067 -270.78395) (xy 379.260911 -270.8265) (xy 379.284613 -270.873012)
			(xy 379.293374 -270.897604) (xy 379.305058 -270.932148) (xy 379.546866 -270.932148) (xy 379.55855 -270.897604)
			(xy 379.567311 -270.873012) (xy 379.591013 -270.8265) (xy 379.621254 -270.78395) (xy 379.657388 -270.746273)
			(xy 379.698637 -270.714278) (xy 379.744117 -270.688653) (xy 379.792853 -270.669946) (xy 379.843799 -270.658558)
			(xy 379.895862 -270.654735) (xy 379.947925 -270.658558) (xy 379.998871 -270.669946) (xy 380.047607 -270.688653)
			(xy 380.093087 -270.714278) (xy 380.134336 -270.746273) (xy 380.17047 -270.78395) (xy 380.200711 -270.8265)
			(xy 380.224413 -270.873012) (xy 380.233174 -270.897604) (xy 380.244858 -270.932148) (xy 380.486666 -270.932148)
			(xy 380.49835 -270.897604) (xy 380.5077 -270.871493) (xy 380.533337 -270.822314) (xy 380.566294 -270.777709)
			(xy 380.605775 -270.738759) (xy 380.650822 -270.706408) (xy 380.700343 -270.68144) (xy 380.75314 -270.664459)
			(xy 380.807932 -270.655877) (xy 380.835662 -270.655288) (xy 380.863493 -270.655852) (xy 380.91847 -270.664561)
			(xy 380.971426 -270.681711) (xy 381.021071 -270.706885) (xy 381.066199 -270.739471) (xy 381.08636 -270.758666)
			(xy 381.096098 -270.767683) (xy 381.119138 -270.780839) (xy 381.144786 -270.787625) (xy 381.171317 -270.787585)
			(xy 381.196944 -270.780723) (xy 381.219945 -270.767499) (xy 381.229616 -270.758412) (xy 381.27305 -270.714978)
			(xy 381.282336 -270.705121) (xy 381.295804 -270.681637) (xy 381.302618 -270.655438) (xy 381.302297 -270.628368)
			(xy 381.294864 -270.602337) (xy 381.280844 -270.579179) (xy 381.261224 -270.560527) (xy 381.237387 -270.547695)
			(xy 381.224282 -270.54429) (xy 381.198563 -270.537755) (xy 381.149273 -270.518106) (xy 381.103443 -270.491361)
			(xy 381.06209 -270.45811) (xy 381.026129 -270.419092) (xy 380.996356 -270.375169) (xy 380.97343 -270.327314)
			(xy 380.957859 -270.276587) (xy 380.949988 -270.224111) (xy 380.949454 -270.19758) (xy 380.950004 -270.169597)
			(xy 380.958762 -270.11432) (xy 380.976058 -270.061093) (xy 381.001466 -270.011227) (xy 381.034362 -269.965949)
			(xy 381.073935 -269.926374) (xy 381.119211 -269.893476) (xy 381.169076 -269.868064) (xy 381.222302 -269.850766)
			(xy 381.277579 -269.842006) (xy 381.305562 -269.841472) (xy 381.332097 -269.841958) (xy 381.384581 -269.849828)
			(xy 381.435316 -269.8654) (xy 381.483178 -269.888328) (xy 381.527108 -269.918105) (xy 381.566132 -269.954071)
			(xy 381.599387 -269.995431) (xy 381.626136 -270.041267) (xy 381.645786 -270.090566) (xy 381.652272 -270.1163)
			(xy 381.655777 -270.129352) (xy 381.668649 -270.153103) (xy 381.6873 -270.172648) (xy 381.710423 -270.186618)
			(xy 381.736401 -270.194035) (xy 381.763414 -270.19438) (xy 381.789572 -270.187629) (xy 381.813045 -270.174254)
			(xy 381.82296 -270.165068) (xy 381.84328 -270.144748) (xy 381.84328 -269.839948) (xy 381.842707 -269.824723)
			(xy 381.833725 -269.795628) (xy 381.816575 -269.770467) (xy 381.792775 -269.751473) (xy 381.764438 -269.740328)
			(xy 381.7493 -269.738602) (xy 381.722739 -269.736166) (xy 381.670727 -269.724352) (xy 381.621059 -269.704911)
			(xy 381.574846 -269.67828) (xy 381.533122 -269.645054) (xy 381.496821 -269.605976) (xy 381.466755 -269.56192)
			(xy 381.443596 -269.513873) (xy 381.427863 -269.46291) (xy 381.419907 -269.410169) (xy 381.419907 -269.356832)
			(xy 381.427863 -269.304092) (xy 381.443596 -269.253128) (xy 381.466754 -269.205081) (xy 381.49682 -269.161025)
			(xy 381.533121 -269.121947) (xy 381.574845 -269.088721) (xy 381.621057 -269.062089) (xy 381.670725 -269.042649)
			(xy 381.722737 -269.030834) (xy 381.7493 -269.028418) (xy 381.764459 -269.02677) (xy 381.79283 -269.015632)
			(xy 381.816656 -268.996625) (xy 381.833821 -268.971439) (xy 381.842798 -268.942312) (xy 381.84328 -268.927072)
			(xy 381.84328 -268.212316) (xy 381.842716 -268.197085) (xy 381.833747 -268.167972) (xy 381.8166 -268.142794)
			(xy 381.792796 -268.123785) (xy 381.764449 -268.112631) (xy 381.7493 -268.11097) (xy 381.722741 -268.108534)
			(xy 381.670734 -268.09672) (xy 381.62107 -268.077281) (xy 381.574862 -268.050652) (xy 381.533142 -268.017429)
			(xy 381.496845 -267.978354) (xy 381.466782 -267.934302) (xy 381.443625 -267.88626) (xy 381.427894 -267.8353)
			(xy 381.419939 -267.782565) (xy 381.419939 -267.729232) (xy 381.427894 -267.676497) (xy 381.443626 -267.625537)
			(xy 381.466783 -267.577495) (xy 381.496847 -267.533443) (xy 381.533145 -267.494369) (xy 381.574865 -267.461146)
			(xy 381.621073 -267.434517) (xy 381.670737 -267.415079) (xy 381.722744 -267.403265) (xy 381.7493 -267.400786)
			(xy 381.764457 -267.399138) (xy 381.792823 -267.387999) (xy 381.816644 -267.368991) (xy 381.833802 -267.343804)
			(xy 381.84277 -267.314678) (xy 381.84328 -267.29944) (xy 381.84328 -266.584684) (xy 381.842712 -266.569456)
			(xy 381.833737 -266.540351) (xy 381.816588 -266.515182) (xy 381.792786 -266.496179) (xy 381.764444 -266.48503)
			(xy 381.7493 -266.483338) (xy 381.722736 -266.480902) (xy 381.670719 -266.469087) (xy 381.621045 -266.449645)
			(xy 381.574828 -266.423011) (xy 381.5331 -266.389782) (xy 381.496795 -266.3507) (xy 381.466725 -266.306641)
			(xy 381.443564 -266.258589) (xy 381.427829 -266.20762) (xy 381.419872 -266.154875) (xy 381.419871 -266.101532)
			(xy 381.427827 -266.048786) (xy 381.443561 -265.997817) (xy 381.466722 -265.949765) (xy 381.496791 -265.905705)
			(xy 381.533095 -265.866623) (xy 381.574822 -265.833393) (xy 381.621039 -265.806758) (xy 381.670712 -265.787315)
			(xy 381.722729 -265.775499) (xy 381.7493 -265.773154) (xy 381.764455 -265.771506) (xy 381.792817 -265.760365)
			(xy 381.816633 -265.741356) (xy 381.833783 -265.716169) (xy 381.842743 -265.687044) (xy 381.84328 -265.671808)
			(xy 381.84328 -264.956798) (xy 381.842714 -264.941568) (xy 381.833741 -264.912461) (xy 381.816593 -264.887287)
			(xy 381.792791 -264.868282) (xy 381.764446 -264.85713) (xy 381.7493 -264.855452) (xy 381.722742 -264.853016)
			(xy 381.670738 -264.841203) (xy 381.621077 -264.821765) (xy 381.574871 -264.795137) (xy 381.533153 -264.761915)
			(xy 381.496858 -264.722842) (xy 381.466796 -264.678792) (xy 381.443641 -264.630752) (xy 381.427911 -264.579795)
			(xy 381.419957 -264.527062) (xy 381.419957 -264.473732) (xy 381.427912 -264.420999) (xy 381.443644 -264.370043)
			(xy 381.466799 -264.322003) (xy 381.496862 -264.277954) (xy 381.533158 -264.238881) (xy 381.574876 -264.20566)
			(xy 381.621082 -264.179033) (xy 381.670743 -264.159595) (xy 381.722748 -264.147783) (xy 381.7493 -264.145268)
			(xy 381.764456 -264.14362) (xy 381.79282 -264.13248) (xy 381.816638 -264.113471) (xy 381.833791 -264.088284)
			(xy 381.842755 -264.059159) (xy 381.84328 -264.043922) (xy 381.84328 -263.328912) (xy 381.842716 -263.313681)
			(xy 381.833746 -263.28457) (xy 381.816598 -263.259393) (xy 381.792795 -263.240384) (xy 381.764448 -263.229231)
			(xy 381.7493 -263.227566) (xy 381.722741 -263.22513) (xy 381.670735 -263.213317) (xy 381.621072 -263.193878)
			(xy 381.574864 -263.167249) (xy 381.533145 -263.134026) (xy 381.496848 -263.094951) (xy 381.466785 -263.0509)
			(xy 381.443629 -263.002858) (xy 381.427898 -262.951899) (xy 381.419943 -262.899164) (xy 381.419943 -262.845832)
			(xy 381.427898 -262.793097) (xy 381.44363 -262.742139) (xy 381.466787 -262.694096) (xy 381.49685 -262.650046)
			(xy 381.533148 -262.610972) (xy 381.574867 -262.577749) (xy 381.621075 -262.551121) (xy 381.670738 -262.531682)
			(xy 381.722745 -262.519869) (xy 381.7493 -262.517382) (xy 381.764457 -262.515734) (xy 381.792823 -262.504594)
			(xy 381.816643 -262.485586) (xy 381.8338 -262.460399) (xy 381.842767 -262.431274) (xy 381.84328 -262.416036)
			(xy 381.84328 -261.70128) (xy 381.842711 -261.686052) (xy 381.833736 -261.656949) (xy 381.816586 -261.63178)
			(xy 381.792785 -261.612778) (xy 381.764443 -261.60163) (xy 381.7493 -261.599934) (xy 381.722736 -261.597498)
			(xy 381.670719 -261.585683) (xy 381.621047 -261.566241) (xy 381.57483 -261.539608) (xy 381.533102 -261.506379)
			(xy 381.496798 -261.467298) (xy 381.466729 -261.423239) (xy 381.443567 -261.375187) (xy 381.427833 -261.324219)
			(xy 381.419876 -261.271474) (xy 381.419875 -261.218132) (xy 381.427831 -261.165387) (xy 381.443565 -261.114418)
			(xy 381.466726 -261.066367) (xy 381.496794 -261.022307) (xy 381.533098 -260.983226) (xy 381.574825 -260.949996)
			(xy 381.621041 -260.923362) (xy 381.670714 -260.903919) (xy 381.72273 -260.892103) (xy 381.7493 -260.88975)
			(xy 381.764455 -260.888102) (xy 381.792817 -260.876961) (xy 381.816631 -260.857952) (xy 381.833781 -260.832765)
			(xy 381.84274 -260.80364) (xy 381.84328 -260.788404) (xy 381.84328 -260.073394) (xy 381.842713 -260.058165)
			(xy 381.83374 -260.029058) (xy 381.816592 -260.003886) (xy 381.792789 -259.984881) (xy 381.764445 -259.97373)
			(xy 381.7493 -259.972048) (xy 381.722743 -259.969612) (xy 381.670739 -259.957799) (xy 381.621078 -259.938361)
			(xy 381.574873 -259.911733) (xy 381.533156 -259.878511) (xy 381.496861 -259.839439) (xy 381.4668 -259.79539)
			(xy 381.443645 -259.74735) (xy 381.427915 -259.696394) (xy 381.419961 -259.643661) (xy 381.419961 -259.590332)
			(xy 381.427916 -259.5376) (xy 381.443647 -259.486644) (xy 381.466803 -259.438604) (xy 381.496865 -259.394556)
			(xy 381.533161 -259.355484) (xy 381.574878 -259.322263) (xy 381.621084 -259.295636) (xy 381.670745 -259.276199)
			(xy 381.722749 -259.264387) (xy 381.7493 -259.261864) (xy 381.764456 -259.260216) (xy 381.792819 -259.249076)
			(xy 381.816636 -259.230067) (xy 381.833789 -259.20488) (xy 381.842752 -259.175755) (xy 381.84328 -259.160518)
			(xy 381.84328 -258.445508) (xy 381.842715 -258.430277) (xy 381.833744 -258.401167) (xy 381.816597 -258.375991)
			(xy 381.792794 -258.356983) (xy 381.764448 -258.345831) (xy 381.7493 -258.344162) (xy 381.722752 -258.341713)
			(xy 381.670769 -258.329877) (xy 381.621132 -258.310422) (xy 381.57495 -258.283784) (xy 381.533257 -258.250559)
			(xy 381.496983 -258.211488) (xy 381.46694 -258.167445) (xy 381.4438 -258.119415) (xy 381.42808 -258.068472)
			(xy 381.420132 -258.015754) (xy 381.420132 -257.962441) (xy 381.428081 -257.909724) (xy 381.443802 -257.858781)
			(xy 381.466943 -257.810751) (xy 381.496986 -257.766709) (xy 381.53326 -257.727638) (xy 381.574954 -257.694413)
			(xy 381.621136 -257.667776) (xy 381.670773 -257.648322) (xy 381.722756 -257.636486) (xy 381.7493 -257.633978)
			(xy 381.764456 -257.63233) (xy 381.792822 -257.62119) (xy 381.816642 -257.602182) (xy 381.833797 -257.576995)
			(xy 381.842764 -257.54787) (xy 381.84328 -257.532632) (xy 381.84328 -256.817876) (xy 381.842711 -256.802649)
			(xy 381.833734 -256.773546) (xy 381.816585 -256.748378) (xy 381.792784 -256.729378) (xy 381.764442 -256.718229)
			(xy 381.7493 -256.71653) (xy 381.722737 -256.714094) (xy 381.67072 -256.702279) (xy 381.621048 -256.682837)
			(xy 381.574832 -256.656204) (xy 381.533105 -256.622976) (xy 381.496801 -256.583895) (xy 381.466732 -256.539836)
			(xy 381.443571 -256.491786) (xy 381.427836 -256.440818) (xy 381.41988 -256.388073) (xy 381.419879 -256.334732)
			(xy 381.427835 -256.281988) (xy 381.443569 -256.23102) (xy 381.466729 -256.182969) (xy 381.496797 -256.13891)
			(xy 381.533101 -256.099828) (xy 381.574827 -256.066599) (xy 381.621043 -256.039965) (xy 381.670715 -256.020523)
			(xy 381.722731 -256.008707) (xy 381.7493 -256.006346) (xy 381.764455 -256.004698) (xy 381.792816 -255.993557)
			(xy 381.81663 -255.974548) (xy 381.833779 -255.94936) (xy 381.842736 -255.920236) (xy 381.84328 -255.905)
			(xy 381.84328 -255.18999) (xy 381.842713 -255.174761) (xy 381.833739 -255.145655) (xy 381.81659 -255.120484)
			(xy 381.792788 -255.10148) (xy 381.764445 -255.09033) (xy 381.7493 -255.088644) (xy 381.722743 -255.086209)
			(xy 381.67074 -255.074395) (xy 381.62108 -255.054957) (xy 381.574875 -255.02833) (xy 381.533158 -254.995108)
			(xy 381.496864 -254.956036) (xy 381.466803 -254.911988) (xy 381.443649 -254.863948) (xy 381.427919 -254.812993)
			(xy 381.419965 -254.760261) (xy 381.419965 -254.706932) (xy 381.42792 -254.6542) (xy 381.443651 -254.603245)
			(xy 381.466807 -254.555206) (xy 381.496868 -254.511158) (xy 381.533164 -254.472087) (xy 381.574881 -254.438866)
			(xy 381.621086 -254.41224) (xy 381.670746 -254.392803) (xy 381.72275 -254.38099) (xy 381.7493 -254.37846)
			(xy 381.764455 -254.376812) (xy 381.792818 -254.365672) (xy 381.816635 -254.346663) (xy 381.833787 -254.321476)
			(xy 381.842748 -254.292351) (xy 381.84328 -254.277114) (xy 381.84328 -249.009662) (xy 381.828223 -248.987147)
			(xy 381.804376 -248.938518) (xy 381.788185 -248.886833) (xy 381.780025 -248.833289) (xy 381.779526 -248.806208)
			(xy 381.780035 -248.77913) (xy 381.788232 -248.725596) (xy 381.804423 -248.673916) (xy 381.828237 -248.625275)
			(xy 381.84328 -248.602754) (xy 381.84328 -247.381776) (xy 381.828222 -247.359262) (xy 381.804373 -247.310632)
			(xy 381.78818 -247.258947) (xy 381.780018 -247.205404) (xy 381.779526 -247.178322) (xy 381.780034 -247.151243)
			(xy 381.788229 -247.097709) (xy 381.804419 -247.046027) (xy 381.828231 -246.997386) (xy 381.84328 -246.974868)
			(xy 381.84328 -246.815864) (xy 381.842792 -246.801135) (xy 381.834389 -246.772903) (xy 381.818264 -246.748251)
			(xy 381.795765 -246.729239) (xy 381.768769 -246.717452) (xy 381.73953 -246.713875) (xy 381.724916 -246.715788)
			(xy 381.710228 -246.718073) (xy 381.680598 -246.720487) (xy 381.665734 -246.720614) (xy 381.639081 -246.720143)
			(xy 381.586369 -246.712203) (xy 381.53543 -246.696494) (xy 381.487401 -246.673369) (xy 381.443355 -246.643343)
			(xy 381.404277 -246.607087) (xy 381.371039 -246.565412) (xy 381.344384 -246.519248) (xy 381.324908 -246.469627)
			(xy 381.313046 -246.417657) (xy 381.309062 -246.3645) (xy 381.313046 -246.311343) (xy 381.324908 -246.259373)
			(xy 381.344384 -246.209752) (xy 381.371039 -246.163588) (xy 381.404277 -246.121913) (xy 381.443355 -246.085657)
			(xy 381.487401 -246.055631) (xy 381.53543 -246.032506) (xy 381.586369 -246.016797) (xy 381.639081 -246.008857)
			(xy 381.665734 -246.008398) (xy 381.680598 -246.008521) (xy 381.710228 -246.010938) (xy 381.724916 -246.013224)
			(xy 381.739513 -246.015156) (xy 381.768718 -246.011513) (xy 381.795673 -245.999696) (xy 381.818142 -245.980687)
			(xy 381.83426 -245.956061) (xy 381.84269 -245.927863) (xy 381.84328 -245.913148) (xy 381.84328 -245.754144)
			(xy 381.828217 -245.731631) (xy 381.80436 -245.683003) (xy 381.788157 -245.631318) (xy 381.779985 -245.577773)
			(xy 381.779526 -245.55069) (xy 381.780037 -245.523612) (xy 381.788236 -245.47008) (xy 381.804429 -245.418401)
			(xy 381.828245 -245.369762) (xy 381.84328 -245.347236) (xy 381.84328 -245.187978) (xy 381.842794 -245.173248)
			(xy 381.834393 -245.145012) (xy 381.818269 -245.120357) (xy 381.795769 -245.101341) (xy 381.768771 -245.089552)
			(xy 381.739529 -245.085975) (xy 381.724916 -245.087902) (xy 381.710228 -245.090187) (xy 381.680598 -245.092601)
			(xy 381.665734 -245.092728) (xy 381.63908 -245.092257) (xy 381.586366 -245.084316) (xy 381.535425 -245.068607)
			(xy 381.487394 -245.045481) (xy 381.443346 -245.015454) (xy 381.404267 -244.979197) (xy 381.371028 -244.93752)
			(xy 381.344372 -244.891354) (xy 381.324895 -244.841731) (xy 381.313032 -244.789759) (xy 381.309048 -244.7366)
			(xy 381.313032 -244.683441) (xy 381.324895 -244.631469) (xy 381.344372 -244.581846) (xy 381.371028 -244.53568)
			(xy 381.404267 -244.494003) (xy 381.443346 -244.457746) (xy 381.487394 -244.427719) (xy 381.535425 -244.404593)
			(xy 381.586366 -244.388884) (xy 381.63908 -244.380943) (xy 381.665734 -244.380512) (xy 381.680598 -244.380635)
			(xy 381.710228 -244.383052) (xy 381.724916 -244.385338) (xy 381.739513 -244.38727) (xy 381.76872 -244.383627)
			(xy 381.795677 -244.371811) (xy 381.818148 -244.352801) (xy 381.834268 -244.328176) (xy 381.842702 -244.299977)
			(xy 381.84328 -244.285262) (xy 381.84328 -244.126258) (xy 381.828223 -244.103743) (xy 381.804377 -244.055114)
			(xy 381.788187 -244.003429) (xy 381.780027 -243.949885) (xy 381.779526 -243.922804) (xy 381.780036 -243.895726)
			(xy 381.788233 -243.842193) (xy 381.804425 -243.790513) (xy 381.828239 -243.741872) (xy 381.84328 -243.71935)
			(xy 381.84328 -243.560346) (xy 381.84279 -243.545619) (xy 381.834383 -243.517391) (xy 381.818258 -243.492744)
			(xy 381.79576 -243.473735) (xy 381.768767 -243.461951) (xy 381.739532 -243.458375) (xy 381.724916 -243.46027)
			(xy 381.710228 -243.462556) (xy 381.680598 -243.464969) (xy 381.665734 -243.465096) (xy 381.639082 -243.464625)
			(xy 381.586373 -243.456685) (xy 381.535436 -243.440978) (xy 381.48741 -243.417853) (xy 381.443366 -243.387829)
			(xy 381.40429 -243.351575) (xy 381.371054 -243.309902) (xy 381.344401 -243.26374) (xy 381.324926 -243.214122)
			(xy 381.313064 -243.162155) (xy 381.30908 -243.109) (xy 381.313064 -243.055845) (xy 381.324926 -243.003878)
			(xy 381.344401 -242.95426) (xy 381.371054 -242.908098) (xy 381.40429 -242.866425) (xy 381.443366 -242.830171)
			(xy 381.48741 -242.800147) (xy 381.535436 -242.777022) (xy 381.586373 -242.761315) (xy 381.639082 -242.753375)
			(xy 381.665734 -242.75288) (xy 381.680598 -242.753003) (xy 381.710228 -242.75542) (xy 381.724916 -242.757706)
			(xy 381.739517 -242.759637) (xy 381.768729 -242.755994) (xy 381.795694 -242.74418) (xy 381.818175 -242.725173)
			(xy 381.834309 -242.700549) (xy 381.84276 -242.672348) (xy 381.84328 -242.65763) (xy 381.84328 -242.498372)
			(xy 381.828222 -242.475858) (xy 381.804374 -242.427228) (xy 381.788182 -242.375543) (xy 381.78002 -242.322)
			(xy 381.779526 -242.294918) (xy 381.780035 -242.267839) (xy 381.78823 -242.214305) (xy 381.80442 -242.162624)
			(xy 381.828233 -242.113983) (xy 381.84328 -242.091464) (xy 381.84328 -241.93246) (xy 381.842792 -241.917732)
			(xy 381.834387 -241.8895) (xy 381.818263 -241.86485) (xy 381.795764 -241.845838) (xy 381.768769 -241.834052)
			(xy 381.739531 -241.830475) (xy 381.724916 -241.832384) (xy 381.710228 -241.834669) (xy 381.680598 -241.837083)
			(xy 381.665734 -241.83721) (xy 381.639081 -241.836739) (xy 381.58637 -241.828799) (xy 381.535431 -241.813091)
			(xy 381.487403 -241.789965) (xy 381.443358 -241.75994) (xy 381.40428 -241.723685) (xy 381.371042 -241.68201)
			(xy 381.344388 -241.635846) (xy 381.324912 -241.586226) (xy 381.31305 -241.534257) (xy 381.309066 -241.4811)
			(xy 381.31305 -241.427943) (xy 381.324912 -241.375974) (xy 381.344388 -241.326354) (xy 381.371042 -241.28019)
			(xy 381.40428 -241.238515) (xy 381.443358 -241.20226) (xy 381.487403 -241.172235) (xy 381.535431 -241.149109)
			(xy 381.58637 -241.133401) (xy 381.639081 -241.125461) (xy 381.665734 -241.124994) (xy 381.680598 -241.125117)
			(xy 381.710228 -241.127534) (xy 381.724916 -241.12982) (xy 381.739517 -241.131751) (xy 381.768731 -241.128108)
			(xy 381.795697 -241.116294) (xy 381.81818 -241.097287) (xy 381.834318 -241.072663) (xy 381.842772 -241.044463)
			(xy 381.84328 -241.029744) (xy 381.84328 -240.87074) (xy 381.828218 -240.848227) (xy 381.80436 -240.799599)
			(xy 381.788158 -240.747914) (xy 381.779987 -240.694369) (xy 381.779526 -240.667286) (xy 381.780037 -240.640208)
			(xy 381.788237 -240.586676) (xy 381.804431 -240.534998) (xy 381.828247 -240.486359) (xy 381.84328 -240.463832)
			(xy 381.84328 -240.304574) (xy 381.842794 -240.289844) (xy 381.834392 -240.261609) (xy 381.818268 -240.236955)
			(xy 381.795768 -240.21794) (xy 381.76877 -240.206152) (xy 381.73953 -240.202575) (xy 381.724916 -240.204498)
			(xy 381.710228 -240.206783) (xy 381.680598 -240.209197) (xy 381.665734 -240.209324) (xy 381.63908 -240.208853)
			(xy 381.586367 -240.200913) (xy 381.535426 -240.185204) (xy 381.487396 -240.162078) (xy 381.443349 -240.132051)
			(xy 381.40427 -240.095794) (xy 381.371031 -240.054118) (xy 381.344375 -240.007953) (xy 381.324899 -239.95833)
			(xy 381.313036 -239.906359) (xy 381.309052 -239.8532) (xy 381.313036 -239.800041) (xy 381.324899 -239.74807)
			(xy 381.344375 -239.698447) (xy 381.371031 -239.652282) (xy 381.40427 -239.610606) (xy 381.443349 -239.574349)
			(xy 381.487396 -239.544322) (xy 381.535426 -239.521196) (xy 381.586367 -239.505487) (xy 381.63908 -239.497547)
			(xy 381.665734 -239.497108) (xy 381.680598 -239.497231) (xy 381.710228 -239.499648) (xy 381.724916 -239.501934)
			(xy 381.739513 -239.503866) (xy 381.768719 -239.500223) (xy 381.795676 -239.488407) (xy 381.818146 -239.469397)
			(xy 381.834266 -239.444772) (xy 381.842699 -239.416573) (xy 381.84328 -239.401858) (xy 381.84328 -239.242854)
			(xy 381.828217 -239.220341) (xy 381.804358 -239.171713) (xy 381.788153 -239.120028) (xy 381.77998 -239.066483)
			(xy 381.779526 -239.0394) (xy 381.780036 -239.012322) (xy 381.788234 -238.958789) (xy 381.804426 -238.907109)
			(xy 381.828241 -238.85847) (xy 381.84328 -238.835946) (xy 381.84328 -238.676942) (xy 381.842789 -238.662216)
			(xy 381.834382 -238.633989) (xy 381.818257 -238.609343) (xy 381.795759 -238.590335) (xy 381.768766 -238.578551)
			(xy 381.739532 -238.574975) (xy 381.724916 -238.576866) (xy 381.710228 -238.579152) (xy 381.680598 -238.581565)
			(xy 381.665734 -238.581692) (xy 381.639082 -238.581221) (xy 381.586374 -238.573281) (xy 381.535438 -238.557574)
			(xy 381.487412 -238.53445) (xy 381.443369 -238.504426) (xy 381.404293 -238.468172) (xy 381.371057 -238.4265)
			(xy 381.344404 -238.380339) (xy 381.324929 -238.330721) (xy 381.313068 -238.278754) (xy 381.309084 -238.2256)
			(xy 381.313068 -238.172446) (xy 381.324929 -238.120479) (xy 381.344404 -238.070861) (xy 381.371057 -238.0247)
			(xy 381.404293 -237.983028) (xy 381.443369 -237.946774) (xy 381.487412 -237.91675) (xy 381.535438 -237.893626)
			(xy 381.586374 -237.877919) (xy 381.639082 -237.869979) (xy 381.665734 -237.869476) (xy 381.680598 -237.869599)
			(xy 381.710228 -237.872016) (xy 381.724916 -237.874302) (xy 381.739516 -237.876233) (xy 381.768729 -237.87259)
			(xy 381.795693 -237.860775) (xy 381.818173 -237.841768) (xy 381.834307 -237.817144) (xy 381.842757 -237.788944)
			(xy 381.84328 -237.774226) (xy 381.84328 -237.614968) (xy 381.828222 -237.592454) (xy 381.804375 -237.543824)
			(xy 381.788183 -237.492139) (xy 381.780022 -237.438596) (xy 381.779526 -237.411514) (xy 381.780035 -237.384435)
			(xy 381.788231 -237.330902) (xy 381.804421 -237.279221) (xy 381.828235 -237.23058) (xy 381.84328 -237.20806)
			(xy 381.84328 -237.04931) (xy 381.842798 -237.034577) (xy 381.834402 -237.006332) (xy 381.81828 -236.981669)
			(xy 381.795777 -236.962646) (xy 381.768775 -236.950853) (xy 381.739527 -236.947275) (xy 381.724916 -236.949234)
			(xy 381.710228 -236.95152) (xy 381.680598 -236.953933) (xy 381.665734 -236.95406) (xy 381.639085 -236.953589)
			(xy 381.586381 -236.94565) (xy 381.535449 -236.929944) (xy 381.487428 -236.906822) (xy 381.443389 -236.876801)
			(xy 381.404316 -236.840551) (xy 381.371084 -236.798882) (xy 381.344433 -236.752725) (xy 381.32496 -236.703111)
			(xy 381.313099 -236.651149) (xy 381.309116 -236.598) (xy 381.313099 -236.544851) (xy 381.32496 -236.492889)
			(xy 381.344433 -236.443275) (xy 381.371084 -236.397118) (xy 381.404316 -236.355449) (xy 381.443389 -236.319199)
			(xy 381.487428 -236.289178) (xy 381.535449 -236.266056) (xy 381.586381 -236.25035) (xy 381.639085 -236.242411)
			(xy 381.665734 -236.241844) (xy 381.680598 -236.241967) (xy 381.710228 -236.244384) (xy 381.724916 -236.24667)
			(xy 381.739515 -236.248601) (xy 381.768724 -236.244958) (xy 381.795685 -236.233143) (xy 381.81816 -236.214135)
			(xy 381.834287 -236.18951) (xy 381.842729 -236.161311) (xy 381.84328 -236.146594) (xy 381.84328 -235.987336)
			(xy 381.828218 -235.964823) (xy 381.804361 -235.916195) (xy 381.78816 -235.86451) (xy 381.779989 -235.810965)
			(xy 381.779526 -235.783882) (xy 381.780037 -235.756804) (xy 381.788238 -235.703272) (xy 381.804432 -235.651594)
			(xy 381.828249 -235.602956) (xy 381.84328 -235.580428) (xy 381.84328 -235.421424) (xy 381.8428 -235.406689)
			(xy 381.834407 -235.378442) (xy 381.818285 -235.353774) (xy 381.795781 -235.334749) (xy 381.768776 -235.322954)
			(xy 381.739526 -235.319375) (xy 381.724916 -235.321348) (xy 381.710228 -235.323634) (xy 381.680598 -235.326047)
			(xy 381.665734 -235.326174) (xy 381.639084 -235.325703) (xy 381.586378 -235.317764) (xy 381.535444 -235.302057)
			(xy 381.487421 -235.278934) (xy 381.44338 -235.248912) (xy 381.404306 -235.21266) (xy 381.371072 -235.17099)
			(xy 381.344421 -235.124831) (xy 381.324947 -235.075215) (xy 381.313085 -235.023251) (xy 381.309102 -234.9701)
			(xy 381.313085 -234.916949) (xy 381.324947 -234.864985) (xy 381.344421 -234.815369) (xy 381.371072 -234.76921)
			(xy 381.404306 -234.72754) (xy 381.44338 -234.691288) (xy 381.487421 -234.661266) (xy 381.535444 -234.638143)
			(xy 381.586378 -234.622436) (xy 381.639084 -234.614497) (xy 381.665734 -234.613958) (xy 381.680598 -234.614081)
			(xy 381.710228 -234.616498) (xy 381.724916 -234.618784) (xy 381.739516 -234.620715) (xy 381.768726 -234.617072)
			(xy 381.795688 -234.605257) (xy 381.818166 -234.586249) (xy 381.834296 -234.561625) (xy 381.842741 -234.533425)
			(xy 381.84328 -234.518708) (xy 381.84328 -234.359704) (xy 381.82822 -234.33719) (xy 381.804368 -234.288561)
			(xy 381.788171 -234.236876) (xy 381.780004 -234.183332) (xy 381.779526 -234.15625) (xy 381.78004 -234.129173)
			(xy 381.788244 -234.075643) (xy 381.804442 -234.023968) (xy 381.828262 -233.975333) (xy 381.84328 -233.952796)
			(xy 381.84328 -233.793538) (xy 381.842789 -233.778812) (xy 381.834381 -233.750586) (xy 381.818255 -233.725941)
			(xy 381.795758 -233.706934) (xy 381.768766 -233.695151) (xy 381.739532 -233.691575) (xy 381.724916 -233.693462)
			(xy 381.710228 -233.695748) (xy 381.680598 -233.698161) (xy 381.665734 -233.698288) (xy 381.639083 -233.697817)
			(xy 381.586375 -233.689877) (xy 381.535439 -233.67417) (xy 381.487414 -233.651046) (xy 381.443371 -233.621023)
			(xy 381.404296 -233.58477) (xy 381.371061 -233.543097) (xy 381.344408 -233.496937) (xy 381.324933 -233.447319)
			(xy 381.313072 -233.395353) (xy 381.309088 -233.3422) (xy 381.313072 -233.289047) (xy 381.324933 -233.237081)
			(xy 381.344408 -233.187463) (xy 381.371061 -233.141303) (xy 381.404296 -233.09963) (xy 381.443371 -233.063377)
			(xy 381.487414 -233.033354) (xy 381.535439 -233.01023) (xy 381.586375 -232.994523) (xy 381.639083 -232.986583)
			(xy 381.665734 -232.986072) (xy 381.680598 -232.986195) (xy 381.710228 -232.988612) (xy 381.724916 -232.990898)
			(xy 381.739516 -232.992829) (xy 381.768728 -232.989186) (xy 381.795691 -232.977371) (xy 381.818171 -232.958364)
			(xy 381.834304 -232.93374) (xy 381.842753 -232.90554) (xy 381.84328 -232.890822) (xy 381.84328 -232.731818)
			(xy 381.828235 -232.709332) (xy 381.8044 -232.660765) (xy 381.788202 -232.609146) (xy 381.780014 -232.555668)
			(xy 381.779526 -232.528618) (xy 381.779526 -232.528364) (xy 381.779983 -232.503109) (xy 381.787153 -232.453108)
			(xy 381.801314 -232.404623) (xy 381.822184 -232.358624) (xy 381.835406 -232.337102) (xy 381.84328 -232.324402)
			(xy 381.84328 -232.247948) (xy 381.666496 -232.071164) (xy 381.646938 -232.070148) (xy 381.620895 -232.068316)
			(xy 381.569721 -232.057985) (xy 381.520604 -232.040292) (xy 381.474596 -232.015619) (xy 381.432683 -231.984494)
			(xy 381.395763 -231.947583) (xy 381.364627 -231.905677) (xy 381.339943 -231.859675) (xy 381.322239 -231.810562)
			(xy 381.311894 -231.759391) (xy 381.310134 -231.733344) (xy 381.309118 -231.713786) (xy 381.254762 -231.65943)
			(xy 381.243956 -231.649384) (xy 381.217975 -231.635426) (xy 381.189091 -231.629467) (xy 381.159708 -231.632005)
			(xy 381.132272 -231.642826) (xy 381.109069 -231.661031) (xy 381.09203 -231.685103) (xy 381.082573 -231.713038)
			(xy 381.081534 -231.727756) (xy 381.08002 -231.755039) (xy 381.069668 -231.808689) (xy 381.051243 -231.860129)
			(xy 381.025176 -231.90815) (xy 380.992079 -231.951625) (xy 380.952729 -231.989534) (xy 380.90805 -232.020987)
			(xy 380.85909 -232.045246) (xy 380.806999 -232.061741) (xy 380.753 -232.070085) (xy 380.72568 -232.070656)
			(xy 380.697697 -232.070106) (xy 380.642419 -232.061348) (xy 380.589192 -232.044053) (xy 380.539325 -232.018644)
			(xy 380.494046 -231.985749) (xy 380.45447 -231.946176) (xy 380.42157 -231.900899) (xy 380.396158 -231.851034)
			(xy 380.378858 -231.797808) (xy 380.370097 -231.742531) (xy 380.369572 -231.714548) (xy 380.370066 -231.687222)
			(xy 380.378409 -231.633209) (xy 380.394905 -231.581106) (xy 380.419168 -231.532134) (xy 380.450627 -231.487444)
			(xy 380.488545 -231.448085) (xy 380.532031 -231.41498) (xy 380.580064 -231.388909) (xy 380.631517 -231.370481)
			(xy 380.68518 -231.360131) (xy 380.712472 -231.358694) (xy 380.727213 -231.35769) (xy 380.755205 -231.348277)
			(xy 380.779334 -231.331248) (xy 380.797581 -231.308026) (xy 380.808421 -231.280555) (xy 380.810946 -231.25113)
			(xy 380.804947 -231.222213) (xy 380.790924 -231.196222) (xy 380.780798 -231.185466) (xy 380.695708 -231.100376)
			(xy 380.685042 -231.090422) (xy 380.659404 -231.07652) (xy 380.630884 -231.070424) (xy 380.601804 -231.072631)
			(xy 380.57453 -231.082961) (xy 380.551285 -231.100574) (xy 380.542292 -231.11206) (xy 380.525364 -231.134058)
			(xy 380.485841 -231.173029) (xy 380.440756 -231.205402) (xy 380.391197 -231.230396) (xy 380.338364 -231.247407)
			(xy 380.283532 -231.256022) (xy 380.25578 -231.256586) (xy 380.227796 -231.256064) (xy 380.172518 -231.247306)
			(xy 380.119291 -231.230008) (xy 380.069425 -231.204596) (xy 380.024149 -231.171697) (xy 379.984576 -231.132119)
			(xy 379.951682 -231.086839) (xy 379.926276 -231.03697) (xy 379.908985 -230.983741) (xy 379.900233 -230.928462)
			(xy 379.899672 -230.900478) (xy 379.900197 -230.872722) (xy 379.908798 -230.817881) (xy 379.925805 -230.765038)
			(xy 379.950805 -230.715475) (xy 379.983192 -230.67039) (xy 380.022183 -230.630877) (xy 380.044198 -230.613966)
			(xy 380.055672 -230.604943) (xy 380.073332 -230.581715) (xy 380.083696 -230.55444) (xy 380.085919 -230.525346)
			(xy 380.079817 -230.496813) (xy 380.065891 -230.471173) (xy 380.055882 -230.46055) (xy 379.981714 -230.386382)
			(xy 379.948948 -230.4034) (xy 379.923621 -230.415808) (xy 379.870024 -230.433356) (xy 379.814332 -230.442244)
			(xy 379.786134 -230.44277) (xy 379.758148 -230.442252) (xy 379.702865 -230.4335) (xy 379.649631 -230.416207)
			(xy 379.599759 -230.390798) (xy 379.554476 -230.357899) (xy 379.514898 -230.318321) (xy 379.482 -230.273038)
			(xy 379.456592 -230.223165) (xy 379.439299 -230.169932) (xy 379.430548 -230.114648) (xy 379.430026 -230.086662)
			(xy 379.430565 -230.058465) (xy 379.439453 -230.002775) (xy 379.457 -229.94918) (xy 379.469396 -229.923848)
			(xy 379.486414 -229.891082) (xy 379.207522 -229.61219) (xy 379.1966 -229.60838) (xy 379.171975 -229.599103)
			(xy 379.125547 -229.574339) (xy 379.083266 -229.543015) (xy 379.046052 -229.505812) (xy 379.014716 -229.46354)
			(xy 378.989939 -229.417118) (xy 378.9807 -229.39248) (xy 378.97689 -229.381558) (xy 378.895102 -229.29977)
			(xy 378.885161 -229.290494) (xy 378.861517 -229.277092) (xy 378.835175 -229.270398) (xy 378.808001 -229.270884)
			(xy 378.781916 -229.278517) (xy 378.758765 -229.292756) (xy 378.740188 -229.312595) (xy 378.727497 -229.336629)
			(xy 378.72416 -229.349808) (xy 378.717903 -229.375855) (xy 378.698628 -229.425835) (xy 378.672084 -229.472363)
			(xy 378.63887 -229.51439) (xy 378.599735 -229.550968) (xy 378.555562 -229.581271) (xy 378.507349 -229.604614)
			(xy 378.456182 -229.620472) (xy 378.403218 -229.628487) (xy 378.376434 -229.628954) (xy 378.348448 -229.628408)
			(xy 378.293164 -229.619657) (xy 378.239929 -229.602366) (xy 378.190055 -229.576961) (xy 378.144769 -229.544066)
			(xy 378.105186 -229.504492) (xy 378.072281 -229.459213) (xy 378.046864 -229.409345) (xy 378.029562 -229.356114)
			(xy 378.020799 -229.300832) (xy 378.020326 -229.272846) (xy 378.020813 -229.246066) (xy 378.028841 -229.19311)
			(xy 378.044707 -229.141954) (xy 378.068054 -229.09375) (xy 378.098356 -229.049585) (xy 378.134929 -229.010456)
			(xy 378.176949 -228.977243) (xy 378.223468 -228.950697) (xy 378.273437 -228.931416) (xy 378.299472 -228.92512)
			(xy 378.31267 -228.921789) (xy 378.336766 -228.909153) (xy 378.356662 -228.890593) (xy 378.37094 -228.86743)
			(xy 378.378581 -228.841316) (xy 378.379043 -228.814111) (xy 378.372292 -228.787753) (xy 378.358808 -228.76412)
			(xy 378.34951 -228.754178) (xy 378.304044 -228.708712) (xy 378.29429 -228.699534) (xy 378.271083 -228.686181)
			(xy 378.245203 -228.679319) (xy 378.218429 -228.679421) (xy 378.192601 -228.686479) (xy 378.169496 -228.700008)
			(xy 378.159772 -228.70922) (xy 378.139557 -228.728918) (xy 378.094058 -228.762315) (xy 378.043866 -228.788125)
			(xy 377.990233 -228.805703) (xy 377.9345 -228.81461) (xy 377.90628 -228.815138) (xy 377.878297 -228.814588)
			(xy 377.823021 -228.80583) (xy 377.769794 -228.788534) (xy 377.719929 -228.763126) (xy 377.674651 -228.73023)
			(xy 377.635077 -228.690656) (xy 377.60218 -228.64538) (xy 377.57677 -228.595515) (xy 377.559472 -228.542289)
			(xy 377.550713 -228.487013) (xy 377.550172 -228.45903) (xy 377.550708 -228.43081) (xy 377.559603 -228.375074)
			(xy 377.577176 -228.321439) (xy 377.602986 -228.271246) (xy 377.636389 -228.22575) (xy 377.65609 -228.205538)
			(xy 377.665347 -228.195848) (xy 377.678885 -228.172729) (xy 377.685948 -228.146887) (xy 377.686052 -228.120096)
			(xy 377.679188 -228.0942) (xy 377.66583 -228.070978) (xy 377.656598 -228.061266) (xy 377.571254 -227.975922)
			(xy 377.542044 -227.985066) (xy 377.516337 -227.992551) (xy 377.463404 -228.000588) (xy 377.436634 -228.001068)
			(xy 377.408648 -228.00055) (xy 377.353365 -227.991798) (xy 377.300131 -227.974505) (xy 377.250259 -227.949096)
			(xy 377.204977 -227.916197) (xy 377.165399 -227.876619) (xy 377.132501 -227.831336) (xy 377.107093 -227.781463)
			(xy 377.0898 -227.728229) (xy 377.08105 -227.672946) (xy 377.080526 -227.64496) (xy 377.081027 -227.618192)
			(xy 377.089059 -227.56526) (xy 377.096528 -227.53955) (xy 377.105672 -227.51034) (xy 376.524012 -226.92868)
			(xy 376.51351 -226.918853) (xy 376.488333 -226.904975) (xy 376.460283 -226.898678) (xy 376.431591 -226.900462)
			(xy 376.404537 -226.910185) (xy 376.381273 -226.927075) (xy 376.36365 -226.949789) (xy 376.357896 -226.96297)
			(xy 376.347606 -226.98744) (xy 376.320838 -227.033279) (xy 376.287567 -227.074641) (xy 376.248529 -227.11061)
			(xy 376.204588 -227.14039) (xy 376.156715 -227.163323) (xy 376.10597 -227.178902) (xy 376.053475 -227.18678)
			(xy 376.026934 -227.187252) (xy 375.998948 -227.186706) (xy 375.943664 -227.177955) (xy 375.89043 -227.160664)
			(xy 375.840555 -227.135259) (xy 375.79527 -227.102364) (xy 375.755687 -227.06279) (xy 375.722782 -227.017511)
			(xy 375.697366 -226.967643) (xy 375.680063 -226.914412) (xy 375.671301 -226.85913) (xy 375.670826 -226.831144)
			(xy 375.671312 -226.804602) (xy 375.679182 -226.752106) (xy 375.694753 -226.701358) (xy 375.717682 -226.653483)
			(xy 375.747461 -226.609539) (xy 375.78343 -226.5705) (xy 375.824793 -226.53723) (xy 375.870635 -226.510466)
			(xy 375.895108 -226.500182) (xy 375.908249 -226.49439) (xy 375.930875 -226.476727) (xy 375.947698 -226.453469)
			(xy 375.957388 -226.42645) (xy 375.959183 -226.397801) (xy 375.952939 -226.369784) (xy 375.939151 -226.344608)
			(xy 375.929398 -226.334066) (xy 375.83745 -226.242118) (xy 375.801636 -226.276154) (xy 375.781687 -226.294321)
			(xy 375.737331 -226.325039) (xy 375.688848 -226.348711) (xy 375.637348 -226.364798) (xy 375.584011 -226.372929)
			(xy 375.557034 -226.373436) (xy 375.5307 -226.372965) (xy 375.478604 -226.365215) (xy 375.428217 -226.349879)
			(xy 375.380638 -226.327291) (xy 375.336903 -226.297944) (xy 375.297965 -226.262478) (xy 375.264674 -226.221665)
			(xy 375.237755 -226.176395) (xy 375.227342 -226.152202) (xy 375.19243 -226.157064) (xy 375.122127 -226.162274)
			(xy 375.08688 -226.162616) (xy 375.05176 -226.162264) (xy 374.981712 -226.157051) (xy 374.946926 -226.152202)
			(xy 374.936501 -226.176388) (xy 374.909572 -226.221649) (xy 374.876278 -226.262456) (xy 374.837341 -226.297919)
			(xy 374.79361 -226.327267) (xy 374.746037 -226.349862) (xy 374.695657 -226.36521) (xy 374.643567 -226.372979)
			(xy 374.617234 -226.373436) (xy 374.591821 -226.372979) (xy 374.541514 -226.365742) (xy 374.492747 -226.351424)
			(xy 374.446512 -226.330317) (xy 374.403748 -226.302849) (xy 374.365325 -226.269579) (xy 374.332024 -226.231183)
			(xy 374.304522 -226.188442) (xy 374.283377 -226.142224) (xy 374.26902 -226.093468) (xy 374.264936 -226.068382)
			(xy 374.258586 -226.024948) (xy 374.036082 -226.024948) (xy 374.029732 -226.068382) (xy 374.025683 -226.09348)
			(xy 374.011351 -226.142257) (xy 373.990223 -226.188497) (xy 373.962727 -226.231259) (xy 373.929424 -226.269671)
			(xy 373.890992 -226.302951) (xy 373.848215 -226.330422) (xy 373.801963 -226.351524) (xy 373.753178 -226.365827)
			(xy 373.702853 -226.37304) (xy 373.677434 -226.373436) (xy 373.6511 -226.372965) (xy 373.599004 -226.365215)
			(xy 373.548617 -226.349879) (xy 373.501038 -226.327291) (xy 373.457303 -226.297944) (xy 373.418365 -226.262478)
			(xy 373.385074 -226.221665) (xy 373.358155 -226.176395) (xy 373.347742 -226.152202) (xy 373.31283 -226.157064)
			(xy 373.242527 -226.162274) (xy 373.20728 -226.162616) (xy 373.17216 -226.162264) (xy 373.102112 -226.157051)
			(xy 373.067326 -226.152202) (xy 373.056901 -226.176388) (xy 373.029972 -226.221649) (xy 372.996678 -226.262456)
			(xy 372.957741 -226.297919) (xy 372.91401 -226.327267) (xy 372.866437 -226.349862) (xy 372.816057 -226.36521)
			(xy 372.763967 -226.372979) (xy 372.737634 -226.373436) (xy 372.712221 -226.372979) (xy 372.661914 -226.365742)
			(xy 372.613147 -226.351424) (xy 372.566912 -226.330317) (xy 372.524148 -226.302849) (xy 372.485725 -226.269579)
			(xy 372.452424 -226.231183) (xy 372.424922 -226.188442) (xy 372.403777 -226.142224) (xy 372.38942 -226.093468)
			(xy 372.385336 -226.068382) (xy 372.378986 -226.024948) (xy 372.156482 -226.024948) (xy 372.150132 -226.068382)
			(xy 372.146083 -226.09348) (xy 372.131751 -226.142257) (xy 372.110623 -226.188497) (xy 372.083127 -226.231259)
			(xy 372.049824 -226.269671) (xy 372.011392 -226.302951) (xy 371.968615 -226.330422) (xy 371.922363 -226.351524)
			(xy 371.873578 -226.365827) (xy 371.823253 -226.37304) (xy 371.797834 -226.373436) (xy 371.7715 -226.372965)
			(xy 371.719404 -226.365215) (xy 371.669017 -226.349879) (xy 371.621438 -226.327291) (xy 371.577703 -226.297944)
			(xy 371.538765 -226.262478) (xy 371.505474 -226.221665) (xy 371.478555 -226.176395) (xy 371.468142 -226.152202)
			(xy 371.43323 -226.157064) (xy 371.362927 -226.162274) (xy 371.32768 -226.162616) (xy 371.29256 -226.162264)
			(xy 371.222512 -226.157051) (xy 371.187726 -226.152202) (xy 371.177301 -226.176388) (xy 371.150372 -226.221649)
			(xy 371.117078 -226.262456) (xy 371.078141 -226.297919) (xy 371.03441 -226.327267) (xy 370.986837 -226.349862)
			(xy 370.936457 -226.36521) (xy 370.884367 -226.372979) (xy 370.858034 -226.373436) (xy 370.832621 -226.372979)
			(xy 370.782314 -226.365742) (xy 370.733547 -226.351424) (xy 370.687312 -226.330317) (xy 370.644548 -226.302849)
			(xy 370.606125 -226.269579) (xy 370.572824 -226.231183) (xy 370.545322 -226.188442) (xy 370.524177 -226.142224)
			(xy 370.50982 -226.093468) (xy 370.505736 -226.068382) (xy 370.499386 -226.024948) (xy 370.276882 -226.024948)
			(xy 370.270532 -226.068382) (xy 370.266483 -226.09348) (xy 370.252151 -226.142257) (xy 370.231023 -226.188497)
			(xy 370.203527 -226.231259) (xy 370.170224 -226.269671) (xy 370.131792 -226.302951) (xy 370.089015 -226.330422)
			(xy 370.042763 -226.351524) (xy 369.993978 -226.365827) (xy 369.943653 -226.37304) (xy 369.918234 -226.373436)
			(xy 369.8919 -226.372965) (xy 369.839804 -226.365215) (xy 369.789417 -226.349879) (xy 369.741838 -226.327291)
			(xy 369.698103 -226.297944) (xy 369.659165 -226.262478) (xy 369.625874 -226.221665) (xy 369.598955 -226.176395)
			(xy 369.588542 -226.152202) (xy 369.55363 -226.157064) (xy 369.483327 -226.162274) (xy 369.44808 -226.162616)
			(xy 369.41296 -226.162264) (xy 369.342912 -226.157051) (xy 369.308126 -226.152202) (xy 369.297701 -226.176388)
			(xy 369.270772 -226.221649) (xy 369.237478 -226.262456) (xy 369.198541 -226.297919) (xy 369.15481 -226.327267)
			(xy 369.107237 -226.349862) (xy 369.056857 -226.36521) (xy 369.004767 -226.372979) (xy 368.978434 -226.373436)
			(xy 368.953021 -226.372979) (xy 368.902714 -226.365742) (xy 368.853947 -226.351424) (xy 368.807712 -226.330317)
			(xy 368.764948 -226.302849) (xy 368.726525 -226.269579) (xy 368.693224 -226.231183) (xy 368.665722 -226.188442)
			(xy 368.644577 -226.142224) (xy 368.63022 -226.093468) (xy 368.626136 -226.068382) (xy 368.619786 -226.024948)
			(xy 368.397282 -226.024948) (xy 368.390932 -226.068382) (xy 368.386883 -226.09348) (xy 368.372551 -226.142257)
			(xy 368.351423 -226.188497) (xy 368.323927 -226.231259) (xy 368.290624 -226.269671) (xy 368.252192 -226.302951)
			(xy 368.209415 -226.330422) (xy 368.163163 -226.351524) (xy 368.114378 -226.365827) (xy 368.064053 -226.37304)
			(xy 368.038634 -226.373436) (xy 368.010646 -226.372919) (xy 367.955359 -226.364167) (xy 367.902121 -226.346875)
			(xy 367.852244 -226.321467) (xy 367.806956 -226.288569) (xy 367.767371 -226.248992) (xy 367.734466 -226.203709)
			(xy 367.709049 -226.153836) (xy 367.691747 -226.100602) (xy 367.682986 -226.045316) (xy 367.682526 -226.017328)
			(xy 367.683022 -225.99035) (xy 367.691156 -225.937011) (xy 367.707242 -225.885509) (xy 367.730912 -225.837022)
			(xy 367.761625 -225.792661) (xy 367.779808 -225.772726) (xy 367.813844 -225.736912) (xy 367.631472 -225.55454)
			(xy 367.607342 -225.557334) (xy 367.597657 -225.558314) (xy 367.578215 -225.559333) (xy 367.56848 -225.559366)
			(xy 367.540497 -225.558844) (xy 367.48522 -225.550085) (xy 367.431994 -225.532787) (xy 367.38213 -225.507375)
			(xy 367.336855 -225.474476) (xy 367.297284 -225.434898) (xy 367.264392 -225.389617) (xy 367.238989 -225.339748)
			(xy 367.2217 -225.286519) (xy 367.212951 -225.231241) (xy 367.212372 -225.203258) (xy 367.21242 -225.193524)
			(xy 367.213438 -225.174082) (xy 367.214404 -225.164396) (xy 367.217198 -225.140266) (xy 367.06048 -224.983548)
			(xy 367.06048 -224.745804) (xy 367.020856 -224.736914) (xy 366.994881 -224.730597) (xy 366.945055 -224.711234)
			(xy 366.898683 -224.684642) (xy 366.856806 -224.651418) (xy 366.820364 -224.612309) (xy 366.790177 -224.568192)
			(xy 366.766922 -224.52006) (xy 366.751122 -224.468992) (xy 366.743132 -224.416137) (xy 366.74313 -224.362681)
			(xy 366.751118 -224.309826) (xy 366.766916 -224.258757) (xy 366.790168 -224.210624) (xy 366.820353 -224.166506)
			(xy 366.856792 -224.127394) (xy 366.898668 -224.094168) (xy 366.945039 -224.067574) (xy 366.994863 -224.048208)
			(xy 367.020856 -224.04197) (xy 367.06048 -224.03308) (xy 367.06048 -223.892364) (xy 367.059882 -223.877256)
			(xy 367.050954 -223.848385) (xy 367.033977 -223.823385) (xy 367.010433 -223.804439) (xy 366.982381 -223.793201)
			(xy 366.952268 -223.790654) (xy 366.922727 -223.797019) (xy 366.896335 -223.811742) (xy 366.885474 -223.82226)
			(xy 366.864266 -223.84347) (xy 366.816078 -223.879176) (xy 366.762588 -223.906303) (xy 366.705309 -223.924083)
			(xy 366.67567 -223.928686) (xy 366.650778 -223.931988) (xy 366.478566 -224.230438) (xy 366.488218 -224.253552)
			(xy 366.496733 -224.275184) (xy 366.508716 -224.320102) (xy 366.514757 -224.366197) (xy 366.515142 -224.389442)
			(xy 366.514644 -224.416091) (xy 366.506701 -224.468795) (xy 366.490991 -224.519725) (xy 366.467865 -224.567746)
			(xy 366.437841 -224.611783) (xy 366.401589 -224.650854) (xy 366.359918 -224.684085) (xy 366.31376 -224.710734)
			(xy 366.264146 -224.730206) (xy 366.212184 -224.742066) (xy 366.159034 -224.74605) (xy 366.105884 -224.742066)
			(xy 366.053922 -224.730206) (xy 366.004308 -224.710734) (xy 365.95815 -224.684085) (xy 365.916479 -224.650854)
			(xy 365.880227 -224.611783) (xy 365.850203 -224.567746) (xy 365.827077 -224.519725) (xy 365.811367 -224.468795)
			(xy 365.803424 -224.416091) (xy 365.802926 -224.389442) (xy 365.803375 -224.363816) (xy 365.810728 -224.313094)
			(xy 365.825272 -224.263949) (xy 365.846709 -224.217395) (xy 365.874595 -224.174393) (xy 365.908355 -224.135831)
			(xy 365.947293 -224.102505) (xy 365.990604 -224.075102) (xy 366.037395 -224.054188) (xy 366.0867 -224.040194)
			(xy 366.112044 -224.036382) (xy 366.136682 -224.03308) (xy 366.308894 -223.734376) (xy 366.299496 -223.711516)
			(xy 366.290977 -223.689885) (xy 366.278984 -223.644967) (xy 366.272935 -223.598871) (xy 366.272572 -223.575626)
			(xy 366.27309 -223.547639) (xy 366.281842 -223.492353) (xy 366.299136 -223.439117) (xy 366.324544 -223.389241)
			(xy 366.357442 -223.343955) (xy 366.39702 -223.304372) (xy 366.442302 -223.271468) (xy 366.492174 -223.246053)
			(xy 366.545408 -223.228753) (xy 366.600693 -223.219994) (xy 366.62868 -223.219518) (xy 366.657385 -223.220064)
			(xy 366.714051 -223.229273) (xy 366.768505 -223.247457) (xy 366.819335 -223.274143) (xy 366.865224 -223.30864)
			(xy 366.885474 -223.328992) (xy 366.896332 -223.339537) (xy 366.92273 -223.354309) (xy 366.952295 -223.360709)
			(xy 366.982439 -223.358175) (xy 367.010522 -223.34693) (xy 367.034084 -223.327958) (xy 367.051062 -223.302922)
			(xy 367.059969 -223.274012) (xy 367.06048 -223.258888) (xy 367.06048 -223.117918) (xy 367.020856 -223.109028)
			(xy 366.994887 -223.102711) (xy 366.945074 -223.08335) (xy 366.898714 -223.056762) (xy 366.856849 -223.023544)
			(xy 366.820418 -222.984442) (xy 366.79024 -222.940334) (xy 366.766994 -222.892212) (xy 366.7512 -222.841155)
			(xy 366.743214 -222.788312) (xy 366.743215 -222.734869) (xy 366.751204 -222.682026) (xy 366.767001 -222.630971)
			(xy 366.79025 -222.582849) (xy 366.82043 -222.538743) (xy 366.856863 -222.499643) (xy 366.89873 -222.466427)
			(xy 366.945092 -222.439841) (xy 366.994906 -222.420483) (xy 367.020856 -222.414084) (xy 367.06048 -222.405194)
			(xy 367.06048 -221.490286) (xy 367.020856 -221.481396) (xy 366.994883 -221.47508) (xy 366.945062 -221.455718)
			(xy 366.898694 -221.429128) (xy 366.85682 -221.395908) (xy 366.820381 -221.356802) (xy 366.790196 -221.31269)
			(xy 366.766942 -221.264562) (xy 366.751142 -221.2135) (xy 366.74315 -221.16065) (xy 366.742726 -221.133924)
			(xy 366.7431 -221.110679) (xy 366.749142 -221.064583) (xy 366.761128 -221.019664) (xy 366.76965 -220.998034)
			(xy 366.779302 -220.97492) (xy 366.606836 -220.676216) (xy 366.581944 -220.672914) (xy 366.556582 -220.669111)
			(xy 366.507231 -220.655168) (xy 366.46039 -220.634289) (xy 366.417029 -220.606906) (xy 366.378045 -220.573587)
			(xy 366.344243 -220.535019) (xy 366.316325 -220.492002) (xy 366.294866 -220.445424) (xy 366.28031 -220.396249)
			(xy 366.27296 -220.345496) (xy 366.272572 -220.319854) (xy 366.273124 -220.291873) (xy 366.281885 -220.2366)
			(xy 366.299183 -220.183378) (xy 366.324594 -220.133516) (xy 366.35749 -220.088243) (xy 366.397063 -220.048673)
			(xy 366.442339 -220.01578) (xy 366.492202 -219.990373) (xy 366.545425 -219.973079) (xy 366.600699 -219.964322)
			(xy 366.62868 -219.963746) (xy 366.657385 -219.964292) (xy 366.71405 -219.973502) (xy 366.768503 -219.991686)
			(xy 366.819332 -220.018374) (xy 366.865219 -220.052873) (xy 366.885474 -220.07322) (xy 366.896333 -220.083762)
			(xy 366.922733 -220.098531) (xy 366.952299 -220.104928) (xy 366.982443 -220.102394) (xy 367.010526 -220.09115)
			(xy 367.034089 -220.072181) (xy 367.051071 -220.047147) (xy 367.059984 -220.01824) (xy 367.06048 -220.003116)
			(xy 367.06048 -219.8624) (xy 367.020856 -219.85351) (xy 366.994881 -219.847193) (xy 366.945056 -219.82783)
			(xy 366.898684 -219.801238) (xy 366.856808 -219.768015) (xy 366.820367 -219.728906) (xy 366.79018 -219.68479)
			(xy 366.766926 -219.636658) (xy 366.751126 -219.585591) (xy 366.743136 -219.532736) (xy 366.743134 -219.479281)
			(xy 366.751122 -219.426426) (xy 366.76692 -219.375358) (xy 366.790172 -219.327225) (xy 366.820356 -219.283107)
			(xy 366.856795 -219.243997) (xy 366.898671 -219.210771) (xy 366.945041 -219.184177) (xy 366.994865 -219.164812)
			(xy 367.020856 -219.158566) (xy 367.06048 -219.149676) (xy 367.06048 -218.234768) (xy 367.020856 -218.225878)
			(xy 366.994884 -218.219561) (xy 366.945064 -218.200199) (xy 366.898697 -218.173609) (xy 366.856825 -218.140388)
			(xy 366.820388 -218.101282) (xy 366.790205 -218.05717) (xy 366.766953 -218.009043) (xy 366.751156 -217.957981)
			(xy 366.743167 -217.905131) (xy 366.742726 -217.878406) (xy 366.743101 -217.855161) (xy 366.749146 -217.809066)
			(xy 366.761133 -217.764148) (xy 366.76965 -217.742516) (xy 366.779302 -217.719402) (xy 366.606836 -217.420698)
			(xy 366.581944 -217.417396) (xy 366.556583 -217.413593) (xy 366.507232 -217.399649) (xy 366.460393 -217.37877)
			(xy 366.417033 -217.351387) (xy 366.378051 -217.318067) (xy 366.344251 -217.2795) (xy 366.316334 -217.236482)
			(xy 366.294877 -217.189904) (xy 366.280324 -217.14073) (xy 366.272977 -217.089977) (xy 366.272572 -217.064336)
			(xy 366.273089 -217.036348) (xy 366.28184 -216.981061) (xy 366.299133 -216.927824) (xy 366.324541 -216.877947)
			(xy 366.357439 -216.832659) (xy 366.397016 -216.793075) (xy 366.442299 -216.76017) (xy 366.492172 -216.734754)
			(xy 366.545406 -216.717454) (xy 366.600692 -216.708694) (xy 366.62868 -216.708228) (xy 366.657385 -216.708774)
			(xy 366.714051 -216.717983) (xy 366.768504 -216.736167) (xy 366.819334 -216.762854) (xy 366.865223 -216.797352)
			(xy 366.885474 -216.817702) (xy 366.896332 -216.828246) (xy 366.922731 -216.843017) (xy 366.952297 -216.849416)
			(xy 366.982441 -216.846882) (xy 367.010523 -216.835637) (xy 367.034086 -216.816666) (xy 367.051065 -216.791631)
			(xy 367.059974 -216.762722) (xy 367.06048 -216.747598) (xy 367.06048 -216.606882) (xy 367.020856 -216.597992)
			(xy 366.994882 -216.591675) (xy 366.94506 -216.572313) (xy 366.898691 -216.545722) (xy 366.856817 -216.512499)
			(xy 366.820378 -216.473392) (xy 366.790193 -216.429277) (xy 366.766941 -216.381147) (xy 366.751142 -216.330083)
			(xy 366.743153 -216.277231) (xy 366.743152 -216.223778) (xy 366.75114 -216.170926) (xy 366.766937 -216.119861)
			(xy 366.790189 -216.07173) (xy 366.820373 -216.027615) (xy 366.85681 -215.988507) (xy 366.898684 -215.955283)
			(xy 366.945052 -215.928691) (xy 366.994874 -215.909327) (xy 367.020856 -215.903048) (xy 367.06048 -215.894158)
			(xy 367.06048 -206.416148) (xy 388.75208 -184.724548) (xy 408.97048 -184.724548) (xy 409.07589 -184.619138)
			(xy 409.023058 -184.56656) (xy 408.999436 -184.568592) (xy 408.9654 -184.570116) (xy 408.938148 -184.56963)
			(xy 408.884199 -184.561874) (xy 408.831903 -184.546518) (xy 408.782325 -184.523876) (xy 408.736474 -184.49441)
			(xy 408.695283 -184.458717) (xy 408.65959 -184.417526) (xy 408.630124 -184.371675) (xy 408.607482 -184.322097)
			(xy 408.592126 -184.269801) (xy 408.58437 -184.215852) (xy 408.58437 -184.161348) (xy 408.592126 -184.107399)
			(xy 408.607482 -184.055103) (xy 408.630124 -184.005525) (xy 408.65959 -183.959674) (xy 408.695283 -183.918483)
			(xy 408.736474 -183.88279) (xy 408.782325 -183.853324) (xy 408.831903 -183.830682) (xy 408.884199 -183.815326)
			(xy 408.938148 -183.80757) (xy 408.9654 -183.8071) (xy 408.992238 -183.807563) (xy 409.045382 -183.815097)
			(xy 409.096947 -183.830001) (xy 409.145915 -183.851983) (xy 409.19132 -183.880608) (xy 409.232268 -183.915313)
			(xy 409.26795 -183.955411) (xy 409.297662 -184.000113) (xy 409.320819 -184.048537) (xy 409.336963 -184.099727)
			(xy 409.341828 -184.126124) (xy 409.344569 -184.139783) (xy 409.356445 -184.164974) (xy 409.374679 -184.186024)
			(xy 409.397918 -184.201371) (xy 409.424437 -184.209875) (xy 409.452267 -184.210906) (xy 409.479343 -184.204387)
			(xy 409.503654 -184.190801) (xy 409.513786 -184.181242) (xy 409.63088 -184.064148) (xy 409.63088 -182.773066)
			(xy 409.593796 -182.762652) (xy 409.567449 -182.754755) (xy 409.517178 -182.732437) (xy 409.470634 -182.70313)
			(xy 409.428782 -182.667442) (xy 409.39249 -182.626112) (xy 409.36251 -182.579999) (xy 409.339463 -182.530058)
			(xy 409.323829 -182.477325) (xy 409.31593 -182.422892) (xy 409.315931 -182.36789) (xy 409.323832 -182.313458)
			(xy 409.339469 -182.260726) (xy 409.362518 -182.210786) (xy 409.3925 -182.164674) (xy 409.428794 -182.123346)
			(xy 409.470648 -182.08766) (xy 409.517193 -182.058355) (xy 409.567465 -182.036039) (xy 409.593796 -182.028084)
			(xy 409.63088 -182.01767) (xy 409.63088 -176.745646) (xy 409.593796 -176.735232) (xy 409.56745 -176.727331)
			(xy 409.517182 -176.705004) (xy 409.470641 -176.675691) (xy 409.428792 -176.639999) (xy 409.392501 -176.598668)
			(xy 409.362521 -176.552554) (xy 409.339473 -176.502614) (xy 409.323834 -176.449881) (xy 409.315929 -176.395449)
			(xy 409.315412 -176.367948) (xy 409.315929 -176.339208) (xy 409.324546 -176.282376) (xy 409.341591 -176.227481)
			(xy 409.366679 -176.175765) (xy 409.399242 -176.128397) (xy 409.418536 -176.10709) (xy 409.428618 -176.095557)
			(xy 409.441978 -176.068007) (xy 409.446577 -176.037735) (xy 409.441999 -176.00746) (xy 409.428658 -175.979901)
			(xy 409.418536 -175.968406) (xy 409.399262 -175.94708) (xy 409.36669 -175.89972) (xy 409.341591 -175.848008)
			(xy 409.324533 -175.793117) (xy 409.315903 -175.736288) (xy 409.315412 -175.707548) (xy 409.31589 -175.680042)
			(xy 409.323785 -175.6256) (xy 409.339418 -175.572857) (xy 409.362464 -175.522905) (xy 409.392447 -175.476782)
			(xy 409.428743 -175.435444) (xy 409.470601 -175.399748) (xy 409.517151 -175.370435) (xy 409.56743 -175.348112)
			(xy 409.593796 -175.340264) (xy 409.63088 -175.32985) (xy 409.63088 -174.137066) (xy 409.593796 -174.126652)
			(xy 409.567449 -174.118755) (xy 409.517178 -174.096437) (xy 409.470634 -174.06713) (xy 409.428782 -174.031442)
			(xy 409.39249 -173.990112) (xy 409.36251 -173.943999) (xy 409.339463 -173.894058) (xy 409.323829 -173.841325)
			(xy 409.31593 -173.786892) (xy 409.315931 -173.73189) (xy 409.323832 -173.677458) (xy 409.339469 -173.624726)
			(xy 409.362518 -173.574786) (xy 409.3925 -173.528674) (xy 409.428794 -173.487346) (xy 409.470648 -173.45166)
			(xy 409.517193 -173.422355) (xy 409.567465 -173.400039) (xy 409.593796 -173.392084) (xy 409.63088 -173.38167)
			(xy 409.63088 -168.109646) (xy 409.593796 -168.099232) (xy 409.56745 -168.091331) (xy 409.517182 -168.069004)
			(xy 409.470641 -168.039691) (xy 409.428792 -168.003999) (xy 409.392501 -167.962668) (xy 409.362521 -167.916554)
			(xy 409.339473 -167.866614) (xy 409.323834 -167.813881) (xy 409.315929 -167.759449) (xy 409.315412 -167.731948)
			(xy 409.315817 -167.707599) (xy 409.322047 -167.659301) (xy 409.334363 -167.612186) (xy 409.343098 -167.589454)
			(xy 409.355544 -167.558212) (xy 408.18308 -166.385748) (xy 398.62252 -166.385748) (xy 398.06626 -165.829488)
			(xy 373.1006 -165.829488) (xy 372.56847 -166.361618) (xy 372.56847 -166.649251) (xy 372.910346 -166.649251)
			(xy 372.910346 -166.594749) (xy 372.918102 -166.5408) (xy 372.933456 -166.488505) (xy 372.956095 -166.438927)
			(xy 372.98556 -166.393075) (xy 373.021249 -166.351882) (xy 373.062438 -166.316188) (xy 373.108286 -166.286718)
			(xy 373.157862 -166.264072) (xy 373.210155 -166.248711) (xy 373.264103 -166.240949) (xy 373.291354 -166.24046)
			(xy 373.319727 -166.240978) (xy 373.375847 -166.249391) (xy 373.430102 -166.266023) (xy 373.481295 -166.290507)
			(xy 373.528297 -166.322303) (xy 373.570071 -166.36071) (xy 373.605696 -166.404881) (xy 373.634386 -166.453841)
			(xy 373.64543 -166.479982) (xy 373.649555 -166.489205) (xy 373.663696 -166.503614) (xy 373.682312 -166.511426)
			(xy 373.7025 -166.511423) (xy 373.711978 -166.507922) (xy 373.743057 -166.495621) (xy 373.807615 -166.478305)
			(xy 373.873884 -166.469579) (xy 373.907304 -166.46906) (xy 373.907812 -166.46906) (xy 373.941031 -166.469606)
			(xy 374.006903 -166.478264) (xy 374.071088 -166.495419) (xy 374.132496 -166.520778) (xy 374.161558 -166.536878)
			(xy 375.08561 -167.070532) (xy 375.114227 -167.087663) (xy 375.167141 -167.128264) (xy 375.214298 -167.17543)
			(xy 375.25489 -167.228352) (xy 375.288221 -167.286122) (xy 375.313719 -167.347752) (xy 375.330949 -167.412184)
			(xy 375.331431 -167.415464) (xy 395.694408 -167.415464) (xy 395.694845 -167.389084) (xy 395.702103 -167.336826)
			(xy 395.716489 -167.286066) (xy 395.737728 -167.23777) (xy 395.765417 -167.192861) (xy 395.799027 -167.152192)
			(xy 395.837918 -167.11654) (xy 395.881349 -167.086585) (xy 395.90472 -167.074342) (xy 395.917115 -167.067697)
			(xy 395.937856 -167.048715) (xy 395.952625 -167.024791) (xy 395.9603 -166.997742) (xy 395.960295 -166.969626)
			(xy 395.952612 -166.94258) (xy 395.937836 -166.91866) (xy 395.917088 -166.899684) (xy 395.90472 -166.892986)
			(xy 395.881381 -166.880687) (xy 395.837957 -166.850734) (xy 395.79907 -166.815087) (xy 395.765461 -166.774426)
			(xy 395.73777 -166.729526) (xy 395.716525 -166.68124) (xy 395.702129 -166.63049) (xy 395.694858 -166.57824)
			(xy 395.694408 -166.551864) (xy 395.694894 -166.524613) (xy 395.70265 -166.470665) (xy 395.718005 -166.41837)
			(xy 395.740647 -166.368793) (xy 395.770113 -166.322943) (xy 395.805804 -166.281752) (xy 395.846995 -166.246061)
			(xy 395.892845 -166.216595) (xy 395.942422 -166.193953) (xy 395.994717 -166.178598) (xy 396.048665 -166.170842)
			(xy 396.103167 -166.170842) (xy 396.157115 -166.178598) (xy 396.20941 -166.193953) (xy 396.258987 -166.216595)
			(xy 396.304837 -166.246061) (xy 396.346028 -166.281752) (xy 396.381719 -166.322943) (xy 396.411185 -166.368793)
			(xy 396.433827 -166.41837) (xy 396.449182 -166.470665) (xy 396.456938 -166.524613) (xy 396.457424 -166.551864)
			(xy 396.456992 -166.578244) (xy 396.449732 -166.630501) (xy 396.435344 -166.681261) (xy 396.414102 -166.729556)
			(xy 396.386413 -166.774465) (xy 396.352803 -166.815133) (xy 396.313912 -166.850786) (xy 396.270483 -166.880743)
			(xy 396.247112 -166.892986) (xy 396.234787 -166.899743) (xy 396.214066 -166.918711) (xy 396.199309 -166.942614)
			(xy 396.191637 -166.969638) (xy 396.191633 -166.99773) (xy 396.199296 -167.024756) (xy 396.214046 -167.048664)
			(xy 396.23476 -167.067639) (xy 396.247112 -167.074342) (xy 396.27047 -167.086606) (xy 396.313893 -167.116565)
			(xy 396.352779 -167.152218) (xy 396.386386 -167.192884) (xy 396.414074 -167.237789) (xy 396.435316 -167.286079)
			(xy 396.449709 -167.336834) (xy 396.456976 -167.389086) (xy 396.457424 -167.415464) (xy 396.456938 -167.442715)
			(xy 396.449182 -167.496663) (xy 396.433827 -167.548958) (xy 396.411185 -167.598535) (xy 396.381719 -167.644385)
			(xy 396.346028 -167.685576) (xy 396.304837 -167.721267) (xy 396.258987 -167.750733) (xy 396.20941 -167.773375)
			(xy 396.157115 -167.78873) (xy 396.103167 -167.796486) (xy 396.048665 -167.796486) (xy 395.994717 -167.78873)
			(xy 395.942422 -167.773375) (xy 395.892845 -167.750733) (xy 395.846995 -167.721267) (xy 395.805804 -167.685576)
			(xy 395.770113 -167.644385) (xy 395.740647 -167.598535) (xy 395.718005 -167.548958) (xy 395.70265 -167.496663)
			(xy 395.694894 -167.442715) (xy 395.694408 -167.415464) (xy 375.331431 -167.415464) (xy 375.3358 -167.445182)
			(xy 375.337563 -167.455112) (xy 375.347644 -167.472558) (xy 375.363672 -167.484767) (xy 375.383168 -167.489853)
			(xy 375.393204 -167.48887) (xy 375.406531 -167.487092) (xy 375.433353 -167.485187) (xy 375.446798 -167.48506)
			(xy 375.447306 -167.48506) (xy 375.474555 -167.485611) (xy 375.528497 -167.493367) (xy 375.580787 -167.508721)
			(xy 375.630359 -167.531361) (xy 375.676205 -167.560825) (xy 375.717391 -167.596513) (xy 375.753079 -167.6377)
			(xy 375.782542 -167.683546) (xy 375.805181 -167.733119) (xy 375.820534 -167.785409) (xy 375.82829 -167.839351)
			(xy 375.82829 -167.893849) (xy 375.820534 -167.947791) (xy 375.805181 -168.000081) (xy 375.782542 -168.049654)
			(xy 375.753079 -168.0955) (xy 375.717391 -168.136687) (xy 375.676205 -168.172375) (xy 375.630359 -168.201839)
			(xy 375.580787 -168.224479) (xy 375.528497 -168.239833) (xy 375.474555 -168.247589) (xy 375.447306 -168.248076)
			(xy 375.418933 -168.247569) (xy 375.362813 -168.239152) (xy 375.30856 -168.222516) (xy 375.257368 -168.19803)
			(xy 375.210366 -168.166232) (xy 375.168592 -168.127824) (xy 375.132966 -168.083654) (xy 375.104275 -168.034695)
			(xy 375.09323 -168.008554) (xy 375.089063 -167.999357) (xy 375.07493 -167.984961) (xy 375.056331 -167.977146)
			(xy 375.036158 -167.977128) (xy 375.026682 -167.980614) (xy 374.995609 -167.992929) (xy 374.931047 -168.010239)
			(xy 374.864777 -168.01896) (xy 374.831356 -168.019476) (xy 374.830848 -168.019476) (xy 374.797629 -168.018942)
			(xy 374.731757 -168.01028) (xy 374.667571 -167.993122) (xy 374.606164 -167.967759) (xy 374.577102 -167.951658)
			(xy 373.65305 -167.418004) (xy 373.624423 -167.400889) (xy 373.571507 -167.360287) (xy 373.524348 -167.31312)
			(xy 373.483757 -167.260196) (xy 373.450428 -167.202422) (xy 373.424932 -167.140789) (xy 373.407708 -167.076353)
			(xy 373.40286 -167.043354) (xy 373.401115 -167.033418) (xy 373.391034 -167.015964) (xy 373.374999 -167.003753)
			(xy 373.355494 -166.998676) (xy 373.345456 -166.999666) (xy 373.332128 -167.001438) (xy 373.305307 -167.003347)
			(xy 373.291862 -167.003476) (xy 373.291354 -167.003476) (xy 373.264103 -167.003051) (xy 373.210155 -166.995289)
			(xy 373.157862 -166.979928) (xy 373.108286 -166.957282) (xy 373.062438 -166.927812) (xy 373.021249 -166.892118)
			(xy 372.98556 -166.850925) (xy 372.956095 -166.805073) (xy 372.933456 -166.755495) (xy 372.918102 -166.7032)
			(xy 372.910346 -166.649251) (xy 372.56847 -166.649251) (xy 372.56847 -168.478708) (xy 397.049242 -168.478708)
			(xy 397.053313 -168.423086) (xy 397.065439 -168.368649) (xy 397.085362 -168.316558) (xy 397.112658 -168.267923)
			(xy 397.146744 -168.22378) (xy 397.186893 -168.185071) (xy 397.232251 -168.15262) (xy 397.281851 -168.127119)
			(xy 397.334635 -168.109112) (xy 397.389478 -168.098982) (xy 397.445212 -168.096945) (xy 397.500649 -168.103045)
			(xy 397.554606 -168.117151) (xy 397.605935 -168.138963) (xy 397.653541 -168.168017) (xy 397.696409 -168.203692)
			(xy 397.733626 -168.245229) (xy 397.764399 -168.291742) (xy 397.788071 -168.342239) (xy 397.804139 -168.395646)
			(xy 397.812259 -168.450822) (xy 397.812768 -168.478708) (xy 397.812259 -168.506594) (xy 397.804139 -168.56177)
			(xy 397.788071 -168.615177) (xy 397.764399 -168.665674) (xy 397.733626 -168.712187) (xy 397.696409 -168.753724)
			(xy 397.653541 -168.789399) (xy 397.605935 -168.818453) (xy 397.554606 -168.840265) (xy 397.500649 -168.854371)
			(xy 397.445212 -168.860471) (xy 397.389478 -168.858434) (xy 397.334635 -168.848304) (xy 397.281851 -168.830297)
			(xy 397.232251 -168.804796) (xy 397.186893 -168.772345) (xy 397.146744 -168.733636) (xy 397.112658 -168.689493)
			(xy 397.085362 -168.640858) (xy 397.065439 -168.588767) (xy 397.053313 -168.53433) (xy 397.049242 -168.478708)
			(xy 372.56847 -168.478708) (xy 372.56847 -168.983152) (xy 399.642589 -168.983152) (xy 399.646611 -168.897432)
			(xy 399.658642 -168.812464) (xy 399.678578 -168.728997) (xy 399.706241 -168.647763) (xy 399.74139 -168.569477)
			(xy 399.783716 -168.494826) (xy 399.832845 -168.424467) (xy 399.888348 -168.359017) (xy 399.949735 -168.299053)
			(xy 400.016468 -168.2451) (xy 400.08796 -168.197633) (xy 400.163582 -168.157069) (xy 400.242671 -168.123765)
			(xy 400.324531 -168.098013) (xy 400.408442 -168.08004) (xy 400.493668 -168.070004) (xy 400.57946 -168.067992)
			(xy 400.665062 -168.074023) (xy 400.749724 -168.088043) (xy 400.832701 -168.109929) (xy 400.913264 -168.13949)
			(xy 400.990704 -168.176464) (xy 401.064343 -168.220528) (xy 401.133531 -168.271294) (xy 401.197662 -168.328315)
			(xy 401.256171 -168.391091) (xy 401.308544 -168.459071) (xy 401.354322 -168.531656) (xy 401.393102 -168.608208)
			(xy 401.424543 -168.688056) (xy 401.448369 -168.770497) (xy 401.46437 -168.854807) (xy 401.472405 -168.940245)
			(xy 401.472908 -168.983152) (xy 401.472405 -169.026059) (xy 401.46437 -169.111497) (xy 401.448369 -169.195807)
			(xy 401.424543 -169.278248) (xy 401.393102 -169.358096) (xy 401.354322 -169.434648) (xy 401.308544 -169.507233)
			(xy 401.256171 -169.575213) (xy 401.197662 -169.637989) (xy 401.133531 -169.69501) (xy 401.064343 -169.745776)
			(xy 400.990704 -169.78984) (xy 400.913264 -169.826814) (xy 400.832701 -169.856375) (xy 400.749724 -169.878261)
			(xy 400.665062 -169.892281) (xy 400.57946 -169.898312) (xy 400.493668 -169.8963) (xy 400.408442 -169.886264)
			(xy 400.324531 -169.868291) (xy 400.242671 -169.842539) (xy 400.163582 -169.809235) (xy 400.08796 -169.768671)
			(xy 400.016468 -169.721204) (xy 399.949735 -169.667251) (xy 399.888348 -169.607287) (xy 399.832845 -169.541837)
			(xy 399.783716 -169.471478) (xy 399.74139 -169.396827) (xy 399.706241 -169.318541) (xy 399.678578 -169.237307)
			(xy 399.658642 -169.15384) (xy 399.646611 -169.068872) (xy 399.642589 -168.983152) (xy 372.56847 -168.983152)
			(xy 372.56847 -169.437558) (xy 371.732278 -170.27375) (xy 372.856503 -170.27375) (xy 372.856503 -170.21925)
			(xy 372.864259 -170.165306) (xy 372.879614 -170.113014) (xy 372.902254 -170.06344) (xy 372.931719 -170.017592)
			(xy 372.967409 -169.976404) (xy 373.008597 -169.940715) (xy 373.054445 -169.911251) (xy 373.10402 -169.888612)
			(xy 373.156312 -169.873258) (xy 373.210256 -169.865503) (xy 373.237506 -169.86504) (xy 373.263769 -169.865487)
			(xy 373.315801 -169.872681) (xy 373.366353 -169.886947) (xy 373.41447 -169.908014) (xy 373.459241 -169.935484)
			(xy 373.49982 -169.968837) (xy 373.535438 -170.007442) (xy 373.565422 -170.05057) (xy 373.589205 -170.097404)
			(xy 373.598186 -170.122088) (xy 373.603029 -170.134699) (xy 373.618255 -170.157) (xy 373.638797 -170.174528)
			(xy 373.663216 -170.186056) (xy 373.689803 -170.190778) (xy 373.716698 -170.188363) (xy 373.729504 -170.184064)
			(xy 373.758027 -170.173888) (xy 373.816887 -170.159637) (xy 373.877023 -170.152479) (xy 373.907304 -170.15206)
			(xy 373.907812 -170.15206) (xy 373.941031 -170.152606) (xy 374.006903 -170.161264) (xy 374.071088 -170.178419)
			(xy 374.132496 -170.203778) (xy 374.161558 -170.219878) (xy 375.08561 -170.753532) (xy 375.11334 -170.770141)
			(xy 375.164778 -170.809287) (xy 375.210847 -170.854629) (xy 375.250808 -170.905436) (xy 375.284017 -170.960893)
			(xy 375.30994 -171.020106) (xy 375.311523 -171.025496) (xy 399.668996 -171.025496) (xy 399.668996 -170.9408)
			(xy 399.677047 -170.856486) (xy 399.693076 -170.77332) (xy 399.716937 -170.692053) (xy 399.748416 -170.613423)
			(xy 399.787227 -170.538142) (xy 399.833017 -170.46689) (xy 399.885373 -170.400314) (xy 399.943821 -170.339016)
			(xy 400.007831 -170.283551) (xy 400.076823 -170.234422) (xy 400.150173 -170.192073) (xy 400.227216 -170.156889)
			(xy 400.307255 -170.129187) (xy 400.389564 -170.109219) (xy 400.473399 -170.097166) (xy 400.558 -170.093136)
			(xy 400.642601 -170.097166) (xy 400.726436 -170.109219) (xy 400.808745 -170.129187) (xy 400.888784 -170.156889)
			(xy 400.965827 -170.192073) (xy 401.039177 -170.234422) (xy 401.108169 -170.283551) (xy 401.172179 -170.339016)
			(xy 401.230627 -170.400314) (xy 401.282983 -170.46689) (xy 401.328773 -170.538142) (xy 401.367584 -170.613423)
			(xy 401.399063 -170.692053) (xy 401.422924 -170.77332) (xy 401.438953 -170.856486) (xy 401.447004 -170.9408)
			(xy 401.447508 -170.983148) (xy 401.447004 -171.025496) (xy 401.438953 -171.10981) (xy 401.422924 -171.192976)
			(xy 401.399063 -171.274243) (xy 401.367584 -171.352873) (xy 401.328773 -171.428154) (xy 401.282983 -171.499406)
			(xy 401.230627 -171.565982) (xy 401.172179 -171.62728) (xy 401.108169 -171.682745) (xy 401.039177 -171.731874)
			(xy 400.965827 -171.774223) (xy 400.888784 -171.809407) (xy 400.808745 -171.837109) (xy 400.726436 -171.857077)
			(xy 400.642601 -171.86913) (xy 400.558 -171.873161) (xy 400.473399 -171.86913) (xy 400.389564 -171.857077)
			(xy 400.307255 -171.837109) (xy 400.227216 -171.809407) (xy 400.150173 -171.774223) (xy 400.076823 -171.731874)
			(xy 400.007831 -171.682745) (xy 399.943821 -171.62728) (xy 399.885373 -171.565982) (xy 399.833017 -171.499406)
			(xy 399.787227 -171.428154) (xy 399.748416 -171.352873) (xy 399.716937 -171.274243) (xy 399.693076 -171.192976)
			(xy 399.677047 -171.10981) (xy 399.668996 -171.025496) (xy 375.311523 -171.025496) (xy 375.32816 -171.082125)
			(xy 375.333768 -171.113958) (xy 375.336406 -171.127741) (xy 375.348162 -171.153212) (xy 375.366406 -171.174521)
			(xy 375.389761 -171.19006) (xy 375.416463 -171.198656) (xy 375.444497 -171.199661) (xy 375.458228 -171.196762)
			(xy 375.480551 -171.191663) (xy 375.526011 -171.186182) (xy 375.548906 -171.18584) (xy 375.57616 -171.18623)
			(xy 375.630114 -171.193988) (xy 375.682415 -171.209346) (xy 375.731998 -171.23199) (xy 375.777853 -171.261461)
			(xy 375.819048 -171.297157) (xy 375.854743 -171.338352) (xy 375.884212 -171.384208) (xy 375.906856 -171.433791)
			(xy 375.922213 -171.486092) (xy 375.92997 -171.540046) (xy 375.92997 -171.594554) (xy 375.922213 -171.648508)
			(xy 375.906856 -171.700809) (xy 375.884212 -171.750392) (xy 375.854743 -171.796248) (xy 375.819048 -171.837443)
			(xy 375.777853 -171.873139) (xy 375.731998 -171.90261) (xy 375.682415 -171.925254) (xy 375.630114 -171.940612)
			(xy 375.57616 -171.94837) (xy 375.548906 -171.948856) (xy 375.520287 -171.948377) (xy 375.463693 -171.939806)
			(xy 375.409013 -171.922885) (xy 375.35747 -171.897993) (xy 375.310219 -171.865687) (xy 375.268318 -171.826692)
			(xy 375.232707 -171.78188) (xy 375.204181 -171.732256) (xy 375.193306 -171.705778) (xy 375.187869 -171.692836)
			(xy 375.170968 -171.670431) (xy 375.14861 -171.653468) (xy 375.122481 -171.643226) (xy 375.094551 -171.640477)
			(xy 375.066927 -171.645429) (xy 375.054114 -171.651168) (xy 375.02802 -171.66343) (xy 374.973662 -171.682655)
			(xy 374.917476 -171.695598) (xy 374.860185 -171.702092) (xy 374.831356 -171.702476) (xy 374.830848 -171.702476)
			(xy 374.797629 -171.701942) (xy 374.731757 -171.69328) (xy 374.667571 -171.676122) (xy 374.606164 -171.650759)
			(xy 374.577102 -171.634658) (xy 373.65305 -171.101004) (xy 373.627375 -171.085656) (xy 373.579425 -171.049891)
			(xy 373.536004 -171.008747) (xy 373.497711 -170.962791) (xy 373.465076 -170.912659) (xy 373.43855 -170.859043)
			(xy 373.4185 -170.802685) (xy 373.405201 -170.744364) (xy 373.40159 -170.71467) (xy 373.399745 -170.701262)
			(xy 373.389879 -170.676069) (xy 373.373746 -170.654348) (xy 373.352479 -170.637622) (xy 373.327568 -170.627065)
			(xy 373.300758 -170.623415) (xy 373.28729 -170.624754) (xy 373.274902 -170.626295) (xy 373.249989 -170.627948)
			(xy 373.237506 -170.628056) (xy 373.210256 -170.627497) (xy 373.156312 -170.619742) (xy 373.10402 -170.604388)
			(xy 373.054445 -170.581749) (xy 373.008597 -170.552285) (xy 372.967409 -170.516596) (xy 372.931719 -170.475408)
			(xy 372.902254 -170.42956) (xy 372.879614 -170.379986) (xy 372.864259 -170.327694) (xy 372.856503 -170.27375)
			(xy 371.732278 -170.27375) (xy 368.608078 -173.39795) (xy 369.046503 -173.39795) (xy 369.046503 -173.34345)
			(xy 369.054259 -173.289506) (xy 369.069614 -173.237214) (xy 369.092254 -173.18764) (xy 369.121719 -173.141792)
			(xy 369.157409 -173.100604) (xy 369.198597 -173.064915) (xy 369.244445 -173.035451) (xy 369.29402 -173.012812)
			(xy 369.346312 -172.997458) (xy 369.400256 -172.989703) (xy 369.427506 -172.98924) (xy 369.42776 -172.98924)
			(xy 369.445519 -172.989456) (xy 369.480882 -172.99276) (xy 369.498372 -172.995844) (xy 369.512061 -172.997936)
			(xy 369.53964 -172.995594) (xy 369.565573 -172.985921) (xy 369.58795 -172.96963) (xy 369.605121 -172.947922)
			(xy 369.615822 -172.922396) (xy 369.618006 -172.908722) (xy 369.622714 -172.875522) (xy 369.639754 -172.810667)
			(xy 369.665162 -172.748612) (xy 369.698499 -172.69043) (xy 369.739187 -172.637129) (xy 369.786522 -172.589632)
			(xy 369.839683 -172.548763) (xy 369.86845 -172.531532) (xy 370.792502 -171.997878) (xy 370.82156 -171.981769)
			(xy 370.882966 -171.9564) (xy 370.947153 -171.939245) (xy 371.013028 -171.930597) (xy 371.046248 -171.93006)
			(xy 371.046756 -171.93006) (xy 371.077038 -171.930454) (xy 371.137178 -171.937611) (xy 371.196043 -171.951854)
			(xy 371.252803 -171.97298) (xy 371.279928 -171.986448) (xy 371.292278 -171.992298) (xy 371.318999 -171.99796)
			(xy 371.346264 -171.99633) (xy 371.372121 -171.987527) (xy 371.394716 -171.97218) (xy 371.41243 -171.95139)
			(xy 371.418612 -171.939204) (xy 371.430507 -171.914913) (xy 371.460114 -171.86965) (xy 371.495813 -171.829018)
			(xy 371.536889 -171.793833) (xy 371.58252 -171.764796) (xy 371.631793 -171.742491) (xy 371.68372 -171.727364)
			(xy 371.737263 -171.719717) (xy 371.764306 -171.71924) (xy 371.79156 -171.71963) (xy 371.845514 -171.727388)
			(xy 371.897815 -171.742746) (xy 371.947398 -171.76539) (xy 371.993253 -171.794861) (xy 372.034448 -171.830557)
			(xy 372.070143 -171.871752) (xy 372.099612 -171.917608) (xy 372.122256 -171.967191) (xy 372.122913 -171.96943)
			(xy 393.4239 -171.96943) (xy 393.427971 -171.913808) (xy 393.440097 -171.859371) (xy 393.46002 -171.80728)
			(xy 393.487316 -171.758645) (xy 393.521402 -171.714502) (xy 393.561551 -171.675793) (xy 393.606909 -171.643342)
			(xy 393.656509 -171.617841) (xy 393.709293 -171.599834) (xy 393.764136 -171.589704) (xy 393.81987 -171.587667)
			(xy 393.875307 -171.593767) (xy 393.929264 -171.607873) (xy 393.980593 -171.629685) (xy 394.028199 -171.658739)
			(xy 394.071067 -171.694414) (xy 394.108284 -171.735951) (xy 394.139057 -171.782464) (xy 394.162729 -171.832961)
			(xy 394.178797 -171.886368) (xy 394.186917 -171.941544) (xy 394.187426 -171.96943) (xy 394.186917 -171.997316)
			(xy 394.178797 -172.052492) (xy 394.162729 -172.105899) (xy 394.139057 -172.156396) (xy 394.108284 -172.202909)
			(xy 394.071067 -172.244446) (xy 394.028199 -172.280121) (xy 393.980593 -172.309175) (xy 393.929264 -172.330987)
			(xy 393.875307 -172.345093) (xy 393.81987 -172.351193) (xy 393.764136 -172.349156) (xy 393.709293 -172.339026)
			(xy 393.656509 -172.321019) (xy 393.606909 -172.295518) (xy 393.561551 -172.263067) (xy 393.521402 -172.224358)
			(xy 393.487316 -172.180215) (xy 393.46002 -172.13158) (xy 393.440097 -172.079489) (xy 393.427971 -172.025052)
			(xy 393.4239 -171.96943) (xy 372.122913 -171.96943) (xy 372.137613 -172.019492) (xy 372.14537 -172.073446)
			(xy 372.14537 -172.127954) (xy 372.137613 -172.181908) (xy 372.122256 -172.234209) (xy 372.099612 -172.283792)
			(xy 372.070143 -172.329648) (xy 372.034448 -172.370843) (xy 371.993253 -172.406539) (xy 371.947398 -172.43601)
			(xy 371.897815 -172.458654) (xy 371.845514 -172.474012) (xy 371.79156 -172.48177) (xy 371.764306 -172.482256)
			(xy 371.764052 -172.482256) (xy 371.739909 -172.481887) (xy 371.692011 -172.475768) (xy 371.668548 -172.470064)
			(xy 371.65522 -172.467082) (xy 371.627922 -172.467468) (xy 371.601706 -172.475084) (xy 371.578451 -172.489383)
			(xy 371.559824 -172.509341) (xy 371.547161 -172.533526) (xy 371.543834 -172.546772) (xy 371.536953 -172.576256)
			(xy 371.517151 -172.633471) (xy 371.490688 -172.687927) (xy 371.457939 -172.73885) (xy 371.419368 -172.785519)
			(xy 371.375522 -172.827271) (xy 371.327023 -172.863514) (xy 371.30101 -172.879004) (xy 370.888023 -173.11751)
			(xy 393.44168 -173.11751) (xy 393.445751 -173.061888) (xy 393.457877 -173.007451) (xy 393.4778 -172.95536)
			(xy 393.505096 -172.906725) (xy 393.539182 -172.862582) (xy 393.579331 -172.823873) (xy 393.624689 -172.791422)
			(xy 393.674289 -172.765921) (xy 393.727073 -172.747914) (xy 393.781916 -172.737784) (xy 393.83765 -172.735747)
			(xy 393.893087 -172.741847) (xy 393.947044 -172.755953) (xy 393.998373 -172.777765) (xy 394.045979 -172.806819)
			(xy 394.088847 -172.842494) (xy 394.126064 -172.884031) (xy 394.156837 -172.930544) (xy 394.180509 -172.981041)
			(xy 394.196577 -173.034448) (xy 394.204697 -173.089624) (xy 394.205206 -173.11751) (xy 394.204697 -173.145396)
			(xy 394.196577 -173.200572) (xy 394.180509 -173.253979) (xy 394.156837 -173.304476) (xy 394.126064 -173.350989)
			(xy 394.088847 -173.392526) (xy 394.045979 -173.428201) (xy 393.998373 -173.457255) (xy 393.947044 -173.479067)
			(xy 393.893087 -173.493173) (xy 393.83765 -173.499273) (xy 393.781916 -173.497236) (xy 393.727073 -173.487106)
			(xy 393.674289 -173.469099) (xy 393.624689 -173.443598) (xy 393.579331 -173.411147) (xy 393.539182 -173.372438)
			(xy 393.505096 -173.328295) (xy 393.4778 -173.27966) (xy 393.457877 -173.227569) (xy 393.445751 -173.173132)
			(xy 393.44168 -173.11751) (xy 370.888023 -173.11751) (xy 370.376958 -173.412658) (xy 370.34791 -173.428786)
			(xy 370.2865 -173.45415) (xy 370.22231 -173.471299) (xy 370.156433 -173.479942) (xy 370.123212 -173.480476)
			(xy 370.122704 -173.480476) (xy 370.088408 -173.479937) (xy 370.020431 -173.470779) (xy 369.954307 -173.452548)
			(xy 369.922552 -173.439582) (xy 369.909674 -173.434488) (xy 369.882228 -173.430832) (xy 369.85481 -173.434688)
			(xy 369.829437 -173.44577) (xy 369.807976 -173.463264) (xy 369.792006 -173.485882) (xy 369.786916 -173.498764)
			(xy 369.776578 -173.526198) (xy 369.748686 -173.577763) (xy 369.713234 -173.624455) (xy 369.671058 -173.665175)
			(xy 369.623149 -173.698964) (xy 369.570636 -173.725027) (xy 369.514754 -173.742751) (xy 369.456819 -173.75172)
			(xy 369.427506 -173.752256) (xy 369.400256 -173.751697) (xy 369.346312 -173.743942) (xy 369.29402 -173.728588)
			(xy 369.244445 -173.705949) (xy 369.198597 -173.676485) (xy 369.157409 -173.640796) (xy 369.121719 -173.599608)
			(xy 369.092254 -173.55376) (xy 369.069614 -173.504186) (xy 369.054259 -173.451894) (xy 369.046503 -173.39795)
			(xy 368.608078 -173.39795) (xy 367.990777 -174.015251) (xy 372.910346 -174.015251) (xy 372.910346 -173.960749)
			(xy 372.918102 -173.9068) (xy 372.933456 -173.854505) (xy 372.956095 -173.804927) (xy 372.98556 -173.759075)
			(xy 373.021249 -173.717882) (xy 373.062438 -173.682188) (xy 373.108286 -173.652718) (xy 373.157862 -173.630072)
			(xy 373.210155 -173.614711) (xy 373.264103 -173.606949) (xy 373.291354 -173.60646) (xy 373.319727 -173.606978)
			(xy 373.375847 -173.615391) (xy 373.430102 -173.632023) (xy 373.481295 -173.656507) (xy 373.528297 -173.688303)
			(xy 373.570071 -173.72671) (xy 373.605696 -173.770881) (xy 373.634386 -173.819841) (xy 373.64543 -173.845982)
			(xy 373.649555 -173.855205) (xy 373.663696 -173.869614) (xy 373.682312 -173.877426) (xy 373.7025 -173.877423)
			(xy 373.711978 -173.873922) (xy 373.743057 -173.861621) (xy 373.807615 -173.844305) (xy 373.873884 -173.835579)
			(xy 373.907304 -173.83506) (xy 373.907812 -173.83506) (xy 373.941031 -173.835606) (xy 374.006903 -173.844264)
			(xy 374.071088 -173.861419) (xy 374.132496 -173.886778) (xy 374.161558 -173.902878) (xy 375.08561 -174.436532)
			(xy 375.114227 -174.453663) (xy 375.167141 -174.494264) (xy 375.214298 -174.54143) (xy 375.25489 -174.594352)
			(xy 375.288221 -174.652122) (xy 375.313719 -174.713752) (xy 375.330949 -174.778184) (xy 375.3358 -174.811182)
			(xy 375.337563 -174.821112) (xy 375.347644 -174.838558) (xy 375.363672 -174.850767) (xy 375.383168 -174.855853)
			(xy 375.393204 -174.85487) (xy 375.406531 -174.853092) (xy 375.433353 -174.851187) (xy 375.446798 -174.85106)
			(xy 375.447306 -174.85106) (xy 375.474555 -174.851611) (xy 375.528497 -174.859367) (xy 375.580787 -174.874721)
			(xy 375.630359 -174.897361) (xy 375.676205 -174.926825) (xy 375.717391 -174.962513) (xy 375.753079 -175.0037)
			(xy 375.782542 -175.049546) (xy 375.805181 -175.099119) (xy 375.820534 -175.151409) (xy 375.82829 -175.205351)
			(xy 375.82829 -175.206152) (xy 399.642589 -175.206152) (xy 399.646611 -175.120432) (xy 399.658642 -175.035464)
			(xy 399.678578 -174.951997) (xy 399.706241 -174.870763) (xy 399.74139 -174.792477) (xy 399.783716 -174.717826)
			(xy 399.832845 -174.647467) (xy 399.888348 -174.582017) (xy 399.949735 -174.522053) (xy 400.016468 -174.4681)
			(xy 400.08796 -174.420633) (xy 400.163582 -174.380069) (xy 400.242671 -174.346765) (xy 400.324531 -174.321013)
			(xy 400.408442 -174.30304) (xy 400.493668 -174.293004) (xy 400.57946 -174.290992) (xy 400.665062 -174.297023)
			(xy 400.749724 -174.311043) (xy 400.832701 -174.332929) (xy 400.913264 -174.36249) (xy 400.990704 -174.399464)
			(xy 401.064343 -174.443528) (xy 401.133531 -174.494294) (xy 401.197662 -174.551315) (xy 401.256171 -174.614091)
			(xy 401.308544 -174.682071) (xy 401.354322 -174.754656) (xy 401.393102 -174.831208) (xy 401.424543 -174.911056)
			(xy 401.448369 -174.993497) (xy 401.46437 -175.077807) (xy 401.472405 -175.163245) (xy 401.472908 -175.206152)
			(xy 401.472405 -175.249059) (xy 401.46437 -175.334497) (xy 401.448369 -175.418807) (xy 401.424543 -175.501248)
			(xy 401.393102 -175.581096) (xy 401.354322 -175.657648) (xy 401.308544 -175.730233) (xy 401.256171 -175.798213)
			(xy 401.197662 -175.860989) (xy 401.133531 -175.91801) (xy 401.064343 -175.968776) (xy 400.990704 -176.01284)
			(xy 400.913264 -176.049814) (xy 400.832701 -176.079375) (xy 400.749724 -176.101261) (xy 400.665062 -176.115281)
			(xy 400.57946 -176.121312) (xy 400.493668 -176.1193) (xy 400.408442 -176.109264) (xy 400.324531 -176.091291)
			(xy 400.242671 -176.065539) (xy 400.163582 -176.032235) (xy 400.08796 -175.991671) (xy 400.016468 -175.944204)
			(xy 399.949735 -175.890251) (xy 399.888348 -175.830287) (xy 399.832845 -175.764837) (xy 399.783716 -175.694478)
			(xy 399.74139 -175.619827) (xy 399.706241 -175.541541) (xy 399.678578 -175.460307) (xy 399.658642 -175.37684)
			(xy 399.646611 -175.291872) (xy 399.642589 -175.206152) (xy 375.82829 -175.206152) (xy 375.82829 -175.259849)
			(xy 375.820534 -175.313791) (xy 375.805181 -175.366081) (xy 375.782542 -175.415654) (xy 375.753079 -175.4615)
			(xy 375.717391 -175.502687) (xy 375.676205 -175.538375) (xy 375.630359 -175.567839) (xy 375.580787 -175.590479)
			(xy 375.528497 -175.605833) (xy 375.474555 -175.613589) (xy 375.447306 -175.614076) (xy 375.418933 -175.613569)
			(xy 375.362813 -175.605152) (xy 375.30856 -175.588516) (xy 375.257368 -175.56403) (xy 375.210366 -175.532232)
			(xy 375.168592 -175.493824) (xy 375.132966 -175.449654) (xy 375.104275 -175.400695) (xy 375.09323 -175.374554)
			(xy 375.089063 -175.365357) (xy 375.07493 -175.350961) (xy 375.056331 -175.343146) (xy 375.036158 -175.343128)
			(xy 375.026682 -175.346614) (xy 374.995609 -175.358929) (xy 374.931047 -175.376239) (xy 374.864777 -175.38496)
			(xy 374.831356 -175.385476) (xy 374.830848 -175.385476) (xy 374.797629 -175.384942) (xy 374.731757 -175.37628)
			(xy 374.667571 -175.359122) (xy 374.606164 -175.333759) (xy 374.577102 -175.317658) (xy 373.65305 -174.784004)
			(xy 373.624423 -174.766889) (xy 373.571507 -174.726287) (xy 373.524348 -174.67912) (xy 373.483757 -174.626196)
			(xy 373.450428 -174.568422) (xy 373.424932 -174.506789) (xy 373.407708 -174.442353) (xy 373.40286 -174.409354)
			(xy 373.401115 -174.399418) (xy 373.391034 -174.381964) (xy 373.374999 -174.369753) (xy 373.355494 -174.364676)
			(xy 373.345456 -174.365666) (xy 373.332128 -174.367438) (xy 373.305307 -174.369347) (xy 373.291862 -174.369476)
			(xy 373.291354 -174.369476) (xy 373.264103 -174.369051) (xy 373.210155 -174.361289) (xy 373.157862 -174.345928)
			(xy 373.108286 -174.323282) (xy 373.062438 -174.293812) (xy 373.021249 -174.258118) (xy 372.98556 -174.216925)
			(xy 372.956095 -174.171073) (xy 372.933456 -174.121495) (xy 372.918102 -174.0692) (xy 372.910346 -174.015251)
			(xy 367.990777 -174.015251) (xy 365.603177 -176.402851) (xy 369.125746 -176.402851) (xy 369.125746 -176.348349)
			(xy 369.133502 -176.2944) (xy 369.148856 -176.242105) (xy 369.171495 -176.192527) (xy 369.20096 -176.146675)
			(xy 369.236649 -176.105482) (xy 369.277838 -176.069788) (xy 369.323686 -176.040318) (xy 369.373262 -176.017672)
			(xy 369.425555 -176.002311) (xy 369.479503 -175.994549) (xy 369.506754 -175.99406) (xy 369.507262 -175.99406)
			(xy 369.520707 -175.994179) (xy 369.547529 -175.996086) (xy 369.560856 -175.99787) (xy 369.570892 -175.998782)
			(xy 369.59037 -175.993694) (xy 369.606397 -175.981511) (xy 369.616511 -175.964104) (xy 369.61826 -175.954182)
			(xy 369.623113 -175.921183) (xy 369.640328 -175.856744) (xy 369.665818 -175.795108) (xy 369.699145 -175.737332)
			(xy 369.739739 -175.684409) (xy 369.786902 -175.637245) (xy 369.839824 -175.59665) (xy 369.86845 -175.579532)
			(xy 370.792502 -175.045878) (xy 370.82156 -175.029769) (xy 370.882966 -175.0044) (xy 370.947153 -174.987245)
			(xy 371.013028 -174.978597) (xy 371.046248 -174.97806) (xy 371.046756 -174.97806) (xy 371.080179 -174.978555)
			(xy 371.146455 -174.987258) (xy 371.211015 -175.004587) (xy 371.242082 -175.016922) (xy 371.251563 -175.020338)
			(xy 371.271699 -175.020246) (xy 371.290265 -175.012452) (xy 371.304434 -174.998144) (xy 371.30863 -174.988982)
			(xy 371.319681 -174.962843) (xy 371.348365 -174.913879) (xy 371.383986 -174.869704) (xy 371.425758 -174.831294)
			(xy 371.47276 -174.799497) (xy 371.523955 -174.775014) (xy 371.578211 -174.758386) (xy 371.634332 -174.74998)
			(xy 371.662706 -174.74946) (xy 371.689955 -174.750011) (xy 371.743897 -174.757767) (xy 371.796187 -174.773121)
			(xy 371.845759 -174.795761) (xy 371.891605 -174.825225) (xy 371.932791 -174.860913) (xy 371.968479 -174.9021)
			(xy 371.997942 -174.947946) (xy 372.020581 -174.997519) (xy 372.035934 -175.049809) (xy 372.04369 -175.103751)
			(xy 372.04369 -175.158249) (xy 372.035934 -175.212191) (xy 372.020581 -175.264481) (xy 371.997942 -175.314054)
			(xy 371.968479 -175.3599) (xy 371.932791 -175.401087) (xy 371.891605 -175.436775) (xy 371.845759 -175.466239)
			(xy 371.796187 -175.488879) (xy 371.743897 -175.504233) (xy 371.689955 -175.511989) (xy 371.662706 -175.512476)
			(xy 371.662198 -175.512476) (xy 371.648753 -175.51236) (xy 371.621931 -175.510451) (xy 371.608604 -175.508666)
			(xy 371.59857 -175.507685) (xy 371.57908 -175.512791) (xy 371.56305 -175.524995) (xy 371.552942 -175.542423)
			(xy 371.5512 -175.552354) (xy 371.546342 -175.585352) (xy 371.529125 -175.649789) (xy 371.503635 -175.711424)
			(xy 371.470307 -175.769199) (xy 371.429715 -175.822123) (xy 371.382554 -175.869287) (xy 371.329634 -175.909884)
			(xy 371.30101 -175.927004) (xy 370.923209 -176.14519) (xy 393.33297 -176.14519) (xy 393.333456 -176.117939)
			(xy 393.341212 -176.063991) (xy 393.356567 -176.011696) (xy 393.379209 -175.962119) (xy 393.408675 -175.916269)
			(xy 393.444366 -175.875078) (xy 393.485557 -175.839387) (xy 393.531407 -175.809921) (xy 393.580984 -175.787279)
			(xy 393.633279 -175.771924) (xy 393.687227 -175.764168) (xy 393.741729 -175.764168) (xy 393.795677 -175.771924)
			(xy 393.847972 -175.787279) (xy 393.897549 -175.809921) (xy 393.943399 -175.839387) (xy 393.98459 -175.875078)
			(xy 394.020281 -175.916269) (xy 394.049747 -175.962119) (xy 394.072389 -176.011696) (xy 394.087744 -176.063991)
			(xy 394.0955 -176.117939) (xy 394.095986 -176.14519) (xy 394.095519 -176.1726) (xy 394.087673 -176.226857)
			(xy 394.072143 -176.279431) (xy 394.049246 -176.329241) (xy 394.019456 -176.375261) (xy 393.983385 -176.416543)
			(xy 393.96289 -176.43475) (xy 393.952758 -176.444076) (xy 393.937417 -176.46693) (xy 393.928736 -176.49305)
			(xy 393.927348 -176.520541) (xy 393.933352 -176.547403) (xy 393.946312 -176.571686) (xy 393.965287 -176.591625)
			(xy 393.97686 -176.599088) (xy 394.000774 -176.613961) (xy 394.044353 -176.649629) (xy 394.082217 -176.691313)
			(xy 394.113543 -176.738111) (xy 394.137651 -176.789003) (xy 394.154018 -176.842887) (xy 394.162288 -176.898591)
			(xy 394.162788 -176.926748) (xy 394.162302 -176.953999) (xy 394.154546 -177.007947) (xy 394.139191 -177.060242)
			(xy 394.116549 -177.109819) (xy 394.087083 -177.155669) (xy 394.051392 -177.19686) (xy 394.010201 -177.232551)
			(xy 393.98539 -177.248496) (xy 399.668996 -177.248496) (xy 399.668996 -177.1638) (xy 399.677047 -177.079486)
			(xy 399.693076 -176.99632) (xy 399.716937 -176.915053) (xy 399.748416 -176.836423) (xy 399.787227 -176.761142)
			(xy 399.833017 -176.68989) (xy 399.885373 -176.623314) (xy 399.943821 -176.562016) (xy 400.007831 -176.506551)
			(xy 400.076823 -176.457422) (xy 400.150173 -176.415073) (xy 400.227216 -176.379889) (xy 400.307255 -176.352187)
			(xy 400.389564 -176.332219) (xy 400.473399 -176.320166) (xy 400.558 -176.316136) (xy 400.642601 -176.320166)
			(xy 400.726436 -176.332219) (xy 400.808745 -176.352187) (xy 400.888784 -176.379889) (xy 400.965827 -176.415073)
			(xy 401.039177 -176.457422) (xy 401.108169 -176.506551) (xy 401.172179 -176.562016) (xy 401.230627 -176.623314)
			(xy 401.282983 -176.68989) (xy 401.328773 -176.761142) (xy 401.367584 -176.836423) (xy 401.399063 -176.915053)
			(xy 401.422924 -176.99632) (xy 401.438953 -177.079486) (xy 401.447004 -177.1638) (xy 401.447508 -177.206148)
			(xy 401.447004 -177.248496) (xy 401.438953 -177.33281) (xy 401.422924 -177.415976) (xy 401.399063 -177.497243)
			(xy 401.367584 -177.575873) (xy 401.328773 -177.651154) (xy 401.282983 -177.722406) (xy 401.230627 -177.788982)
			(xy 401.172179 -177.85028) (xy 401.108169 -177.905745) (xy 401.039177 -177.954874) (xy 400.965827 -177.997223)
			(xy 400.888784 -178.032407) (xy 400.808745 -178.060109) (xy 400.726436 -178.080077) (xy 400.642601 -178.09213)
			(xy 400.558 -178.096161) (xy 400.473399 -178.09213) (xy 400.389564 -178.080077) (xy 400.307255 -178.060109)
			(xy 400.227216 -178.032407) (xy 400.150173 -177.997223) (xy 400.076823 -177.954874) (xy 400.007831 -177.905745)
			(xy 399.943821 -177.85028) (xy 399.885373 -177.788982) (xy 399.833017 -177.722406) (xy 399.787227 -177.651154)
			(xy 399.748416 -177.575873) (xy 399.716937 -177.497243) (xy 399.693076 -177.415976) (xy 399.677047 -177.33281)
			(xy 399.668996 -177.248496) (xy 393.98539 -177.248496) (xy 393.964351 -177.262017) (xy 393.914774 -177.284659)
			(xy 393.862479 -177.300014) (xy 393.808531 -177.30777) (xy 393.754029 -177.30777) (xy 393.700081 -177.300014)
			(xy 393.647786 -177.284659) (xy 393.598209 -177.262017) (xy 393.552359 -177.232551) (xy 393.511168 -177.19686)
			(xy 393.475477 -177.155669) (xy 393.446011 -177.109819) (xy 393.423369 -177.060242) (xy 393.408014 -177.007947)
			(xy 393.400258 -176.953999) (xy 393.399772 -176.926748) (xy 393.400245 -176.899338) (xy 393.408087 -176.845081)
			(xy 393.423615 -176.792506) (xy 393.44651 -176.742695) (xy 393.4763 -176.696675) (xy 393.512372 -176.655394)
			(xy 393.532868 -176.637188) (xy 393.542967 -176.627826) (xy 393.558316 -176.604983) (xy 393.567004 -176.57887)
			(xy 393.568399 -176.551384) (xy 393.5624 -176.524525) (xy 393.549443 -176.500245) (xy 393.530469 -176.48031)
			(xy 393.518898 -176.47285) (xy 393.494992 -176.457966) (xy 393.451415 -176.422298) (xy 393.413552 -176.380615)
			(xy 393.382226 -176.33382) (xy 393.358116 -176.282929) (xy 393.341747 -176.229048) (xy 393.333473 -176.173346)
			(xy 393.33297 -176.14519) (xy 370.923209 -176.14519) (xy 370.376958 -176.460658) (xy 370.34791 -176.476786)
			(xy 370.2865 -176.50215) (xy 370.22231 -176.519299) (xy 370.156433 -176.527942) (xy 370.123212 -176.528476)
			(xy 370.122704 -176.528476) (xy 370.089281 -176.527991) (xy 370.023005 -176.519283) (xy 369.958445 -176.501951)
			(xy 369.927378 -176.489614) (xy 369.917888 -176.486261) (xy 369.897781 -176.486367) (xy 369.879243 -176.494152)
			(xy 369.86509 -176.508435) (xy 369.86083 -176.517554) (xy 369.84983 -176.543715) (xy 369.821138 -176.59268)
			(xy 369.785509 -176.636854) (xy 369.743729 -176.675262) (xy 369.69672 -176.707056) (xy 369.645519 -176.731535)
			(xy 369.591256 -176.748158) (xy 369.53513 -176.756559) (xy 369.506754 -176.757076) (xy 369.479503 -176.756651)
			(xy 369.425555 -176.748889) (xy 369.373262 -176.733528) (xy 369.323686 -176.710882) (xy 369.277838 -176.681412)
			(xy 369.236649 -176.645718) (xy 369.20096 -176.604525) (xy 369.171495 -176.558673) (xy 369.148856 -176.509095)
			(xy 369.133502 -176.4568) (xy 369.125746 -176.402851) (xy 365.603177 -176.402851) (xy 364.312182 -177.693846)
			(xy 372.866228 -177.693846) (xy 372.866228 -177.639354) (xy 372.873982 -177.585417) (xy 372.889333 -177.533133)
			(xy 372.911968 -177.483565) (xy 372.941427 -177.437723) (xy 372.977109 -177.396539) (xy 373.018289 -177.360852)
			(xy 373.064128 -177.331389) (xy 373.113693 -177.308748) (xy 373.165976 -177.293391) (xy 373.219912 -177.285631)
			(xy 373.247158 -177.285142) (xy 373.274024 -177.285603) (xy 373.327225 -177.293138) (xy 373.378843 -177.308064)
			(xy 373.427855 -177.330086) (xy 373.473291 -177.358768) (xy 373.514253 -177.393542) (xy 373.549929 -177.433721)
			(xy 373.579615 -177.478508) (xy 373.591582 -177.502566) (xy 373.598639 -177.516151) (xy 373.619382 -177.538647)
			(xy 373.645854 -177.553994) (xy 373.675682 -177.560817) (xy 373.706194 -177.558504) (xy 373.720614 -177.553366)
			(xy 373.750446 -177.542159) (xy 373.812202 -177.526422) (xy 373.875439 -177.518524) (xy 373.907304 -177.51806)
			(xy 373.907812 -177.51806) (xy 373.941031 -177.518606) (xy 374.006903 -177.527264) (xy 374.071088 -177.544419)
			(xy 374.132496 -177.569778) (xy 374.161558 -177.585878) (xy 375.08561 -178.119532) (xy 375.114227 -178.136663)
			(xy 375.167141 -178.177264) (xy 375.214298 -178.22443) (xy 375.25489 -178.277352) (xy 375.288221 -178.335122)
			(xy 375.313719 -178.396752) (xy 375.330949 -178.461184) (xy 375.3358 -178.494182) (xy 375.337563 -178.504112)
			(xy 375.347644 -178.521558) (xy 375.363672 -178.533767) (xy 375.383168 -178.538853) (xy 375.393204 -178.53787)
			(xy 375.406531 -178.536092) (xy 375.433353 -178.534187) (xy 375.446798 -178.53406) (xy 375.447306 -178.53406)
			(xy 375.474555 -178.534611) (xy 375.528497 -178.542367) (xy 375.580787 -178.557721) (xy 375.630359 -178.580361)
			(xy 375.676205 -178.609825) (xy 375.717391 -178.645513) (xy 375.753079 -178.6867) (xy 375.782542 -178.732546)
			(xy 375.805181 -178.782119) (xy 375.820534 -178.834409) (xy 375.82829 -178.888351) (xy 375.82829 -178.942849)
			(xy 375.820534 -178.996791) (xy 375.805181 -179.049081) (xy 375.782542 -179.098654) (xy 375.753079 -179.1445)
			(xy 375.717391 -179.185687) (xy 375.676205 -179.221375) (xy 375.630359 -179.250839) (xy 375.580787 -179.273479)
			(xy 375.528497 -179.288833) (xy 375.474555 -179.296589) (xy 375.447306 -179.297076) (xy 375.418933 -179.296569)
			(xy 375.362813 -179.288152) (xy 375.30856 -179.271516) (xy 375.257368 -179.24703) (xy 375.210366 -179.215232)
			(xy 375.168592 -179.176824) (xy 375.132966 -179.132654) (xy 375.104275 -179.083695) (xy 375.09323 -179.057554)
			(xy 375.089063 -179.048357) (xy 375.07493 -179.033961) (xy 375.056331 -179.026146) (xy 375.036158 -179.026128)
			(xy 375.026682 -179.029614) (xy 374.995609 -179.041929) (xy 374.931047 -179.059239) (xy 374.864777 -179.06796)
			(xy 374.831356 -179.068476) (xy 374.830848 -179.068476) (xy 374.797629 -179.067942) (xy 374.731757 -179.05928)
			(xy 374.667571 -179.042122) (xy 374.606164 -179.016759) (xy 374.577102 -179.000658) (xy 373.65305 -178.467004)
			(xy 373.62649 -178.451169) (xy 373.57706 -178.414014) (xy 373.532505 -178.371135) (xy 373.493483 -178.323165)
			(xy 373.460571 -178.270814) (xy 373.434256 -178.214856) (xy 373.414926 -178.156118) (xy 373.408448 -178.125882)
			(xy 373.404945 -178.110999) (xy 373.390353 -178.084147) (xy 373.368471 -178.062812) (xy 373.341257 -178.048905)
			(xy 373.311147 -178.04367) (xy 373.295926 -178.04511) (xy 373.283785 -178.046545) (xy 373.259383 -178.048072)
			(xy 373.247158 -178.048158) (xy 373.219912 -178.047569) (xy 373.165976 -178.039809) (xy 373.113693 -178.024452)
			(xy 373.064128 -178.001811) (xy 373.018289 -177.972348) (xy 372.977109 -177.936661) (xy 372.941427 -177.895477)
			(xy 372.911968 -177.849635) (xy 372.889333 -177.800067) (xy 372.873982 -177.747783) (xy 372.866228 -177.693846)
			(xy 364.312182 -177.693846) (xy 362.555177 -179.450851) (xy 369.125746 -179.450851) (xy 369.125746 -179.396349)
			(xy 369.133502 -179.3424) (xy 369.148856 -179.290105) (xy 369.171495 -179.240527) (xy 369.20096 -179.194675)
			(xy 369.236649 -179.153482) (xy 369.277838 -179.117788) (xy 369.323686 -179.088318) (xy 369.373262 -179.065672)
			(xy 369.425555 -179.050311) (xy 369.479503 -179.042549) (xy 369.506754 -179.04206) (xy 369.507262 -179.04206)
			(xy 369.520707 -179.042179) (xy 369.547529 -179.044086) (xy 369.560856 -179.04587) (xy 369.570892 -179.046782)
			(xy 369.59037 -179.041694) (xy 369.606397 -179.029511) (xy 369.616511 -179.012104) (xy 369.61826 -179.002182)
			(xy 369.623113 -178.969183) (xy 369.640328 -178.904744) (xy 369.665818 -178.843108) (xy 369.699145 -178.785332)
			(xy 369.739739 -178.732409) (xy 369.786902 -178.685245) (xy 369.839824 -178.64465) (xy 369.86845 -178.627532)
			(xy 370.792502 -178.093878) (xy 370.82156 -178.077769) (xy 370.882966 -178.0524) (xy 370.947153 -178.035245)
			(xy 371.013028 -178.026597) (xy 371.046248 -178.02606) (xy 371.046756 -178.02606) (xy 371.080179 -178.026555)
			(xy 371.146455 -178.035258) (xy 371.211015 -178.052587) (xy 371.242082 -178.064922) (xy 371.251563 -178.068338)
			(xy 371.271699 -178.068246) (xy 371.290265 -178.060452) (xy 371.304434 -178.046144) (xy 371.30863 -178.036982)
			(xy 371.319681 -178.010843) (xy 371.348365 -177.961879) (xy 371.383986 -177.917704) (xy 371.425758 -177.879294)
			(xy 371.47276 -177.847497) (xy 371.523955 -177.823014) (xy 371.578211 -177.806386) (xy 371.634332 -177.79798)
			(xy 371.662706 -177.79746) (xy 371.689955 -177.798011) (xy 371.743897 -177.805767) (xy 371.796187 -177.821121)
			(xy 371.845759 -177.843761) (xy 371.891605 -177.873225) (xy 371.932791 -177.908913) (xy 371.968479 -177.9501)
			(xy 371.997942 -177.995946) (xy 372.020581 -178.045519) (xy 372.035934 -178.097809) (xy 372.04369 -178.151751)
			(xy 372.04369 -178.206249) (xy 372.035934 -178.260191) (xy 372.020581 -178.312481) (xy 371.997942 -178.362054)
			(xy 371.968479 -178.4079) (xy 371.932791 -178.449087) (xy 371.891605 -178.484775) (xy 371.845759 -178.514239)
			(xy 371.796187 -178.536879) (xy 371.743897 -178.552233) (xy 371.689955 -178.559989) (xy 371.662706 -178.560476)
			(xy 371.662198 -178.560476) (xy 371.648753 -178.56036) (xy 371.621931 -178.558451) (xy 371.608604 -178.556666)
			(xy 371.59857 -178.555685) (xy 371.57908 -178.560791) (xy 371.56305 -178.572995) (xy 371.552942 -178.590423)
			(xy 371.5512 -178.600354) (xy 371.546342 -178.633352) (xy 371.529125 -178.697789) (xy 371.503635 -178.759424)
			(xy 371.470307 -178.817199) (xy 371.429715 -178.870123) (xy 371.382554 -178.917287) (xy 371.329634 -178.957884)
			(xy 371.30101 -178.975004) (xy 370.610727 -179.373653) (xy 392.93263 -179.373653) (xy 392.93263 -179.319147)
			(xy 392.940386 -179.265195) (xy 392.955742 -179.212897) (xy 392.978383 -179.163316) (xy 393.00785 -179.117461)
			(xy 393.043542 -179.076266) (xy 393.084734 -179.04057) (xy 393.130586 -179.0111) (xy 393.180165 -178.988454)
			(xy 393.232462 -178.973094) (xy 393.286413 -178.965332) (xy 393.313666 -178.964844) (xy 393.31392 -178.964844)
			(xy 393.341164 -178.965318) (xy 393.395095 -178.973092) (xy 393.421362 -178.980338) (xy 393.436348 -178.98414)
			(xy 393.467243 -178.983622) (xy 393.496574 -178.9739) (xy 393.521661 -178.955861) (xy 393.540216 -178.931153)
			(xy 393.550545 -178.902031) (xy 393.551664 -178.886612) (xy 393.553084 -178.860019) (xy 393.562379 -178.807582)
			(xy 393.578876 -178.756948) (xy 393.602256 -178.709101) (xy 393.632064 -178.66497) (xy 393.667719 -178.625415)
			(xy 393.708531 -178.591203) (xy 393.753703 -178.563) (xy 393.80236 -178.541354) (xy 393.853554 -178.526687)
			(xy 393.906291 -178.519282) (xy 393.932918 -178.51882) (xy 393.96017 -178.519251) (xy 394.01412 -178.52701)
			(xy 394.066417 -178.542368) (xy 394.115995 -178.565012) (xy 394.161847 -178.594481) (xy 394.203038 -178.630175)
			(xy 394.23873 -178.671368) (xy 394.268197 -178.717221) (xy 394.290838 -178.7668) (xy 394.306194 -178.819097)
			(xy 394.31395 -178.873048) (xy 394.31395 -178.927552) (xy 394.306194 -178.981503) (xy 394.290838 -179.0338)
			(xy 394.268197 -179.083379) (xy 394.23873 -179.129232) (xy 394.203038 -179.170425) (xy 394.161847 -179.206119)
			(xy 394.115995 -179.235588) (xy 394.066417 -179.258232) (xy 394.01412 -179.27359) (xy 393.96017 -179.281349)
			(xy 393.932918 -179.281836) (xy 393.932664 -179.281836) (xy 393.90542 -179.281367) (xy 393.851489 -179.27359)
			(xy 393.825222 -179.266342) (xy 393.810237 -179.262541) (xy 393.779343 -179.263063) (xy 393.750015 -179.272787)
			(xy 393.724929 -179.290825) (xy 393.706373 -179.315531) (xy 393.696042 -179.34465) (xy 393.69492 -179.360068)
			(xy 393.693497 -179.386661) (xy 393.684205 -179.439099) (xy 393.667709 -179.489734) (xy 393.64433 -179.537582)
			(xy 393.614523 -179.581713) (xy 393.578868 -179.62127) (xy 393.538056 -179.655482) (xy 393.492883 -179.683684)
			(xy 393.444226 -179.705329) (xy 393.393031 -179.719996) (xy 393.340293 -179.727399) (xy 393.313666 -179.72786)
			(xy 393.286413 -179.727468) (xy 393.232462 -179.719706) (xy 393.180165 -179.704346) (xy 393.130586 -179.6817)
			(xy 393.084734 -179.65223) (xy 393.043542 -179.616534) (xy 393.00785 -179.575339) (xy 392.978383 -179.529484)
			(xy 392.955742 -179.479903) (xy 392.940386 -179.427605) (xy 392.93263 -179.373653) (xy 370.610727 -179.373653)
			(xy 370.376958 -179.508658) (xy 370.34791 -179.524786) (xy 370.2865 -179.55015) (xy 370.22231 -179.567299)
			(xy 370.156433 -179.575942) (xy 370.123212 -179.576476) (xy 370.122704 -179.576476) (xy 370.089281 -179.575991)
			(xy 370.023005 -179.567283) (xy 369.958445 -179.549951) (xy 369.927378 -179.537614) (xy 369.917888 -179.534261)
			(xy 369.897781 -179.534367) (xy 369.879243 -179.542152) (xy 369.86509 -179.556435) (xy 369.86083 -179.565554)
			(xy 369.84983 -179.591715) (xy 369.821138 -179.64068) (xy 369.785509 -179.684854) (xy 369.743729 -179.723262)
			(xy 369.69672 -179.755056) (xy 369.645519 -179.779535) (xy 369.591256 -179.796158) (xy 369.53513 -179.804559)
			(xy 369.506754 -179.805076) (xy 369.479503 -179.804651) (xy 369.425555 -179.796889) (xy 369.373262 -179.781528)
			(xy 369.323686 -179.758882) (xy 369.277838 -179.729412) (xy 369.236649 -179.693718) (xy 369.20096 -179.652525)
			(xy 369.171495 -179.606673) (xy 369.148856 -179.557095) (xy 369.133502 -179.5048) (xy 369.125746 -179.450851)
			(xy 362.555177 -179.450851) (xy 362.133642 -179.872386) (xy 397.069054 -179.872386) (xy 397.073125 -179.816764)
			(xy 397.085251 -179.762327) (xy 397.105174 -179.710236) (xy 397.13247 -179.661601) (xy 397.166556 -179.617458)
			(xy 397.206705 -179.578749) (xy 397.252063 -179.546298) (xy 397.301663 -179.520797) (xy 397.354447 -179.50279)
			(xy 397.40929 -179.49266) (xy 397.465024 -179.490623) (xy 397.520461 -179.496723) (xy 397.574418 -179.510829)
			(xy 397.625747 -179.532641) (xy 397.673353 -179.561695) (xy 397.716221 -179.59737) (xy 397.753438 -179.638907)
			(xy 397.784211 -179.68542) (xy 397.807883 -179.735917) (xy 397.823951 -179.789324) (xy 397.832071 -179.8445)
			(xy 397.83258 -179.872386) (xy 397.832071 -179.900272) (xy 397.823951 -179.955448) (xy 397.807883 -180.008855)
			(xy 397.784211 -180.059352) (xy 397.753438 -180.105865) (xy 397.716221 -180.147402) (xy 397.673353 -180.183077)
			(xy 397.625747 -180.212131) (xy 397.574418 -180.233943) (xy 397.520461 -180.248049) (xy 397.465024 -180.254149)
			(xy 397.40929 -180.252112) (xy 397.354447 -180.241982) (xy 397.301663 -180.223975) (xy 397.252063 -180.198474)
			(xy 397.206705 -180.166023) (xy 397.166556 -180.127314) (xy 397.13247 -180.083171) (xy 397.105174 -180.034536)
			(xy 397.085251 -179.982445) (xy 397.073125 -179.928008) (xy 397.069054 -179.872386) (xy 362.133642 -179.872386)
			(xy 361.695238 -180.31079) (xy 393.417042 -180.31079) (xy 393.421113 -180.255168) (xy 393.433239 -180.200731)
			(xy 393.453162 -180.14864) (xy 393.480458 -180.100005) (xy 393.514544 -180.055862) (xy 393.554693 -180.017153)
			(xy 393.600051 -179.984702) (xy 393.649651 -179.959201) (xy 393.702435 -179.941194) (xy 393.757278 -179.931064)
			(xy 393.813012 -179.929027) (xy 393.868449 -179.935127) (xy 393.922406 -179.949233) (xy 393.973735 -179.971045)
			(xy 394.021341 -180.000099) (xy 394.064209 -180.035774) (xy 394.101426 -180.077311) (xy 394.132199 -180.123824)
			(xy 394.155871 -180.174321) (xy 394.171939 -180.227728) (xy 394.180059 -180.282904) (xy 394.180568 -180.31079)
			(xy 394.180059 -180.338676) (xy 394.171939 -180.393852) (xy 394.155871 -180.447259) (xy 394.132199 -180.497756)
			(xy 394.101426 -180.544269) (xy 394.064209 -180.585806) (xy 394.021341 -180.621481) (xy 393.973735 -180.650535)
			(xy 393.922406 -180.672347) (xy 393.868449 -180.686453) (xy 393.813012 -180.692553) (xy 393.757278 -180.690516)
			(xy 393.702435 -180.680386) (xy 393.649651 -180.662379) (xy 393.600051 -180.636878) (xy 393.554693 -180.604427)
			(xy 393.514544 -180.565718) (xy 393.480458 -180.521575) (xy 393.453162 -180.47294) (xy 393.433239 -180.420849)
			(xy 393.421113 -180.366412) (xy 393.417042 -180.31079) (xy 361.695238 -180.31079) (xy 359.514878 -182.49115)
			(xy 369.046503 -182.49115) (xy 369.046503 -182.43665) (xy 369.054259 -182.382706) (xy 369.069614 -182.330414)
			(xy 369.092254 -182.28084) (xy 369.121719 -182.234992) (xy 369.157409 -182.193804) (xy 369.198597 -182.158115)
			(xy 369.244445 -182.128651) (xy 369.29402 -182.106012) (xy 369.346312 -182.090658) (xy 369.400256 -182.082903)
			(xy 369.427506 -182.08244) (xy 369.42776 -182.08244) (xy 369.447139 -182.082678) (xy 369.485696 -182.086624)
			(xy 369.504722 -182.090314) (xy 369.51782 -182.092594) (xy 369.544354 -182.091052) (xy 369.569596 -182.082731)
			(xy 369.591845 -182.068192) (xy 369.6096 -182.048415) (xy 369.621666 -182.024734) (xy 369.624864 -182.011828)
			(xy 369.631576 -181.982009) (xy 369.651189 -181.924118) (xy 369.677596 -181.868994) (xy 369.710416 -181.81743)
			(xy 369.749177 -181.770169) (xy 369.79332 -181.727891) (xy 369.84221 -181.691206) (xy 369.86845 -181.675532)
			(xy 370.792502 -181.141878) (xy 370.82156 -181.125769) (xy 370.882966 -181.1004) (xy 370.947153 -181.083245)
			(xy 371.013028 -181.074597) (xy 371.046248 -181.07406) (xy 371.046756 -181.07406) (xy 371.080179 -181.074555)
			(xy 371.146455 -181.083258) (xy 371.211015 -181.100587) (xy 371.242082 -181.112922) (xy 371.251563 -181.116338)
			(xy 371.271699 -181.116246) (xy 371.290265 -181.108452) (xy 371.304434 -181.094144) (xy 371.30863 -181.084982)
			(xy 371.319681 -181.058843) (xy 371.348365 -181.009879) (xy 371.383986 -180.965704) (xy 371.425758 -180.927294)
			(xy 371.47276 -180.895497) (xy 371.523955 -180.871014) (xy 371.578211 -180.854386) (xy 371.634332 -180.84598)
			(xy 371.662706 -180.84546) (xy 371.689955 -180.846011) (xy 371.743897 -180.853767) (xy 371.796187 -180.869121)
			(xy 371.845759 -180.891761) (xy 371.891605 -180.921225) (xy 371.932791 -180.956913) (xy 371.968479 -180.9981)
			(xy 371.997942 -181.043946) (xy 372.020581 -181.093519) (xy 372.035934 -181.145809) (xy 372.04369 -181.199751)
			(xy 372.04369 -181.254249) (xy 372.035934 -181.308191) (xy 372.020581 -181.360481) (xy 372.011096 -181.381251)
			(xy 372.910346 -181.381251) (xy 372.910346 -181.326749) (xy 372.918102 -181.2728) (xy 372.933456 -181.220505)
			(xy 372.956095 -181.170927) (xy 372.98556 -181.125075) (xy 373.021249 -181.083882) (xy 373.062438 -181.048188)
			(xy 373.108286 -181.018718) (xy 373.157862 -180.996072) (xy 373.210155 -180.980711) (xy 373.264103 -180.972949)
			(xy 373.291354 -180.97246) (xy 373.319727 -180.972978) (xy 373.375847 -180.981391) (xy 373.430102 -180.998023)
			(xy 373.481295 -181.022507) (xy 373.528297 -181.054303) (xy 373.570071 -181.09271) (xy 373.605696 -181.136881)
			(xy 373.634386 -181.185841) (xy 373.64543 -181.211982) (xy 373.649555 -181.221205) (xy 373.663696 -181.235614)
			(xy 373.682312 -181.243426) (xy 373.7025 -181.243423) (xy 373.711978 -181.239922) (xy 373.743057 -181.227621)
			(xy 373.807615 -181.210305) (xy 373.873884 -181.201579) (xy 373.907304 -181.20106) (xy 373.907812 -181.20106)
			(xy 373.941031 -181.201606) (xy 374.006903 -181.210264) (xy 374.071088 -181.227419) (xy 374.132496 -181.252778)
			(xy 374.161558 -181.268878) (xy 374.439081 -181.429152) (xy 399.642589 -181.429152) (xy 399.646611 -181.343432)
			(xy 399.658642 -181.258464) (xy 399.678578 -181.174997) (xy 399.706241 -181.093763) (xy 399.74139 -181.015477)
			(xy 399.783716 -180.940826) (xy 399.832845 -180.870467) (xy 399.888348 -180.805017) (xy 399.949735 -180.745053)
			(xy 400.016468 -180.6911) (xy 400.08796 -180.643633) (xy 400.163582 -180.603069) (xy 400.242671 -180.569765)
			(xy 400.324531 -180.544013) (xy 400.408442 -180.52604) (xy 400.493668 -180.516004) (xy 400.57946 -180.513992)
			(xy 400.665062 -180.520023) (xy 400.749724 -180.534043) (xy 400.832701 -180.555929) (xy 400.913264 -180.58549)
			(xy 400.990704 -180.622464) (xy 401.064343 -180.666528) (xy 401.133531 -180.717294) (xy 401.197662 -180.774315)
			(xy 401.256171 -180.837091) (xy 401.308544 -180.905071) (xy 401.354322 -180.977656) (xy 401.393102 -181.054208)
			(xy 401.424543 -181.134056) (xy 401.448369 -181.216497) (xy 401.46437 -181.300807) (xy 401.472405 -181.386245)
			(xy 401.472908 -181.429152) (xy 401.472405 -181.472059) (xy 401.46437 -181.557497) (xy 401.448369 -181.641807)
			(xy 401.424543 -181.724248) (xy 401.393102 -181.804096) (xy 401.354322 -181.880648) (xy 401.308544 -181.953233)
			(xy 401.256171 -182.021213) (xy 401.197662 -182.083989) (xy 401.133531 -182.14101) (xy 401.064343 -182.191776)
			(xy 400.990704 -182.23584) (xy 400.913264 -182.272814) (xy 400.832701 -182.302375) (xy 400.749724 -182.324261)
			(xy 400.665062 -182.338281) (xy 400.57946 -182.344312) (xy 400.493668 -182.3423) (xy 400.408442 -182.332264)
			(xy 400.324531 -182.314291) (xy 400.242671 -182.288539) (xy 400.163582 -182.255235) (xy 400.08796 -182.214671)
			(xy 400.016468 -182.167204) (xy 399.949735 -182.113251) (xy 399.888348 -182.053287) (xy 399.832845 -181.987837)
			(xy 399.783716 -181.917478) (xy 399.74139 -181.842827) (xy 399.706241 -181.764541) (xy 399.678578 -181.683307)
			(xy 399.658642 -181.59984) (xy 399.646611 -181.514872) (xy 399.642589 -181.429152) (xy 374.439081 -181.429152)
			(xy 375.08561 -181.802532) (xy 375.114227 -181.819663) (xy 375.167141 -181.860264) (xy 375.214298 -181.90743)
			(xy 375.25489 -181.960352) (xy 375.288221 -182.018122) (xy 375.313719 -182.079752) (xy 375.330949 -182.144184)
			(xy 375.3358 -182.177182) (xy 375.337563 -182.187112) (xy 375.347644 -182.204558) (xy 375.363672 -182.216767)
			(xy 375.383168 -182.221853) (xy 375.393204 -182.22087) (xy 375.406531 -182.219092) (xy 375.433353 -182.217187)
			(xy 375.446798 -182.21706) (xy 375.447306 -182.21706) (xy 375.474555 -182.217611) (xy 375.528497 -182.225367)
			(xy 375.580787 -182.240721) (xy 375.630359 -182.263361) (xy 375.676205 -182.292825) (xy 375.717391 -182.328513)
			(xy 375.753079 -182.3697) (xy 375.782542 -182.415546) (xy 375.805181 -182.465119) (xy 375.820534 -182.517409)
			(xy 375.82829 -182.571351) (xy 375.82829 -182.625849) (xy 375.820534 -182.679791) (xy 375.805181 -182.732081)
			(xy 375.782542 -182.781654) (xy 375.753079 -182.8275) (xy 375.717391 -182.868687) (xy 375.676205 -182.904375)
			(xy 375.630359 -182.933839) (xy 375.580787 -182.956479) (xy 375.528497 -182.971833) (xy 375.474555 -182.979589)
			(xy 375.447306 -182.980076) (xy 375.418933 -182.979569) (xy 375.362813 -182.971152) (xy 375.30856 -182.954516)
			(xy 375.257368 -182.93003) (xy 375.210366 -182.898232) (xy 375.168592 -182.859824) (xy 375.132966 -182.815654)
			(xy 375.104275 -182.766695) (xy 375.09323 -182.740554) (xy 375.089063 -182.731357) (xy 375.07493 -182.716961)
			(xy 375.056331 -182.709146) (xy 375.036158 -182.709128) (xy 375.026682 -182.712614) (xy 374.995609 -182.724929)
			(xy 374.931047 -182.742239) (xy 374.864777 -182.75096) (xy 374.831356 -182.751476) (xy 374.830848 -182.751476)
			(xy 374.797629 -182.750942) (xy 374.731757 -182.74228) (xy 374.667571 -182.725122) (xy 374.606164 -182.699759)
			(xy 374.577102 -182.683658) (xy 373.65305 -182.150004) (xy 373.624423 -182.132889) (xy 373.571507 -182.092287)
			(xy 373.524348 -182.04512) (xy 373.483757 -181.992196) (xy 373.450428 -181.934422) (xy 373.424932 -181.872789)
			(xy 373.407708 -181.808353) (xy 373.40286 -181.775354) (xy 373.401115 -181.765418) (xy 373.391034 -181.747964)
			(xy 373.374999 -181.735753) (xy 373.355494 -181.730676) (xy 373.345456 -181.731666) (xy 373.332128 -181.733438)
			(xy 373.305307 -181.735347) (xy 373.291862 -181.735476) (xy 373.291354 -181.735476) (xy 373.264103 -181.735051)
			(xy 373.210155 -181.727289) (xy 373.157862 -181.711928) (xy 373.108286 -181.689282) (xy 373.062438 -181.659812)
			(xy 373.021249 -181.624118) (xy 372.98556 -181.582925) (xy 372.956095 -181.537073) (xy 372.933456 -181.487495)
			(xy 372.918102 -181.4352) (xy 372.910346 -181.381251) (xy 372.011096 -181.381251) (xy 371.997942 -181.410054)
			(xy 371.968479 -181.4559) (xy 371.932791 -181.497087) (xy 371.891605 -181.532775) (xy 371.845759 -181.562239)
			(xy 371.796187 -181.584879) (xy 371.743897 -181.600233) (xy 371.689955 -181.607989) (xy 371.662706 -181.608476)
			(xy 371.662198 -181.608476) (xy 371.648753 -181.60836) (xy 371.621931 -181.606451) (xy 371.608604 -181.604666)
			(xy 371.59857 -181.603685) (xy 371.57908 -181.608791) (xy 371.56305 -181.620995) (xy 371.552942 -181.638423)
			(xy 371.5512 -181.648354) (xy 371.546342 -181.681352) (xy 371.529125 -181.745789) (xy 371.503635 -181.807424)
			(xy 371.470307 -181.865199) (xy 371.429715 -181.918123) (xy 371.382554 -181.965287) (xy 371.329634 -182.005884)
			(xy 371.30101 -182.023004) (xy 370.376958 -182.556658) (xy 370.34791 -182.572786) (xy 370.2865 -182.59815)
			(xy 370.22231 -182.615299) (xy 370.156433 -182.623942) (xy 370.123212 -182.624476) (xy 370.122704 -182.624476)
			(xy 370.085716 -182.623822) (xy 370.012514 -182.613154) (xy 369.941633 -182.591985) (xy 369.90782 -182.576978)
			(xy 369.895566 -182.571811) (xy 369.869385 -182.567226) (xy 369.842906 -182.569549) (xy 369.817923 -182.578624)
			(xy 369.796126 -182.593837) (xy 369.778991 -182.614156) (xy 369.772946 -182.626) (xy 369.761066 -182.65026)
			(xy 369.731442 -182.695431) (xy 369.695744 -182.735974) (xy 369.654687 -182.771078) (xy 369.60909 -182.800042)
			(xy 369.559864 -182.822288) (xy 369.507994 -182.83737) (xy 369.454515 -182.844987) (xy 369.427506 -182.845456)
			(xy 369.400256 -182.844897) (xy 369.346312 -182.837142) (xy 369.29402 -182.821788) (xy 369.244445 -182.799149)
			(xy 369.198597 -182.769685) (xy 369.157409 -182.733996) (xy 369.121719 -182.692808) (xy 369.092254 -182.64696)
			(xy 369.069614 -182.597386) (xy 369.054259 -182.545094) (xy 369.046503 -182.49115) (xy 359.514878 -182.49115)
			(xy 358.880918 -183.12511) (xy 364.66094 -183.12511) (xy 364.665011 -183.069488) (xy 364.677137 -183.015051)
			(xy 364.69706 -182.96296) (xy 364.724356 -182.914325) (xy 364.758442 -182.870182) (xy 364.798591 -182.831473)
			(xy 364.843949 -182.799022) (xy 364.893549 -182.773521) (xy 364.946333 -182.755514) (xy 365.001176 -182.745384)
			(xy 365.05691 -182.743347) (xy 365.112347 -182.749447) (xy 365.166304 -182.763553) (xy 365.217633 -182.785365)
			(xy 365.265239 -182.814419) (xy 365.308107 -182.850094) (xy 365.345324 -182.891631) (xy 365.376097 -182.938144)
			(xy 365.399769 -182.988641) (xy 365.415837 -183.042048) (xy 365.423957 -183.097224) (xy 365.424466 -183.12511)
			(xy 365.423957 -183.152996) (xy 365.415837 -183.208172) (xy 365.400478 -183.259222) (xy 373.211596 -183.259222)
			(xy 373.215667 -183.2036) (xy 373.227793 -183.149163) (xy 373.247716 -183.097072) (xy 373.275012 -183.048437)
			(xy 373.309098 -183.004294) (xy 373.349247 -182.965585) (xy 373.394605 -182.933134) (xy 373.444205 -182.907633)
			(xy 373.496989 -182.889626) (xy 373.551832 -182.879496) (xy 373.607566 -182.877459) (xy 373.663003 -182.883559)
			(xy 373.71696 -182.897665) (xy 373.768289 -182.919477) (xy 373.815895 -182.948531) (xy 373.858763 -182.984206)
			(xy 373.89598 -183.025743) (xy 373.926753 -183.072256) (xy 373.950425 -183.122753) (xy 373.966493 -183.17616)
			(xy 373.974613 -183.231336) (xy 373.975122 -183.259222) (xy 373.974613 -183.287108) (xy 373.966493 -183.342284)
			(xy 373.950425 -183.395691) (xy 373.926753 -183.446188) (xy 373.910009 -183.471496) (xy 399.668996 -183.471496)
			(xy 399.668996 -183.3868) (xy 399.677047 -183.302486) (xy 399.693076 -183.21932) (xy 399.716937 -183.138053)
			(xy 399.748416 -183.059423) (xy 399.787227 -182.984142) (xy 399.833017 -182.91289) (xy 399.885373 -182.846314)
			(xy 399.943821 -182.785016) (xy 400.007831 -182.729551) (xy 400.076823 -182.680422) (xy 400.150173 -182.638073)
			(xy 400.227216 -182.602889) (xy 400.307255 -182.575187) (xy 400.389564 -182.555219) (xy 400.473399 -182.543166)
			(xy 400.558 -182.539136) (xy 400.642601 -182.543166) (xy 400.726436 -182.555219) (xy 400.808745 -182.575187)
			(xy 400.888784 -182.602889) (xy 400.965827 -182.638073) (xy 401.039177 -182.680422) (xy 401.108169 -182.729551)
			(xy 401.172179 -182.785016) (xy 401.230627 -182.846314) (xy 401.282983 -182.91289) (xy 401.328773 -182.984142)
			(xy 401.367584 -183.059423) (xy 401.399063 -183.138053) (xy 401.422924 -183.21932) (xy 401.438953 -183.302486)
			(xy 401.447004 -183.3868) (xy 401.447508 -183.429148) (xy 401.447004 -183.471496) (xy 401.438953 -183.55581)
			(xy 401.422924 -183.638976) (xy 401.399063 -183.720243) (xy 401.367584 -183.798873) (xy 401.328773 -183.874154)
			(xy 401.282983 -183.945406) (xy 401.230627 -184.011982) (xy 401.172179 -184.07328) (xy 401.108169 -184.128745)
			(xy 401.039177 -184.177874) (xy 400.965827 -184.220223) (xy 400.888784 -184.255407) (xy 400.808745 -184.283109)
			(xy 400.726436 -184.303077) (xy 400.642601 -184.31513) (xy 400.558 -184.319161) (xy 400.473399 -184.31513)
			(xy 400.389564 -184.303077) (xy 400.307255 -184.283109) (xy 400.227216 -184.255407) (xy 400.150173 -184.220223)
			(xy 400.076823 -184.177874) (xy 400.007831 -184.128745) (xy 399.943821 -184.07328) (xy 399.885373 -184.011982)
			(xy 399.833017 -183.945406) (xy 399.787227 -183.874154) (xy 399.748416 -183.798873) (xy 399.716937 -183.720243)
			(xy 399.693076 -183.638976) (xy 399.677047 -183.55581) (xy 399.668996 -183.471496) (xy 373.910009 -183.471496)
			(xy 373.89598 -183.492701) (xy 373.858763 -183.534238) (xy 373.815895 -183.569913) (xy 373.768289 -183.598967)
			(xy 373.71696 -183.620779) (xy 373.663003 -183.634885) (xy 373.607566 -183.640985) (xy 373.551832 -183.638948)
			(xy 373.496989 -183.628818) (xy 373.444205 -183.610811) (xy 373.394605 -183.58531) (xy 373.349247 -183.552859)
			(xy 373.309098 -183.51415) (xy 373.275012 -183.470007) (xy 373.247716 -183.421372) (xy 373.227793 -183.369281)
			(xy 373.215667 -183.314844) (xy 373.211596 -183.259222) (xy 365.400478 -183.259222) (xy 365.399769 -183.261579)
			(xy 365.376097 -183.312076) (xy 365.345324 -183.358589) (xy 365.308107 -183.400126) (xy 365.265239 -183.435801)
			(xy 365.217633 -183.464855) (xy 365.166304 -183.486667) (xy 365.112347 -183.500773) (xy 365.05691 -183.506873)
			(xy 365.001176 -183.504836) (xy 364.946333 -183.494706) (xy 364.893549 -183.476699) (xy 364.843949 -183.451198)
			(xy 364.798591 -183.418747) (xy 364.758442 -183.380038) (xy 364.724356 -183.335895) (xy 364.69706 -183.28726)
			(xy 364.677137 -183.235169) (xy 364.665011 -183.180732) (xy 364.66094 -183.12511) (xy 358.880918 -183.12511)
			(xy 357.361998 -184.64403) (xy 369.50218 -184.64403) (xy 369.506251 -184.588408) (xy 369.518377 -184.533971)
			(xy 369.5383 -184.48188) (xy 369.565596 -184.433245) (xy 369.599682 -184.389102) (xy 369.639831 -184.350393)
			(xy 369.685189 -184.317942) (xy 369.734789 -184.292441) (xy 369.787573 -184.274434) (xy 369.842416 -184.264304)
			(xy 369.89815 -184.262267) (xy 369.953587 -184.268367) (xy 370.007544 -184.282473) (xy 370.058873 -184.304285)
			(xy 370.106479 -184.333339) (xy 370.149347 -184.369014) (xy 370.186564 -184.410551) (xy 370.217337 -184.457064)
			(xy 370.241009 -184.507561) (xy 370.257077 -184.560968) (xy 370.265197 -184.616144) (xy 370.265706 -184.64403)
			(xy 370.265197 -184.671916) (xy 370.263529 -184.683251) (xy 372.097546 -184.683251) (xy 372.097546 -184.628749)
			(xy 372.105302 -184.5748) (xy 372.120656 -184.522505) (xy 372.143295 -184.472927) (xy 372.17276 -184.427075)
			(xy 372.208449 -184.385882) (xy 372.249638 -184.350188) (xy 372.295486 -184.320718) (xy 372.345062 -184.298072)
			(xy 372.397355 -184.282711) (xy 372.451303 -184.274949) (xy 372.478554 -184.27446) (xy 372.506927 -184.274978)
			(xy 372.563047 -184.283391) (xy 372.617302 -184.300023) (xy 372.668495 -184.324507) (xy 372.715497 -184.356303)
			(xy 372.757271 -184.39471) (xy 372.792896 -184.438881) (xy 372.821586 -184.487841) (xy 372.83263 -184.513982)
			(xy 372.836755 -184.523205) (xy 372.850896 -184.537614) (xy 372.869512 -184.545426) (xy 372.8897 -184.545423)
			(xy 372.899178 -184.541922) (xy 372.930257 -184.529621) (xy 372.994815 -184.512305) (xy 373.061084 -184.503579)
			(xy 373.094504 -184.50306) (xy 373.095012 -184.50306) (xy 373.128231 -184.503606) (xy 373.194103 -184.512264)
			(xy 373.258288 -184.529419) (xy 373.319696 -184.554778) (xy 373.348758 -184.570878) (xy 374.27281 -185.104532)
			(xy 374.301427 -185.121663) (xy 374.354341 -185.162264) (xy 374.401498 -185.20943) (xy 374.44209 -185.262352)
			(xy 374.475421 -185.320122) (xy 374.500919 -185.381752) (xy 374.518149 -185.446184) (xy 374.523 -185.479182)
			(xy 374.524763 -185.489112) (xy 374.534844 -185.506558) (xy 374.550872 -185.518767) (xy 374.570368 -185.523853)
			(xy 374.580404 -185.52287) (xy 374.593731 -185.521092) (xy 374.620553 -185.519187) (xy 374.633998 -185.51906)
			(xy 374.634506 -185.51906) (xy 374.661755 -185.519611) (xy 374.715697 -185.527367) (xy 374.767987 -185.542721)
			(xy 374.817559 -185.565361) (xy 374.863405 -185.594825) (xy 374.904591 -185.630513) (xy 374.940279 -185.6717)
			(xy 374.969742 -185.717546) (xy 374.992381 -185.767119) (xy 375.007734 -185.819409) (xy 375.01549 -185.873351)
			(xy 375.01549 -185.927849) (xy 375.007734 -185.981791) (xy 374.992381 -186.034081) (xy 374.982596 -186.055508)
			(xy 380.051562 -186.055508) (xy 380.055633 -185.999886) (xy 380.067759 -185.945449) (xy 380.087682 -185.893358)
			(xy 380.114978 -185.844723) (xy 380.149064 -185.80058) (xy 380.189213 -185.761871) (xy 380.234571 -185.72942)
			(xy 380.284171 -185.703919) (xy 380.336955 -185.685912) (xy 380.391798 -185.675782) (xy 380.447532 -185.673745)
			(xy 380.502969 -185.679845) (xy 380.556926 -185.693951) (xy 380.608255 -185.715763) (xy 380.655861 -185.744817)
			(xy 380.698729 -185.780492) (xy 380.735946 -185.822029) (xy 380.766719 -185.868542) (xy 380.790391 -185.919039)
			(xy 380.806459 -185.972446) (xy 380.814579 -186.027622) (xy 380.815088 -186.055508) (xy 380.814579 -186.083394)
			(xy 380.806459 -186.13857) (xy 380.790391 -186.191977) (xy 380.766719 -186.242474) (xy 380.735946 -186.288987)
			(xy 380.698729 -186.330524) (xy 380.655861 -186.366199) (xy 380.608255 -186.395253) (xy 380.556926 -186.417065)
			(xy 380.502969 -186.431171) (xy 380.447532 -186.437271) (xy 380.391798 -186.435234) (xy 380.336955 -186.425104)
			(xy 380.284171 -186.407097) (xy 380.234571 -186.381596) (xy 380.189213 -186.349145) (xy 380.149064 -186.310436)
			(xy 380.114978 -186.266293) (xy 380.087682 -186.217658) (xy 380.067759 -186.165567) (xy 380.055633 -186.11113)
			(xy 380.051562 -186.055508) (xy 374.982596 -186.055508) (xy 374.969742 -186.083654) (xy 374.940279 -186.1295)
			(xy 374.904591 -186.170687) (xy 374.863405 -186.206375) (xy 374.817559 -186.235839) (xy 374.767987 -186.258479)
			(xy 374.715697 -186.273833) (xy 374.661755 -186.281589) (xy 374.634506 -186.282076) (xy 374.606133 -186.281569)
			(xy 374.550013 -186.273152) (xy 374.49576 -186.256516) (xy 374.444568 -186.23203) (xy 374.397566 -186.200232)
			(xy 374.355792 -186.161824) (xy 374.320166 -186.117654) (xy 374.291475 -186.068695) (xy 374.28043 -186.042554)
			(xy 374.276263 -186.033357) (xy 374.26213 -186.018961) (xy 374.243531 -186.011146) (xy 374.223358 -186.011128)
			(xy 374.213882 -186.014614) (xy 374.182809 -186.026929) (xy 374.118247 -186.044239) (xy 374.051977 -186.05296)
			(xy 374.018556 -186.053476) (xy 374.018048 -186.053476) (xy 373.984829 -186.052942) (xy 373.918957 -186.04428)
			(xy 373.854771 -186.027122) (xy 373.793364 -186.001759) (xy 373.764302 -185.985658) (xy 372.84025 -185.452004)
			(xy 372.811623 -185.434889) (xy 372.758707 -185.394287) (xy 372.711548 -185.34712) (xy 372.670957 -185.294196)
			(xy 372.637628 -185.236422) (xy 372.612132 -185.174789) (xy 372.594908 -185.110353) (xy 372.59006 -185.077354)
			(xy 372.588315 -185.067418) (xy 372.578234 -185.049964) (xy 372.562199 -185.037753) (xy 372.542694 -185.032676)
			(xy 372.532656 -185.033666) (xy 372.519328 -185.035438) (xy 372.492507 -185.037347) (xy 372.479062 -185.037476)
			(xy 372.478554 -185.037476) (xy 372.451303 -185.037051) (xy 372.397355 -185.029289) (xy 372.345062 -185.013928)
			(xy 372.295486 -184.991282) (xy 372.249638 -184.961812) (xy 372.208449 -184.926118) (xy 372.17276 -184.884925)
			(xy 372.143295 -184.839073) (xy 372.120656 -184.789495) (xy 372.105302 -184.7372) (xy 372.097546 -184.683251)
			(xy 370.263529 -184.683251) (xy 370.257077 -184.727092) (xy 370.241009 -184.780499) (xy 370.217337 -184.830996)
			(xy 370.186564 -184.877509) (xy 370.149347 -184.919046) (xy 370.106479 -184.954721) (xy 370.058873 -184.983775)
			(xy 370.007544 -185.005587) (xy 369.953587 -185.019693) (xy 369.89815 -185.025793) (xy 369.842416 -185.023756)
			(xy 369.787573 -185.013626) (xy 369.734789 -184.995619) (xy 369.685189 -184.970118) (xy 369.639831 -184.937667)
			(xy 369.599682 -184.898958) (xy 369.565596 -184.854815) (xy 369.5383 -184.80618) (xy 369.518377 -184.754089)
			(xy 369.506251 -184.699652) (xy 369.50218 -184.64403) (xy 357.361998 -184.64403) (xy 356.813612 -185.192416)
			(xy 363.706154 -185.192416) (xy 363.710225 -185.136794) (xy 363.722351 -185.082357) (xy 363.742274 -185.030266)
			(xy 363.76957 -184.981631) (xy 363.803656 -184.937488) (xy 363.843805 -184.898779) (xy 363.889163 -184.866328)
			(xy 363.938763 -184.840827) (xy 363.991547 -184.82282) (xy 364.04639 -184.81269) (xy 364.102124 -184.810653)
			(xy 364.157561 -184.816753) (xy 364.211518 -184.830859) (xy 364.262847 -184.852671) (xy 364.310453 -184.881725)
			(xy 364.353321 -184.9174) (xy 364.390538 -184.958937) (xy 364.421311 -185.00545) (xy 364.444983 -185.055947)
			(xy 364.461051 -185.109354) (xy 364.469171 -185.16453) (xy 364.46968 -185.192416) (xy 364.469171 -185.220302)
			(xy 364.461051 -185.275478) (xy 364.444983 -185.328885) (xy 364.425489 -185.37047) (xy 370.50548 -185.37047)
			(xy 370.509551 -185.314848) (xy 370.521677 -185.260411) (xy 370.5416 -185.20832) (xy 370.568896 -185.159685)
			(xy 370.602982 -185.115542) (xy 370.643131 -185.076833) (xy 370.688489 -185.044382) (xy 370.738089 -185.018881)
			(xy 370.790873 -185.000874) (xy 370.845716 -184.990744) (xy 370.90145 -184.988707) (xy 370.956887 -184.994807)
			(xy 371.010844 -185.008913) (xy 371.062173 -185.030725) (xy 371.109779 -185.059779) (xy 371.152647 -185.095454)
			(xy 371.189864 -185.136991) (xy 371.220637 -185.183504) (xy 371.244309 -185.234001) (xy 371.260377 -185.287408)
			(xy 371.268497 -185.342584) (xy 371.269006 -185.37047) (xy 371.268497 -185.398356) (xy 371.260377 -185.453532)
			(xy 371.244309 -185.506939) (xy 371.220637 -185.557436) (xy 371.189864 -185.603949) (xy 371.152647 -185.645486)
			(xy 371.109779 -185.681161) (xy 371.062173 -185.710215) (xy 371.010844 -185.732027) (xy 370.956887 -185.746133)
			(xy 370.90145 -185.752233) (xy 370.845716 -185.750196) (xy 370.790873 -185.740066) (xy 370.738089 -185.722059)
			(xy 370.688489 -185.696558) (xy 370.643131 -185.664107) (xy 370.602982 -185.625398) (xy 370.568896 -185.581255)
			(xy 370.5416 -185.53262) (xy 370.521677 -185.480529) (xy 370.509551 -185.426092) (xy 370.50548 -185.37047)
			(xy 364.425489 -185.37047) (xy 364.421311 -185.379382) (xy 364.390538 -185.425895) (xy 364.353321 -185.467432)
			(xy 364.310453 -185.503107) (xy 364.262847 -185.532161) (xy 364.211518 -185.553973) (xy 364.157561 -185.568079)
			(xy 364.102124 -185.574179) (xy 364.04639 -185.572142) (xy 363.991547 -185.562012) (xy 363.938763 -185.544005)
			(xy 363.889163 -185.518504) (xy 363.843805 -185.486053) (xy 363.803656 -185.447344) (xy 363.76957 -185.403201)
			(xy 363.742274 -185.354566) (xy 363.722351 -185.302475) (xy 363.710225 -185.248038) (xy 363.706154 -185.192416)
			(xy 356.813612 -185.192416) (xy 356.230174 -185.775854) (xy 369.36375 -185.775854) (xy 369.367821 -185.720232)
			(xy 369.379947 -185.665795) (xy 369.39987 -185.613704) (xy 369.427166 -185.565069) (xy 369.461252 -185.520926)
			(xy 369.501401 -185.482217) (xy 369.546759 -185.449766) (xy 369.596359 -185.424265) (xy 369.649143 -185.406258)
			(xy 369.703986 -185.396128) (xy 369.75972 -185.394091) (xy 369.815157 -185.400191) (xy 369.869114 -185.414297)
			(xy 369.920443 -185.436109) (xy 369.968049 -185.465163) (xy 370.010917 -185.500838) (xy 370.048134 -185.542375)
			(xy 370.078907 -185.588888) (xy 370.102579 -185.639385) (xy 370.118647 -185.692792) (xy 370.126767 -185.747968)
			(xy 370.127276 -185.775854) (xy 370.126767 -185.80374) (xy 370.118647 -185.858916) (xy 370.102579 -185.912323)
			(xy 370.078907 -185.96282) (xy 370.048134 -186.009333) (xy 370.010917 -186.05087) (xy 369.968049 -186.086545)
			(xy 369.920443 -186.115599) (xy 369.869114 -186.137411) (xy 369.815157 -186.151517) (xy 369.75972 -186.157617)
			(xy 369.703986 -186.15558) (xy 369.649143 -186.14545) (xy 369.596359 -186.127443) (xy 369.546759 -186.101942)
			(xy 369.501401 -186.069491) (xy 369.461252 -186.030782) (xy 369.427166 -185.986639) (xy 369.39987 -185.938004)
			(xy 369.379947 -185.885913) (xy 369.367821 -185.831476) (xy 369.36375 -185.775854) (xy 356.230174 -185.775854)
			(xy 354.291138 -187.71489) (xy 369.84813 -187.71489) (xy 369.848588 -187.687829) (xy 369.856255 -187.634252)
			(xy 369.871419 -187.582297) (xy 369.893775 -187.533008) (xy 369.922876 -187.487374) (xy 369.958135 -187.446312)
			(xy 369.978178 -187.428124) (xy 369.988628 -187.418318) (xy 370.004113 -187.394223) (xy 370.012298 -187.366775)
			(xy 370.01254 -187.338134) (xy 370.00482 -187.310552) (xy 369.989744 -187.286198) (xy 369.979448 -187.276232)
			(xy 369.960047 -187.258099) (xy 369.925991 -187.217353) (xy 369.897921 -187.172273) (xy 369.876382 -187.123734)
			(xy 369.861789 -187.072674) (xy 369.854427 -187.020082) (xy 369.853972 -186.99353) (xy 369.854486 -186.966592)
			(xy 369.862063 -186.913251) (xy 369.877068 -186.861507) (xy 369.899205 -186.812389) (xy 369.928033 -186.766874)
			(xy 369.962978 -186.725867) (xy 370.003345 -186.690186) (xy 370.04833 -186.660539) (xy 370.09704 -186.637517)
			(xy 370.148504 -186.621576) (xy 370.175028 -186.616848) (xy 370.188069 -186.614283) (xy 370.212312 -186.603417)
			(xy 370.232929 -186.586664) (xy 370.248525 -186.565157) (xy 370.258042 -186.540354) (xy 370.260837 -186.513936)
			(xy 370.256719 -186.487691) (xy 370.251736 -186.47537) (xy 370.241396 -186.450951) (xy 370.226818 -186.399965)
			(xy 370.219442 -186.347452) (xy 370.21897 -186.320938) (xy 370.21897 -186.32043) (xy 370.219456 -186.293179)
			(xy 370.227212 -186.239231) (xy 370.242567 -186.186936) (xy 370.265209 -186.137359) (xy 370.294675 -186.091509)
			(xy 370.330366 -186.050318) (xy 370.371557 -186.014627) (xy 370.417407 -185.985161) (xy 370.466984 -185.962519)
			(xy 370.519279 -185.947164) (xy 370.573227 -185.939408) (xy 370.627729 -185.939408) (xy 370.681677 -185.947164)
			(xy 370.733972 -185.962519) (xy 370.783549 -185.985161) (xy 370.829399 -186.014627) (xy 370.87059 -186.050318)
			(xy 370.906281 -186.091509) (xy 370.935747 -186.137359) (xy 370.958389 -186.186936) (xy 370.973744 -186.239231)
			(xy 370.9815 -186.293179) (xy 370.981986 -186.32043) (xy 370.981562 -186.347371) (xy 370.973977 -186.400718)
			(xy 370.958961 -186.452466) (xy 370.936814 -186.501587) (xy 370.907976 -186.547103) (xy 370.873021 -186.588109)
			(xy 370.832644 -186.623789) (xy 370.787649 -186.653433) (xy 370.73893 -186.676452) (xy 370.687458 -186.692387)
			(xy 370.66093 -186.697112) (xy 370.647897 -186.699704) (xy 370.623663 -186.710572) (xy 370.603052 -186.727323)
			(xy 370.58746 -186.748824) (xy 370.577941 -186.773619) (xy 370.57514 -186.80003) (xy 370.579246 -186.82627)
			(xy 370.584222 -186.83859) (xy 370.59249 -186.858148) (xy 374.039382 -186.858148) (xy 374.043453 -186.802526)
			(xy 374.055579 -186.748089) (xy 374.075502 -186.695998) (xy 374.102798 -186.647363) (xy 374.136884 -186.60322)
			(xy 374.177033 -186.564511) (xy 374.222391 -186.53206) (xy 374.271991 -186.506559) (xy 374.324775 -186.488552)
			(xy 374.379618 -186.478422) (xy 374.435352 -186.476385) (xy 374.490789 -186.482485) (xy 374.544746 -186.496591)
			(xy 374.596075 -186.518403) (xy 374.643681 -186.547457) (xy 374.686549 -186.583132) (xy 374.723766 -186.624669)
			(xy 374.754539 -186.671182) (xy 374.778211 -186.721679) (xy 374.794279 -186.775086) (xy 374.802399 -186.830262)
			(xy 374.802908 -186.858148) (xy 374.802399 -186.886034) (xy 374.794279 -186.94121) (xy 374.778211 -186.994617)
			(xy 374.754539 -187.045114) (xy 374.723766 -187.091627) (xy 374.686549 -187.133164) (xy 374.643681 -187.168839)
			(xy 374.596075 -187.197893) (xy 374.544746 -187.219705) (xy 374.490789 -187.233811) (xy 374.435352 -187.239911)
			(xy 374.379618 -187.237874) (xy 374.324775 -187.227744) (xy 374.271991 -187.209737) (xy 374.222391 -187.184236)
			(xy 374.177033 -187.151785) (xy 374.136884 -187.113076) (xy 374.102798 -187.068933) (xy 374.075502 -187.020298)
			(xy 374.055579 -186.968207) (xy 374.043453 -186.91377) (xy 374.039382 -186.858148) (xy 370.59249 -186.858148)
			(xy 370.594547 -186.863015) (xy 370.609131 -186.913998) (xy 370.616513 -186.966509) (xy 370.616988 -186.993022)
			(xy 370.616988 -186.99353) (xy 370.61647 -187.020589) (xy 370.608814 -187.074163) (xy 370.593662 -187.126117)
			(xy 370.571317 -187.175406) (xy 370.542227 -187.221041) (xy 370.506978 -187.262106) (xy 370.48694 -187.280296)
			(xy 370.476476 -187.290085) (xy 370.461005 -187.314188) (xy 370.452829 -187.341638) (xy 370.45259 -187.370279)
			(xy 370.460309 -187.397861) (xy 370.475378 -187.422218) (xy 370.48567 -187.432188) (xy 370.505035 -187.450357)
			(xy 370.539094 -187.491096) (xy 370.567168 -187.536168) (xy 370.588714 -187.584701) (xy 370.603314 -187.635754)
			(xy 370.610686 -187.68834) (xy 370.611146 -187.71489) (xy 370.610691 -187.741754) (xy 370.603143 -187.79495)
			(xy 370.588209 -187.846561) (xy 370.566184 -187.895568) (xy 370.537503 -187.941001) (xy 370.520468 -187.961778)
			(xy 370.511027 -187.973755) (xy 370.499095 -188.001807) (xy 370.495953 -188.032128) (xy 370.50188 -188.06203)
			(xy 370.51635 -188.088861) (xy 370.526818 -188.099954) (xy 370.548014 -188.121619) (xy 370.583974 -188.170406)
			(xy 370.611767 -188.224264) (xy 370.630695 -188.28184) (xy 370.632644 -188.29401) (xy 382.993392 -188.29401)
			(xy 382.993945 -188.265472) (xy 383.002435 -188.209031) (xy 383.019241 -188.154486) (xy 383.043988 -188.103055)
			(xy 383.076123 -188.055885) (xy 383.11493 -188.014032) (xy 383.136902 -187.995814) (xy 383.147143 -187.98716)
			(xy 383.163017 -187.965562) (xy 383.172726 -187.940577) (xy 383.175599 -187.913927) (xy 383.171439 -187.887447)
			(xy 383.160532 -187.862962) (xy 383.152396 -187.852304) (xy 383.136247 -187.83179) (xy 383.109068 -187.787213)
			(xy 383.088225 -187.739345) (xy 383.074106 -187.689082) (xy 383.066976 -187.637362) (xy 383.066544 -187.611258)
			(xy 383.06703 -187.584007) (xy 383.074786 -187.530059) (xy 383.090141 -187.477764) (xy 383.112783 -187.428187)
			(xy 383.142249 -187.382337) (xy 383.17794 -187.341146) (xy 383.219131 -187.305455) (xy 383.264981 -187.275989)
			(xy 383.314558 -187.253347) (xy 383.366853 -187.237992) (xy 383.420801 -187.230236) (xy 383.475303 -187.230236)
			(xy 383.529251 -187.237992) (xy 383.581546 -187.253347) (xy 383.631123 -187.275989) (xy 383.676973 -187.305455)
			(xy 383.718164 -187.341146) (xy 383.753855 -187.382337) (xy 383.783321 -187.428187) (xy 383.805963 -187.477764)
			(xy 383.821318 -187.530059) (xy 383.829074 -187.584007) (xy 383.82956 -187.611258) (xy 383.829036 -187.639797)
			(xy 383.820538 -187.696238) (xy 383.803725 -187.750783) (xy 383.778972 -187.802214) (xy 383.746833 -187.849383)
			(xy 383.708024 -187.891236) (xy 383.68605 -187.909454) (xy 383.675837 -187.918136) (xy 383.659968 -187.939729)
			(xy 383.650261 -187.964706) (xy 383.647384 -187.991348) (xy 383.651534 -188.017822) (xy 383.662427 -188.042305)
			(xy 383.670556 -188.052964) (xy 383.686744 -188.073449) (xy 383.713915 -188.118034) (xy 383.73475 -188.16591)
			(xy 383.74886 -188.216179) (xy 383.755981 -188.267904) (xy 383.756408 -188.29401) (xy 383.755922 -188.321261)
			(xy 383.748166 -188.375209) (xy 383.732811 -188.427504) (xy 383.710169 -188.477081) (xy 383.680703 -188.522931)
			(xy 383.645012 -188.564122) (xy 383.603821 -188.599813) (xy 383.557971 -188.629279) (xy 383.508394 -188.651921)
			(xy 383.456099 -188.667276) (xy 383.402151 -188.675032) (xy 383.347649 -188.675032) (xy 383.293701 -188.667276)
			(xy 383.241406 -188.651921) (xy 383.191829 -188.629279) (xy 383.145979 -188.599813) (xy 383.104788 -188.564122)
			(xy 383.069097 -188.522931) (xy 383.039631 -188.477081) (xy 383.016989 -188.427504) (xy 383.001634 -188.375209)
			(xy 382.993878 -188.321261) (xy 382.993392 -188.29401) (xy 370.632644 -188.29401) (xy 370.64028 -188.341684)
			(xy 370.640864 -188.371988) (xy 370.640378 -188.399239) (xy 370.632622 -188.453187) (xy 370.617267 -188.505482)
			(xy 370.594625 -188.555059) (xy 370.565159 -188.600909) (xy 370.529468 -188.6421) (xy 370.488277 -188.677791)
			(xy 370.442427 -188.707257) (xy 370.39285 -188.729899) (xy 370.340555 -188.745254) (xy 370.286607 -188.75301)
			(xy 370.232105 -188.75301) (xy 370.178157 -188.745254) (xy 370.125862 -188.729899) (xy 370.076285 -188.707257)
			(xy 370.030435 -188.677791) (xy 369.989244 -188.6421) (xy 369.953553 -188.600909) (xy 369.924087 -188.555059)
			(xy 369.901445 -188.505482) (xy 369.88609 -188.453187) (xy 369.878334 -188.399239) (xy 369.877848 -188.371988)
			(xy 369.878292 -188.345124) (xy 369.885843 -188.291927) (xy 369.90078 -188.240316) (xy 369.922807 -188.19131)
			(xy 369.95149 -188.145877) (xy 369.968526 -188.1251) (xy 369.977889 -188.113066) (xy 369.989832 -188.085036)
			(xy 369.99299 -188.054732) (xy 369.987082 -188.024842) (xy 369.972633 -187.998017) (xy 369.962176 -187.986924)
			(xy 369.940968 -187.96527) (xy 369.90501 -187.91648) (xy 369.877219 -187.862619) (xy 369.858294 -187.805041)
			(xy 369.848712 -187.745194) (xy 369.84813 -187.71489) (xy 354.291138 -187.71489) (xy 353.49688 -188.509148)
			(xy 353.49688 -189.812422) (xy 381.82372 -189.812422) (xy 381.827791 -189.7568) (xy 381.839917 -189.702363)
			(xy 381.85984 -189.650272) (xy 381.887136 -189.601637) (xy 381.921222 -189.557494) (xy 381.961371 -189.518785)
			(xy 382.006729 -189.486334) (xy 382.056329 -189.460833) (xy 382.109113 -189.442826) (xy 382.163956 -189.432696)
			(xy 382.21969 -189.430659) (xy 382.275127 -189.436759) (xy 382.329084 -189.450865) (xy 382.380413 -189.472677)
			(xy 382.428019 -189.501731) (xy 382.470887 -189.537406) (xy 382.508104 -189.578943) (xy 382.538877 -189.625456)
			(xy 382.562549 -189.675953) (xy 382.578617 -189.72936) (xy 382.586737 -189.784536) (xy 382.587246 -189.812422)
			(xy 382.586737 -189.840308) (xy 382.578617 -189.895484) (xy 382.562549 -189.948891) (xy 382.538877 -189.999388)
			(xy 382.508104 -190.045901) (xy 382.470887 -190.087438) (xy 382.428019 -190.123113) (xy 382.380413 -190.152167)
			(xy 382.329084 -190.173979) (xy 382.275127 -190.188085) (xy 382.21969 -190.194185) (xy 382.163956 -190.192148)
			(xy 382.109113 -190.182018) (xy 382.056329 -190.164011) (xy 382.006729 -190.13851) (xy 381.961371 -190.106059)
			(xy 381.921222 -190.06735) (xy 381.887136 -190.023207) (xy 381.85984 -189.974572) (xy 381.839917 -189.922481)
			(xy 381.827791 -189.868044) (xy 381.82372 -189.812422) (xy 353.49688 -189.812422) (xy 353.49688 -213.374986)
			(xy 353.538282 -213.38286) (xy 353.565071 -213.388474) (xy 353.616636 -213.406822) (xy 353.664789 -213.432841)
			(xy 353.708395 -213.465919) (xy 353.746429 -213.505277) (xy 353.777995 -213.54999) (xy 353.802351 -213.599005)
			(xy 353.818923 -213.651168) (xy 353.827322 -213.705252) (xy 353.827842 -213.732618) (xy 353.827329 -213.759267)
			(xy 354.055924 -213.759267) (xy 354.055924 -213.705969) (xy 354.063867 -213.653265) (xy 354.079577 -213.602335)
			(xy 354.102703 -213.554314) (xy 354.132727 -213.510277) (xy 354.168979 -213.471206) (xy 354.21065 -213.437975)
			(xy 354.256808 -213.411326) (xy 354.306422 -213.391854) (xy 354.358384 -213.379994) (xy 354.411534 -213.376011)
			(xy 354.464684 -213.379994) (xy 354.516646 -213.391854) (xy 354.56626 -213.411326) (xy 354.612418 -213.437975)
			(xy 354.654089 -213.471206) (xy 354.690341 -213.510277) (xy 354.720365 -213.554314) (xy 354.743491 -213.602335)
			(xy 354.759201 -213.653265) (xy 354.767144 -213.705969) (xy 354.767642 -213.732618) (xy 354.995226 -213.732618)
			(xy 354.995724 -213.705969) (xy 355.003667 -213.653265) (xy 355.019377 -213.602335) (xy 355.042503 -213.554314)
			(xy 355.072527 -213.510277) (xy 355.108779 -213.471206) (xy 355.15045 -213.437975) (xy 355.196608 -213.411326)
			(xy 355.246222 -213.391854) (xy 355.298184 -213.379994) (xy 355.351334 -213.376011) (xy 355.404484 -213.379994)
			(xy 355.456446 -213.391854) (xy 355.50606 -213.411326) (xy 355.552218 -213.437975) (xy 355.593889 -213.471206)
			(xy 355.630141 -213.510277) (xy 355.660165 -213.554314) (xy 355.683291 -213.602335) (xy 355.699001 -213.653265)
			(xy 355.706944 -213.705969) (xy 355.707442 -213.732618) (xy 355.706924 -213.759267) (xy 355.935524 -213.759267)
			(xy 355.935524 -213.705969) (xy 355.943467 -213.653265) (xy 355.959177 -213.602335) (xy 355.982303 -213.554314)
			(xy 356.012327 -213.510277) (xy 356.048579 -213.471206) (xy 356.09025 -213.437975) (xy 356.136408 -213.411326)
			(xy 356.186022 -213.391854) (xy 356.237984 -213.379994) (xy 356.291134 -213.376011) (xy 356.344284 -213.379994)
			(xy 356.396246 -213.391854) (xy 356.44586 -213.411326) (xy 356.492018 -213.437975) (xy 356.533689 -213.471206)
			(xy 356.569941 -213.510277) (xy 356.599965 -213.554314) (xy 356.623091 -213.602335) (xy 356.638801 -213.653265)
			(xy 356.646744 -213.705969) (xy 356.647242 -213.732618) (xy 356.646744 -213.759267) (xy 363.453924 -213.759267)
			(xy 363.453924 -213.705969) (xy 363.461867 -213.653265) (xy 363.477577 -213.602335) (xy 363.500703 -213.554314)
			(xy 363.530727 -213.510277) (xy 363.566979 -213.471206) (xy 363.60865 -213.437975) (xy 363.654808 -213.411326)
			(xy 363.704422 -213.391854) (xy 363.756384 -213.379994) (xy 363.809534 -213.376011) (xy 363.862684 -213.379994)
			(xy 363.914646 -213.391854) (xy 363.96426 -213.411326) (xy 364.010418 -213.437975) (xy 364.052089 -213.471206)
			(xy 364.088341 -213.510277) (xy 364.118365 -213.554314) (xy 364.141491 -213.602335) (xy 364.157201 -213.653265)
			(xy 364.165144 -213.705969) (xy 364.165642 -213.732618) (xy 364.165144 -213.759267) (xy 365.333524 -213.759267)
			(xy 365.333524 -213.705969) (xy 365.341467 -213.653265) (xy 365.357177 -213.602335) (xy 365.380303 -213.554314)
			(xy 365.410327 -213.510277) (xy 365.446579 -213.471206) (xy 365.48825 -213.437975) (xy 365.534408 -213.411326)
			(xy 365.584022 -213.391854) (xy 365.635984 -213.379994) (xy 365.689134 -213.376011) (xy 365.742284 -213.379994)
			(xy 365.794246 -213.391854) (xy 365.84386 -213.411326) (xy 365.890018 -213.437975) (xy 365.931689 -213.471206)
			(xy 365.967941 -213.510277) (xy 365.997965 -213.554314) (xy 366.021091 -213.602335) (xy 366.036801 -213.653265)
			(xy 366.044744 -213.705969) (xy 366.045242 -213.732618) (xy 366.044744 -213.759267) (xy 366.036801 -213.811971)
			(xy 366.021091 -213.862901) (xy 365.997965 -213.910922) (xy 365.967941 -213.954959) (xy 365.931689 -213.99403)
			(xy 365.890018 -214.027261) (xy 365.84386 -214.05391) (xy 365.794246 -214.073382) (xy 365.742284 -214.085242)
			(xy 365.689134 -214.089226) (xy 365.635984 -214.085242) (xy 365.584022 -214.073382) (xy 365.534408 -214.05391)
			(xy 365.48825 -214.027261) (xy 365.446579 -213.99403) (xy 365.410327 -213.954959) (xy 365.380303 -213.910922)
			(xy 365.357177 -213.862901) (xy 365.341467 -213.811971) (xy 365.333524 -213.759267) (xy 364.165144 -213.759267)
			(xy 364.157201 -213.811971) (xy 364.141491 -213.862901) (xy 364.118365 -213.910922) (xy 364.088341 -213.954959)
			(xy 364.052089 -213.99403) (xy 364.010418 -214.027261) (xy 363.96426 -214.05391) (xy 363.914646 -214.073382)
			(xy 363.862684 -214.085242) (xy 363.809534 -214.089226) (xy 363.756384 -214.085242) (xy 363.704422 -214.073382)
			(xy 363.654808 -214.05391) (xy 363.60865 -214.027261) (xy 363.566979 -213.99403) (xy 363.530727 -213.954959)
			(xy 363.500703 -213.910922) (xy 363.477577 -213.862901) (xy 363.461867 -213.811971) (xy 363.453924 -213.759267)
			(xy 356.646744 -213.759267) (xy 356.638801 -213.811971) (xy 356.623091 -213.862901) (xy 356.599965 -213.910922)
			(xy 356.569941 -213.954959) (xy 356.533689 -213.99403) (xy 356.492018 -214.027261) (xy 356.44586 -214.05391)
			(xy 356.396246 -214.073382) (xy 356.344284 -214.085242) (xy 356.291134 -214.089226) (xy 356.237984 -214.085242)
			(xy 356.186022 -214.073382) (xy 356.136408 -214.05391) (xy 356.09025 -214.027261) (xy 356.048579 -213.99403)
			(xy 356.012327 -213.954959) (xy 355.982303 -213.910922) (xy 355.959177 -213.862901) (xy 355.943467 -213.811971)
			(xy 355.935524 -213.759267) (xy 355.706924 -213.759267) (xy 355.706901 -213.760435) (xy 355.698257 -213.815393)
			(xy 355.681168 -213.868337) (xy 355.669088 -213.8934) (xy 355.65715 -213.916768) (xy 355.841554 -214.266272)
			(xy 355.867462 -214.269574) (xy 355.892807 -214.273456) (xy 355.942143 -214.287405) (xy 355.988969 -214.308285)
			(xy 356.032317 -214.335665) (xy 356.07129 -214.368977) (xy 356.105084 -214.407534) (xy 356.133 -214.450538)
			(xy 356.15446 -214.497101) (xy 356.169022 -214.54626) (xy 356.176383 -214.596999) (xy 356.176834 -214.622634)
			(xy 356.176336 -214.649283) (xy 356.168393 -214.701987) (xy 356.152683 -214.752917) (xy 356.129557 -214.800938)
			(xy 356.099533 -214.844975) (xy 356.063281 -214.884046) (xy 356.02161 -214.917277) (xy 355.975452 -214.943926)
			(xy 355.925838 -214.963398) (xy 355.873876 -214.975258) (xy 355.820726 -214.979242) (xy 355.767576 -214.975258)
			(xy 355.715614 -214.963398) (xy 355.666 -214.943926) (xy 355.619842 -214.917277) (xy 355.578171 -214.884046)
			(xy 355.541919 -214.844975) (xy 355.511895 -214.800938) (xy 355.488769 -214.752917) (xy 355.473059 -214.701987)
			(xy 355.465116 -214.649283) (xy 355.464618 -214.622634) (xy 355.465146 -214.594816) (xy 355.473795 -214.539858)
			(xy 355.490889 -214.486914) (xy 355.502972 -214.461852) (xy 355.51491 -214.438484) (xy 355.330506 -214.08898)
			(xy 355.304598 -214.085678) (xy 355.27924 -214.081874) (xy 355.2299 -214.067917) (xy 355.183071 -214.047028)
			(xy 355.139722 -214.01964) (xy 355.100748 -213.986319) (xy 355.066955 -213.947753) (xy 355.039042 -213.90474)
			(xy 355.017586 -213.858169) (xy 355.003029 -213.809002) (xy 354.995674 -213.758256) (xy 354.995226 -213.732618)
			(xy 354.767642 -213.732618) (xy 354.767144 -213.759267) (xy 354.759201 -213.811971) (xy 354.743491 -213.862901)
			(xy 354.720365 -213.910922) (xy 354.690341 -213.954959) (xy 354.654089 -213.99403) (xy 354.612418 -214.027261)
			(xy 354.56626 -214.05391) (xy 354.516646 -214.073382) (xy 354.464684 -214.085242) (xy 354.411534 -214.089226)
			(xy 354.358384 -214.085242) (xy 354.306422 -214.073382) (xy 354.256808 -214.05391) (xy 354.21065 -214.027261)
			(xy 354.168979 -213.99403) (xy 354.132727 -213.954959) (xy 354.102703 -213.910922) (xy 354.079577 -213.862901)
			(xy 354.063867 -213.811971) (xy 354.055924 -213.759267) (xy 353.827329 -213.759267) (xy 353.827306 -213.760435)
			(xy 353.818654 -213.815392) (xy 353.801565 -213.868336) (xy 353.789488 -213.8934) (xy 353.77755 -213.916768)
			(xy 353.961954 -214.266272) (xy 353.987862 -214.269574) (xy 354.013224 -214.273377) (xy 354.062576 -214.287321)
			(xy 354.109416 -214.3082) (xy 354.152778 -214.335582) (xy 354.191762 -214.368902) (xy 354.225564 -214.407469)
			(xy 354.253484 -214.450487) (xy 354.274944 -214.497064) (xy 354.2895 -214.546238) (xy 354.296852 -214.596992)
			(xy 354.297234 -214.622634) (xy 354.296683 -214.650616) (xy 354.287923 -214.705891) (xy 354.270626 -214.759115)
			(xy 354.245217 -214.808978) (xy 354.21232 -214.854253) (xy 354.172747 -214.893826) (xy 354.127471 -214.926721)
			(xy 354.077607 -214.952129) (xy 354.024383 -214.969425) (xy 353.969108 -214.978183) (xy 353.941126 -214.978742)
			(xy 353.915995 -214.978311) (xy 353.866233 -214.971246) (xy 353.817958 -214.957253) (xy 353.772132 -214.93661)
			(xy 353.729664 -214.909727) (xy 353.691399 -214.877138) (xy 353.674426 -214.8586) (xy 353.665034 -214.848696)
			(xy 353.642152 -214.833835) (xy 353.616151 -214.825568) (xy 353.588888 -214.824484) (xy 353.562312 -214.830661)
			(xy 353.538322 -214.843657) (xy 353.518632 -214.862544) (xy 353.504649 -214.885973) (xy 353.497372 -214.912269)
			(xy 353.49688 -214.92591) (xy 353.49688 -215.079072) (xy 353.538282 -215.086946) (xy 353.565059 -215.092568)
			(xy 353.616599 -215.11093) (xy 353.664723 -215.136959) (xy 353.7083 -215.170043) (xy 353.746303 -215.209404)
			(xy 353.777837 -215.254115) (xy 353.802162 -215.303123) (xy 353.818703 -215.355275) (xy 353.827072 -215.409344)
			(xy 353.827072 -215.436704) (xy 354.055172 -215.436704) (xy 354.055579 -215.411074) (xy 354.062915 -215.360342)
			(xy 354.07745 -215.311186) (xy 354.098884 -215.264623) (xy 354.126773 -215.221614) (xy 354.160541 -215.183049)
			(xy 354.199491 -215.149725) (xy 354.242817 -215.122331) (xy 354.289623 -215.101433) (xy 354.338942 -215.087463)
			(xy 354.36429 -215.083644) (xy 354.388928 -215.080342) (xy 354.561394 -214.781638) (xy 354.551742 -214.758524)
			(xy 354.543237 -214.736888) (xy 354.531245 -214.691972) (xy 354.525196 -214.645878) (xy 354.524818 -214.622634)
			(xy 354.525316 -214.595985) (xy 354.533259 -214.543281) (xy 354.548969 -214.492351) (xy 354.572095 -214.44433)
			(xy 354.602119 -214.400293) (xy 354.638371 -214.361222) (xy 354.680042 -214.327991) (xy 354.7262 -214.301342)
			(xy 354.775814 -214.28187) (xy 354.827776 -214.27001) (xy 354.880926 -214.266027) (xy 354.934076 -214.27001)
			(xy 354.986038 -214.28187) (xy 355.035652 -214.301342) (xy 355.08181 -214.327991) (xy 355.123481 -214.361222)
			(xy 355.159733 -214.400293) (xy 355.189757 -214.44433) (xy 355.212883 -214.492351) (xy 355.228593 -214.543281)
			(xy 355.236536 -214.595985) (xy 355.237034 -214.622634) (xy 355.236564 -214.648262) (xy 355.229237 -214.698991)
			(xy 355.214711 -214.748146) (xy 355.193285 -214.794708) (xy 355.165403 -214.837717) (xy 355.131641 -214.876282)
			(xy 355.092698 -214.909607) (xy 355.049378 -214.937003) (xy 355.002576 -214.957902) (xy 354.953262 -214.971874)
			(xy 354.927916 -214.975694) (xy 354.903278 -214.978996) (xy 354.730812 -215.2777) (xy 354.740464 -215.300814)
			(xy 354.748981 -215.322446) (xy 354.760968 -215.367364) (xy 354.767013 -215.413459) (xy 354.767388 -215.436704)
			(xy 354.76689 -215.463353) (xy 354.99547 -215.463353) (xy 354.99547 -215.410055) (xy 355.003413 -215.357351)
			(xy 355.019123 -215.306421) (xy 355.042249 -215.2584) (xy 355.072273 -215.214363) (xy 355.108525 -215.175292)
			(xy 355.150196 -215.142061) (xy 355.196354 -215.115412) (xy 355.245968 -215.09594) (xy 355.29793 -215.08408)
			(xy 355.35108 -215.080097) (xy 355.40423 -215.08408) (xy 355.456192 -215.09594) (xy 355.505806 -215.115412)
			(xy 355.551964 -215.142061) (xy 355.593635 -215.175292) (xy 355.629887 -215.214363) (xy 355.659911 -215.2584)
			(xy 355.683037 -215.306421) (xy 355.698747 -215.357351) (xy 355.70669 -215.410055) (xy 355.707188 -215.436704)
			(xy 355.934772 -215.436704) (xy 355.935179 -215.411074) (xy 355.942515 -215.360342) (xy 355.95705 -215.311186)
			(xy 355.978484 -215.264623) (xy 356.006373 -215.221614) (xy 356.040141 -215.183049) (xy 356.079091 -215.149725)
			(xy 356.122417 -215.122331) (xy 356.169223 -215.101433) (xy 356.218542 -215.087463) (xy 356.24389 -215.083644)
			(xy 356.268528 -215.080342) (xy 356.440994 -214.781638) (xy 356.431342 -214.758524) (xy 356.422837 -214.736888)
			(xy 356.410845 -214.691972) (xy 356.404796 -214.645878) (xy 356.404418 -214.622634) (xy 356.404916 -214.595985)
			(xy 356.412859 -214.543281) (xy 356.428569 -214.492351) (xy 356.451695 -214.44433) (xy 356.481719 -214.400293)
			(xy 356.517971 -214.361222) (xy 356.559642 -214.327991) (xy 356.6058 -214.301342) (xy 356.655414 -214.28187)
			(xy 356.707376 -214.27001) (xy 356.760526 -214.266027) (xy 356.813676 -214.27001) (xy 356.865638 -214.28187)
			(xy 356.915252 -214.301342) (xy 356.96141 -214.327991) (xy 357.003081 -214.361222) (xy 357.039333 -214.400293)
			(xy 357.069357 -214.44433) (xy 357.092483 -214.492351) (xy 357.108193 -214.543281) (xy 357.116136 -214.595985)
			(xy 357.116634 -214.622634) (xy 357.116164 -214.648262) (xy 357.116017 -214.649283) (xy 357.344716 -214.649283)
			(xy 357.344716 -214.595985) (xy 357.352659 -214.543281) (xy 357.368369 -214.492351) (xy 357.391495 -214.44433)
			(xy 357.421519 -214.400293) (xy 357.457771 -214.361222) (xy 357.499442 -214.327991) (xy 357.5456 -214.301342)
			(xy 357.595214 -214.28187) (xy 357.647176 -214.27001) (xy 357.700326 -214.266027) (xy 357.753476 -214.27001)
			(xy 357.805438 -214.28187) (xy 357.855052 -214.301342) (xy 357.90121 -214.327991) (xy 357.942881 -214.361222)
			(xy 357.979133 -214.400293) (xy 358.009157 -214.44433) (xy 358.032283 -214.492351) (xy 358.047993 -214.543281)
			(xy 358.055936 -214.595985) (xy 358.056434 -214.622634) (xy 358.284018 -214.622634) (xy 358.284516 -214.595985)
			(xy 358.292459 -214.543281) (xy 358.308169 -214.492351) (xy 358.331295 -214.44433) (xy 358.361319 -214.400293)
			(xy 358.397571 -214.361222) (xy 358.439242 -214.327991) (xy 358.4854 -214.301342) (xy 358.535014 -214.28187)
			(xy 358.586976 -214.27001) (xy 358.640126 -214.266027) (xy 358.693276 -214.27001) (xy 358.745238 -214.28187)
			(xy 358.794852 -214.301342) (xy 358.84101 -214.327991) (xy 358.882681 -214.361222) (xy 358.918933 -214.400293)
			(xy 358.948957 -214.44433) (xy 358.972083 -214.492351) (xy 358.987793 -214.543281) (xy 358.995736 -214.595985)
			(xy 358.996234 -214.622634) (xy 358.995861 -214.645837) (xy 358.995408 -214.649283) (xy 359.224316 -214.649283)
			(xy 359.224316 -214.595985) (xy 359.232259 -214.543281) (xy 359.247969 -214.492351) (xy 359.271095 -214.44433)
			(xy 359.301119 -214.400293) (xy 359.337371 -214.361222) (xy 359.379042 -214.327991) (xy 359.4252 -214.301342)
			(xy 359.474814 -214.28187) (xy 359.526776 -214.27001) (xy 359.579926 -214.266027) (xy 359.633076 -214.27001)
			(xy 359.685038 -214.28187) (xy 359.734652 -214.301342) (xy 359.78081 -214.327991) (xy 359.822481 -214.361222)
			(xy 359.858733 -214.400293) (xy 359.888757 -214.44433) (xy 359.911883 -214.492351) (xy 359.927593 -214.543281)
			(xy 359.935536 -214.595985) (xy 359.936034 -214.622634) (xy 359.935536 -214.649283) (xy 359.927593 -214.701987)
			(xy 359.911883 -214.752917) (xy 359.888757 -214.800938) (xy 359.858733 -214.844975) (xy 359.822481 -214.884046)
			(xy 359.78081 -214.917277) (xy 359.734652 -214.943926) (xy 359.685038 -214.963398) (xy 359.633076 -214.975258)
			(xy 359.579926 -214.979242) (xy 359.526776 -214.975258) (xy 359.474814 -214.963398) (xy 359.4252 -214.943926)
			(xy 359.379042 -214.917277) (xy 359.337371 -214.884046) (xy 359.301119 -214.844975) (xy 359.271095 -214.800938)
			(xy 359.247969 -214.752917) (xy 359.232259 -214.701987) (xy 359.224316 -214.649283) (xy 358.995408 -214.649283)
			(xy 358.989808 -214.691848) (xy 358.977821 -214.73668) (xy 358.96931 -214.75827) (xy 358.959912 -214.781384)
			(xy 359.132632 -215.080342) (xy 359.157524 -215.083644) (xy 359.182844 -215.08753) (xy 359.232113 -215.101548)
			(xy 359.278867 -215.122477) (xy 359.322141 -215.149886) (xy 359.361045 -215.18321) (xy 359.394774 -215.221762)
			(xy 359.422636 -215.264747) (xy 359.444054 -215.311278) (xy 359.458588 -215.360398) (xy 359.465937 -215.411092)
			(xy 359.466388 -215.436704) (xy 359.46589 -215.463353) (xy 359.69447 -215.463353) (xy 359.69447 -215.410055)
			(xy 359.702413 -215.357351) (xy 359.718123 -215.306421) (xy 359.741249 -215.2584) (xy 359.771273 -215.214363)
			(xy 359.807525 -215.175292) (xy 359.849196 -215.142061) (xy 359.895354 -215.115412) (xy 359.944968 -215.09594)
			(xy 359.99693 -215.08408) (xy 360.05008 -215.080097) (xy 360.10323 -215.08408) (xy 360.155192 -215.09594)
			(xy 360.204806 -215.115412) (xy 360.250964 -215.142061) (xy 360.292635 -215.175292) (xy 360.328887 -215.214363)
			(xy 360.358911 -215.2584) (xy 360.382037 -215.306421) (xy 360.397747 -215.357351) (xy 360.40569 -215.410055)
			(xy 360.406188 -215.436704) (xy 360.40569 -215.463353) (xy 360.63427 -215.463353) (xy 360.63427 -215.410055)
			(xy 360.642213 -215.357351) (xy 360.657923 -215.306421) (xy 360.681049 -215.2584) (xy 360.711073 -215.214363)
			(xy 360.747325 -215.175292) (xy 360.788996 -215.142061) (xy 360.835154 -215.115412) (xy 360.884768 -215.09594)
			(xy 360.93673 -215.08408) (xy 360.98988 -215.080097) (xy 361.04303 -215.08408) (xy 361.094992 -215.09594)
			(xy 361.144606 -215.115412) (xy 361.190764 -215.142061) (xy 361.232435 -215.175292) (xy 361.268687 -215.214363)
			(xy 361.298711 -215.2584) (xy 361.321837 -215.306421) (xy 361.337547 -215.357351) (xy 361.34549 -215.410055)
			(xy 361.345988 -215.436704) (xy 361.34549 -215.463353) (xy 362.51387 -215.463353) (xy 362.51387 -215.410055)
			(xy 362.521813 -215.357351) (xy 362.537523 -215.306421) (xy 362.560649 -215.2584) (xy 362.590673 -215.214363)
			(xy 362.626925 -215.175292) (xy 362.668596 -215.142061) (xy 362.714754 -215.115412) (xy 362.764368 -215.09594)
			(xy 362.81633 -215.08408) (xy 362.86948 -215.080097) (xy 362.92263 -215.08408) (xy 362.974592 -215.09594)
			(xy 363.024206 -215.115412) (xy 363.070364 -215.142061) (xy 363.112035 -215.175292) (xy 363.148287 -215.214363)
			(xy 363.178311 -215.2584) (xy 363.201437 -215.306421) (xy 363.217147 -215.357351) (xy 363.22509 -215.410055)
			(xy 363.225588 -215.436704) (xy 363.22509 -215.463353) (xy 363.217147 -215.516057) (xy 363.201437 -215.566987)
			(xy 363.178311 -215.615008) (xy 363.148287 -215.659045) (xy 363.112035 -215.698116) (xy 363.070364 -215.731347)
			(xy 363.024206 -215.757996) (xy 362.974592 -215.777468) (xy 362.92263 -215.789328) (xy 362.86948 -215.793312)
			(xy 362.81633 -215.789328) (xy 362.764368 -215.777468) (xy 362.714754 -215.757996) (xy 362.668596 -215.731347)
			(xy 362.626925 -215.698116) (xy 362.590673 -215.659045) (xy 362.560649 -215.615008) (xy 362.537523 -215.566987)
			(xy 362.521813 -215.516057) (xy 362.51387 -215.463353) (xy 361.34549 -215.463353) (xy 361.337547 -215.516057)
			(xy 361.321837 -215.566987) (xy 361.298711 -215.615008) (xy 361.268687 -215.659045) (xy 361.232435 -215.698116)
			(xy 361.190764 -215.731347) (xy 361.144606 -215.757996) (xy 361.094992 -215.777468) (xy 361.04303 -215.789328)
			(xy 360.98988 -215.793312) (xy 360.93673 -215.789328) (xy 360.884768 -215.777468) (xy 360.835154 -215.757996)
			(xy 360.788996 -215.731347) (xy 360.747325 -215.698116) (xy 360.711073 -215.659045) (xy 360.681049 -215.615008)
			(xy 360.657923 -215.566987) (xy 360.642213 -215.516057) (xy 360.63427 -215.463353) (xy 360.40569 -215.463353)
			(xy 360.397747 -215.516057) (xy 360.382037 -215.566987) (xy 360.358911 -215.615008) (xy 360.328887 -215.659045)
			(xy 360.292635 -215.698116) (xy 360.250964 -215.731347) (xy 360.204806 -215.757996) (xy 360.155192 -215.777468)
			(xy 360.10323 -215.789328) (xy 360.05008 -215.793312) (xy 359.99693 -215.789328) (xy 359.944968 -215.777468)
			(xy 359.895354 -215.757996) (xy 359.849196 -215.731347) (xy 359.807525 -215.698116) (xy 359.771273 -215.659045)
			(xy 359.741249 -215.615008) (xy 359.718123 -215.566987) (xy 359.702413 -215.516057) (xy 359.69447 -215.463353)
			(xy 359.46589 -215.463353) (xy 359.457947 -215.516057) (xy 359.442237 -215.566987) (xy 359.419111 -215.615008)
			(xy 359.389087 -215.659045) (xy 359.352835 -215.698116) (xy 359.311164 -215.731347) (xy 359.265006 -215.757996)
			(xy 359.215392 -215.777468) (xy 359.16343 -215.789328) (xy 359.11028 -215.793312) (xy 359.05713 -215.789328)
			(xy 359.005168 -215.777468) (xy 358.955554 -215.757996) (xy 358.909396 -215.731347) (xy 358.867725 -215.698116)
			(xy 358.831473 -215.659045) (xy 358.801449 -215.615008) (xy 358.778323 -215.566987) (xy 358.762613 -215.516057)
			(xy 358.75467 -215.463353) (xy 358.754172 -215.436704) (xy 358.754556 -215.413501) (xy 358.760605 -215.367491)
			(xy 358.772587 -215.322658) (xy 358.781096 -215.301068) (xy 358.790494 -215.277954) (xy 358.618028 -214.978996)
			(xy 358.593136 -214.975694) (xy 358.567786 -214.971911) (xy 358.51848 -214.957915) (xy 358.471687 -214.936999)
			(xy 358.428375 -214.909592) (xy 358.389438 -214.876262) (xy 358.355678 -214.837697) (xy 358.327792 -214.794692)
			(xy 358.306357 -214.748135) (xy 358.291815 -214.698986) (xy 358.284466 -214.648261) (xy 358.284018 -214.622634)
			(xy 358.056434 -214.622634) (xy 358.055936 -214.649283) (xy 358.047993 -214.701987) (xy 358.032283 -214.752917)
			(xy 358.009157 -214.800938) (xy 357.979133 -214.844975) (xy 357.942881 -214.884046) (xy 357.90121 -214.917277)
			(xy 357.855052 -214.943926) (xy 357.805438 -214.963398) (xy 357.753476 -214.975258) (xy 357.700326 -214.979242)
			(xy 357.647176 -214.975258) (xy 357.595214 -214.963398) (xy 357.5456 -214.943926) (xy 357.499442 -214.917277)
			(xy 357.457771 -214.884046) (xy 357.421519 -214.844975) (xy 357.391495 -214.800938) (xy 357.368369 -214.752917)
			(xy 357.352659 -214.701987) (xy 357.344716 -214.649283) (xy 357.116017 -214.649283) (xy 357.108837 -214.698991)
			(xy 357.094311 -214.748146) (xy 357.072885 -214.794708) (xy 357.045003 -214.837717) (xy 357.011241 -214.876282)
			(xy 356.972298 -214.909607) (xy 356.928978 -214.937003) (xy 356.882176 -214.957902) (xy 356.832862 -214.971874)
			(xy 356.807516 -214.975694) (xy 356.782878 -214.978996) (xy 356.610412 -215.2777) (xy 356.620064 -215.300814)
			(xy 356.628581 -215.322446) (xy 356.640568 -215.367364) (xy 356.646613 -215.413459) (xy 356.646988 -215.4367)
			(xy 356.874096 -215.4367) (xy 356.878079 -215.383553) (xy 356.889938 -215.331593) (xy 356.909409 -215.281981)
			(xy 356.936056 -215.235824) (xy 356.969285 -215.194155) (xy 357.008352 -215.157903) (xy 357.052387 -215.127879)
			(xy 357.100404 -215.104753) (xy 357.151332 -215.089041) (xy 357.204032 -215.081095) (xy 357.23068 -215.080596)
			(xy 357.255693 -215.081056) (xy 357.305229 -215.088037) (xy 357.353301 -215.10188) (xy 357.398964 -215.122312)
			(xy 357.44132 -215.148931) (xy 357.479535 -215.181213) (xy 357.512858 -215.218524) (xy 357.527098 -215.239092)
			(xy 357.874062 -215.239092) (xy 357.888292 -215.218516) (xy 357.921622 -215.181209) (xy 357.959841 -215.148928)
			(xy 358.002198 -215.122307) (xy 358.04786 -215.10187) (xy 358.095931 -215.088016) (xy 358.145466 -215.081019)
			(xy 358.17048 -215.080596) (xy 358.197132 -215.08106) (xy 358.249842 -215.089002) (xy 358.30078 -215.104711)
			(xy 358.348806 -215.127837) (xy 358.39285 -215.157864) (xy 358.431926 -215.194119) (xy 358.465162 -215.235793)
			(xy 358.491815 -215.281956) (xy 358.511291 -215.331576) (xy 358.523152 -215.383544) (xy 358.527136 -215.4367)
			(xy 358.523152 -215.489856) (xy 358.511291 -215.541824) (xy 358.491815 -215.591444) (xy 358.465162 -215.637607)
			(xy 358.431926 -215.679281) (xy 358.39285 -215.715536) (xy 358.348806 -215.745563) (xy 358.30078 -215.768689)
			(xy 358.249842 -215.784398) (xy 358.197132 -215.79234) (xy 358.17048 -215.792812) (xy 358.145466 -215.792379)
			(xy 358.095929 -215.785392) (xy 358.047857 -215.771545) (xy 358.002194 -215.751108) (xy 357.959839 -215.724486)
			(xy 357.921624 -215.6922) (xy 357.888301 -215.654885) (xy 357.874062 -215.634316) (xy 357.527098 -215.634316)
			(xy 357.512832 -215.654865) (xy 357.479507 -215.692173) (xy 357.441295 -215.724455) (xy 357.398944 -215.751079)
			(xy 357.353288 -215.771521) (xy 357.305223 -215.785381) (xy 357.255692 -215.792385) (xy 357.23068 -215.792812)
			(xy 357.204032 -215.792305) (xy 357.151332 -215.784359) (xy 357.100404 -215.768647) (xy 357.052387 -215.745521)
			(xy 357.008352 -215.715497) (xy 356.969285 -215.679245) (xy 356.936056 -215.637576) (xy 356.909409 -215.591419)
			(xy 356.889938 -215.541807) (xy 356.878079 -215.489847) (xy 356.874096 -215.4367) (xy 356.646988 -215.4367)
			(xy 356.646988 -215.436704) (xy 356.64649 -215.463353) (xy 356.638547 -215.516057) (xy 356.622837 -215.566987)
			(xy 356.599711 -215.615008) (xy 356.569687 -215.659045) (xy 356.533435 -215.698116) (xy 356.491764 -215.731347)
			(xy 356.445606 -215.757996) (xy 356.395992 -215.777468) (xy 356.34403 -215.789328) (xy 356.29088 -215.793312)
			(xy 356.23773 -215.789328) (xy 356.185768 -215.777468) (xy 356.136154 -215.757996) (xy 356.089996 -215.731347)
			(xy 356.048325 -215.698116) (xy 356.012073 -215.659045) (xy 355.982049 -215.615008) (xy 355.958923 -215.566987)
			(xy 355.943213 -215.516057) (xy 355.93527 -215.463353) (xy 355.934772 -215.436704) (xy 355.707188 -215.436704)
			(xy 355.70669 -215.463353) (xy 355.698747 -215.516057) (xy 355.683037 -215.566987) (xy 355.659911 -215.615008)
			(xy 355.629887 -215.659045) (xy 355.593635 -215.698116) (xy 355.551964 -215.731347) (xy 355.505806 -215.757996)
			(xy 355.456192 -215.777468) (xy 355.40423 -215.789328) (xy 355.35108 -215.793312) (xy 355.29793 -215.789328)
			(xy 355.245968 -215.777468) (xy 355.196354 -215.757996) (xy 355.150196 -215.731347) (xy 355.108525 -215.698116)
			(xy 355.072273 -215.659045) (xy 355.042249 -215.615008) (xy 355.019123 -215.566987) (xy 355.003413 -215.516057)
			(xy 354.99547 -215.463353) (xy 354.76689 -215.463353) (xy 354.758947 -215.516057) (xy 354.743237 -215.566987)
			(xy 354.720111 -215.615008) (xy 354.690087 -215.659045) (xy 354.653835 -215.698116) (xy 354.612164 -215.731347)
			(xy 354.566006 -215.757996) (xy 354.516392 -215.777468) (xy 354.46443 -215.789328) (xy 354.41128 -215.793312)
			(xy 354.35813 -215.789328) (xy 354.306168 -215.777468) (xy 354.256554 -215.757996) (xy 354.210396 -215.731347)
			(xy 354.168725 -215.698116) (xy 354.132473 -215.659045) (xy 354.102449 -215.615008) (xy 354.079323 -215.566987)
			(xy 354.063613 -215.516057) (xy 354.05567 -215.463353) (xy 354.055172 -215.436704) (xy 353.827072 -215.436704)
			(xy 353.827072 -215.464057) (xy 353.818703 -215.518126) (xy 353.802161 -215.570278) (xy 353.777837 -215.619287)
			(xy 353.746302 -215.663997) (xy 353.708299 -215.703358) (xy 353.664722 -215.736442) (xy 353.616597 -215.762471)
			(xy 353.565058 -215.780832) (xy 353.538282 -215.786462) (xy 353.49688 -215.794336) (xy 353.49688 -215.947752)
			(xy 353.497318 -215.961431) (xy 353.504577 -215.987808) (xy 353.518586 -216.011307) (xy 353.538337 -216.030237)
			(xy 353.562409 -216.043236) (xy 353.589071 -216.049369) (xy 353.616403 -216.048196) (xy 353.642441 -216.039799)
			(xy 353.66531 -216.024784) (xy 353.67468 -216.014808) (xy 353.691657 -215.99623) (xy 353.729941 -215.963565)
			(xy 353.772443 -215.936617) (xy 353.818316 -215.915923) (xy 353.866647 -215.901895) (xy 353.916471 -215.894813)
			(xy 353.941634 -215.894412) (xy 353.96828 -215.894913) (xy 354.020977 -215.90286) (xy 354.0719 -215.918572)
			(xy 354.119913 -215.941698) (xy 354.163944 -215.971721) (xy 354.203008 -216.007971) (xy 354.236233 -216.049638)
			(xy 354.262878 -216.095791) (xy 354.282347 -216.1454) (xy 354.294205 -216.197357) (xy 354.298187 -216.2505)
			(xy 354.296189 -216.277169) (xy 354.525824 -216.277169) (xy 354.525824 -216.223871) (xy 354.533767 -216.171167)
			(xy 354.549477 -216.120237) (xy 354.572603 -216.072216) (xy 354.602627 -216.028179) (xy 354.638879 -215.989108)
			(xy 354.68055 -215.955877) (xy 354.726708 -215.929228) (xy 354.776322 -215.909756) (xy 354.828284 -215.897896)
			(xy 354.881434 -215.893913) (xy 354.934584 -215.897896) (xy 354.986546 -215.909756) (xy 355.03616 -215.929228)
			(xy 355.082318 -215.955877) (xy 355.123989 -215.989108) (xy 355.160241 -216.028179) (xy 355.190265 -216.072216)
			(xy 355.213391 -216.120237) (xy 355.229101 -216.171167) (xy 355.237044 -216.223871) (xy 355.237542 -216.25052)
			(xy 355.237044 -216.277169) (xy 355.465624 -216.277169) (xy 355.465624 -216.223871) (xy 355.473567 -216.171167)
			(xy 355.489277 -216.120237) (xy 355.512403 -216.072216) (xy 355.542427 -216.028179) (xy 355.578679 -215.989108)
			(xy 355.62035 -215.955877) (xy 355.666508 -215.929228) (xy 355.716122 -215.909756) (xy 355.768084 -215.897896)
			(xy 355.821234 -215.893913) (xy 355.874384 -215.897896) (xy 355.926346 -215.909756) (xy 355.97596 -215.929228)
			(xy 356.022118 -215.955877) (xy 356.063789 -215.989108) (xy 356.100041 -216.028179) (xy 356.130065 -216.072216)
			(xy 356.153191 -216.120237) (xy 356.168901 -216.171167) (xy 356.176844 -216.223871) (xy 356.177342 -216.25052)
			(xy 356.176844 -216.277169) (xy 356.405424 -216.277169) (xy 356.405424 -216.223871) (xy 356.413367 -216.171167)
			(xy 356.429077 -216.120237) (xy 356.452203 -216.072216) (xy 356.482227 -216.028179) (xy 356.518479 -215.989108)
			(xy 356.56015 -215.955877) (xy 356.606308 -215.929228) (xy 356.655922 -215.909756) (xy 356.707884 -215.897896)
			(xy 356.761034 -215.893913) (xy 356.814184 -215.897896) (xy 356.866146 -215.909756) (xy 356.91576 -215.929228)
			(xy 356.961918 -215.955877) (xy 357.003589 -215.989108) (xy 357.039841 -216.028179) (xy 357.069865 -216.072216)
			(xy 357.092991 -216.120237) (xy 357.108701 -216.171167) (xy 357.116644 -216.223871) (xy 357.117142 -216.25052)
			(xy 357.116644 -216.277169) (xy 357.345224 -216.277169) (xy 357.345224 -216.223871) (xy 357.353167 -216.171167)
			(xy 357.368877 -216.120237) (xy 357.392003 -216.072216) (xy 357.422027 -216.028179) (xy 357.458279 -215.989108)
			(xy 357.49995 -215.955877) (xy 357.546108 -215.929228) (xy 357.595722 -215.909756) (xy 357.647684 -215.897896)
			(xy 357.700834 -215.893913) (xy 357.753984 -215.897896) (xy 357.805946 -215.909756) (xy 357.85556 -215.929228)
			(xy 357.901718 -215.955877) (xy 357.943389 -215.989108) (xy 357.979641 -216.028179) (xy 358.009665 -216.072216)
			(xy 358.032791 -216.120237) (xy 358.048501 -216.171167) (xy 358.056444 -216.223871) (xy 358.056942 -216.25052)
			(xy 358.056444 -216.277169) (xy 358.285024 -216.277169) (xy 358.285024 -216.223871) (xy 358.292967 -216.171167)
			(xy 358.308677 -216.120237) (xy 358.331803 -216.072216) (xy 358.361827 -216.028179) (xy 358.398079 -215.989108)
			(xy 358.43975 -215.955877) (xy 358.485908 -215.929228) (xy 358.535522 -215.909756) (xy 358.587484 -215.897896)
			(xy 358.640634 -215.893913) (xy 358.693784 -215.897896) (xy 358.745746 -215.909756) (xy 358.79536 -215.929228)
			(xy 358.841518 -215.955877) (xy 358.883189 -215.989108) (xy 358.919441 -216.028179) (xy 358.949465 -216.072216)
			(xy 358.972591 -216.120237) (xy 358.988301 -216.171167) (xy 358.996244 -216.223871) (xy 358.996742 -216.25052)
			(xy 358.996244 -216.277169) (xy 359.224824 -216.277169) (xy 359.224824 -216.223871) (xy 359.232767 -216.171167)
			(xy 359.248477 -216.120237) (xy 359.271603 -216.072216) (xy 359.301627 -216.028179) (xy 359.337879 -215.989108)
			(xy 359.37955 -215.955877) (xy 359.425708 -215.929228) (xy 359.475322 -215.909756) (xy 359.527284 -215.897896)
			(xy 359.580434 -215.893913) (xy 359.633584 -215.897896) (xy 359.685546 -215.909756) (xy 359.73516 -215.929228)
			(xy 359.781318 -215.955877) (xy 359.822989 -215.989108) (xy 359.859241 -216.028179) (xy 359.889265 -216.072216)
			(xy 359.912391 -216.120237) (xy 359.928101 -216.171167) (xy 359.936044 -216.223871) (xy 359.936542 -216.25052)
			(xy 359.936044 -216.277169) (xy 360.16437 -216.277169) (xy 360.16437 -216.223871) (xy 360.172313 -216.171167)
			(xy 360.188023 -216.120237) (xy 360.211149 -216.072216) (xy 360.241173 -216.028179) (xy 360.277425 -215.989108)
			(xy 360.319096 -215.955877) (xy 360.365254 -215.929228) (xy 360.414868 -215.909756) (xy 360.46683 -215.897896)
			(xy 360.51998 -215.893913) (xy 360.57313 -215.897896) (xy 360.625092 -215.909756) (xy 360.674706 -215.929228)
			(xy 360.720864 -215.955877) (xy 360.762535 -215.989108) (xy 360.798787 -216.028179) (xy 360.828811 -216.072216)
			(xy 360.851937 -216.120237) (xy 360.867647 -216.171167) (xy 360.87559 -216.223871) (xy 360.876088 -216.25052)
			(xy 360.87559 -216.277169) (xy 361.10417 -216.277169) (xy 361.10417 -216.223871) (xy 361.112113 -216.171167)
			(xy 361.127823 -216.120237) (xy 361.150949 -216.072216) (xy 361.180973 -216.028179) (xy 361.217225 -215.989108)
			(xy 361.258896 -215.955877) (xy 361.305054 -215.929228) (xy 361.354668 -215.909756) (xy 361.40663 -215.897896)
			(xy 361.45978 -215.893913) (xy 361.51293 -215.897896) (xy 361.564892 -215.909756) (xy 361.614506 -215.929228)
			(xy 361.660664 -215.955877) (xy 361.702335 -215.989108) (xy 361.738587 -216.028179) (xy 361.768611 -216.072216)
			(xy 361.791737 -216.120237) (xy 361.807447 -216.171167) (xy 361.81539 -216.223871) (xy 361.815888 -216.25052)
			(xy 361.81539 -216.277169) (xy 362.044224 -216.277169) (xy 362.044224 -216.223871) (xy 362.052167 -216.171167)
			(xy 362.067877 -216.120237) (xy 362.091003 -216.072216) (xy 362.121027 -216.028179) (xy 362.157279 -215.989108)
			(xy 362.19895 -215.955877) (xy 362.245108 -215.929228) (xy 362.294722 -215.909756) (xy 362.346684 -215.897896)
			(xy 362.399834 -215.893913) (xy 362.452984 -215.897896) (xy 362.504946 -215.909756) (xy 362.55456 -215.929228)
			(xy 362.600718 -215.955877) (xy 362.642389 -215.989108) (xy 362.678641 -216.028179) (xy 362.708665 -216.072216)
			(xy 362.731791 -216.120237) (xy 362.747501 -216.171167) (xy 362.755444 -216.223871) (xy 362.755942 -216.25052)
			(xy 362.755444 -216.277169) (xy 362.98377 -216.277169) (xy 362.98377 -216.223871) (xy 362.991713 -216.171167)
			(xy 363.007423 -216.120237) (xy 363.030549 -216.072216) (xy 363.060573 -216.028179) (xy 363.096825 -215.989108)
			(xy 363.138496 -215.955877) (xy 363.184654 -215.929228) (xy 363.234268 -215.909756) (xy 363.28623 -215.897896)
			(xy 363.33938 -215.893913) (xy 363.39253 -215.897896) (xy 363.444492 -215.909756) (xy 363.494106 -215.929228)
			(xy 363.540264 -215.955877) (xy 363.581935 -215.989108) (xy 363.618187 -216.028179) (xy 363.648211 -216.072216)
			(xy 363.671337 -216.120237) (xy 363.687047 -216.171167) (xy 363.69499 -216.223871) (xy 363.695488 -216.25052)
			(xy 363.69499 -216.277169) (xy 363.923824 -216.277169) (xy 363.923824 -216.223871) (xy 363.931767 -216.171167)
			(xy 363.947477 -216.120237) (xy 363.970603 -216.072216) (xy 364.000627 -216.028179) (xy 364.036879 -215.989108)
			(xy 364.07855 -215.955877) (xy 364.124708 -215.929228) (xy 364.174322 -215.909756) (xy 364.226284 -215.897896)
			(xy 364.279434 -215.893913) (xy 364.332584 -215.897896) (xy 364.384546 -215.909756) (xy 364.43416 -215.929228)
			(xy 364.480318 -215.955877) (xy 364.521989 -215.989108) (xy 364.558241 -216.028179) (xy 364.588265 -216.072216)
			(xy 364.611391 -216.120237) (xy 364.627101 -216.171167) (xy 364.635044 -216.223871) (xy 364.635542 -216.25052)
			(xy 364.635044 -216.277169) (xy 364.863624 -216.277169) (xy 364.863624 -216.223871) (xy 364.871567 -216.171167)
			(xy 364.887277 -216.120237) (xy 364.910403 -216.072216) (xy 364.940427 -216.028179) (xy 364.976679 -215.989108)
			(xy 365.01835 -215.955877) (xy 365.064508 -215.929228) (xy 365.114122 -215.909756) (xy 365.166084 -215.897896)
			(xy 365.219234 -215.893913) (xy 365.272384 -215.897896) (xy 365.324346 -215.909756) (xy 365.37396 -215.929228)
			(xy 365.420118 -215.955877) (xy 365.461789 -215.989108) (xy 365.498041 -216.028179) (xy 365.528065 -216.072216)
			(xy 365.551191 -216.120237) (xy 365.566901 -216.171167) (xy 365.574844 -216.223871) (xy 365.575342 -216.25052)
			(xy 365.574844 -216.277169) (xy 365.803424 -216.277169) (xy 365.803424 -216.223871) (xy 365.811367 -216.171167)
			(xy 365.827077 -216.120237) (xy 365.850203 -216.072216) (xy 365.880227 -216.028179) (xy 365.916479 -215.989108)
			(xy 365.95815 -215.955877) (xy 366.004308 -215.929228) (xy 366.053922 -215.909756) (xy 366.105884 -215.897896)
			(xy 366.159034 -215.893913) (xy 366.212184 -215.897896) (xy 366.264146 -215.909756) (xy 366.31376 -215.929228)
			(xy 366.359918 -215.955877) (xy 366.401589 -215.989108) (xy 366.437841 -216.028179) (xy 366.467865 -216.072216)
			(xy 366.490991 -216.120237) (xy 366.506701 -216.171167) (xy 366.514644 -216.223871) (xy 366.515142 -216.25052)
			(xy 366.514644 -216.277169) (xy 366.506701 -216.329873) (xy 366.490991 -216.380803) (xy 366.467865 -216.428824)
			(xy 366.437841 -216.472861) (xy 366.401589 -216.511932) (xy 366.359918 -216.545163) (xy 366.31376 -216.571812)
			(xy 366.264146 -216.591284) (xy 366.212184 -216.603144) (xy 366.159034 -216.607128) (xy 366.105884 -216.603144)
			(xy 366.053922 -216.591284) (xy 366.004308 -216.571812) (xy 365.95815 -216.545163) (xy 365.916479 -216.511932)
			(xy 365.880227 -216.472861) (xy 365.850203 -216.428824) (xy 365.827077 -216.380803) (xy 365.811367 -216.329873)
			(xy 365.803424 -216.277169) (xy 365.574844 -216.277169) (xy 365.566901 -216.329873) (xy 365.551191 -216.380803)
			(xy 365.528065 -216.428824) (xy 365.498041 -216.472861) (xy 365.461789 -216.511932) (xy 365.420118 -216.545163)
			(xy 365.37396 -216.571812) (xy 365.324346 -216.591284) (xy 365.272384 -216.603144) (xy 365.219234 -216.607128)
			(xy 365.166084 -216.603144) (xy 365.114122 -216.591284) (xy 365.064508 -216.571812) (xy 365.01835 -216.545163)
			(xy 364.976679 -216.511932) (xy 364.940427 -216.472861) (xy 364.910403 -216.428824) (xy 364.887277 -216.380803)
			(xy 364.871567 -216.329873) (xy 364.863624 -216.277169) (xy 364.635044 -216.277169) (xy 364.627101 -216.329873)
			(xy 364.611391 -216.380803) (xy 364.588265 -216.428824) (xy 364.558241 -216.472861) (xy 364.521989 -216.511932)
			(xy 364.480318 -216.545163) (xy 364.43416 -216.571812) (xy 364.384546 -216.591284) (xy 364.332584 -216.603144)
			(xy 364.279434 -216.607128) (xy 364.226284 -216.603144) (xy 364.174322 -216.591284) (xy 364.124708 -216.571812)
			(xy 364.07855 -216.545163) (xy 364.036879 -216.511932) (xy 364.000627 -216.472861) (xy 363.970603 -216.428824)
			(xy 363.947477 -216.380803) (xy 363.931767 -216.329873) (xy 363.923824 -216.277169) (xy 363.69499 -216.277169)
			(xy 363.687047 -216.329873) (xy 363.671337 -216.380803) (xy 363.648211 -216.428824) (xy 363.618187 -216.472861)
			(xy 363.581935 -216.511932) (xy 363.540264 -216.545163) (xy 363.494106 -216.571812) (xy 363.444492 -216.591284)
			(xy 363.39253 -216.603144) (xy 363.33938 -216.607128) (xy 363.28623 -216.603144) (xy 363.234268 -216.591284)
			(xy 363.184654 -216.571812) (xy 363.138496 -216.545163) (xy 363.096825 -216.511932) (xy 363.060573 -216.472861)
			(xy 363.030549 -216.428824) (xy 363.007423 -216.380803) (xy 362.991713 -216.329873) (xy 362.98377 -216.277169)
			(xy 362.755444 -216.277169) (xy 362.747501 -216.329873) (xy 362.731791 -216.380803) (xy 362.708665 -216.428824)
			(xy 362.678641 -216.472861) (xy 362.642389 -216.511932) (xy 362.600718 -216.545163) (xy 362.55456 -216.571812)
			(xy 362.504946 -216.591284) (xy 362.452984 -216.603144) (xy 362.399834 -216.607128) (xy 362.346684 -216.603144)
			(xy 362.294722 -216.591284) (xy 362.245108 -216.571812) (xy 362.19895 -216.545163) (xy 362.157279 -216.511932)
			(xy 362.121027 -216.472861) (xy 362.091003 -216.428824) (xy 362.067877 -216.380803) (xy 362.052167 -216.329873)
			(xy 362.044224 -216.277169) (xy 361.81539 -216.277169) (xy 361.807447 -216.329873) (xy 361.791737 -216.380803)
			(xy 361.768611 -216.428824) (xy 361.738587 -216.472861) (xy 361.702335 -216.511932) (xy 361.660664 -216.545163)
			(xy 361.614506 -216.571812) (xy 361.564892 -216.591284) (xy 361.51293 -216.603144) (xy 361.45978 -216.607128)
			(xy 361.40663 -216.603144) (xy 361.354668 -216.591284) (xy 361.305054 -216.571812) (xy 361.258896 -216.545163)
			(xy 361.217225 -216.511932) (xy 361.180973 -216.472861) (xy 361.150949 -216.428824) (xy 361.127823 -216.380803)
			(xy 361.112113 -216.329873) (xy 361.10417 -216.277169) (xy 360.87559 -216.277169) (xy 360.867647 -216.329873)
			(xy 360.851937 -216.380803) (xy 360.828811 -216.428824) (xy 360.798787 -216.472861) (xy 360.762535 -216.511932)
			(xy 360.720864 -216.545163) (xy 360.674706 -216.571812) (xy 360.625092 -216.591284) (xy 360.57313 -216.603144)
			(xy 360.51998 -216.607128) (xy 360.46683 -216.603144) (xy 360.414868 -216.591284) (xy 360.365254 -216.571812)
			(xy 360.319096 -216.545163) (xy 360.277425 -216.511932) (xy 360.241173 -216.472861) (xy 360.211149 -216.428824)
			(xy 360.188023 -216.380803) (xy 360.172313 -216.329873) (xy 360.16437 -216.277169) (xy 359.936044 -216.277169)
			(xy 359.928101 -216.329873) (xy 359.912391 -216.380803) (xy 359.889265 -216.428824) (xy 359.859241 -216.472861)
			(xy 359.822989 -216.511932) (xy 359.781318 -216.545163) (xy 359.73516 -216.571812) (xy 359.685546 -216.591284)
			(xy 359.633584 -216.603144) (xy 359.580434 -216.607128) (xy 359.527284 -216.603144) (xy 359.475322 -216.591284)
			(xy 359.425708 -216.571812) (xy 359.37955 -216.545163) (xy 359.337879 -216.511932) (xy 359.301627 -216.472861)
			(xy 359.271603 -216.428824) (xy 359.248477 -216.380803) (xy 359.232767 -216.329873) (xy 359.224824 -216.277169)
			(xy 358.996244 -216.277169) (xy 358.988301 -216.329873) (xy 358.972591 -216.380803) (xy 358.949465 -216.428824)
			(xy 358.919441 -216.472861) (xy 358.883189 -216.511932) (xy 358.841518 -216.545163) (xy 358.79536 -216.571812)
			(xy 358.745746 -216.591284) (xy 358.693784 -216.603144) (xy 358.640634 -216.607128) (xy 358.587484 -216.603144)
			(xy 358.535522 -216.591284) (xy 358.485908 -216.571812) (xy 358.43975 -216.545163) (xy 358.398079 -216.511932)
			(xy 358.361827 -216.472861) (xy 358.331803 -216.428824) (xy 358.308677 -216.380803) (xy 358.292967 -216.329873)
			(xy 358.285024 -216.277169) (xy 358.056444 -216.277169) (xy 358.048501 -216.329873) (xy 358.032791 -216.380803)
			(xy 358.009665 -216.428824) (xy 357.979641 -216.472861) (xy 357.943389 -216.511932) (xy 357.901718 -216.545163)
			(xy 357.85556 -216.571812) (xy 357.805946 -216.591284) (xy 357.753984 -216.603144) (xy 357.700834 -216.607128)
			(xy 357.647684 -216.603144) (xy 357.595722 -216.591284) (xy 357.546108 -216.571812) (xy 357.49995 -216.545163)
			(xy 357.458279 -216.511932) (xy 357.422027 -216.472861) (xy 357.392003 -216.428824) (xy 357.368877 -216.380803)
			(xy 357.353167 -216.329873) (xy 357.345224 -216.277169) (xy 357.116644 -216.277169) (xy 357.108701 -216.329873)
			(xy 357.092991 -216.380803) (xy 357.069865 -216.428824) (xy 357.039841 -216.472861) (xy 357.003589 -216.511932)
			(xy 356.961918 -216.545163) (xy 356.91576 -216.571812) (xy 356.866146 -216.591284) (xy 356.814184 -216.603144)
			(xy 356.761034 -216.607128) (xy 356.707884 -216.603144) (xy 356.655922 -216.591284) (xy 356.606308 -216.571812)
			(xy 356.56015 -216.545163) (xy 356.518479 -216.511932) (xy 356.482227 -216.472861) (xy 356.452203 -216.428824)
			(xy 356.429077 -216.380803) (xy 356.413367 -216.329873) (xy 356.405424 -216.277169) (xy 356.176844 -216.277169)
			(xy 356.168901 -216.329873) (xy 356.153191 -216.380803) (xy 356.130065 -216.428824) (xy 356.100041 -216.472861)
			(xy 356.063789 -216.511932) (xy 356.022118 -216.545163) (xy 355.97596 -216.571812) (xy 355.926346 -216.591284)
			(xy 355.874384 -216.603144) (xy 355.821234 -216.607128) (xy 355.768084 -216.603144) (xy 355.716122 -216.591284)
			(xy 355.666508 -216.571812) (xy 355.62035 -216.545163) (xy 355.578679 -216.511932) (xy 355.542427 -216.472861)
			(xy 355.512403 -216.428824) (xy 355.489277 -216.380803) (xy 355.473567 -216.329873) (xy 355.465624 -216.277169)
			(xy 355.237044 -216.277169) (xy 355.229101 -216.329873) (xy 355.213391 -216.380803) (xy 355.190265 -216.428824)
			(xy 355.160241 -216.472861) (xy 355.123989 -216.511932) (xy 355.082318 -216.545163) (xy 355.03616 -216.571812)
			(xy 354.986546 -216.591284) (xy 354.934584 -216.603144) (xy 354.881434 -216.607128) (xy 354.828284 -216.603144)
			(xy 354.776322 -216.591284) (xy 354.726708 -216.571812) (xy 354.68055 -216.545163) (xy 354.638879 -216.511932)
			(xy 354.602627 -216.472861) (xy 354.572603 -216.428824) (xy 354.549477 -216.380803) (xy 354.533767 -216.329873)
			(xy 354.525824 -216.277169) (xy 354.296189 -216.277169) (xy 354.294205 -216.303643) (xy 354.282347 -216.3556)
			(xy 354.262878 -216.405209) (xy 354.236233 -216.451362) (xy 354.203008 -216.493029) (xy 354.163944 -216.529279)
			(xy 354.119913 -216.559302) (xy 354.0719 -216.582428) (xy 354.020977 -216.59814) (xy 353.96828 -216.606087)
			(xy 353.941634 -216.606628) (xy 353.916474 -216.60619) (xy 353.866657 -216.5991) (xy 353.818334 -216.585069)
			(xy 353.772465 -216.564378) (xy 353.729965 -216.537439) (xy 353.691679 -216.504786) (xy 353.67468 -216.486232)
			(xy 353.665311 -216.476274) (xy 353.642443 -216.461307) (xy 353.616422 -216.452946) (xy 353.589115 -216.451793)
			(xy 353.562482 -216.457928) (xy 353.538432 -216.470913) (xy 353.518692 -216.489816) (xy 353.504678 -216.51328)
			(xy 353.497394 -216.539623) (xy 353.49688 -216.553288) (xy 353.49688 -216.706704) (xy 353.538282 -216.714578)
			(xy 353.565057 -216.7202) (xy 353.616592 -216.738561) (xy 353.664711 -216.764589) (xy 353.708284 -216.797671)
			(xy 353.746282 -216.837029) (xy 353.777814 -216.881736) (xy 353.802135 -216.93074) (xy 353.818674 -216.982888)
			(xy 353.827041 -217.036953) (xy 353.82704 -217.090985) (xy 354.055924 -217.090985) (xy 354.055924 -217.037687)
			(xy 354.063867 -216.984983) (xy 354.079577 -216.934053) (xy 354.102703 -216.886032) (xy 354.132727 -216.841995)
			(xy 354.168979 -216.802924) (xy 354.21065 -216.769693) (xy 354.256808 -216.743044) (xy 354.306422 -216.723572)
			(xy 354.358384 -216.711712) (xy 354.411534 -216.707729) (xy 354.464684 -216.711712) (xy 354.516646 -216.723572)
			(xy 354.56626 -216.743044) (xy 354.612418 -216.769693) (xy 354.654089 -216.802924) (xy 354.690341 -216.841995)
			(xy 354.720365 -216.886032) (xy 354.743491 -216.934053) (xy 354.759201 -216.984983) (xy 354.767144 -217.037687)
			(xy 354.767642 -217.064336) (xy 354.767144 -217.090985) (xy 354.759201 -217.143689) (xy 354.743491 -217.194619)
			(xy 354.720365 -217.24264) (xy 354.690341 -217.286677) (xy 354.654089 -217.325748) (xy 354.612418 -217.358979)
			(xy 354.56626 -217.385628) (xy 354.516646 -217.4051) (xy 354.464684 -217.41696) (xy 354.411534 -217.420944)
			(xy 354.358384 -217.41696) (xy 354.306422 -217.4051) (xy 354.256808 -217.385628) (xy 354.21065 -217.358979)
			(xy 354.168979 -217.325748) (xy 354.132727 -217.286677) (xy 354.102703 -217.24264) (xy 354.079577 -217.194619)
			(xy 354.063867 -217.143689) (xy 354.055924 -217.090985) (xy 353.82704 -217.090985) (xy 353.82704 -217.091661)
			(xy 353.818671 -217.145725) (xy 353.80213 -217.197872) (xy 353.777807 -217.246876) (xy 353.746274 -217.291582)
			(xy 353.708273 -217.330938) (xy 353.6647 -217.364019) (xy 353.616579 -217.390045) (xy 353.565044 -217.408403)
			(xy 353.538282 -217.414094) (xy 353.49688 -217.421968) (xy 353.49688 -217.575638) (xy 353.497316 -217.589319)
			(xy 353.504573 -217.615699) (xy 353.518582 -217.639201) (xy 353.538334 -217.658134) (xy 353.562408 -217.671136)
			(xy 353.589072 -217.67727) (xy 353.616407 -217.676095) (xy 353.642446 -217.667696) (xy 353.665317 -217.652678)
			(xy 353.67468 -217.642694) (xy 353.691657 -217.624117) (xy 353.729942 -217.591453) (xy 353.772444 -217.564506)
			(xy 353.818317 -217.543813) (xy 353.866648 -217.529785) (xy 353.916472 -217.522703) (xy 353.941634 -217.522298)
			(xy 353.969615 -217.52285) (xy 354.024888 -217.531609) (xy 354.07811 -217.548906) (xy 354.127971 -217.574316)
			(xy 354.173244 -217.607213) (xy 354.212813 -217.646787) (xy 354.245705 -217.692063) (xy 354.271109 -217.741927)
			(xy 354.288401 -217.795151) (xy 354.297154 -217.850425) (xy 354.297742 -217.878406) (xy 354.525326 -217.878406)
			(xy 354.525775 -217.852778) (xy 354.533109 -217.802049) (xy 354.547642 -217.752897) (xy 354.569072 -217.706336)
			(xy 354.596957 -217.663329) (xy 354.63072 -217.624765) (xy 354.669664 -217.59144) (xy 354.712984 -217.564044)
			(xy 354.759785 -217.543143) (xy 354.809099 -217.529168) (xy 354.834444 -217.525346) (xy 354.859082 -217.522044)
			(xy 355.031548 -217.22334) (xy 355.021896 -217.200226) (xy 355.013389 -217.178591) (xy 355.001399 -217.133674)
			(xy 354.99535 -217.087581) (xy 354.994972 -217.064336) (xy 354.99547 -217.037687) (xy 355.003413 -216.984983)
			(xy 355.019123 -216.934053) (xy 355.042249 -216.886032) (xy 355.072273 -216.841995) (xy 355.108525 -216.802924)
			(xy 355.150196 -216.769693) (xy 355.196354 -216.743044) (xy 355.245968 -216.723572) (xy 355.29793 -216.711712)
			(xy 355.35108 -216.707729) (xy 355.40423 -216.711712) (xy 355.456192 -216.723572) (xy 355.505806 -216.743044)
			(xy 355.551964 -216.769693) (xy 355.593635 -216.802924) (xy 355.629887 -216.841995) (xy 355.659911 -216.886032)
			(xy 355.683037 -216.934053) (xy 355.698747 -216.984983) (xy 355.70669 -217.037687) (xy 355.707188 -217.064336)
			(xy 355.706674 -217.089962) (xy 355.706526 -217.090985) (xy 355.935524 -217.090985) (xy 355.935524 -217.037687)
			(xy 355.943467 -216.984983) (xy 355.959177 -216.934053) (xy 355.982303 -216.886032) (xy 356.012327 -216.841995)
			(xy 356.048579 -216.802924) (xy 356.09025 -216.769693) (xy 356.136408 -216.743044) (xy 356.186022 -216.723572)
			(xy 356.237984 -216.711712) (xy 356.291134 -216.707729) (xy 356.344284 -216.711712) (xy 356.396246 -216.723572)
			(xy 356.44586 -216.743044) (xy 356.492018 -216.769693) (xy 356.533689 -216.802924) (xy 356.569941 -216.841995)
			(xy 356.599965 -216.886032) (xy 356.623091 -216.934053) (xy 356.638801 -216.984983) (xy 356.646744 -217.037687)
			(xy 356.647242 -217.064336) (xy 356.646744 -217.090985) (xy 356.638801 -217.143689) (xy 356.623091 -217.194619)
			(xy 356.599965 -217.24264) (xy 356.569941 -217.286677) (xy 356.533689 -217.325748) (xy 356.492018 -217.358979)
			(xy 356.44586 -217.385628) (xy 356.396246 -217.4051) (xy 356.344284 -217.41696) (xy 356.291134 -217.420944)
			(xy 356.237984 -217.41696) (xy 356.186022 -217.4051) (xy 356.136408 -217.385628) (xy 356.09025 -217.358979)
			(xy 356.048579 -217.325748) (xy 356.012327 -217.286677) (xy 355.982303 -217.24264) (xy 355.959177 -217.194619)
			(xy 355.943467 -217.143689) (xy 355.935524 -217.090985) (xy 355.706526 -217.090985) (xy 355.699348 -217.140687)
			(xy 355.684823 -217.189838) (xy 355.663401 -217.236398) (xy 355.635524 -217.279404) (xy 355.601768 -217.317969)
			(xy 355.56283 -217.351295) (xy 355.519517 -217.378692) (xy 355.472722 -217.399596) (xy 355.423413 -217.413573)
			(xy 355.39807 -217.417396) (xy 355.373432 -217.420698) (xy 355.200966 -217.719402) (xy 355.210618 -217.742516)
			(xy 355.219138 -217.764146) (xy 355.231123 -217.809065) (xy 355.237167 -217.855161) (xy 355.237542 -217.878406)
			(xy 355.465126 -217.878406) (xy 355.465624 -217.851757) (xy 355.473567 -217.799053) (xy 355.489277 -217.748123)
			(xy 355.512403 -217.700102) (xy 355.542427 -217.656065) (xy 355.578679 -217.616994) (xy 355.62035 -217.583763)
			(xy 355.666508 -217.557114) (xy 355.716122 -217.537642) (xy 355.768084 -217.525782) (xy 355.821234 -217.521799)
			(xy 355.874384 -217.525782) (xy 355.926346 -217.537642) (xy 355.97596 -217.557114) (xy 356.022118 -217.583763)
			(xy 356.063789 -217.616994) (xy 356.100041 -217.656065) (xy 356.130065 -217.700102) (xy 356.153191 -217.748123)
			(xy 356.168901 -217.799053) (xy 356.176844 -217.851757) (xy 356.177342 -217.878406) (xy 356.404926 -217.878406)
			(xy 356.405375 -217.852778) (xy 356.412709 -217.802049) (xy 356.427242 -217.752897) (xy 356.448672 -217.706336)
			(xy 356.476557 -217.663329) (xy 356.51032 -217.624765) (xy 356.549264 -217.59144) (xy 356.592584 -217.564044)
			(xy 356.639385 -217.543143) (xy 356.688699 -217.529168) (xy 356.714044 -217.525346) (xy 356.738682 -217.522044)
			(xy 356.911148 -217.22334) (xy 356.901496 -217.200226) (xy 356.892989 -217.178591) (xy 356.880999 -217.133674)
			(xy 356.87495 -217.087581) (xy 356.874572 -217.064336) (xy 356.87507 -217.037687) (xy 356.883013 -216.984983)
			(xy 356.898723 -216.934053) (xy 356.921849 -216.886032) (xy 356.951873 -216.841995) (xy 356.988125 -216.802924)
			(xy 357.029796 -216.769693) (xy 357.075954 -216.743044) (xy 357.125568 -216.723572) (xy 357.17753 -216.711712)
			(xy 357.23068 -216.707729) (xy 357.28383 -216.711712) (xy 357.335792 -216.723572) (xy 357.385406 -216.743044)
			(xy 357.431564 -216.769693) (xy 357.473235 -216.802924) (xy 357.509487 -216.841995) (xy 357.539511 -216.886032)
			(xy 357.562637 -216.934053) (xy 357.578347 -216.984983) (xy 357.58629 -217.037687) (xy 357.586788 -217.064336)
			(xy 357.586274 -217.089962) (xy 357.586126 -217.090985) (xy 357.815124 -217.090985) (xy 357.815124 -217.037687)
			(xy 357.823067 -216.984983) (xy 357.838777 -216.934053) (xy 357.861903 -216.886032) (xy 357.891927 -216.841995)
			(xy 357.928179 -216.802924) (xy 357.96985 -216.769693) (xy 358.016008 -216.743044) (xy 358.065622 -216.723572)
			(xy 358.117584 -216.711712) (xy 358.170734 -216.707729) (xy 358.223884 -216.711712) (xy 358.275846 -216.723572)
			(xy 358.32546 -216.743044) (xy 358.371618 -216.769693) (xy 358.413289 -216.802924) (xy 358.449541 -216.841995)
			(xy 358.479565 -216.886032) (xy 358.502691 -216.934053) (xy 358.518401 -216.984983) (xy 358.526344 -217.037687)
			(xy 358.526842 -217.064336) (xy 358.526344 -217.090985) (xy 358.518401 -217.143689) (xy 358.502691 -217.194619)
			(xy 358.479565 -217.24264) (xy 358.449541 -217.286677) (xy 358.413289 -217.325748) (xy 358.371618 -217.358979)
			(xy 358.32546 -217.385628) (xy 358.275846 -217.4051) (xy 358.223884 -217.41696) (xy 358.170734 -217.420944)
			(xy 358.117584 -217.41696) (xy 358.065622 -217.4051) (xy 358.016008 -217.385628) (xy 357.96985 -217.358979)
			(xy 357.928179 -217.325748) (xy 357.891927 -217.286677) (xy 357.861903 -217.24264) (xy 357.838777 -217.194619)
			(xy 357.823067 -217.143689) (xy 357.815124 -217.090985) (xy 357.586126 -217.090985) (xy 357.578948 -217.140687)
			(xy 357.564423 -217.189838) (xy 357.543001 -217.236398) (xy 357.515124 -217.279404) (xy 357.481368 -217.317969)
			(xy 357.44243 -217.351295) (xy 357.399117 -217.378692) (xy 357.352322 -217.399596) (xy 357.303013 -217.413573)
			(xy 357.27767 -217.417396) (xy 357.253032 -217.420698) (xy 357.080566 -217.719402) (xy 357.090218 -217.742516)
			(xy 357.098738 -217.764146) (xy 357.110723 -217.809065) (xy 357.116767 -217.855161) (xy 357.117142 -217.878406)
			(xy 357.344726 -217.878406) (xy 357.345224 -217.851757) (xy 357.353167 -217.799053) (xy 357.368877 -217.748123)
			(xy 357.392003 -217.700102) (xy 357.422027 -217.656065) (xy 357.458279 -217.616994) (xy 357.49995 -217.583763)
			(xy 357.546108 -217.557114) (xy 357.595722 -217.537642) (xy 357.647684 -217.525782) (xy 357.700834 -217.521799)
			(xy 357.753984 -217.525782) (xy 357.805946 -217.537642) (xy 357.85556 -217.557114) (xy 357.901718 -217.583763)
			(xy 357.943389 -217.616994) (xy 357.979641 -217.656065) (xy 358.009665 -217.700102) (xy 358.032791 -217.748123)
			(xy 358.048501 -217.799053) (xy 358.056444 -217.851757) (xy 358.056942 -217.878406) (xy 358.284526 -217.878406)
			(xy 358.284975 -217.852778) (xy 358.292309 -217.802049) (xy 358.306842 -217.752897) (xy 358.328272 -217.706336)
			(xy 358.356157 -217.663329) (xy 358.38992 -217.624765) (xy 358.428864 -217.59144) (xy 358.472184 -217.564044)
			(xy 358.518985 -217.543143) (xy 358.568299 -217.529168) (xy 358.593644 -217.525346) (xy 358.618282 -217.522044)
			(xy 358.790748 -217.223086) (xy 358.78135 -217.199972) (xy 358.772858 -217.178376) (xy 358.760881 -217.133544)
			(xy 358.75482 -217.087538) (xy 358.754426 -217.064336) (xy 358.754924 -217.037687) (xy 358.762867 -216.984983)
			(xy 358.778577 -216.934053) (xy 358.801703 -216.886032) (xy 358.831727 -216.841995) (xy 358.867979 -216.802924)
			(xy 358.90965 -216.769693) (xy 358.955808 -216.743044) (xy 359.005422 -216.723572) (xy 359.057384 -216.711712)
			(xy 359.110534 -216.707729) (xy 359.163684 -216.711712) (xy 359.215646 -216.723572) (xy 359.26526 -216.743044)
			(xy 359.311418 -216.769693) (xy 359.353089 -216.802924) (xy 359.389341 -216.841995) (xy 359.419365 -216.886032)
			(xy 359.442491 -216.934053) (xy 359.458201 -216.984983) (xy 359.466144 -217.037687) (xy 359.466642 -217.064336)
			(xy 359.466167 -217.089964) (xy 359.46602 -217.090985) (xy 359.694724 -217.090985) (xy 359.694724 -217.037687)
			(xy 359.702667 -216.984983) (xy 359.718377 -216.934053) (xy 359.741503 -216.886032) (xy 359.771527 -216.841995)
			(xy 359.807779 -216.802924) (xy 359.84945 -216.769693) (xy 359.895608 -216.743044) (xy 359.945222 -216.723572)
			(xy 359.997184 -216.711712) (xy 360.050334 -216.707729) (xy 360.103484 -216.711712) (xy 360.155446 -216.723572)
			(xy 360.20506 -216.743044) (xy 360.251218 -216.769693) (xy 360.292889 -216.802924) (xy 360.329141 -216.841995)
			(xy 360.359165 -216.886032) (xy 360.382291 -216.934053) (xy 360.398001 -216.984983) (xy 360.405944 -217.037687)
			(xy 360.406442 -217.064336) (xy 360.633772 -217.064336) (xy 360.63427 -217.037687) (xy 360.642213 -216.984983)
			(xy 360.657923 -216.934053) (xy 360.681049 -216.886032) (xy 360.711073 -216.841995) (xy 360.747325 -216.802924)
			(xy 360.788996 -216.769693) (xy 360.835154 -216.743044) (xy 360.884768 -216.723572) (xy 360.93673 -216.711712)
			(xy 360.98988 -216.707729) (xy 361.04303 -216.711712) (xy 361.094992 -216.723572) (xy 361.144606 -216.743044)
			(xy 361.190764 -216.769693) (xy 361.232435 -216.802924) (xy 361.268687 -216.841995) (xy 361.298711 -216.886032)
			(xy 361.321837 -216.934053) (xy 361.337547 -216.984983) (xy 361.34549 -217.037687) (xy 361.345988 -217.064336)
			(xy 361.345619 -217.08754) (xy 361.345166 -217.090985) (xy 361.574324 -217.090985) (xy 361.574324 -217.037687)
			(xy 361.582267 -216.984983) (xy 361.597977 -216.934053) (xy 361.621103 -216.886032) (xy 361.651127 -216.841995)
			(xy 361.687379 -216.802924) (xy 361.72905 -216.769693) (xy 361.775208 -216.743044) (xy 361.824822 -216.723572)
			(xy 361.876784 -216.711712) (xy 361.929934 -216.707729) (xy 361.983084 -216.711712) (xy 362.035046 -216.723572)
			(xy 362.08466 -216.743044) (xy 362.130818 -216.769693) (xy 362.172489 -216.802924) (xy 362.208741 -216.841995)
			(xy 362.238765 -216.886032) (xy 362.261891 -216.934053) (xy 362.277601 -216.984983) (xy 362.285544 -217.037687)
			(xy 362.286042 -217.064336) (xy 362.513372 -217.064336) (xy 362.51387 -217.037687) (xy 362.521813 -216.984983)
			(xy 362.537523 -216.934053) (xy 362.560649 -216.886032) (xy 362.590673 -216.841995) (xy 362.626925 -216.802924)
			(xy 362.668596 -216.769693) (xy 362.714754 -216.743044) (xy 362.764368 -216.723572) (xy 362.81633 -216.711712)
			(xy 362.86948 -216.707729) (xy 362.92263 -216.711712) (xy 362.974592 -216.723572) (xy 363.024206 -216.743044)
			(xy 363.070364 -216.769693) (xy 363.112035 -216.802924) (xy 363.148287 -216.841995) (xy 363.178311 -216.886032)
			(xy 363.201437 -216.934053) (xy 363.217147 -216.984983) (xy 363.22509 -217.037687) (xy 363.225588 -217.064336)
			(xy 363.225219 -217.08754) (xy 363.224766 -217.090985) (xy 363.453924 -217.090985) (xy 363.453924 -217.037687)
			(xy 363.461867 -216.984983) (xy 363.477577 -216.934053) (xy 363.500703 -216.886032) (xy 363.530727 -216.841995)
			(xy 363.566979 -216.802924) (xy 363.60865 -216.769693) (xy 363.654808 -216.743044) (xy 363.704422 -216.723572)
			(xy 363.756384 -216.711712) (xy 363.809534 -216.707729) (xy 363.862684 -216.711712) (xy 363.914646 -216.723572)
			(xy 363.96426 -216.743044) (xy 364.010418 -216.769693) (xy 364.052089 -216.802924) (xy 364.088341 -216.841995)
			(xy 364.118365 -216.886032) (xy 364.141491 -216.934053) (xy 364.157201 -216.984983) (xy 364.165144 -217.037687)
			(xy 364.165642 -217.064336) (xy 364.392972 -217.064336) (xy 364.39347 -217.037687) (xy 364.401413 -216.984983)
			(xy 364.417123 -216.934053) (xy 364.440249 -216.886032) (xy 364.470273 -216.841995) (xy 364.506525 -216.802924)
			(xy 364.548196 -216.769693) (xy 364.594354 -216.743044) (xy 364.643968 -216.723572) (xy 364.69593 -216.711712)
			(xy 364.74908 -216.707729) (xy 364.80223 -216.711712) (xy 364.854192 -216.723572) (xy 364.903806 -216.743044)
			(xy 364.949964 -216.769693) (xy 364.991635 -216.802924) (xy 365.027887 -216.841995) (xy 365.057911 -216.886032)
			(xy 365.081037 -216.934053) (xy 365.096747 -216.984983) (xy 365.10469 -217.037687) (xy 365.105188 -217.064336)
			(xy 365.104819 -217.08754) (xy 365.104366 -217.090985) (xy 365.333524 -217.090985) (xy 365.333524 -217.037687)
			(xy 365.341467 -216.984983) (xy 365.357177 -216.934053) (xy 365.380303 -216.886032) (xy 365.410327 -216.841995)
			(xy 365.446579 -216.802924) (xy 365.48825 -216.769693) (xy 365.534408 -216.743044) (xy 365.584022 -216.723572)
			(xy 365.635984 -216.711712) (xy 365.689134 -216.707729) (xy 365.742284 -216.711712) (xy 365.794246 -216.723572)
			(xy 365.84386 -216.743044) (xy 365.890018 -216.769693) (xy 365.931689 -216.802924) (xy 365.967941 -216.841995)
			(xy 365.997965 -216.886032) (xy 366.021091 -216.934053) (xy 366.036801 -216.984983) (xy 366.044744 -217.037687)
			(xy 366.045242 -217.064336) (xy 366.044744 -217.090985) (xy 366.036801 -217.143689) (xy 366.021091 -217.194619)
			(xy 365.997965 -217.24264) (xy 365.967941 -217.286677) (xy 365.931689 -217.325748) (xy 365.890018 -217.358979)
			(xy 365.84386 -217.385628) (xy 365.794246 -217.4051) (xy 365.742284 -217.41696) (xy 365.689134 -217.420944)
			(xy 365.635984 -217.41696) (xy 365.584022 -217.4051) (xy 365.534408 -217.385628) (xy 365.48825 -217.358979)
			(xy 365.446579 -217.325748) (xy 365.410327 -217.286677) (xy 365.380303 -217.24264) (xy 365.357177 -217.194619)
			(xy 365.341467 -217.143689) (xy 365.333524 -217.090985) (xy 365.104366 -217.090985) (xy 365.098765 -217.13355)
			(xy 365.086776 -217.178383) (xy 365.078264 -217.199972) (xy 365.068866 -217.223086) (xy 365.241586 -217.522044)
			(xy 365.266224 -217.525346) (xy 365.291558 -217.529218) (xy 365.34086 -217.543205) (xy 365.387649 -217.564113)
			(xy 365.430959 -217.591509) (xy 365.469897 -217.624829) (xy 365.503658 -217.663384) (xy 365.531546 -217.706379)
			(xy 365.552985 -217.752926) (xy 365.567533 -217.802065) (xy 365.57489 -217.852782) (xy 365.575342 -217.878406)
			(xy 365.574844 -217.905055) (xy 365.566901 -217.957759) (xy 365.551191 -218.008689) (xy 365.528065 -218.05671)
			(xy 365.498041 -218.100747) (xy 365.461789 -218.139818) (xy 365.420118 -218.173049) (xy 365.37396 -218.199698)
			(xy 365.324346 -218.21917) (xy 365.272384 -218.23103) (xy 365.219234 -218.235014) (xy 365.166084 -218.23103)
			(xy 365.114122 -218.21917) (xy 365.064508 -218.199698) (xy 365.01835 -218.173049) (xy 364.976679 -218.139818)
			(xy 364.940427 -218.100747) (xy 364.910403 -218.05671) (xy 364.887277 -218.008689) (xy 364.871567 -217.957759)
			(xy 364.863624 -217.905055) (xy 364.863126 -217.878406) (xy 364.863495 -217.855161) (xy 364.869542 -217.809065)
			(xy 364.881532 -217.764148) (xy 364.89005 -217.742516) (xy 364.899702 -217.719402) (xy 364.727236 -217.420698)
			(xy 364.702344 -217.417396) (xy 364.676995 -217.413539) (xy 364.627656 -217.399588) (xy 364.580828 -217.378707)
			(xy 364.537479 -217.351325) (xy 364.498505 -217.31801) (xy 364.464711 -217.27945) (xy 364.436796 -217.236443)
			(xy 364.415338 -217.189877) (xy 364.400779 -217.140714) (xy 364.393421 -217.089972) (xy 364.392972 -217.064336)
			(xy 364.165642 -217.064336) (xy 364.165144 -217.090985) (xy 364.157201 -217.143689) (xy 364.141491 -217.194619)
			(xy 364.118365 -217.24264) (xy 364.088341 -217.286677) (xy 364.052089 -217.325748) (xy 364.010418 -217.358979)
			(xy 363.96426 -217.385628) (xy 363.914646 -217.4051) (xy 363.862684 -217.41696) (xy 363.809534 -217.420944)
			(xy 363.756384 -217.41696) (xy 363.704422 -217.4051) (xy 363.654808 -217.385628) (xy 363.60865 -217.358979)
			(xy 363.566979 -217.325748) (xy 363.530727 -217.286677) (xy 363.500703 -217.24264) (xy 363.477577 -217.194619)
			(xy 363.461867 -217.143689) (xy 363.453924 -217.090985) (xy 363.224766 -217.090985) (xy 363.219165 -217.13355)
			(xy 363.207176 -217.178383) (xy 363.198664 -217.199972) (xy 363.189266 -217.223086) (xy 363.361986 -217.522044)
			(xy 363.386624 -217.525346) (xy 363.411958 -217.529218) (xy 363.46126 -217.543205) (xy 363.508049 -217.564113)
			(xy 363.551359 -217.591509) (xy 363.590297 -217.624829) (xy 363.624058 -217.663384) (xy 363.651946 -217.706379)
			(xy 363.673385 -217.752926) (xy 363.687933 -217.802065) (xy 363.69529 -217.852782) (xy 363.695742 -217.878406)
			(xy 363.695244 -217.905055) (xy 363.687301 -217.957759) (xy 363.671591 -218.008689) (xy 363.648465 -218.05671)
			(xy 363.618441 -218.100747) (xy 363.582189 -218.139818) (xy 363.540518 -218.173049) (xy 363.49436 -218.199698)
			(xy 363.444746 -218.21917) (xy 363.392784 -218.23103) (xy 363.339634 -218.235014) (xy 363.286484 -218.23103)
			(xy 363.234522 -218.21917) (xy 363.184908 -218.199698) (xy 363.13875 -218.173049) (xy 363.097079 -218.139818)
			(xy 363.060827 -218.100747) (xy 363.030803 -218.05671) (xy 363.007677 -218.008689) (xy 362.991967 -217.957759)
			(xy 362.984024 -217.905055) (xy 362.983526 -217.878406) (xy 362.983895 -217.855161) (xy 362.989942 -217.809065)
			(xy 363.001932 -217.764148) (xy 363.01045 -217.742516) (xy 363.020102 -217.719402) (xy 362.847636 -217.420698)
			(xy 362.822744 -217.417396) (xy 362.797395 -217.413539) (xy 362.748056 -217.399588) (xy 362.701228 -217.378707)
			(xy 362.657879 -217.351325) (xy 362.618905 -217.31801) (xy 362.585111 -217.27945) (xy 362.557196 -217.236443)
			(xy 362.535738 -217.189877) (xy 362.521179 -217.140714) (xy 362.513821 -217.089972) (xy 362.513372 -217.064336)
			(xy 362.286042 -217.064336) (xy 362.285544 -217.090985) (xy 362.277601 -217.143689) (xy 362.261891 -217.194619)
			(xy 362.238765 -217.24264) (xy 362.208741 -217.286677) (xy 362.172489 -217.325748) (xy 362.130818 -217.358979)
			(xy 362.08466 -217.385628) (xy 362.035046 -217.4051) (xy 361.983084 -217.41696) (xy 361.929934 -217.420944)
			(xy 361.876784 -217.41696) (xy 361.824822 -217.4051) (xy 361.775208 -217.385628) (xy 361.72905 -217.358979)
			(xy 361.687379 -217.325748) (xy 361.651127 -217.286677) (xy 361.621103 -217.24264) (xy 361.597977 -217.194619)
			(xy 361.582267 -217.143689) (xy 361.574324 -217.090985) (xy 361.345166 -217.090985) (xy 361.339565 -217.13355)
			(xy 361.327576 -217.178383) (xy 361.319064 -217.199972) (xy 361.309666 -217.223086) (xy 361.482386 -217.522044)
			(xy 361.507024 -217.525346) (xy 361.532358 -217.529218) (xy 361.58166 -217.543205) (xy 361.628449 -217.564113)
			(xy 361.671759 -217.591509) (xy 361.710697 -217.624829) (xy 361.744458 -217.663384) (xy 361.772346 -217.706379)
			(xy 361.793785 -217.752926) (xy 361.808333 -217.802065) (xy 361.81569 -217.852782) (xy 361.816142 -217.878406)
			(xy 361.815644 -217.905055) (xy 361.807701 -217.957759) (xy 361.791991 -218.008689) (xy 361.768865 -218.05671)
			(xy 361.738841 -218.100747) (xy 361.702589 -218.139818) (xy 361.660918 -218.173049) (xy 361.61476 -218.199698)
			(xy 361.565146 -218.21917) (xy 361.513184 -218.23103) (xy 361.460034 -218.235014) (xy 361.406884 -218.23103)
			(xy 361.354922 -218.21917) (xy 361.305308 -218.199698) (xy 361.25915 -218.173049) (xy 361.217479 -218.139818)
			(xy 361.181227 -218.100747) (xy 361.151203 -218.05671) (xy 361.128077 -218.008689) (xy 361.112367 -217.957759)
			(xy 361.104424 -217.905055) (xy 361.103926 -217.878406) (xy 361.104295 -217.855161) (xy 361.110342 -217.809065)
			(xy 361.122332 -217.764148) (xy 361.13085 -217.742516) (xy 361.140502 -217.719402) (xy 360.968036 -217.420698)
			(xy 360.943144 -217.417396) (xy 360.917795 -217.413539) (xy 360.868456 -217.399588) (xy 360.821628 -217.378707)
			(xy 360.778279 -217.351325) (xy 360.739305 -217.31801) (xy 360.705511 -217.27945) (xy 360.677596 -217.236443)
			(xy 360.656138 -217.189877) (xy 360.641579 -217.140714) (xy 360.634221 -217.089972) (xy 360.633772 -217.064336)
			(xy 360.406442 -217.064336) (xy 360.405944 -217.090985) (xy 360.398001 -217.143689) (xy 360.382291 -217.194619)
			(xy 360.359165 -217.24264) (xy 360.329141 -217.286677) (xy 360.292889 -217.325748) (xy 360.251218 -217.358979)
			(xy 360.20506 -217.385628) (xy 360.155446 -217.4051) (xy 360.103484 -217.41696) (xy 360.050334 -217.420944)
			(xy 359.997184 -217.41696) (xy 359.945222 -217.4051) (xy 359.895608 -217.385628) (xy 359.84945 -217.358979)
			(xy 359.807779 -217.325748) (xy 359.771527 -217.286677) (xy 359.741503 -217.24264) (xy 359.718377 -217.194619)
			(xy 359.702667 -217.143689) (xy 359.694724 -217.090985) (xy 359.46602 -217.090985) (xy 359.45884 -217.140693)
			(xy 359.444314 -217.189846) (xy 359.422888 -217.236409) (xy 359.395007 -217.279417) (xy 359.361246 -217.317982)
			(xy 359.322303 -217.351307) (xy 359.278984 -217.378703) (xy 359.232183 -217.399603) (xy 359.182869 -217.413576)
			(xy 359.157524 -217.417396) (xy 359.132632 -217.420698) (xy 358.960166 -217.719402) (xy 358.969818 -217.742516)
			(xy 358.978338 -217.764146) (xy 358.990323 -217.809065) (xy 358.996367 -217.855161) (xy 358.996742 -217.878406)
			(xy 358.996244 -217.905055) (xy 359.224824 -217.905055) (xy 359.224824 -217.851757) (xy 359.232767 -217.799053)
			(xy 359.248477 -217.748123) (xy 359.271603 -217.700102) (xy 359.301627 -217.656065) (xy 359.337879 -217.616994)
			(xy 359.37955 -217.583763) (xy 359.425708 -217.557114) (xy 359.475322 -217.537642) (xy 359.527284 -217.525782)
			(xy 359.580434 -217.521799) (xy 359.633584 -217.525782) (xy 359.685546 -217.537642) (xy 359.73516 -217.557114)
			(xy 359.781318 -217.583763) (xy 359.822989 -217.616994) (xy 359.859241 -217.656065) (xy 359.889265 -217.700102)
			(xy 359.912391 -217.748123) (xy 359.928101 -217.799053) (xy 359.936044 -217.851757) (xy 359.936542 -217.878406)
			(xy 359.936044 -217.905055) (xy 359.928101 -217.957759) (xy 359.912391 -218.008689) (xy 359.889265 -218.05671)
			(xy 359.859241 -218.100747) (xy 359.822989 -218.139818) (xy 359.781318 -218.173049) (xy 359.73516 -218.199698)
			(xy 359.685546 -218.21917) (xy 359.633584 -218.23103) (xy 359.580434 -218.235014) (xy 359.527284 -218.23103)
			(xy 359.475322 -218.21917) (xy 359.425708 -218.199698) (xy 359.37955 -218.173049) (xy 359.337879 -218.139818)
			(xy 359.301627 -218.100747) (xy 359.271603 -218.05671) (xy 359.248477 -218.008689) (xy 359.232767 -217.957759)
			(xy 359.224824 -217.905055) (xy 358.996244 -217.905055) (xy 358.988301 -217.957759) (xy 358.972591 -218.008689)
			(xy 358.949465 -218.05671) (xy 358.919441 -218.100747) (xy 358.883189 -218.139818) (xy 358.841518 -218.173049)
			(xy 358.79536 -218.199698) (xy 358.745746 -218.21917) (xy 358.693784 -218.23103) (xy 358.640634 -218.235014)
			(xy 358.587484 -218.23103) (xy 358.535522 -218.21917) (xy 358.485908 -218.199698) (xy 358.43975 -218.173049)
			(xy 358.398079 -218.139818) (xy 358.361827 -218.100747) (xy 358.331803 -218.05671) (xy 358.308677 -218.008689)
			(xy 358.292967 -217.957759) (xy 358.285024 -217.905055) (xy 358.284526 -217.878406) (xy 358.056942 -217.878406)
			(xy 358.05656 -217.901609) (xy 358.05051 -217.947619) (xy 358.038527 -217.992452) (xy 358.030018 -218.014042)
			(xy 358.02062 -218.037156) (xy 358.193086 -218.33586) (xy 358.217724 -218.339162) (xy 358.243061 -218.343019)
			(xy 358.292364 -218.357007) (xy 358.339154 -218.377915) (xy 358.382465 -218.405313) (xy 358.421402 -218.438634)
			(xy 358.455164 -218.477192) (xy 358.483051 -218.520189) (xy 358.50449 -218.566738) (xy 358.519036 -218.615879)
			(xy 358.526391 -218.666598) (xy 358.526842 -218.692222) (xy 358.526344 -218.718871) (xy 358.755178 -218.718871)
			(xy 358.755178 -218.665573) (xy 358.763121 -218.612869) (xy 358.778831 -218.561939) (xy 358.801957 -218.513918)
			(xy 358.831981 -218.469881) (xy 358.868233 -218.43081) (xy 358.909904 -218.397579) (xy 358.956062 -218.37093)
			(xy 359.005676 -218.351458) (xy 359.057638 -218.339598) (xy 359.110788 -218.335615) (xy 359.163938 -218.339598)
			(xy 359.2159 -218.351458) (xy 359.265514 -218.37093) (xy 359.311672 -218.397579) (xy 359.353343 -218.43081)
			(xy 359.389595 -218.469881) (xy 359.419619 -218.513918) (xy 359.442745 -218.561939) (xy 359.458455 -218.612869)
			(xy 359.466398 -218.665573) (xy 359.466896 -218.692222) (xy 359.693972 -218.692222) (xy 359.694396 -218.666593)
			(xy 359.701729 -218.615861) (xy 359.716262 -218.566706) (xy 359.737693 -218.520142) (xy 359.765581 -218.477134)
			(xy 359.799347 -218.438569) (xy 359.838295 -218.405244) (xy 359.88162 -218.37785) (xy 359.928425 -218.356952)
			(xy 359.977743 -218.342981) (xy 360.00309 -218.339162) (xy 360.027728 -218.33586) (xy 360.200194 -218.036902)
			(xy 360.190796 -218.013788) (xy 360.182369 -217.992266) (xy 360.170485 -217.9476) (xy 360.164494 -217.90177)
			(xy 360.164126 -217.87866) (xy 360.164126 -217.878406) (xy 360.164624 -217.851757) (xy 360.172567 -217.799053)
			(xy 360.188277 -217.748123) (xy 360.211403 -217.700102) (xy 360.241427 -217.656065) (xy 360.277679 -217.616994)
			(xy 360.31935 -217.583763) (xy 360.365508 -217.557114) (xy 360.415122 -217.537642) (xy 360.467084 -217.525782)
			(xy 360.520234 -217.521799) (xy 360.573384 -217.525782) (xy 360.625346 -217.537642) (xy 360.67496 -217.557114)
			(xy 360.721118 -217.583763) (xy 360.762789 -217.616994) (xy 360.799041 -217.656065) (xy 360.829065 -217.700102)
			(xy 360.852191 -217.748123) (xy 360.867901 -217.799053) (xy 360.875844 -217.851757) (xy 360.876342 -217.878406)
			(xy 360.875869 -217.904055) (xy 360.868508 -217.954821) (xy 360.853939 -218.004006) (xy 360.832464 -218.050592)
			(xy 360.804527 -218.093615) (xy 360.770705 -218.132183) (xy 360.7317 -218.1655) (xy 360.688318 -218.192876)
			(xy 360.641457 -218.213744) (xy 360.592087 -218.227672) (xy 360.566716 -218.231466) (xy 360.541824 -218.234768)
			(xy 360.369612 -218.533218) (xy 360.379264 -218.556332) (xy 360.387786 -218.577962) (xy 360.399771 -218.622881)
			(xy 360.405814 -218.668977) (xy 360.406188 -218.692222) (xy 360.40569 -218.718871) (xy 360.63427 -218.718871)
			(xy 360.63427 -218.665573) (xy 360.642213 -218.612869) (xy 360.657923 -218.561939) (xy 360.681049 -218.513918)
			(xy 360.711073 -218.469881) (xy 360.747325 -218.43081) (xy 360.788996 -218.397579) (xy 360.835154 -218.37093)
			(xy 360.884768 -218.351458) (xy 360.93673 -218.339598) (xy 360.98988 -218.335615) (xy 361.04303 -218.339598)
			(xy 361.094992 -218.351458) (xy 361.144606 -218.37093) (xy 361.190764 -218.397579) (xy 361.232435 -218.43081)
			(xy 361.268687 -218.469881) (xy 361.298711 -218.513918) (xy 361.321837 -218.561939) (xy 361.337547 -218.612869)
			(xy 361.34549 -218.665573) (xy 361.345988 -218.692222) (xy 361.573826 -218.692222) (xy 361.57429 -218.666594)
			(xy 361.581622 -218.615866) (xy 361.596152 -218.566714) (xy 361.61758 -218.520153) (xy 361.645463 -218.477146)
			(xy 361.679225 -218.438582) (xy 361.718168 -218.405257) (xy 361.761487 -218.377861) (xy 361.808286 -218.356959)
			(xy 361.857599 -218.342984) (xy 361.882944 -218.339162) (xy 361.907582 -218.33586) (xy 362.080048 -218.037156)
			(xy 362.07065 -218.014042) (xy 362.062149 -217.99245) (xy 362.050176 -217.947616) (xy 362.044118 -217.901608)
			(xy 362.043726 -217.878406) (xy 362.044224 -217.851757) (xy 362.052167 -217.799053) (xy 362.067877 -217.748123)
			(xy 362.091003 -217.700102) (xy 362.121027 -217.656065) (xy 362.157279 -217.616994) (xy 362.19895 -217.583763)
			(xy 362.245108 -217.557114) (xy 362.294722 -217.537642) (xy 362.346684 -217.525782) (xy 362.399834 -217.521799)
			(xy 362.452984 -217.525782) (xy 362.504946 -217.537642) (xy 362.55456 -217.557114) (xy 362.600718 -217.583763)
			(xy 362.642389 -217.616994) (xy 362.678641 -217.656065) (xy 362.708665 -217.700102) (xy 362.731791 -217.748123)
			(xy 362.747501 -217.799053) (xy 362.755444 -217.851757) (xy 362.755942 -217.878406) (xy 362.755498 -217.904046)
			(xy 362.748154 -217.954797) (xy 362.733606 -218.003969) (xy 362.712154 -218.050546) (xy 362.684241 -218.093563)
			(xy 362.650446 -218.132131) (xy 362.611468 -218.165452) (xy 362.568112 -218.192836) (xy 362.521277 -218.213716)
			(xy 362.47193 -218.227662) (xy 362.44657 -218.231466) (xy 362.421678 -218.234768) (xy 362.249466 -218.533218)
			(xy 362.259118 -218.556332) (xy 362.267643 -218.577961) (xy 362.279626 -218.62288) (xy 362.285668 -218.668977)
			(xy 362.286042 -218.692222) (xy 362.285544 -218.718871) (xy 362.514124 -218.718871) (xy 362.514124 -218.665573)
			(xy 362.522067 -218.612869) (xy 362.537777 -218.561939) (xy 362.560903 -218.513918) (xy 362.590927 -218.469881)
			(xy 362.627179 -218.43081) (xy 362.66885 -218.397579) (xy 362.715008 -218.37093) (xy 362.764622 -218.351458)
			(xy 362.816584 -218.339598) (xy 362.869734 -218.335615) (xy 362.922884 -218.339598) (xy 362.974846 -218.351458)
			(xy 363.02446 -218.37093) (xy 363.070618 -218.397579) (xy 363.112289 -218.43081) (xy 363.148541 -218.469881)
			(xy 363.178565 -218.513918) (xy 363.201691 -218.561939) (xy 363.217401 -218.612869) (xy 363.225344 -218.665573)
			(xy 363.225842 -218.692222) (xy 363.453172 -218.692222) (xy 363.453596 -218.666593) (xy 363.460929 -218.615861)
			(xy 363.475462 -218.566706) (xy 363.496893 -218.520142) (xy 363.524781 -218.477134) (xy 363.558547 -218.438569)
			(xy 363.597495 -218.405244) (xy 363.64082 -218.37785) (xy 363.687625 -218.356952) (xy 363.736943 -218.342981)
			(xy 363.76229 -218.339162) (xy 363.786928 -218.33586) (xy 363.959394 -218.036902) (xy 363.949996 -218.013788)
			(xy 363.941569 -217.992266) (xy 363.929685 -217.9476) (xy 363.923694 -217.90177) (xy 363.923326 -217.87866)
			(xy 363.923326 -217.878406) (xy 363.923824 -217.851757) (xy 363.931767 -217.799053) (xy 363.947477 -217.748123)
			(xy 363.970603 -217.700102) (xy 364.000627 -217.656065) (xy 364.036879 -217.616994) (xy 364.07855 -217.583763)
			(xy 364.124708 -217.557114) (xy 364.174322 -217.537642) (xy 364.226284 -217.525782) (xy 364.279434 -217.521799)
			(xy 364.332584 -217.525782) (xy 364.384546 -217.537642) (xy 364.43416 -217.557114) (xy 364.480318 -217.583763)
			(xy 364.521989 -217.616994) (xy 364.558241 -217.656065) (xy 364.588265 -217.700102) (xy 364.611391 -217.748123)
			(xy 364.627101 -217.799053) (xy 364.635044 -217.851757) (xy 364.635542 -217.878406) (xy 364.635069 -217.904055)
			(xy 364.627708 -217.954821) (xy 364.613139 -218.004006) (xy 364.591664 -218.050592) (xy 364.563727 -218.093615)
			(xy 364.529905 -218.132183) (xy 364.4909 -218.1655) (xy 364.447518 -218.192876) (xy 364.400657 -218.213744)
			(xy 364.351287 -218.227672) (xy 364.325916 -218.231466) (xy 364.301024 -218.234768) (xy 364.128812 -218.533218)
			(xy 364.138464 -218.556332) (xy 364.146986 -218.577962) (xy 364.158971 -218.622881) (xy 364.165014 -218.668977)
			(xy 364.165388 -218.692222) (xy 365.332772 -218.692222) (xy 365.333196 -218.666593) (xy 365.340529 -218.615861)
			(xy 365.355062 -218.566706) (xy 365.376493 -218.520142) (xy 365.404381 -218.477134) (xy 365.438147 -218.438569)
			(xy 365.477095 -218.405244) (xy 365.52042 -218.37785) (xy 365.567225 -218.356952) (xy 365.616543 -218.342981)
			(xy 365.64189 -218.339162) (xy 365.666528 -218.33586) (xy 365.838994 -218.036902) (xy 365.829596 -218.013788)
			(xy 365.821169 -217.992266) (xy 365.809285 -217.9476) (xy 365.803294 -217.90177) (xy 365.802926 -217.87866)
			(xy 365.802926 -217.878406) (xy 365.803424 -217.851757) (xy 365.811367 -217.799053) (xy 365.827077 -217.748123)
			(xy 365.850203 -217.700102) (xy 365.880227 -217.656065) (xy 365.916479 -217.616994) (xy 365.95815 -217.583763)
			(xy 366.004308 -217.557114) (xy 366.053922 -217.537642) (xy 366.105884 -217.525782) (xy 366.159034 -217.521799)
			(xy 366.212184 -217.525782) (xy 366.264146 -217.537642) (xy 366.31376 -217.557114) (xy 366.359918 -217.583763)
			(xy 366.401589 -217.616994) (xy 366.437841 -217.656065) (xy 366.467865 -217.700102) (xy 366.490991 -217.748123)
			(xy 366.506701 -217.799053) (xy 366.514644 -217.851757) (xy 366.515142 -217.878406) (xy 366.514669 -217.904055)
			(xy 366.507308 -217.954821) (xy 366.492739 -218.004006) (xy 366.471264 -218.050592) (xy 366.443327 -218.093615)
			(xy 366.409505 -218.132183) (xy 366.3705 -218.1655) (xy 366.327118 -218.192876) (xy 366.280257 -218.213744)
			(xy 366.230887 -218.227672) (xy 366.205516 -218.231466) (xy 366.180624 -218.234768) (xy 366.008412 -218.533218)
			(xy 366.018064 -218.556332) (xy 366.026586 -218.577962) (xy 366.038571 -218.622881) (xy 366.044614 -218.668977)
			(xy 366.044988 -218.692222) (xy 366.04449 -218.718871) (xy 366.036547 -218.771575) (xy 366.020837 -218.822505)
			(xy 365.997711 -218.870526) (xy 365.967687 -218.914563) (xy 365.931435 -218.953634) (xy 365.889764 -218.986865)
			(xy 365.843606 -219.013514) (xy 365.793992 -219.032986) (xy 365.74203 -219.044846) (xy 365.68888 -219.04883)
			(xy 365.63573 -219.044846) (xy 365.583768 -219.032986) (xy 365.534154 -219.013514) (xy 365.487996 -218.986865)
			(xy 365.446325 -218.953634) (xy 365.410073 -218.914563) (xy 365.380049 -218.870526) (xy 365.356923 -218.822505)
			(xy 365.341213 -218.771575) (xy 365.33327 -218.718871) (xy 365.332772 -218.692222) (xy 364.165388 -218.692222)
			(xy 364.16489 -218.718871) (xy 364.156947 -218.771575) (xy 364.141237 -218.822505) (xy 364.118111 -218.870526)
			(xy 364.088087 -218.914563) (xy 364.051835 -218.953634) (xy 364.010164 -218.986865) (xy 363.964006 -219.013514)
			(xy 363.914392 -219.032986) (xy 363.86243 -219.044846) (xy 363.80928 -219.04883) (xy 363.75613 -219.044846)
			(xy 363.704168 -219.032986) (xy 363.654554 -219.013514) (xy 363.608396 -218.986865) (xy 363.566725 -218.953634)
			(xy 363.530473 -218.914563) (xy 363.500449 -218.870526) (xy 363.477323 -218.822505) (xy 363.461613 -218.771575)
			(xy 363.45367 -218.718871) (xy 363.453172 -218.692222) (xy 363.225842 -218.692222) (xy 363.225344 -218.718871)
			(xy 363.217401 -218.771575) (xy 363.201691 -218.822505) (xy 363.178565 -218.870526) (xy 363.148541 -218.914563)
			(xy 363.112289 -218.953634) (xy 363.070618 -218.986865) (xy 363.02446 -219.013514) (xy 362.974846 -219.032986)
			(xy 362.922884 -219.044846) (xy 362.869734 -219.04883) (xy 362.816584 -219.044846) (xy 362.764622 -219.032986)
			(xy 362.715008 -219.013514) (xy 362.66885 -218.986865) (xy 362.627179 -218.953634) (xy 362.590927 -218.914563)
			(xy 362.560903 -218.870526) (xy 362.537777 -218.822505) (xy 362.522067 -218.771575) (xy 362.514124 -218.718871)
			(xy 362.285544 -218.718871) (xy 362.277601 -218.771575) (xy 362.261891 -218.822505) (xy 362.238765 -218.870526)
			(xy 362.208741 -218.914563) (xy 362.172489 -218.953634) (xy 362.130818 -218.986865) (xy 362.08466 -219.013514)
			(xy 362.035046 -219.032986) (xy 361.983084 -219.044846) (xy 361.929934 -219.04883) (xy 361.876784 -219.044846)
			(xy 361.824822 -219.032986) (xy 361.775208 -219.013514) (xy 361.72905 -218.986865) (xy 361.687379 -218.953634)
			(xy 361.651127 -218.914563) (xy 361.621103 -218.870526) (xy 361.597977 -218.822505) (xy 361.582267 -218.771575)
			(xy 361.574324 -218.718871) (xy 361.573826 -218.692222) (xy 361.345988 -218.692222) (xy 361.34549 -218.718871)
			(xy 361.337547 -218.771575) (xy 361.321837 -218.822505) (xy 361.298711 -218.870526) (xy 361.268687 -218.914563)
			(xy 361.232435 -218.953634) (xy 361.190764 -218.986865) (xy 361.144606 -219.013514) (xy 361.094992 -219.032986)
			(xy 361.04303 -219.044846) (xy 360.98988 -219.04883) (xy 360.93673 -219.044846) (xy 360.884768 -219.032986)
			(xy 360.835154 -219.013514) (xy 360.788996 -218.986865) (xy 360.747325 -218.953634) (xy 360.711073 -218.914563)
			(xy 360.681049 -218.870526) (xy 360.657923 -218.822505) (xy 360.642213 -218.771575) (xy 360.63427 -218.718871)
			(xy 360.40569 -218.718871) (xy 360.397747 -218.771575) (xy 360.382037 -218.822505) (xy 360.358911 -218.870526)
			(xy 360.328887 -218.914563) (xy 360.292635 -218.953634) (xy 360.250964 -218.986865) (xy 360.204806 -219.013514)
			(xy 360.155192 -219.032986) (xy 360.10323 -219.044846) (xy 360.05008 -219.04883) (xy 359.99693 -219.044846)
			(xy 359.944968 -219.032986) (xy 359.895354 -219.013514) (xy 359.849196 -218.986865) (xy 359.807525 -218.953634)
			(xy 359.771273 -218.914563) (xy 359.741249 -218.870526) (xy 359.718123 -218.822505) (xy 359.702413 -218.771575)
			(xy 359.69447 -218.718871) (xy 359.693972 -218.692222) (xy 359.466896 -218.692222) (xy 359.466398 -218.718871)
			(xy 359.458455 -218.771575) (xy 359.442745 -218.822505) (xy 359.419619 -218.870526) (xy 359.389595 -218.914563)
			(xy 359.353343 -218.953634) (xy 359.311672 -218.986865) (xy 359.265514 -219.013514) (xy 359.2159 -219.032986)
			(xy 359.163938 -219.044846) (xy 359.110788 -219.04883) (xy 359.057638 -219.044846) (xy 359.005676 -219.032986)
			(xy 358.956062 -219.013514) (xy 358.909904 -218.986865) (xy 358.868233 -218.953634) (xy 358.831981 -218.914563)
			(xy 358.801957 -218.870526) (xy 358.778831 -218.822505) (xy 358.763121 -218.771575) (xy 358.755178 -218.718871)
			(xy 358.526344 -218.718871) (xy 358.518401 -218.771575) (xy 358.502691 -218.822505) (xy 358.479565 -218.870526)
			(xy 358.449541 -218.914563) (xy 358.413289 -218.953634) (xy 358.371618 -218.986865) (xy 358.32546 -219.013514)
			(xy 358.275846 -219.032986) (xy 358.223884 -219.044846) (xy 358.170734 -219.04883) (xy 358.117584 -219.044846)
			(xy 358.065622 -219.032986) (xy 358.016008 -219.013514) (xy 357.96985 -218.986865) (xy 357.928179 -218.953634)
			(xy 357.891927 -218.914563) (xy 357.861903 -218.870526) (xy 357.838777 -218.822505) (xy 357.823067 -218.771575)
			(xy 357.815124 -218.718871) (xy 357.814626 -218.692222) (xy 357.815 -218.668977) (xy 357.821045 -218.622882)
			(xy 357.833033 -218.577964) (xy 357.84155 -218.556332) (xy 357.851202 -218.533218) (xy 357.678736 -218.234768)
			(xy 357.654098 -218.231466) (xy 357.628738 -218.227674) (xy 357.579397 -218.213716) (xy 357.532567 -218.192826)
			(xy 357.489218 -218.165437) (xy 357.450244 -218.132114) (xy 357.416451 -218.093547) (xy 357.388538 -218.050533)
			(xy 357.367082 -218.00396) (xy 357.352527 -217.954792) (xy 357.345173 -217.904045) (xy 357.344726 -217.878406)
			(xy 357.117142 -217.878406) (xy 357.116644 -217.905055) (xy 357.108701 -217.957759) (xy 357.092991 -218.008689)
			(xy 357.069865 -218.05671) (xy 357.039841 -218.100747) (xy 357.003589 -218.139818) (xy 356.961918 -218.173049)
			(xy 356.91576 -218.199698) (xy 356.866146 -218.21917) (xy 356.814184 -218.23103) (xy 356.761034 -218.235014)
			(xy 356.707884 -218.23103) (xy 356.655922 -218.21917) (xy 356.606308 -218.199698) (xy 356.56015 -218.173049)
			(xy 356.518479 -218.139818) (xy 356.482227 -218.100747) (xy 356.452203 -218.05671) (xy 356.429077 -218.008689)
			(xy 356.413367 -217.957759) (xy 356.405424 -217.905055) (xy 356.404926 -217.878406) (xy 356.177342 -217.878406)
			(xy 356.176972 -217.901651) (xy 356.170925 -217.947747) (xy 356.158935 -217.992664) (xy 356.150418 -218.014296)
			(xy 356.140766 -218.03741) (xy 356.313232 -218.33586) (xy 356.33787 -218.339162) (xy 356.363213 -218.342982)
			(xy 356.412516 -218.356977) (xy 356.459306 -218.377891) (xy 356.502616 -218.405294) (xy 356.541553 -218.438619)
			(xy 356.575313 -218.47718) (xy 356.603199 -218.52018) (xy 356.624637 -218.566732) (xy 356.639183 -218.615876)
			(xy 356.646537 -218.666597) (xy 356.646988 -218.692222) (xy 356.64649 -218.718871) (xy 356.87507 -218.718871)
			(xy 356.87507 -218.665573) (xy 356.883013 -218.612869) (xy 356.898723 -218.561939) (xy 356.921849 -218.513918)
			(xy 356.951873 -218.469881) (xy 356.988125 -218.43081) (xy 357.029796 -218.397579) (xy 357.075954 -218.37093)
			(xy 357.125568 -218.351458) (xy 357.17753 -218.339598) (xy 357.23068 -218.335615) (xy 357.28383 -218.339598)
			(xy 357.335792 -218.351458) (xy 357.385406 -218.37093) (xy 357.431564 -218.397579) (xy 357.473235 -218.43081)
			(xy 357.509487 -218.469881) (xy 357.539511 -218.513918) (xy 357.562637 -218.561939) (xy 357.578347 -218.612869)
			(xy 357.58629 -218.665573) (xy 357.586788 -218.692222) (xy 357.58629 -218.718871) (xy 357.578347 -218.771575)
			(xy 357.562637 -218.822505) (xy 357.539511 -218.870526) (xy 357.509487 -218.914563) (xy 357.473235 -218.953634)
			(xy 357.431564 -218.986865) (xy 357.385406 -219.013514) (xy 357.335792 -219.032986) (xy 357.28383 -219.044846)
			(xy 357.23068 -219.04883) (xy 357.17753 -219.044846) (xy 357.125568 -219.032986) (xy 357.075954 -219.013514)
			(xy 357.029796 -218.986865) (xy 356.988125 -218.953634) (xy 356.951873 -218.914563) (xy 356.921849 -218.870526)
			(xy 356.898723 -218.822505) (xy 356.883013 -218.771575) (xy 356.87507 -218.718871) (xy 356.64649 -218.718871)
			(xy 356.638547 -218.771575) (xy 356.622837 -218.822505) (xy 356.599711 -218.870526) (xy 356.569687 -218.914563)
			(xy 356.533435 -218.953634) (xy 356.491764 -218.986865) (xy 356.445606 -219.013514) (xy 356.395992 -219.032986)
			(xy 356.34403 -219.044846) (xy 356.29088 -219.04883) (xy 356.23773 -219.044846) (xy 356.185768 -219.032986)
			(xy 356.136154 -219.013514) (xy 356.089996 -218.986865) (xy 356.048325 -218.953634) (xy 356.012073 -218.914563)
			(xy 355.982049 -218.870526) (xy 355.958923 -218.822505) (xy 355.943213 -218.771575) (xy 355.93527 -218.718871)
			(xy 355.934772 -218.692222) (xy 355.93515 -218.668977) (xy 355.941193 -218.622882) (xy 355.95318 -218.577964)
			(xy 355.961696 -218.556332) (xy 355.971348 -218.533218) (xy 355.798882 -218.234768) (xy 355.774244 -218.231466)
			(xy 355.748891 -218.227704) (xy 355.699582 -218.213708) (xy 355.652788 -218.19279) (xy 355.609474 -218.165382)
			(xy 355.570536 -218.13205) (xy 355.536776 -218.093481) (xy 355.508891 -218.050473) (xy 355.487458 -218.003913)
			(xy 355.472918 -217.954762) (xy 355.465572 -217.904034) (xy 355.465126 -217.878406) (xy 355.237542 -217.878406)
			(xy 355.237044 -217.905055) (xy 355.229101 -217.957759) (xy 355.213391 -218.008689) (xy 355.190265 -218.05671)
			(xy 355.160241 -218.100747) (xy 355.123989 -218.139818) (xy 355.082318 -218.173049) (xy 355.03616 -218.199698)
			(xy 354.986546 -218.21917) (xy 354.934584 -218.23103) (xy 354.881434 -218.235014) (xy 354.828284 -218.23103)
			(xy 354.776322 -218.21917) (xy 354.726708 -218.199698) (xy 354.68055 -218.173049) (xy 354.638879 -218.139818)
			(xy 354.602627 -218.100747) (xy 354.572603 -218.05671) (xy 354.549477 -218.008689) (xy 354.533767 -217.957759)
			(xy 354.525824 -217.905055) (xy 354.525326 -217.878406) (xy 354.297742 -217.878406) (xy 354.297366 -217.901651)
			(xy 354.291321 -217.947746) (xy 354.279335 -217.992664) (xy 354.270818 -218.014296) (xy 354.261166 -218.03741)
			(xy 354.433632 -218.33586) (xy 354.45827 -218.339162) (xy 354.483614 -218.342985) (xy 354.532926 -218.356961)
			(xy 354.579723 -218.377864) (xy 354.62304 -218.405261) (xy 354.661982 -218.438586) (xy 354.695742 -218.47715)
			(xy 354.723624 -218.520157) (xy 354.745051 -218.566717) (xy 354.75958 -218.615868) (xy 354.766912 -218.666595)
			(xy 354.767388 -218.692222) (xy 354.76689 -218.718871) (xy 354.99547 -218.718871) (xy 354.99547 -218.665573)
			(xy 355.003413 -218.612869) (xy 355.019123 -218.561939) (xy 355.042249 -218.513918) (xy 355.072273 -218.469881)
			(xy 355.108525 -218.43081) (xy 355.150196 -218.397579) (xy 355.196354 -218.37093) (xy 355.245968 -218.351458)
			(xy 355.29793 -218.339598) (xy 355.35108 -218.335615) (xy 355.40423 -218.339598) (xy 355.456192 -218.351458)
			(xy 355.505806 -218.37093) (xy 355.551964 -218.397579) (xy 355.593635 -218.43081) (xy 355.629887 -218.469881)
			(xy 355.659911 -218.513918) (xy 355.683037 -218.561939) (xy 355.698747 -218.612869) (xy 355.70669 -218.665573)
			(xy 355.707188 -218.692222) (xy 355.70669 -218.718871) (xy 355.698747 -218.771575) (xy 355.683037 -218.822505)
			(xy 355.659911 -218.870526) (xy 355.629887 -218.914563) (xy 355.593635 -218.953634) (xy 355.551964 -218.986865)
			(xy 355.505806 -219.013514) (xy 355.456192 -219.032986) (xy 355.40423 -219.044846) (xy 355.35108 -219.04883)
			(xy 355.29793 -219.044846) (xy 355.245968 -219.032986) (xy 355.196354 -219.013514) (xy 355.150196 -218.986865)
			(xy 355.108525 -218.953634) (xy 355.072273 -218.914563) (xy 355.042249 -218.870526) (xy 355.019123 -218.822505)
			(xy 355.003413 -218.771575) (xy 354.99547 -218.718871) (xy 354.76689 -218.718871) (xy 354.758947 -218.771575)
			(xy 354.743237 -218.822505) (xy 354.720111 -218.870526) (xy 354.690087 -218.914563) (xy 354.653835 -218.953634)
			(xy 354.612164 -218.986865) (xy 354.566006 -219.013514) (xy 354.516392 -219.032986) (xy 354.46443 -219.044846)
			(xy 354.41128 -219.04883) (xy 354.35813 -219.044846) (xy 354.306168 -219.032986) (xy 354.256554 -219.013514)
			(xy 354.210396 -218.986865) (xy 354.168725 -218.953634) (xy 354.132473 -218.914563) (xy 354.102449 -218.870526)
			(xy 354.079323 -218.822505) (xy 354.063613 -218.771575) (xy 354.05567 -218.718871) (xy 354.055172 -218.692222)
			(xy 354.055546 -218.668977) (xy 354.061588 -218.62288) (xy 354.073572 -218.577961) (xy 354.082096 -218.556332)
			(xy 354.091748 -218.533218) (xy 353.919282 -218.234768) (xy 353.894644 -218.231466) (xy 353.86944 -218.227677)
			(xy 353.820391 -218.213823) (xy 353.773822 -218.193111) (xy 353.730684 -218.165966) (xy 353.691862 -218.132943)
			(xy 353.67468 -218.114118) (xy 353.66531 -218.104161) (xy 353.642441 -218.089195) (xy 353.61642 -218.080836)
			(xy 353.589113 -218.079683) (xy 353.56248 -218.085819) (xy 353.538431 -218.098803) (xy 353.51869 -218.117705)
			(xy 353.504673 -218.141168) (xy 353.497387 -218.167509) (xy 353.49688 -218.181174) (xy 353.49688 -218.33459)
			(xy 353.538282 -218.342464) (xy 353.565058 -218.348086) (xy 353.616595 -218.366447) (xy 353.664717 -218.392476)
			(xy 353.708291 -218.425559) (xy 353.746291 -218.464918) (xy 353.777824 -218.509627) (xy 353.802147 -218.558633)
			(xy 353.818687 -218.610783) (xy 353.827055 -218.664849) (xy 353.827054 -218.719559) (xy 353.818685 -218.773625)
			(xy 353.802144 -218.825775) (xy 353.77782 -218.87478) (xy 353.746286 -218.919488) (xy 353.708285 -218.958847)
			(xy 353.66471 -218.991929) (xy 353.616587 -219.017956) (xy 353.56505 -219.036316) (xy 353.538282 -219.04198)
			(xy 353.49688 -219.049854) (xy 353.49688 -219.20327) (xy 353.49732 -219.216947) (xy 353.504582 -219.24332)
			(xy 353.518592 -219.266814) (xy 353.538342 -219.28574) (xy 353.562411 -219.298737) (xy 353.589069 -219.304869)
			(xy 353.616399 -219.303696) (xy 353.642433 -219.295303) (xy 353.665301 -219.280291) (xy 353.67468 -219.270326)
			(xy 353.691659 -219.251752) (xy 353.729945 -219.219094) (xy 353.772448 -219.192152) (xy 353.818321 -219.171463)
			(xy 353.86665 -219.157438) (xy 353.916473 -219.150358) (xy 353.941634 -219.14993) (xy 353.968279 -219.15043)
			(xy 354.020973 -219.158377) (xy 354.071893 -219.174089) (xy 354.119904 -219.197214) (xy 354.163932 -219.227235)
			(xy 354.202995 -219.263483) (xy 354.236218 -219.305148) (xy 354.262862 -219.351299) (xy 354.28233 -219.400906)
			(xy 354.294187 -219.452859) (xy 354.298169 -219.506) (xy 354.296169 -219.532687) (xy 354.525824 -219.532687)
			(xy 354.525824 -219.479389) (xy 354.533767 -219.426685) (xy 354.549477 -219.375755) (xy 354.572603 -219.327734)
			(xy 354.602627 -219.283697) (xy 354.638879 -219.244626) (xy 354.68055 -219.211395) (xy 354.726708 -219.184746)
			(xy 354.776322 -219.165274) (xy 354.828284 -219.153414) (xy 354.881434 -219.149431) (xy 354.934584 -219.153414)
			(xy 354.986546 -219.165274) (xy 355.03616 -219.184746) (xy 355.082318 -219.211395) (xy 355.123989 -219.244626)
			(xy 355.160241 -219.283697) (xy 355.190265 -219.327734) (xy 355.213391 -219.375755) (xy 355.229101 -219.426685)
			(xy 355.237044 -219.479389) (xy 355.237542 -219.506038) (xy 355.237044 -219.532687) (xy 355.465624 -219.532687)
			(xy 355.465624 -219.479389) (xy 355.473567 -219.426685) (xy 355.489277 -219.375755) (xy 355.512403 -219.327734)
			(xy 355.542427 -219.283697) (xy 355.578679 -219.244626) (xy 355.62035 -219.211395) (xy 355.666508 -219.184746)
			(xy 355.716122 -219.165274) (xy 355.768084 -219.153414) (xy 355.821234 -219.149431) (xy 355.874384 -219.153414)
			(xy 355.926346 -219.165274) (xy 355.97596 -219.184746) (xy 356.022118 -219.211395) (xy 356.063789 -219.244626)
			(xy 356.100041 -219.283697) (xy 356.130065 -219.327734) (xy 356.153191 -219.375755) (xy 356.168901 -219.426685)
			(xy 356.176844 -219.479389) (xy 356.177342 -219.506038) (xy 356.176844 -219.532687) (xy 356.405424 -219.532687)
			(xy 356.405424 -219.479389) (xy 356.413367 -219.426685) (xy 356.429077 -219.375755) (xy 356.452203 -219.327734)
			(xy 356.482227 -219.283697) (xy 356.518479 -219.244626) (xy 356.56015 -219.211395) (xy 356.606308 -219.184746)
			(xy 356.655922 -219.165274) (xy 356.707884 -219.153414) (xy 356.761034 -219.149431) (xy 356.814184 -219.153414)
			(xy 356.866146 -219.165274) (xy 356.91576 -219.184746) (xy 356.961918 -219.211395) (xy 357.003589 -219.244626)
			(xy 357.039841 -219.283697) (xy 357.069865 -219.327734) (xy 357.092991 -219.375755) (xy 357.108701 -219.426685)
			(xy 357.116644 -219.479389) (xy 357.117142 -219.506038) (xy 357.116644 -219.532687) (xy 357.345224 -219.532687)
			(xy 357.345224 -219.479389) (xy 357.353167 -219.426685) (xy 357.368877 -219.375755) (xy 357.392003 -219.327734)
			(xy 357.422027 -219.283697) (xy 357.458279 -219.244626) (xy 357.49995 -219.211395) (xy 357.546108 -219.184746)
			(xy 357.595722 -219.165274) (xy 357.647684 -219.153414) (xy 357.700834 -219.149431) (xy 357.753984 -219.153414)
			(xy 357.805946 -219.165274) (xy 357.85556 -219.184746) (xy 357.901718 -219.211395) (xy 357.943389 -219.244626)
			(xy 357.979641 -219.283697) (xy 358.009665 -219.327734) (xy 358.032791 -219.375755) (xy 358.048501 -219.426685)
			(xy 358.056444 -219.479389) (xy 358.056942 -219.506038) (xy 358.056444 -219.532687) (xy 358.285024 -219.532687)
			(xy 358.285024 -219.479389) (xy 358.292967 -219.426685) (xy 358.308677 -219.375755) (xy 358.331803 -219.327734)
			(xy 358.361827 -219.283697) (xy 358.398079 -219.244626) (xy 358.43975 -219.211395) (xy 358.485908 -219.184746)
			(xy 358.535522 -219.165274) (xy 358.587484 -219.153414) (xy 358.640634 -219.149431) (xy 358.693784 -219.153414)
			(xy 358.745746 -219.165274) (xy 358.79536 -219.184746) (xy 358.841518 -219.211395) (xy 358.883189 -219.244626)
			(xy 358.919441 -219.283697) (xy 358.949465 -219.327734) (xy 358.972591 -219.375755) (xy 358.988301 -219.426685)
			(xy 358.996244 -219.479389) (xy 358.996742 -219.506038) (xy 358.996244 -219.532687) (xy 359.224824 -219.532687)
			(xy 359.224824 -219.479389) (xy 359.232767 -219.426685) (xy 359.248477 -219.375755) (xy 359.271603 -219.327734)
			(xy 359.301627 -219.283697) (xy 359.337879 -219.244626) (xy 359.37955 -219.211395) (xy 359.425708 -219.184746)
			(xy 359.475322 -219.165274) (xy 359.527284 -219.153414) (xy 359.580434 -219.149431) (xy 359.633584 -219.153414)
			(xy 359.685546 -219.165274) (xy 359.73516 -219.184746) (xy 359.781318 -219.211395) (xy 359.822989 -219.244626)
			(xy 359.859241 -219.283697) (xy 359.889265 -219.327734) (xy 359.912391 -219.375755) (xy 359.928101 -219.426685)
			(xy 359.936044 -219.479389) (xy 359.936542 -219.506038) (xy 359.936044 -219.532687) (xy 360.164624 -219.532687)
			(xy 360.164624 -219.479389) (xy 360.172567 -219.426685) (xy 360.188277 -219.375755) (xy 360.211403 -219.327734)
			(xy 360.241427 -219.283697) (xy 360.277679 -219.244626) (xy 360.31935 -219.211395) (xy 360.365508 -219.184746)
			(xy 360.415122 -219.165274) (xy 360.467084 -219.153414) (xy 360.520234 -219.149431) (xy 360.573384 -219.153414)
			(xy 360.625346 -219.165274) (xy 360.67496 -219.184746) (xy 360.721118 -219.211395) (xy 360.762789 -219.244626)
			(xy 360.799041 -219.283697) (xy 360.829065 -219.327734) (xy 360.852191 -219.375755) (xy 360.867901 -219.426685)
			(xy 360.875844 -219.479389) (xy 360.876342 -219.506038) (xy 360.875844 -219.532687) (xy 361.104424 -219.532687)
			(xy 361.104424 -219.479389) (xy 361.112367 -219.426685) (xy 361.128077 -219.375755) (xy 361.151203 -219.327734)
			(xy 361.181227 -219.283697) (xy 361.217479 -219.244626) (xy 361.25915 -219.211395) (xy 361.305308 -219.184746)
			(xy 361.354922 -219.165274) (xy 361.406884 -219.153414) (xy 361.460034 -219.149431) (xy 361.513184 -219.153414)
			(xy 361.565146 -219.165274) (xy 361.61476 -219.184746) (xy 361.660918 -219.211395) (xy 361.702589 -219.244626)
			(xy 361.738841 -219.283697) (xy 361.768865 -219.327734) (xy 361.791991 -219.375755) (xy 361.807701 -219.426685)
			(xy 361.815644 -219.479389) (xy 361.816142 -219.506038) (xy 361.815644 -219.532687) (xy 362.044224 -219.532687)
			(xy 362.044224 -219.479389) (xy 362.052167 -219.426685) (xy 362.067877 -219.375755) (xy 362.091003 -219.327734)
			(xy 362.121027 -219.283697) (xy 362.157279 -219.244626) (xy 362.19895 -219.211395) (xy 362.245108 -219.184746)
			(xy 362.294722 -219.165274) (xy 362.346684 -219.153414) (xy 362.399834 -219.149431) (xy 362.452984 -219.153414)
			(xy 362.504946 -219.165274) (xy 362.55456 -219.184746) (xy 362.600718 -219.211395) (xy 362.642389 -219.244626)
			(xy 362.678641 -219.283697) (xy 362.708665 -219.327734) (xy 362.731791 -219.375755) (xy 362.747501 -219.426685)
			(xy 362.755444 -219.479389) (xy 362.755942 -219.506038) (xy 362.755444 -219.532687) (xy 362.984024 -219.532687)
			(xy 362.984024 -219.479389) (xy 362.991967 -219.426685) (xy 363.007677 -219.375755) (xy 363.030803 -219.327734)
			(xy 363.060827 -219.283697) (xy 363.097079 -219.244626) (xy 363.13875 -219.211395) (xy 363.184908 -219.184746)
			(xy 363.234522 -219.165274) (xy 363.286484 -219.153414) (xy 363.339634 -219.149431) (xy 363.392784 -219.153414)
			(xy 363.444746 -219.165274) (xy 363.49436 -219.184746) (xy 363.540518 -219.211395) (xy 363.582189 -219.244626)
			(xy 363.618441 -219.283697) (xy 363.648465 -219.327734) (xy 363.671591 -219.375755) (xy 363.687301 -219.426685)
			(xy 363.695244 -219.479389) (xy 363.695742 -219.506038) (xy 363.695244 -219.532687) (xy 363.923824 -219.532687)
			(xy 363.923824 -219.479389) (xy 363.931767 -219.426685) (xy 363.947477 -219.375755) (xy 363.970603 -219.327734)
			(xy 364.000627 -219.283697) (xy 364.036879 -219.244626) (xy 364.07855 -219.211395) (xy 364.124708 -219.184746)
			(xy 364.174322 -219.165274) (xy 364.226284 -219.153414) (xy 364.279434 -219.149431) (xy 364.332584 -219.153414)
			(xy 364.384546 -219.165274) (xy 364.43416 -219.184746) (xy 364.480318 -219.211395) (xy 364.521989 -219.244626)
			(xy 364.558241 -219.283697) (xy 364.588265 -219.327734) (xy 364.611391 -219.375755) (xy 364.627101 -219.426685)
			(xy 364.635044 -219.479389) (xy 364.635542 -219.506038) (xy 364.635044 -219.532687) (xy 364.863624 -219.532687)
			(xy 364.863624 -219.479389) (xy 364.871567 -219.426685) (xy 364.887277 -219.375755) (xy 364.910403 -219.327734)
			(xy 364.940427 -219.283697) (xy 364.976679 -219.244626) (xy 365.01835 -219.211395) (xy 365.064508 -219.184746)
			(xy 365.114122 -219.165274) (xy 365.166084 -219.153414) (xy 365.219234 -219.149431) (xy 365.272384 -219.153414)
			(xy 365.324346 -219.165274) (xy 365.37396 -219.184746) (xy 365.420118 -219.211395) (xy 365.461789 -219.244626)
			(xy 365.498041 -219.283697) (xy 365.528065 -219.327734) (xy 365.551191 -219.375755) (xy 365.566901 -219.426685)
			(xy 365.574844 -219.479389) (xy 365.575342 -219.506038) (xy 365.574844 -219.532687) (xy 365.803424 -219.532687)
			(xy 365.803424 -219.479389) (xy 365.811367 -219.426685) (xy 365.827077 -219.375755) (xy 365.850203 -219.327734)
			(xy 365.880227 -219.283697) (xy 365.916479 -219.244626) (xy 365.95815 -219.211395) (xy 366.004308 -219.184746)
			(xy 366.053922 -219.165274) (xy 366.105884 -219.153414) (xy 366.159034 -219.149431) (xy 366.212184 -219.153414)
			(xy 366.264146 -219.165274) (xy 366.31376 -219.184746) (xy 366.359918 -219.211395) (xy 366.401589 -219.244626)
			(xy 366.437841 -219.283697) (xy 366.467865 -219.327734) (xy 366.490991 -219.375755) (xy 366.506701 -219.426685)
			(xy 366.514644 -219.479389) (xy 366.515142 -219.506038) (xy 366.514644 -219.532687) (xy 366.506701 -219.585391)
			(xy 366.490991 -219.636321) (xy 366.467865 -219.684342) (xy 366.437841 -219.728379) (xy 366.401589 -219.76745)
			(xy 366.359918 -219.800681) (xy 366.31376 -219.82733) (xy 366.264146 -219.846802) (xy 366.212184 -219.858662)
			(xy 366.159034 -219.862646) (xy 366.105884 -219.858662) (xy 366.053922 -219.846802) (xy 366.004308 -219.82733)
			(xy 365.95815 -219.800681) (xy 365.916479 -219.76745) (xy 365.880227 -219.728379) (xy 365.850203 -219.684342)
			(xy 365.827077 -219.636321) (xy 365.811367 -219.585391) (xy 365.803424 -219.532687) (xy 365.574844 -219.532687)
			(xy 365.566901 -219.585391) (xy 365.551191 -219.636321) (xy 365.528065 -219.684342) (xy 365.498041 -219.728379)
			(xy 365.461789 -219.76745) (xy 365.420118 -219.800681) (xy 365.37396 -219.82733) (xy 365.324346 -219.846802)
			(xy 365.272384 -219.858662) (xy 365.219234 -219.862646) (xy 365.166084 -219.858662) (xy 365.114122 -219.846802)
			(xy 365.064508 -219.82733) (xy 365.01835 -219.800681) (xy 364.976679 -219.76745) (xy 364.940427 -219.728379)
			(xy 364.910403 -219.684342) (xy 364.887277 -219.636321) (xy 364.871567 -219.585391) (xy 364.863624 -219.532687)
			(xy 364.635044 -219.532687) (xy 364.627101 -219.585391) (xy 364.611391 -219.636321) (xy 364.588265 -219.684342)
			(xy 364.558241 -219.728379) (xy 364.521989 -219.76745) (xy 364.480318 -219.800681) (xy 364.43416 -219.82733)
			(xy 364.384546 -219.846802) (xy 364.332584 -219.858662) (xy 364.279434 -219.862646) (xy 364.226284 -219.858662)
			(xy 364.174322 -219.846802) (xy 364.124708 -219.82733) (xy 364.07855 -219.800681) (xy 364.036879 -219.76745)
			(xy 364.000627 -219.728379) (xy 363.970603 -219.684342) (xy 363.947477 -219.636321) (xy 363.931767 -219.585391)
			(xy 363.923824 -219.532687) (xy 363.695244 -219.532687) (xy 363.687301 -219.585391) (xy 363.671591 -219.636321)
			(xy 363.648465 -219.684342) (xy 363.618441 -219.728379) (xy 363.582189 -219.76745) (xy 363.540518 -219.800681)
			(xy 363.49436 -219.82733) (xy 363.444746 -219.846802) (xy 363.392784 -219.858662) (xy 363.339634 -219.862646)
			(xy 363.286484 -219.858662) (xy 363.234522 -219.846802) (xy 363.184908 -219.82733) (xy 363.13875 -219.800681)
			(xy 363.097079 -219.76745) (xy 363.060827 -219.728379) (xy 363.030803 -219.684342) (xy 363.007677 -219.636321)
			(xy 362.991967 -219.585391) (xy 362.984024 -219.532687) (xy 362.755444 -219.532687) (xy 362.747501 -219.585391)
			(xy 362.731791 -219.636321) (xy 362.708665 -219.684342) (xy 362.678641 -219.728379) (xy 362.642389 -219.76745)
			(xy 362.600718 -219.800681) (xy 362.55456 -219.82733) (xy 362.504946 -219.846802) (xy 362.452984 -219.858662)
			(xy 362.399834 -219.862646) (xy 362.346684 -219.858662) (xy 362.294722 -219.846802) (xy 362.245108 -219.82733)
			(xy 362.19895 -219.800681) (xy 362.157279 -219.76745) (xy 362.121027 -219.728379) (xy 362.091003 -219.684342)
			(xy 362.067877 -219.636321) (xy 362.052167 -219.585391) (xy 362.044224 -219.532687) (xy 361.815644 -219.532687)
			(xy 361.807701 -219.585391) (xy 361.791991 -219.636321) (xy 361.768865 -219.684342) (xy 361.738841 -219.728379)
			(xy 361.702589 -219.76745) (xy 361.660918 -219.800681) (xy 361.61476 -219.82733) (xy 361.565146 -219.846802)
			(xy 361.513184 -219.858662) (xy 361.460034 -219.862646) (xy 361.406884 -219.858662) (xy 361.354922 -219.846802)
			(xy 361.305308 -219.82733) (xy 361.25915 -219.800681) (xy 361.217479 -219.76745) (xy 361.181227 -219.728379)
			(xy 361.151203 -219.684342) (xy 361.128077 -219.636321) (xy 361.112367 -219.585391) (xy 361.104424 -219.532687)
			(xy 360.875844 -219.532687) (xy 360.867901 -219.585391) (xy 360.852191 -219.636321) (xy 360.829065 -219.684342)
			(xy 360.799041 -219.728379) (xy 360.762789 -219.76745) (xy 360.721118 -219.800681) (xy 360.67496 -219.82733)
			(xy 360.625346 -219.846802) (xy 360.573384 -219.858662) (xy 360.520234 -219.862646) (xy 360.467084 -219.858662)
			(xy 360.415122 -219.846802) (xy 360.365508 -219.82733) (xy 360.31935 -219.800681) (xy 360.277679 -219.76745)
			(xy 360.241427 -219.728379) (xy 360.211403 -219.684342) (xy 360.188277 -219.636321) (xy 360.172567 -219.585391)
			(xy 360.164624 -219.532687) (xy 359.936044 -219.532687) (xy 359.928101 -219.585391) (xy 359.912391 -219.636321)
			(xy 359.889265 -219.684342) (xy 359.859241 -219.728379) (xy 359.822989 -219.76745) (xy 359.781318 -219.800681)
			(xy 359.73516 -219.82733) (xy 359.685546 -219.846802) (xy 359.633584 -219.858662) (xy 359.580434 -219.862646)
			(xy 359.527284 -219.858662) (xy 359.475322 -219.846802) (xy 359.425708 -219.82733) (xy 359.37955 -219.800681)
			(xy 359.337879 -219.76745) (xy 359.301627 -219.728379) (xy 359.271603 -219.684342) (xy 359.248477 -219.636321)
			(xy 359.232767 -219.585391) (xy 359.224824 -219.532687) (xy 358.996244 -219.532687) (xy 358.988301 -219.585391)
			(xy 358.972591 -219.636321) (xy 358.949465 -219.684342) (xy 358.919441 -219.728379) (xy 358.883189 -219.76745)
			(xy 358.841518 -219.800681) (xy 358.79536 -219.82733) (xy 358.745746 -219.846802) (xy 358.693784 -219.858662)
			(xy 358.640634 -219.862646) (xy 358.587484 -219.858662) (xy 358.535522 -219.846802) (xy 358.485908 -219.82733)
			(xy 358.43975 -219.800681) (xy 358.398079 -219.76745) (xy 358.361827 -219.728379) (xy 358.331803 -219.684342)
			(xy 358.308677 -219.636321) (xy 358.292967 -219.585391) (xy 358.285024 -219.532687) (xy 358.056444 -219.532687)
			(xy 358.048501 -219.585391) (xy 358.032791 -219.636321) (xy 358.009665 -219.684342) (xy 357.979641 -219.728379)
			(xy 357.943389 -219.76745) (xy 357.901718 -219.800681) (xy 357.85556 -219.82733) (xy 357.805946 -219.846802)
			(xy 357.753984 -219.858662) (xy 357.700834 -219.862646) (xy 357.647684 -219.858662) (xy 357.595722 -219.846802)
			(xy 357.546108 -219.82733) (xy 357.49995 -219.800681) (xy 357.458279 -219.76745) (xy 357.422027 -219.728379)
			(xy 357.392003 -219.684342) (xy 357.368877 -219.636321) (xy 357.353167 -219.585391) (xy 357.345224 -219.532687)
			(xy 357.116644 -219.532687) (xy 357.108701 -219.585391) (xy 357.092991 -219.636321) (xy 357.069865 -219.684342)
			(xy 357.039841 -219.728379) (xy 357.003589 -219.76745) (xy 356.961918 -219.800681) (xy 356.91576 -219.82733)
			(xy 356.866146 -219.846802) (xy 356.814184 -219.858662) (xy 356.761034 -219.862646) (xy 356.707884 -219.858662)
			(xy 356.655922 -219.846802) (xy 356.606308 -219.82733) (xy 356.56015 -219.800681) (xy 356.518479 -219.76745)
			(xy 356.482227 -219.728379) (xy 356.452203 -219.684342) (xy 356.429077 -219.636321) (xy 356.413367 -219.585391)
			(xy 356.405424 -219.532687) (xy 356.176844 -219.532687) (xy 356.168901 -219.585391) (xy 356.153191 -219.636321)
			(xy 356.130065 -219.684342) (xy 356.100041 -219.728379) (xy 356.063789 -219.76745) (xy 356.022118 -219.800681)
			(xy 355.97596 -219.82733) (xy 355.926346 -219.846802) (xy 355.874384 -219.858662) (xy 355.821234 -219.862646)
			(xy 355.768084 -219.858662) (xy 355.716122 -219.846802) (xy 355.666508 -219.82733) (xy 355.62035 -219.800681)
			(xy 355.578679 -219.76745) (xy 355.542427 -219.728379) (xy 355.512403 -219.684342) (xy 355.489277 -219.636321)
			(xy 355.473567 -219.585391) (xy 355.465624 -219.532687) (xy 355.237044 -219.532687) (xy 355.229101 -219.585391)
			(xy 355.213391 -219.636321) (xy 355.190265 -219.684342) (xy 355.160241 -219.728379) (xy 355.123989 -219.76745)
			(xy 355.082318 -219.800681) (xy 355.03616 -219.82733) (xy 354.986546 -219.846802) (xy 354.934584 -219.858662)
			(xy 354.881434 -219.862646) (xy 354.828284 -219.858662) (xy 354.776322 -219.846802) (xy 354.726708 -219.82733)
			(xy 354.68055 -219.800681) (xy 354.638879 -219.76745) (xy 354.602627 -219.728379) (xy 354.572603 -219.684342)
			(xy 354.549477 -219.636321) (xy 354.533767 -219.585391) (xy 354.525824 -219.532687) (xy 354.296169 -219.532687)
			(xy 354.294187 -219.559141) (xy 354.28233 -219.611094) (xy 354.262862 -219.660701) (xy 354.236218 -219.706852)
			(xy 354.202995 -219.748517) (xy 354.163932 -219.784765) (xy 354.119904 -219.814786) (xy 354.071893 -219.837911)
			(xy 354.020973 -219.853623) (xy 353.968279 -219.86157) (xy 353.941634 -219.862146) (xy 353.916474 -219.861708)
			(xy 353.866657 -219.854618) (xy 353.818333 -219.840588) (xy 353.772464 -219.819898) (xy 353.729963 -219.792959)
			(xy 353.691675 -219.760308) (xy 353.67468 -219.74175) (xy 353.665312 -219.731791) (xy 353.642445 -219.716821)
			(xy 353.616424 -219.708459) (xy 353.589118 -219.707304) (xy 353.562484 -219.71344) (xy 353.538435 -219.726426)
			(xy 353.518696 -219.745331) (xy 353.504684 -219.768797) (xy 353.497404 -219.795141) (xy 353.49688 -219.808806)
			(xy 353.49688 -219.962222) (xy 353.538282 -219.970096) (xy 353.565056 -219.975724) (xy 353.616587 -219.994095)
			(xy 353.664703 -220.02013) (xy 353.708272 -220.053216) (xy 353.746269 -220.092577) (xy 353.777799 -220.137285)
			(xy 353.802121 -220.186289) (xy 353.818664 -220.238436) (xy 353.827037 -220.2925) (xy 353.827588 -220.319854)
			(xy 353.827193 -220.343056) (xy 353.826739 -220.346503) (xy 354.055924 -220.346503) (xy 354.055924 -220.293205)
			(xy 354.063867 -220.240501) (xy 354.079577 -220.189571) (xy 354.102703 -220.14155) (xy 354.132727 -220.097513)
			(xy 354.168979 -220.058442) (xy 354.21065 -220.025211) (xy 354.256808 -219.998562) (xy 354.306422 -219.97909)
			(xy 354.358384 -219.96723) (xy 354.411534 -219.963247) (xy 354.464684 -219.96723) (xy 354.516646 -219.97909)
			(xy 354.56626 -219.998562) (xy 354.612418 -220.025211) (xy 354.654089 -220.058442) (xy 354.690341 -220.097513)
			(xy 354.720365 -220.14155) (xy 354.743491 -220.189571) (xy 354.759201 -220.240501) (xy 354.767144 -220.293205)
			(xy 354.767642 -220.319854) (xy 354.994972 -220.319854) (xy 354.99547 -220.293205) (xy 355.003413 -220.240501)
			(xy 355.019123 -220.189571) (xy 355.042249 -220.14155) (xy 355.072273 -220.097513) (xy 355.108525 -220.058442)
			(xy 355.150196 -220.025211) (xy 355.196354 -219.998562) (xy 355.245968 -219.97909) (xy 355.29793 -219.96723)
			(xy 355.35108 -219.963247) (xy 355.40423 -219.96723) (xy 355.456192 -219.97909) (xy 355.505806 -219.998562)
			(xy 355.551964 -220.025211) (xy 355.593635 -220.058442) (xy 355.629887 -220.097513) (xy 355.659911 -220.14155)
			(xy 355.683037 -220.189571) (xy 355.698747 -220.240501) (xy 355.70669 -220.293205) (xy 355.707188 -220.319854)
			(xy 355.706793 -220.343057) (xy 355.70634 -220.346503) (xy 355.935524 -220.346503) (xy 355.935524 -220.293205)
			(xy 355.943467 -220.240501) (xy 355.959177 -220.189571) (xy 355.982303 -220.14155) (xy 356.012327 -220.097513)
			(xy 356.048579 -220.058442) (xy 356.09025 -220.025211) (xy 356.136408 -219.998562) (xy 356.186022 -219.97909)
			(xy 356.237984 -219.96723) (xy 356.291134 -219.963247) (xy 356.344284 -219.96723) (xy 356.396246 -219.97909)
			(xy 356.44586 -219.998562) (xy 356.492018 -220.025211) (xy 356.533689 -220.058442) (xy 356.569941 -220.097513)
			(xy 356.599965 -220.14155) (xy 356.623091 -220.189571) (xy 356.638801 -220.240501) (xy 356.646744 -220.293205)
			(xy 356.647242 -220.319854) (xy 356.874572 -220.319854) (xy 356.87507 -220.293205) (xy 356.883013 -220.240501)
			(xy 356.898723 -220.189571) (xy 356.921849 -220.14155) (xy 356.951873 -220.097513) (xy 356.988125 -220.058442)
			(xy 357.029796 -220.025211) (xy 357.075954 -219.998562) (xy 357.125568 -219.97909) (xy 357.17753 -219.96723)
			(xy 357.23068 -219.963247) (xy 357.28383 -219.96723) (xy 357.335792 -219.97909) (xy 357.385406 -219.998562)
			(xy 357.431564 -220.025211) (xy 357.473235 -220.058442) (xy 357.509487 -220.097513) (xy 357.539511 -220.14155)
			(xy 357.562637 -220.189571) (xy 357.578347 -220.240501) (xy 357.58629 -220.293205) (xy 357.586788 -220.319854)
			(xy 357.586393 -220.343057) (xy 357.58594 -220.346503) (xy 357.815124 -220.346503) (xy 357.815124 -220.293205)
			(xy 357.823067 -220.240501) (xy 357.838777 -220.189571) (xy 357.861903 -220.14155) (xy 357.891927 -220.097513)
			(xy 357.928179 -220.058442) (xy 357.96985 -220.025211) (xy 358.016008 -219.998562) (xy 358.065622 -219.97909)
			(xy 358.117584 -219.96723) (xy 358.170734 -219.963247) (xy 358.223884 -219.96723) (xy 358.275846 -219.97909)
			(xy 358.32546 -219.998562) (xy 358.371618 -220.025211) (xy 358.413289 -220.058442) (xy 358.449541 -220.097513)
			(xy 358.479565 -220.14155) (xy 358.502691 -220.189571) (xy 358.518401 -220.240501) (xy 358.526344 -220.293205)
			(xy 358.526842 -220.319854) (xy 358.754172 -220.319854) (xy 358.75467 -220.293205) (xy 358.762613 -220.240501)
			(xy 358.778323 -220.189571) (xy 358.801449 -220.14155) (xy 358.831473 -220.097513) (xy 358.867725 -220.058442)
			(xy 358.909396 -220.025211) (xy 358.955554 -219.998562) (xy 359.005168 -219.97909) (xy 359.05713 -219.96723)
			(xy 359.11028 -219.963247) (xy 359.16343 -219.96723) (xy 359.215392 -219.97909) (xy 359.265006 -219.998562)
			(xy 359.311164 -220.025211) (xy 359.352835 -220.058442) (xy 359.389087 -220.097513) (xy 359.419111 -220.14155)
			(xy 359.442237 -220.189571) (xy 359.457947 -220.240501) (xy 359.46589 -220.293205) (xy 359.466388 -220.319854)
			(xy 359.465993 -220.343057) (xy 359.46554 -220.346503) (xy 359.694724 -220.346503) (xy 359.694724 -220.293205)
			(xy 359.702667 -220.240501) (xy 359.718377 -220.189571) (xy 359.741503 -220.14155) (xy 359.771527 -220.097513)
			(xy 359.807779 -220.058442) (xy 359.84945 -220.025211) (xy 359.895608 -219.998562) (xy 359.945222 -219.97909)
			(xy 359.997184 -219.96723) (xy 360.050334 -219.963247) (xy 360.103484 -219.96723) (xy 360.155446 -219.97909)
			(xy 360.20506 -219.998562) (xy 360.251218 -220.025211) (xy 360.292889 -220.058442) (xy 360.329141 -220.097513)
			(xy 360.359165 -220.14155) (xy 360.382291 -220.189571) (xy 360.398001 -220.240501) (xy 360.405944 -220.293205)
			(xy 360.406442 -220.319854) (xy 360.633772 -220.319854) (xy 360.63427 -220.293205) (xy 360.642213 -220.240501)
			(xy 360.657923 -220.189571) (xy 360.681049 -220.14155) (xy 360.711073 -220.097513) (xy 360.747325 -220.058442)
			(xy 360.788996 -220.025211) (xy 360.835154 -219.998562) (xy 360.884768 -219.97909) (xy 360.93673 -219.96723)
			(xy 360.98988 -219.963247) (xy 361.04303 -219.96723) (xy 361.094992 -219.97909) (xy 361.144606 -219.998562)
			(xy 361.190764 -220.025211) (xy 361.232435 -220.058442) (xy 361.268687 -220.097513) (xy 361.298711 -220.14155)
			(xy 361.321837 -220.189571) (xy 361.337547 -220.240501) (xy 361.34549 -220.293205) (xy 361.345988 -220.319854)
			(xy 361.345593 -220.343057) (xy 361.34514 -220.346503) (xy 361.574324 -220.346503) (xy 361.574324 -220.293205)
			(xy 361.582267 -220.240501) (xy 361.597977 -220.189571) (xy 361.621103 -220.14155) (xy 361.651127 -220.097513)
			(xy 361.687379 -220.058442) (xy 361.72905 -220.025211) (xy 361.775208 -219.998562) (xy 361.824822 -219.97909)
			(xy 361.876784 -219.96723) (xy 361.929934 -219.963247) (xy 361.983084 -219.96723) (xy 362.035046 -219.97909)
			(xy 362.08466 -219.998562) (xy 362.130818 -220.025211) (xy 362.172489 -220.058442) (xy 362.208741 -220.097513)
			(xy 362.238765 -220.14155) (xy 362.261891 -220.189571) (xy 362.277601 -220.240501) (xy 362.285544 -220.293205)
			(xy 362.286042 -220.319854) (xy 362.513372 -220.319854) (xy 362.51387 -220.293205) (xy 362.521813 -220.240501)
			(xy 362.537523 -220.189571) (xy 362.560649 -220.14155) (xy 362.590673 -220.097513) (xy 362.626925 -220.058442)
			(xy 362.668596 -220.025211) (xy 362.714754 -219.998562) (xy 362.764368 -219.97909) (xy 362.81633 -219.96723)
			(xy 362.86948 -219.963247) (xy 362.92263 -219.96723) (xy 362.974592 -219.97909) (xy 363.024206 -219.998562)
			(xy 363.070364 -220.025211) (xy 363.112035 -220.058442) (xy 363.148287 -220.097513) (xy 363.178311 -220.14155)
			(xy 363.201437 -220.189571) (xy 363.217147 -220.240501) (xy 363.22509 -220.293205) (xy 363.225588 -220.319854)
			(xy 363.225193 -220.343057) (xy 363.22474 -220.346503) (xy 363.453924 -220.346503) (xy 363.453924 -220.293205)
			(xy 363.461867 -220.240501) (xy 363.477577 -220.189571) (xy 363.500703 -220.14155) (xy 363.530727 -220.097513)
			(xy 363.566979 -220.058442) (xy 363.60865 -220.025211) (xy 363.654808 -219.998562) (xy 363.704422 -219.97909)
			(xy 363.756384 -219.96723) (xy 363.809534 -219.963247) (xy 363.862684 -219.96723) (xy 363.914646 -219.97909)
			(xy 363.96426 -219.998562) (xy 364.010418 -220.025211) (xy 364.052089 -220.058442) (xy 364.088341 -220.097513)
			(xy 364.118365 -220.14155) (xy 364.141491 -220.189571) (xy 364.157201 -220.240501) (xy 364.165144 -220.293205)
			(xy 364.165642 -220.319854) (xy 364.392972 -220.319854) (xy 364.39347 -220.293205) (xy 364.401413 -220.240501)
			(xy 364.417123 -220.189571) (xy 364.440249 -220.14155) (xy 364.470273 -220.097513) (xy 364.506525 -220.058442)
			(xy 364.548196 -220.025211) (xy 364.594354 -219.998562) (xy 364.643968 -219.97909) (xy 364.69593 -219.96723)
			(xy 364.74908 -219.963247) (xy 364.80223 -219.96723) (xy 364.854192 -219.97909) (xy 364.903806 -219.998562)
			(xy 364.949964 -220.025211) (xy 364.991635 -220.058442) (xy 365.027887 -220.097513) (xy 365.057911 -220.14155)
			(xy 365.081037 -220.189571) (xy 365.096747 -220.240501) (xy 365.10469 -220.293205) (xy 365.105188 -220.319854)
			(xy 365.104793 -220.343057) (xy 365.10434 -220.346503) (xy 365.333524 -220.346503) (xy 365.333524 -220.293205)
			(xy 365.341467 -220.240501) (xy 365.357177 -220.189571) (xy 365.380303 -220.14155) (xy 365.410327 -220.097513)
			(xy 365.446579 -220.058442) (xy 365.48825 -220.025211) (xy 365.534408 -219.998562) (xy 365.584022 -219.97909)
			(xy 365.635984 -219.96723) (xy 365.689134 -219.963247) (xy 365.742284 -219.96723) (xy 365.794246 -219.97909)
			(xy 365.84386 -219.998562) (xy 365.890018 -220.025211) (xy 365.931689 -220.058442) (xy 365.967941 -220.097513)
			(xy 365.997965 -220.14155) (xy 366.021091 -220.189571) (xy 366.036801 -220.240501) (xy 366.044744 -220.293205)
			(xy 366.045242 -220.319854) (xy 366.044744 -220.346503) (xy 366.036801 -220.399207) (xy 366.021091 -220.450137)
			(xy 365.997965 -220.498158) (xy 365.967941 -220.542195) (xy 365.931689 -220.581266) (xy 365.890018 -220.614497)
			(xy 365.84386 -220.641146) (xy 365.794246 -220.660618) (xy 365.742284 -220.672478) (xy 365.689134 -220.676462)
			(xy 365.635984 -220.672478) (xy 365.584022 -220.660618) (xy 365.534408 -220.641146) (xy 365.48825 -220.614497)
			(xy 365.446579 -220.581266) (xy 365.410327 -220.542195) (xy 365.380303 -220.498158) (xy 365.357177 -220.450137)
			(xy 365.341467 -220.399207) (xy 365.333524 -220.346503) (xy 365.10434 -220.346503) (xy 365.098749 -220.389067)
			(xy 365.086771 -220.4339) (xy 365.078264 -220.45549) (xy 365.068866 -220.478604) (xy 365.241586 -220.777562)
			(xy 365.266224 -220.780864) (xy 365.291561 -220.784719) (xy 365.340865 -220.798707) (xy 365.387655 -220.819616)
			(xy 365.430965 -220.847014) (xy 365.469903 -220.880335) (xy 365.503664 -220.918892) (xy 365.531552 -220.96189)
			(xy 365.55299 -221.008439) (xy 365.567537 -221.057581) (xy 365.574891 -221.1083) (xy 365.575342 -221.133924)
			(xy 365.574844 -221.160573) (xy 365.566901 -221.213277) (xy 365.551191 -221.264207) (xy 365.528065 -221.312228)
			(xy 365.498041 -221.356265) (xy 365.461789 -221.395336) (xy 365.420118 -221.428567) (xy 365.37396 -221.455216)
			(xy 365.324346 -221.474688) (xy 365.272384 -221.486548) (xy 365.219234 -221.490532) (xy 365.166084 -221.486548)
			(xy 365.114122 -221.474688) (xy 365.064508 -221.455216) (xy 365.01835 -221.428567) (xy 364.976679 -221.395336)
			(xy 364.940427 -221.356265) (xy 364.910403 -221.312228) (xy 364.887277 -221.264207) (xy 364.871567 -221.213277)
			(xy 364.863624 -221.160573) (xy 364.863126 -221.133924) (xy 364.863501 -221.110679) (xy 364.869545 -221.064584)
			(xy 364.881533 -221.019666) (xy 364.89005 -220.998034) (xy 364.899702 -220.97492) (xy 364.727236 -220.676216)
			(xy 364.702344 -220.672914) (xy 364.676998 -220.669039) (xy 364.627661 -220.65509) (xy 364.580834 -220.634209)
			(xy 364.537486 -220.60683) (xy 364.498512 -220.573517) (xy 364.464718 -220.534959) (xy 364.436802 -220.491954)
			(xy 364.415343 -220.44539) (xy 364.400782 -220.39623) (xy 364.393422 -220.345489) (xy 364.392972 -220.319854)
			(xy 364.165642 -220.319854) (xy 364.165144 -220.346503) (xy 364.157201 -220.399207) (xy 364.141491 -220.450137)
			(xy 364.118365 -220.498158) (xy 364.088341 -220.542195) (xy 364.052089 -220.581266) (xy 364.010418 -220.614497)
			(xy 363.96426 -220.641146) (xy 363.914646 -220.660618) (xy 363.862684 -220.672478) (xy 363.809534 -220.676462)
			(xy 363.756384 -220.672478) (xy 363.704422 -220.660618) (xy 363.654808 -220.641146) (xy 363.60865 -220.614497)
			(xy 363.566979 -220.581266) (xy 363.530727 -220.542195) (xy 363.500703 -220.498158) (xy 363.477577 -220.450137)
			(xy 363.461867 -220.399207) (xy 363.453924 -220.346503) (xy 363.22474 -220.346503) (xy 363.219149 -220.389067)
			(xy 363.207171 -220.4339) (xy 363.198664 -220.45549) (xy 363.189266 -220.478604) (xy 363.361986 -220.777562)
			(xy 363.386624 -220.780864) (xy 363.411961 -220.784719) (xy 363.461265 -220.798707) (xy 363.508055 -220.819616)
			(xy 363.551365 -220.847014) (xy 363.590303 -220.880335) (xy 363.624064 -220.918892) (xy 363.651952 -220.96189)
			(xy 363.67339 -221.008439) (xy 363.687937 -221.057581) (xy 363.695291 -221.1083) (xy 363.695742 -221.133924)
			(xy 363.695244 -221.160573) (xy 363.687301 -221.213277) (xy 363.671591 -221.264207) (xy 363.648465 -221.312228)
			(xy 363.618441 -221.356265) (xy 363.582189 -221.395336) (xy 363.540518 -221.428567) (xy 363.49436 -221.455216)
			(xy 363.444746 -221.474688) (xy 363.392784 -221.486548) (xy 363.339634 -221.490532) (xy 363.286484 -221.486548)
			(xy 363.234522 -221.474688) (xy 363.184908 -221.455216) (xy 363.13875 -221.428567) (xy 363.097079 -221.395336)
			(xy 363.060827 -221.356265) (xy 363.030803 -221.312228) (xy 363.007677 -221.264207) (xy 362.991967 -221.213277)
			(xy 362.984024 -221.160573) (xy 362.983526 -221.133924) (xy 362.983901 -221.110679) (xy 362.989945 -221.064584)
			(xy 363.001933 -221.019666) (xy 363.01045 -220.998034) (xy 363.020102 -220.97492) (xy 362.847636 -220.676216)
			(xy 362.822744 -220.672914) (xy 362.797398 -220.669039) (xy 362.748061 -220.65509) (xy 362.701234 -220.634209)
			(xy 362.657886 -220.60683) (xy 362.618912 -220.573517) (xy 362.585118 -220.534959) (xy 362.557202 -220.491954)
			(xy 362.535743 -220.44539) (xy 362.521182 -220.39623) (xy 362.513822 -220.345489) (xy 362.513372 -220.319854)
			(xy 362.286042 -220.319854) (xy 362.285544 -220.346503) (xy 362.277601 -220.399207) (xy 362.261891 -220.450137)
			(xy 362.238765 -220.498158) (xy 362.208741 -220.542195) (xy 362.172489 -220.581266) (xy 362.130818 -220.614497)
			(xy 362.08466 -220.641146) (xy 362.035046 -220.660618) (xy 361.983084 -220.672478) (xy 361.929934 -220.676462)
			(xy 361.876784 -220.672478) (xy 361.824822 -220.660618) (xy 361.775208 -220.641146) (xy 361.72905 -220.614497)
			(xy 361.687379 -220.581266) (xy 361.651127 -220.542195) (xy 361.621103 -220.498158) (xy 361.597977 -220.450137)
			(xy 361.582267 -220.399207) (xy 361.574324 -220.346503) (xy 361.34514 -220.346503) (xy 361.339549 -220.389067)
			(xy 361.327571 -220.4339) (xy 361.319064 -220.45549) (xy 361.309666 -220.478604) (xy 361.482386 -220.777562)
			(xy 361.507024 -220.780864) (xy 361.532361 -220.784719) (xy 361.581665 -220.798707) (xy 361.628455 -220.819616)
			(xy 361.671765 -220.847014) (xy 361.710703 -220.880335) (xy 361.744464 -220.918892) (xy 361.772352 -220.96189)
			(xy 361.79379 -221.008439) (xy 361.808337 -221.057581) (xy 361.815691 -221.1083) (xy 361.816142 -221.133924)
			(xy 361.815644 -221.160573) (xy 361.807701 -221.213277) (xy 361.791991 -221.264207) (xy 361.768865 -221.312228)
			(xy 361.738841 -221.356265) (xy 361.702589 -221.395336) (xy 361.660918 -221.428567) (xy 361.61476 -221.455216)
			(xy 361.565146 -221.474688) (xy 361.513184 -221.486548) (xy 361.460034 -221.490532) (xy 361.406884 -221.486548)
			(xy 361.354922 -221.474688) (xy 361.305308 -221.455216) (xy 361.25915 -221.428567) (xy 361.217479 -221.395336)
			(xy 361.181227 -221.356265) (xy 361.151203 -221.312228) (xy 361.128077 -221.264207) (xy 361.112367 -221.213277)
			(xy 361.104424 -221.160573) (xy 361.103926 -221.133924) (xy 361.104301 -221.110679) (xy 361.110345 -221.064584)
			(xy 361.122333 -221.019666) (xy 361.13085 -220.998034) (xy 361.140502 -220.97492) (xy 360.968036 -220.676216)
			(xy 360.943144 -220.672914) (xy 360.917798 -220.669039) (xy 360.868461 -220.65509) (xy 360.821634 -220.634209)
			(xy 360.778286 -220.60683) (xy 360.739312 -220.573517) (xy 360.705518 -220.534959) (xy 360.677602 -220.491954)
			(xy 360.656143 -220.44539) (xy 360.641582 -220.39623) (xy 360.634222 -220.345489) (xy 360.633772 -220.319854)
			(xy 360.406442 -220.319854) (xy 360.405944 -220.346503) (xy 360.398001 -220.399207) (xy 360.382291 -220.450137)
			(xy 360.359165 -220.498158) (xy 360.329141 -220.542195) (xy 360.292889 -220.581266) (xy 360.251218 -220.614497)
			(xy 360.20506 -220.641146) (xy 360.155446 -220.660618) (xy 360.103484 -220.672478) (xy 360.050334 -220.676462)
			(xy 359.997184 -220.672478) (xy 359.945222 -220.660618) (xy 359.895608 -220.641146) (xy 359.84945 -220.614497)
			(xy 359.807779 -220.581266) (xy 359.771527 -220.542195) (xy 359.741503 -220.498158) (xy 359.718377 -220.450137)
			(xy 359.702667 -220.399207) (xy 359.694724 -220.346503) (xy 359.46554 -220.346503) (xy 359.459949 -220.389067)
			(xy 359.447971 -220.4339) (xy 359.439464 -220.45549) (xy 359.430066 -220.478604) (xy 359.602786 -220.777562)
			(xy 359.627424 -220.780864) (xy 359.652761 -220.784719) (xy 359.702065 -220.798707) (xy 359.748855 -220.819616)
			(xy 359.792165 -220.847014) (xy 359.831103 -220.880335) (xy 359.864864 -220.918892) (xy 359.892752 -220.96189)
			(xy 359.91419 -221.008439) (xy 359.928737 -221.057581) (xy 359.936091 -221.1083) (xy 359.936542 -221.133924)
			(xy 359.936044 -221.160573) (xy 359.928101 -221.213277) (xy 359.912391 -221.264207) (xy 359.889265 -221.312228)
			(xy 359.859241 -221.356265) (xy 359.822989 -221.395336) (xy 359.781318 -221.428567) (xy 359.73516 -221.455216)
			(xy 359.685546 -221.474688) (xy 359.633584 -221.486548) (xy 359.580434 -221.490532) (xy 359.527284 -221.486548)
			(xy 359.475322 -221.474688) (xy 359.425708 -221.455216) (xy 359.37955 -221.428567) (xy 359.337879 -221.395336)
			(xy 359.301627 -221.356265) (xy 359.271603 -221.312228) (xy 359.248477 -221.264207) (xy 359.232767 -221.213277)
			(xy 359.224824 -221.160573) (xy 359.224326 -221.133924) (xy 359.224701 -221.110679) (xy 359.230745 -221.064584)
			(xy 359.242733 -221.019666) (xy 359.25125 -220.998034) (xy 359.260902 -220.97492) (xy 359.088436 -220.676216)
			(xy 359.063544 -220.672914) (xy 359.038198 -220.669039) (xy 358.988861 -220.65509) (xy 358.942034 -220.634209)
			(xy 358.898686 -220.60683) (xy 358.859712 -220.573517) (xy 358.825918 -220.534959) (xy 358.798002 -220.491954)
			(xy 358.776543 -220.44539) (xy 358.761982 -220.39623) (xy 358.754622 -220.345489) (xy 358.754172 -220.319854)
			(xy 358.526842 -220.319854) (xy 358.526344 -220.346503) (xy 358.518401 -220.399207) (xy 358.502691 -220.450137)
			(xy 358.479565 -220.498158) (xy 358.449541 -220.542195) (xy 358.413289 -220.581266) (xy 358.371618 -220.614497)
			(xy 358.32546 -220.641146) (xy 358.275846 -220.660618) (xy 358.223884 -220.672478) (xy 358.170734 -220.676462)
			(xy 358.117584 -220.672478) (xy 358.065622 -220.660618) (xy 358.016008 -220.641146) (xy 357.96985 -220.614497)
			(xy 357.928179 -220.581266) (xy 357.891927 -220.542195) (xy 357.861903 -220.498158) (xy 357.838777 -220.450137)
			(xy 357.823067 -220.399207) (xy 357.815124 -220.346503) (xy 357.58594 -220.346503) (xy 357.580349 -220.389067)
			(xy 357.568371 -220.4339) (xy 357.559864 -220.45549) (xy 357.550466 -220.478604) (xy 357.723186 -220.777562)
			(xy 357.747824 -220.780864) (xy 357.773161 -220.784719) (xy 357.822465 -220.798707) (xy 357.869255 -220.819616)
			(xy 357.912565 -220.847014) (xy 357.951503 -220.880335) (xy 357.985264 -220.918892) (xy 358.013152 -220.96189)
			(xy 358.03459 -221.008439) (xy 358.049137 -221.057581) (xy 358.056491 -221.1083) (xy 358.056942 -221.133924)
			(xy 358.056444 -221.160573) (xy 358.048501 -221.213277) (xy 358.032791 -221.264207) (xy 358.009665 -221.312228)
			(xy 357.979641 -221.356265) (xy 357.943389 -221.395336) (xy 357.901718 -221.428567) (xy 357.85556 -221.455216)
			(xy 357.805946 -221.474688) (xy 357.753984 -221.486548) (xy 357.700834 -221.490532) (xy 357.647684 -221.486548)
			(xy 357.595722 -221.474688) (xy 357.546108 -221.455216) (xy 357.49995 -221.428567) (xy 357.458279 -221.395336)
			(xy 357.422027 -221.356265) (xy 357.392003 -221.312228) (xy 357.368877 -221.264207) (xy 357.353167 -221.213277)
			(xy 357.345224 -221.160573) (xy 357.344726 -221.133924) (xy 357.345101 -221.110679) (xy 357.351145 -221.064584)
			(xy 357.363133 -221.019666) (xy 357.37165 -220.998034) (xy 357.381302 -220.97492) (xy 357.208836 -220.676216)
			(xy 357.183944 -220.672914) (xy 357.158598 -220.669039) (xy 357.109261 -220.65509) (xy 357.062434 -220.634209)
			(xy 357.019086 -220.60683) (xy 356.980112 -220.573517) (xy 356.946318 -220.534959) (xy 356.918402 -220.491954)
			(xy 356.896943 -220.44539) (xy 356.882382 -220.39623) (xy 356.875022 -220.345489) (xy 356.874572 -220.319854)
			(xy 356.647242 -220.319854) (xy 356.646744 -220.346503) (xy 356.638801 -220.399207) (xy 356.623091 -220.450137)
			(xy 356.599965 -220.498158) (xy 356.569941 -220.542195) (xy 356.533689 -220.581266) (xy 356.492018 -220.614497)
			(xy 356.44586 -220.641146) (xy 356.396246 -220.660618) (xy 356.344284 -220.672478) (xy 356.291134 -220.676462)
			(xy 356.237984 -220.672478) (xy 356.186022 -220.660618) (xy 356.136408 -220.641146) (xy 356.09025 -220.614497)
			(xy 356.048579 -220.581266) (xy 356.012327 -220.542195) (xy 355.982303 -220.498158) (xy 355.959177 -220.450137)
			(xy 355.943467 -220.399207) (xy 355.935524 -220.346503) (xy 355.70634 -220.346503) (xy 355.700749 -220.389067)
			(xy 355.688771 -220.4339) (xy 355.680264 -220.45549) (xy 355.670866 -220.478604) (xy 355.843586 -220.777562)
			(xy 355.868224 -220.780864) (xy 355.893561 -220.784719) (xy 355.942865 -220.798707) (xy 355.989655 -220.819616)
			(xy 356.032965 -220.847014) (xy 356.071903 -220.880335) (xy 356.105664 -220.918892) (xy 356.133552 -220.96189)
			(xy 356.15499 -221.008439) (xy 356.169537 -221.057581) (xy 356.176891 -221.1083) (xy 356.177342 -221.133924)
			(xy 356.176844 -221.160573) (xy 356.168901 -221.213277) (xy 356.153191 -221.264207) (xy 356.130065 -221.312228)
			(xy 356.100041 -221.356265) (xy 356.063789 -221.395336) (xy 356.022118 -221.428567) (xy 355.97596 -221.455216)
			(xy 355.926346 -221.474688) (xy 355.874384 -221.486548) (xy 355.821234 -221.490532) (xy 355.768084 -221.486548)
			(xy 355.716122 -221.474688) (xy 355.666508 -221.455216) (xy 355.62035 -221.428567) (xy 355.578679 -221.395336)
			(xy 355.542427 -221.356265) (xy 355.512403 -221.312228) (xy 355.489277 -221.264207) (xy 355.473567 -221.213277)
			(xy 355.465624 -221.160573) (xy 355.465126 -221.133924) (xy 355.465501 -221.110679) (xy 355.471545 -221.064584)
			(xy 355.483533 -221.019666) (xy 355.49205 -220.998034) (xy 355.501702 -220.97492) (xy 355.329236 -220.676216)
			(xy 355.304344 -220.672914) (xy 355.278998 -220.669039) (xy 355.229661 -220.65509) (xy 355.182834 -220.634209)
			(xy 355.139486 -220.60683) (xy 355.100512 -220.573517) (xy 355.066718 -220.534959) (xy 355.038802 -220.491954)
			(xy 355.017343 -220.44539) (xy 355.002782 -220.39623) (xy 354.995422 -220.345489) (xy 354.994972 -220.319854)
			(xy 354.767642 -220.319854) (xy 354.767144 -220.346503) (xy 354.759201 -220.399207) (xy 354.743491 -220.450137)
			(xy 354.720365 -220.498158) (xy 354.690341 -220.542195) (xy 354.654089 -220.581266) (xy 354.612418 -220.614497)
			(xy 354.56626 -220.641146) (xy 354.516646 -220.660618) (xy 354.464684 -220.672478) (xy 354.411534 -220.676462)
			(xy 354.358384 -220.672478) (xy 354.306422 -220.660618) (xy 354.256808 -220.641146) (xy 354.21065 -220.614497)
			(xy 354.168979 -220.581266) (xy 354.132727 -220.542195) (xy 354.102703 -220.498158) (xy 354.079577 -220.450137)
			(xy 354.063867 -220.399207) (xy 354.055924 -220.346503) (xy 353.826739 -220.346503) (xy 353.821129 -220.389061)
			(xy 353.809151 -220.433893) (xy 353.800664 -220.45549) (xy 353.791266 -220.478604) (xy 353.963986 -220.777562)
			(xy 353.988624 -220.780864) (xy 354.01397 -220.784684) (xy 354.063287 -220.798656) (xy 354.11009 -220.819555)
			(xy 354.153413 -220.84695) (xy 354.192359 -220.880275) (xy 354.226124 -220.91884) (xy 354.25401 -220.961848)
			(xy 354.27544 -221.00841) (xy 354.289972 -221.057565) (xy 354.297304 -221.108295) (xy 354.297742 -221.133924)
			(xy 354.297191 -221.161907) (xy 354.288433 -221.217183) (xy 354.271137 -221.270409) (xy 354.245728 -221.320274)
			(xy 354.212832 -221.365552) (xy 354.173259 -221.405126) (xy 354.127983 -221.438023) (xy 354.078118 -221.463433)
			(xy 354.024893 -221.480731) (xy 353.969617 -221.48949) (xy 353.941634 -221.490032) (xy 353.916474 -221.489594)
			(xy 353.866657 -221.482504) (xy 353.818334 -221.468473) (xy 353.772465 -221.447783) (xy 353.729965 -221.420843)
			(xy 353.691678 -221.388191) (xy 353.67468 -221.369636) (xy 353.665311 -221.359678) (xy 353.642443 -221.34471)
			(xy 353.616422 -221.336349) (xy 353.589116 -221.335195) (xy 353.562482 -221.341331) (xy 353.538433 -221.354316)
			(xy 353.518693 -221.373219) (xy 353.504679 -221.396684) (xy 353.497396 -221.423027) (xy 353.49688 -221.436692)
			(xy 353.49688 -221.590108) (xy 353.538282 -221.597982) (xy 353.565056 -221.603604) (xy 353.616591 -221.621965)
			(xy 353.66471 -221.647992) (xy 353.708281 -221.681074) (xy 353.74628 -221.720432) (xy 353.777811 -221.765139)
			(xy 353.802132 -221.814143) (xy 353.81867 -221.86629) (xy 353.827038 -221.920354) (xy 353.827037 -221.94774)
			(xy 354.055172 -221.94774) (xy 354.055612 -221.922111) (xy 354.062943 -221.87138) (xy 354.077473 -221.822225)
			(xy 354.098903 -221.775662) (xy 354.126788 -221.732653) (xy 354.160553 -221.694088) (xy 354.1995 -221.660763)
			(xy 354.242823 -221.633369) (xy 354.289626 -221.61247) (xy 354.338943 -221.598499) (xy 354.36429 -221.59468)
			(xy 354.388928 -221.591378) (xy 354.561394 -221.29242) (xy 354.551996 -221.269306) (xy 354.543545 -221.247793)
			(xy 354.531669 -221.203122) (xy 354.525689 -221.157289) (xy 354.525326 -221.134178) (xy 354.525326 -221.133924)
			(xy 354.525824 -221.107275) (xy 354.533767 -221.054571) (xy 354.549477 -221.003641) (xy 354.572603 -220.95562)
			(xy 354.602627 -220.911583) (xy 354.638879 -220.872512) (xy 354.68055 -220.839281) (xy 354.726708 -220.812632)
			(xy 354.776322 -220.79316) (xy 354.828284 -220.7813) (xy 354.881434 -220.777317) (xy 354.934584 -220.7813)
			(xy 354.986546 -220.79316) (xy 355.03616 -220.812632) (xy 355.082318 -220.839281) (xy 355.123989 -220.872512)
			(xy 355.160241 -220.911583) (xy 355.190265 -220.95562) (xy 355.213391 -221.003641) (xy 355.229101 -221.054571)
			(xy 355.237044 -221.107275) (xy 355.237542 -221.133924) (xy 355.237086 -221.159573) (xy 355.229722 -221.21034)
			(xy 355.215151 -221.259526) (xy 355.193674 -221.306112) (xy 355.165734 -221.349134) (xy 355.131911 -221.387703)
			(xy 355.092904 -221.421019) (xy 355.049521 -221.448395) (xy 355.002659 -221.469263) (xy 354.953287 -221.483191)
			(xy 354.927916 -221.486984) (xy 354.903024 -221.490286) (xy 354.730812 -221.788736) (xy 354.740464 -221.81185)
			(xy 354.748992 -221.833478) (xy 354.760975 -221.878398) (xy 354.767015 -221.924495) (xy 354.767388 -221.94774)
			(xy 354.76689 -221.974389) (xy 354.99547 -221.974389) (xy 354.99547 -221.921091) (xy 355.003413 -221.868387)
			(xy 355.019123 -221.817457) (xy 355.042249 -221.769436) (xy 355.072273 -221.725399) (xy 355.108525 -221.686328)
			(xy 355.150196 -221.653097) (xy 355.196354 -221.626448) (xy 355.245968 -221.606976) (xy 355.29793 -221.595116)
			(xy 355.35108 -221.591133) (xy 355.40423 -221.595116) (xy 355.456192 -221.606976) (xy 355.505806 -221.626448)
			(xy 355.551964 -221.653097) (xy 355.593635 -221.686328) (xy 355.629887 -221.725399) (xy 355.659911 -221.769436)
			(xy 355.683037 -221.817457) (xy 355.698747 -221.868387) (xy 355.70669 -221.921091) (xy 355.707188 -221.94774)
			(xy 355.934772 -221.94774) (xy 355.935212 -221.922111) (xy 355.942543 -221.87138) (xy 355.957073 -221.822225)
			(xy 355.978503 -221.775662) (xy 356.006388 -221.732653) (xy 356.040153 -221.694088) (xy 356.0791 -221.660763)
			(xy 356.122423 -221.633369) (xy 356.169226 -221.61247) (xy 356.218543 -221.598499) (xy 356.24389 -221.59468)
			(xy 356.268528 -221.591378) (xy 356.440994 -221.29242) (xy 356.431596 -221.269306) (xy 356.423145 -221.247793)
			(xy 356.411269 -221.203122) (xy 356.405289 -221.157289) (xy 356.404926 -221.134178) (xy 356.404926 -221.133924)
			(xy 356.405424 -221.107275) (xy 356.413367 -221.054571) (xy 356.429077 -221.003641) (xy 356.452203 -220.95562)
			(xy 356.482227 -220.911583) (xy 356.518479 -220.872512) (xy 356.56015 -220.839281) (xy 356.606308 -220.812632)
			(xy 356.655922 -220.79316) (xy 356.707884 -220.7813) (xy 356.761034 -220.777317) (xy 356.814184 -220.7813)
			(xy 356.866146 -220.79316) (xy 356.91576 -220.812632) (xy 356.961918 -220.839281) (xy 357.003589 -220.872512)
			(xy 357.039841 -220.911583) (xy 357.069865 -220.95562) (xy 357.092991 -221.003641) (xy 357.108701 -221.054571)
			(xy 357.116644 -221.107275) (xy 357.117142 -221.133924) (xy 357.116686 -221.159573) (xy 357.109322 -221.21034)
			(xy 357.094751 -221.259526) (xy 357.073274 -221.306112) (xy 357.045334 -221.349134) (xy 357.011511 -221.387703)
			(xy 356.972504 -221.421019) (xy 356.929121 -221.448395) (xy 356.882259 -221.469263) (xy 356.832887 -221.483191)
			(xy 356.807516 -221.486984) (xy 356.782624 -221.490286) (xy 356.610412 -221.788736) (xy 356.620064 -221.81185)
			(xy 356.628592 -221.833478) (xy 356.640575 -221.878398) (xy 356.646615 -221.924495) (xy 356.646988 -221.94774)
			(xy 356.64649 -221.974389) (xy 356.87507 -221.974389) (xy 356.87507 -221.921091) (xy 356.883013 -221.868387)
			(xy 356.898723 -221.817457) (xy 356.921849 -221.769436) (xy 356.951873 -221.725399) (xy 356.988125 -221.686328)
			(xy 357.029796 -221.653097) (xy 357.075954 -221.626448) (xy 357.125568 -221.606976) (xy 357.17753 -221.595116)
			(xy 357.23068 -221.591133) (xy 357.28383 -221.595116) (xy 357.335792 -221.606976) (xy 357.385406 -221.626448)
			(xy 357.431564 -221.653097) (xy 357.473235 -221.686328) (xy 357.509487 -221.725399) (xy 357.539511 -221.769436)
			(xy 357.562637 -221.817457) (xy 357.578347 -221.868387) (xy 357.58629 -221.921091) (xy 357.586788 -221.94774)
			(xy 357.814626 -221.94774) (xy 357.815106 -221.922113) (xy 357.822436 -221.871386) (xy 357.836964 -221.822234)
			(xy 357.85839 -221.775673) (xy 357.886271 -221.732666) (xy 357.920031 -221.694101) (xy 357.958972 -221.660776)
			(xy 358.00229 -221.63338) (xy 358.049088 -221.612478) (xy 358.0984 -221.598502) (xy 358.123744 -221.59468)
			(xy 358.148382 -221.591378) (xy 358.320848 -221.292674) (xy 358.31145 -221.26956) (xy 358.302955 -221.247966)
			(xy 358.290979 -221.203133) (xy 358.284919 -221.157126) (xy 358.284526 -221.133924) (xy 358.285024 -221.107275)
			(xy 358.292967 -221.054571) (xy 358.308677 -221.003641) (xy 358.331803 -220.95562) (xy 358.361827 -220.911583)
			(xy 358.398079 -220.872512) (xy 358.43975 -220.839281) (xy 358.485908 -220.812632) (xy 358.535522 -220.79316)
			(xy 358.587484 -220.7813) (xy 358.640634 -220.777317) (xy 358.693784 -220.7813) (xy 358.745746 -220.79316)
			(xy 358.79536 -220.812632) (xy 358.841518 -220.839281) (xy 358.883189 -220.872512) (xy 358.919441 -220.911583)
			(xy 358.949465 -220.95562) (xy 358.972591 -221.003641) (xy 358.988301 -221.054571) (xy 358.996244 -221.107275)
			(xy 358.996742 -221.133924) (xy 358.996314 -221.159564) (xy 358.988968 -221.210316) (xy 358.974418 -221.259489)
			(xy 358.952963 -221.306066) (xy 358.925049 -221.349083) (xy 358.891252 -221.38765) (xy 358.852272 -221.420971)
			(xy 358.808915 -221.448354) (xy 358.762078 -221.469235) (xy 358.71273 -221.48318) (xy 358.68737 -221.486984)
			(xy 358.662478 -221.490286) (xy 358.490266 -221.788736) (xy 358.499918 -221.81185) (xy 358.508448 -221.833477)
			(xy 358.52043 -221.878397) (xy 358.526469 -221.924494) (xy 358.526842 -221.94774) (xy 358.526344 -221.974389)
			(xy 358.754924 -221.974389) (xy 358.754924 -221.921091) (xy 358.762867 -221.868387) (xy 358.778577 -221.817457)
			(xy 358.801703 -221.769436) (xy 358.831727 -221.725399) (xy 358.867979 -221.686328) (xy 358.90965 -221.653097)
			(xy 358.955808 -221.626448) (xy 359.005422 -221.606976) (xy 359.057384 -221.595116) (xy 359.110534 -221.591133)
			(xy 359.163684 -221.595116) (xy 359.215646 -221.606976) (xy 359.26526 -221.626448) (xy 359.311418 -221.653097)
			(xy 359.353089 -221.686328) (xy 359.389341 -221.725399) (xy 359.419365 -221.769436) (xy 359.442491 -221.817457)
			(xy 359.458201 -221.868387) (xy 359.466144 -221.921091) (xy 359.466642 -221.94774) (xy 359.693972 -221.94774)
			(xy 359.694412 -221.922111) (xy 359.701743 -221.87138) (xy 359.716273 -221.822225) (xy 359.737703 -221.775662)
			(xy 359.765588 -221.732653) (xy 359.799353 -221.694088) (xy 359.8383 -221.660763) (xy 359.881623 -221.633369)
			(xy 359.928426 -221.61247) (xy 359.977743 -221.598499) (xy 360.00309 -221.59468) (xy 360.027728 -221.591378)
			(xy 360.200194 -221.29242) (xy 360.190796 -221.269306) (xy 360.182345 -221.247793) (xy 360.170469 -221.203122)
			(xy 360.164489 -221.157289) (xy 360.164126 -221.134178) (xy 360.164126 -221.133924) (xy 360.164624 -221.107275)
			(xy 360.172567 -221.054571) (xy 360.188277 -221.003641) (xy 360.211403 -220.95562) (xy 360.241427 -220.911583)
			(xy 360.277679 -220.872512) (xy 360.31935 -220.839281) (xy 360.365508 -220.812632) (xy 360.415122 -220.79316)
			(xy 360.467084 -220.7813) (xy 360.520234 -220.777317) (xy 360.573384 -220.7813) (xy 360.625346 -220.79316)
			(xy 360.67496 -220.812632) (xy 360.721118 -220.839281) (xy 360.762789 -220.872512) (xy 360.799041 -220.911583)
			(xy 360.829065 -220.95562) (xy 360.852191 -221.003641) (xy 360.867901 -221.054571) (xy 360.875844 -221.107275)
			(xy 360.876342 -221.133924) (xy 360.875886 -221.159573) (xy 360.868522 -221.21034) (xy 360.853951 -221.259526)
			(xy 360.832474 -221.306112) (xy 360.804534 -221.349134) (xy 360.770711 -221.387703) (xy 360.731704 -221.421019)
			(xy 360.688321 -221.448395) (xy 360.641459 -221.469263) (xy 360.592087 -221.483191) (xy 360.566716 -221.486984)
			(xy 360.541824 -221.490286) (xy 360.369612 -221.788736) (xy 360.379264 -221.81185) (xy 360.387792 -221.833478)
			(xy 360.399775 -221.878398) (xy 360.405815 -221.924495) (xy 360.406188 -221.94774) (xy 360.40569 -221.974389)
			(xy 360.63427 -221.974389) (xy 360.63427 -221.921091) (xy 360.642213 -221.868387) (xy 360.657923 -221.817457)
			(xy 360.681049 -221.769436) (xy 360.711073 -221.725399) (xy 360.747325 -221.686328) (xy 360.788996 -221.653097)
			(xy 360.835154 -221.626448) (xy 360.884768 -221.606976) (xy 360.93673 -221.595116) (xy 360.98988 -221.591133)
			(xy 361.04303 -221.595116) (xy 361.094992 -221.606976) (xy 361.144606 -221.626448) (xy 361.190764 -221.653097)
			(xy 361.232435 -221.686328) (xy 361.268687 -221.725399) (xy 361.298711 -221.769436) (xy 361.321837 -221.817457)
			(xy 361.337547 -221.868387) (xy 361.34549 -221.921091) (xy 361.345988 -221.94774) (xy 361.573826 -221.94774)
			(xy 361.574306 -221.922113) (xy 361.581636 -221.871386) (xy 361.596164 -221.822234) (xy 361.61759 -221.775673)
			(xy 361.645471 -221.732666) (xy 361.679231 -221.694101) (xy 361.718172 -221.660776) (xy 361.76149 -221.63338)
			(xy 361.808288 -221.612478) (xy 361.8576 -221.598502) (xy 361.882944 -221.59468) (xy 361.907582 -221.591378)
			(xy 362.080048 -221.292674) (xy 362.07065 -221.26956) (xy 362.062155 -221.247966) (xy 362.050179 -221.203133)
			(xy 362.044119 -221.157126) (xy 362.043726 -221.133924) (xy 362.044224 -221.107275) (xy 362.052167 -221.054571)
			(xy 362.067877 -221.003641) (xy 362.091003 -220.95562) (xy 362.121027 -220.911583) (xy 362.157279 -220.872512)
			(xy 362.19895 -220.839281) (xy 362.245108 -220.812632) (xy 362.294722 -220.79316) (xy 362.346684 -220.7813)
			(xy 362.399834 -220.777317) (xy 362.452984 -220.7813) (xy 362.504946 -220.79316) (xy 362.55456 -220.812632)
			(xy 362.600718 -220.839281) (xy 362.642389 -220.872512) (xy 362.678641 -220.911583) (xy 362.708665 -220.95562)
			(xy 362.731791 -221.003641) (xy 362.747501 -221.054571) (xy 362.755444 -221.107275) (xy 362.755942 -221.133924)
			(xy 362.755514 -221.159564) (xy 362.748168 -221.210316) (xy 362.733618 -221.259489) (xy 362.712163 -221.306066)
			(xy 362.684249 -221.349083) (xy 362.650452 -221.38765) (xy 362.611472 -221.420971) (xy 362.568115 -221.448354)
			(xy 362.521278 -221.469235) (xy 362.47193 -221.48318) (xy 362.44657 -221.486984) (xy 362.421678 -221.490286)
			(xy 362.249466 -221.788736) (xy 362.259118 -221.81185) (xy 362.267648 -221.833477) (xy 362.27963 -221.878397)
			(xy 362.285669 -221.924494) (xy 362.286042 -221.94774) (xy 362.285544 -221.974389) (xy 362.514124 -221.974389)
			(xy 362.514124 -221.921091) (xy 362.522067 -221.868387) (xy 362.537777 -221.817457) (xy 362.560903 -221.769436)
			(xy 362.590927 -221.725399) (xy 362.627179 -221.686328) (xy 362.66885 -221.653097) (xy 362.715008 -221.626448)
			(xy 362.764622 -221.606976) (xy 362.816584 -221.595116) (xy 362.869734 -221.591133) (xy 362.922884 -221.595116)
			(xy 362.974846 -221.606976) (xy 363.02446 -221.626448) (xy 363.070618 -221.653097) (xy 363.112289 -221.686328)
			(xy 363.148541 -221.725399) (xy 363.178565 -221.769436) (xy 363.201691 -221.817457) (xy 363.217401 -221.868387)
			(xy 363.225344 -221.921091) (xy 363.225842 -221.94774) (xy 363.453172 -221.94774) (xy 363.453612 -221.922111)
			(xy 363.460943 -221.87138) (xy 363.475473 -221.822225) (xy 363.496903 -221.775662) (xy 363.524788 -221.732653)
			(xy 363.558553 -221.694088) (xy 363.5975 -221.660763) (xy 363.640823 -221.633369) (xy 363.687626 -221.61247)
			(xy 363.736943 -221.598499) (xy 363.76229 -221.59468) (xy 363.786928 -221.591378) (xy 363.959394 -221.29242)
			(xy 363.949996 -221.269306) (xy 363.941545 -221.247793) (xy 363.929669 -221.203122) (xy 363.923689 -221.157289)
			(xy 363.923326 -221.134178) (xy 363.923326 -221.133924) (xy 363.923824 -221.107275) (xy 363.931767 -221.054571)
			(xy 363.947477 -221.003641) (xy 363.970603 -220.95562) (xy 364.000627 -220.911583) (xy 364.036879 -220.872512)
			(xy 364.07855 -220.839281) (xy 364.124708 -220.812632) (xy 364.174322 -220.79316) (xy 364.226284 -220.7813)
			(xy 364.279434 -220.777317) (xy 364.332584 -220.7813) (xy 364.384546 -220.79316) (xy 364.43416 -220.812632)
			(xy 364.480318 -220.839281) (xy 364.521989 -220.872512) (xy 364.558241 -220.911583) (xy 364.588265 -220.95562)
			(xy 364.611391 -221.003641) (xy 364.627101 -221.054571) (xy 364.635044 -221.107275) (xy 364.635542 -221.133924)
			(xy 364.635086 -221.159573) (xy 364.627722 -221.21034) (xy 364.613151 -221.259526) (xy 364.591674 -221.306112)
			(xy 364.563734 -221.349134) (xy 364.529911 -221.387703) (xy 364.490904 -221.421019) (xy 364.447521 -221.448395)
			(xy 364.400659 -221.469263) (xy 364.351287 -221.483191) (xy 364.325916 -221.486984) (xy 364.301024 -221.490286)
			(xy 364.128812 -221.788736) (xy 364.138464 -221.81185) (xy 364.146992 -221.833478) (xy 364.158975 -221.878398)
			(xy 364.165015 -221.924495) (xy 364.165388 -221.94774) (xy 365.332772 -221.94774) (xy 365.333212 -221.922111)
			(xy 365.340543 -221.87138) (xy 365.355073 -221.822225) (xy 365.376503 -221.775662) (xy 365.404388 -221.732653)
			(xy 365.438153 -221.694088) (xy 365.4771 -221.660763) (xy 365.520423 -221.633369) (xy 365.567226 -221.61247)
			(xy 365.616543 -221.598499) (xy 365.64189 -221.59468) (xy 365.666528 -221.591378) (xy 365.838994 -221.29242)
			(xy 365.829596 -221.269306) (xy 365.821145 -221.247793) (xy 365.809269 -221.203122) (xy 365.803289 -221.157289)
			(xy 365.802926 -221.134178) (xy 365.802926 -221.133924) (xy 365.803424 -221.107275) (xy 365.811367 -221.054571)
			(xy 365.827077 -221.003641) (xy 365.850203 -220.95562) (xy 365.880227 -220.911583) (xy 365.916479 -220.872512)
			(xy 365.95815 -220.839281) (xy 366.004308 -220.812632) (xy 366.053922 -220.79316) (xy 366.105884 -220.7813)
			(xy 366.159034 -220.777317) (xy 366.212184 -220.7813) (xy 366.264146 -220.79316) (xy 366.31376 -220.812632)
			(xy 366.359918 -220.839281) (xy 366.401589 -220.872512) (xy 366.437841 -220.911583) (xy 366.467865 -220.95562)
			(xy 366.490991 -221.003641) (xy 366.506701 -221.054571) (xy 366.514644 -221.107275) (xy 366.515142 -221.133924)
			(xy 366.514686 -221.159573) (xy 366.507322 -221.21034) (xy 366.492751 -221.259526) (xy 366.471274 -221.306112)
			(xy 366.443334 -221.349134) (xy 366.409511 -221.387703) (xy 366.370504 -221.421019) (xy 366.327121 -221.448395)
			(xy 366.280259 -221.469263) (xy 366.230887 -221.483191) (xy 366.205516 -221.486984) (xy 366.180624 -221.490286)
			(xy 366.008412 -221.788736) (xy 366.018064 -221.81185) (xy 366.026592 -221.833478) (xy 366.038575 -221.878398)
			(xy 366.044615 -221.924495) (xy 366.044988 -221.94774) (xy 366.04449 -221.974389) (xy 366.036547 -222.027093)
			(xy 366.020837 -222.078023) (xy 365.997711 -222.126044) (xy 365.967687 -222.170081) (xy 365.931435 -222.209152)
			(xy 365.889764 -222.242383) (xy 365.843606 -222.269032) (xy 365.793992 -222.288504) (xy 365.74203 -222.300364)
			(xy 365.68888 -222.304348) (xy 365.63573 -222.300364) (xy 365.583768 -222.288504) (xy 365.534154 -222.269032)
			(xy 365.487996 -222.242383) (xy 365.446325 -222.209152) (xy 365.410073 -222.170081) (xy 365.380049 -222.126044)
			(xy 365.356923 -222.078023) (xy 365.341213 -222.027093) (xy 365.33327 -221.974389) (xy 365.332772 -221.94774)
			(xy 364.165388 -221.94774) (xy 364.16489 -221.974389) (xy 364.156947 -222.027093) (xy 364.141237 -222.078023)
			(xy 364.118111 -222.126044) (xy 364.088087 -222.170081) (xy 364.051835 -222.209152) (xy 364.010164 -222.242383)
			(xy 363.964006 -222.269032) (xy 363.914392 -222.288504) (xy 363.86243 -222.300364) (xy 363.80928 -222.304348)
			(xy 363.75613 -222.300364) (xy 363.704168 -222.288504) (xy 363.654554 -222.269032) (xy 363.608396 -222.242383)
			(xy 363.566725 -222.209152) (xy 363.530473 -222.170081) (xy 363.500449 -222.126044) (xy 363.477323 -222.078023)
			(xy 363.461613 -222.027093) (xy 363.45367 -221.974389) (xy 363.453172 -221.94774) (xy 363.225842 -221.94774)
			(xy 363.225344 -221.974389) (xy 363.217401 -222.027093) (xy 363.201691 -222.078023) (xy 363.178565 -222.126044)
			(xy 363.148541 -222.170081) (xy 363.112289 -222.209152) (xy 363.070618 -222.242383) (xy 363.02446 -222.269032)
			(xy 362.974846 -222.288504) (xy 362.922884 -222.300364) (xy 362.869734 -222.304348) (xy 362.816584 -222.300364)
			(xy 362.764622 -222.288504) (xy 362.715008 -222.269032) (xy 362.66885 -222.242383) (xy 362.627179 -222.209152)
			(xy 362.590927 -222.170081) (xy 362.560903 -222.126044) (xy 362.537777 -222.078023) (xy 362.522067 -222.027093)
			(xy 362.514124 -221.974389) (xy 362.285544 -221.974389) (xy 362.277601 -222.027093) (xy 362.261891 -222.078023)
			(xy 362.238765 -222.126044) (xy 362.208741 -222.170081) (xy 362.172489 -222.209152) (xy 362.130818 -222.242383)
			(xy 362.08466 -222.269032) (xy 362.035046 -222.288504) (xy 361.983084 -222.300364) (xy 361.929934 -222.304348)
			(xy 361.876784 -222.300364) (xy 361.824822 -222.288504) (xy 361.775208 -222.269032) (xy 361.72905 -222.242383)
			(xy 361.687379 -222.209152) (xy 361.651127 -222.170081) (xy 361.621103 -222.126044) (xy 361.597977 -222.078023)
			(xy 361.582267 -222.027093) (xy 361.574324 -221.974389) (xy 361.573826 -221.94774) (xy 361.345988 -221.94774)
			(xy 361.34549 -221.974389) (xy 361.337547 -222.027093) (xy 361.321837 -222.078023) (xy 361.298711 -222.126044)
			(xy 361.268687 -222.170081) (xy 361.232435 -222.209152) (xy 361.190764 -222.242383) (xy 361.144606 -222.269032)
			(xy 361.094992 -222.288504) (xy 361.04303 -222.300364) (xy 360.98988 -222.304348) (xy 360.93673 -222.300364)
			(xy 360.884768 -222.288504) (xy 360.835154 -222.269032) (xy 360.788996 -222.242383) (xy 360.747325 -222.209152)
			(xy 360.711073 -222.170081) (xy 360.681049 -222.126044) (xy 360.657923 -222.078023) (xy 360.642213 -222.027093)
			(xy 360.63427 -221.974389) (xy 360.40569 -221.974389) (xy 360.397747 -222.027093) (xy 360.382037 -222.078023)
			(xy 360.358911 -222.126044) (xy 360.328887 -222.170081) (xy 360.292635 -222.209152) (xy 360.250964 -222.242383)
			(xy 360.204806 -222.269032) (xy 360.155192 -222.288504) (xy 360.10323 -222.300364) (xy 360.05008 -222.304348)
			(xy 359.99693 -222.300364) (xy 359.944968 -222.288504) (xy 359.895354 -222.269032) (xy 359.849196 -222.242383)
			(xy 359.807525 -222.209152) (xy 359.771273 -222.170081) (xy 359.741249 -222.126044) (xy 359.718123 -222.078023)
			(xy 359.702413 -222.027093) (xy 359.69447 -221.974389) (xy 359.693972 -221.94774) (xy 359.466642 -221.94774)
			(xy 359.466144 -221.974389) (xy 359.458201 -222.027093) (xy 359.442491 -222.078023) (xy 359.419365 -222.126044)
			(xy 359.389341 -222.170081) (xy 359.353089 -222.209152) (xy 359.311418 -222.242383) (xy 359.26526 -222.269032)
			(xy 359.215646 -222.288504) (xy 359.163684 -222.300364) (xy 359.110534 -222.304348) (xy 359.057384 -222.300364)
			(xy 359.005422 -222.288504) (xy 358.955808 -222.269032) (xy 358.90965 -222.242383) (xy 358.867979 -222.209152)
			(xy 358.831727 -222.170081) (xy 358.801703 -222.126044) (xy 358.778577 -222.078023) (xy 358.762867 -222.027093)
			(xy 358.754924 -221.974389) (xy 358.526344 -221.974389) (xy 358.518401 -222.027093) (xy 358.502691 -222.078023)
			(xy 358.479565 -222.126044) (xy 358.449541 -222.170081) (xy 358.413289 -222.209152) (xy 358.371618 -222.242383)
			(xy 358.32546 -222.269032) (xy 358.275846 -222.288504) (xy 358.223884 -222.300364) (xy 358.170734 -222.304348)
			(xy 358.117584 -222.300364) (xy 358.065622 -222.288504) (xy 358.016008 -222.269032) (xy 357.96985 -222.242383)
			(xy 357.928179 -222.209152) (xy 357.891927 -222.170081) (xy 357.861903 -222.126044) (xy 357.838777 -222.078023)
			(xy 357.823067 -222.027093) (xy 357.815124 -221.974389) (xy 357.814626 -221.94774) (xy 357.586788 -221.94774)
			(xy 357.58629 -221.974389) (xy 357.578347 -222.027093) (xy 357.562637 -222.078023) (xy 357.539511 -222.126044)
			(xy 357.509487 -222.170081) (xy 357.473235 -222.209152) (xy 357.431564 -222.242383) (xy 357.385406 -222.269032)
			(xy 357.335792 -222.288504) (xy 357.28383 -222.300364) (xy 357.23068 -222.304348) (xy 357.17753 -222.300364)
			(xy 357.125568 -222.288504) (xy 357.075954 -222.269032) (xy 357.029796 -222.242383) (xy 356.988125 -222.209152)
			(xy 356.951873 -222.170081) (xy 356.921849 -222.126044) (xy 356.898723 -222.078023) (xy 356.883013 -222.027093)
			(xy 356.87507 -221.974389) (xy 356.64649 -221.974389) (xy 356.638547 -222.027093) (xy 356.622837 -222.078023)
			(xy 356.599711 -222.126044) (xy 356.569687 -222.170081) (xy 356.533435 -222.209152) (xy 356.491764 -222.242383)
			(xy 356.445606 -222.269032) (xy 356.395992 -222.288504) (xy 356.34403 -222.300364) (xy 356.29088 -222.304348)
			(xy 356.23773 -222.300364) (xy 356.185768 -222.288504) (xy 356.136154 -222.269032) (xy 356.089996 -222.242383)
			(xy 356.048325 -222.209152) (xy 356.012073 -222.170081) (xy 355.982049 -222.126044) (xy 355.958923 -222.078023)
			(xy 355.943213 -222.027093) (xy 355.93527 -221.974389) (xy 355.934772 -221.94774) (xy 355.707188 -221.94774)
			(xy 355.70669 -221.974389) (xy 355.698747 -222.027093) (xy 355.683037 -222.078023) (xy 355.659911 -222.126044)
			(xy 355.629887 -222.170081) (xy 355.593635 -222.209152) (xy 355.551964 -222.242383) (xy 355.505806 -222.269032)
			(xy 355.456192 -222.288504) (xy 355.40423 -222.300364) (xy 355.35108 -222.304348) (xy 355.29793 -222.300364)
			(xy 355.245968 -222.288504) (xy 355.196354 -222.269032) (xy 355.150196 -222.242383) (xy 355.108525 -222.209152)
			(xy 355.072273 -222.170081) (xy 355.042249 -222.126044) (xy 355.019123 -222.078023) (xy 355.003413 -222.027093)
			(xy 354.99547 -221.974389) (xy 354.76689 -221.974389) (xy 354.758947 -222.027093) (xy 354.743237 -222.078023)
			(xy 354.720111 -222.126044) (xy 354.690087 -222.170081) (xy 354.653835 -222.209152) (xy 354.612164 -222.242383)
			(xy 354.566006 -222.269032) (xy 354.516392 -222.288504) (xy 354.46443 -222.300364) (xy 354.41128 -222.304348)
			(xy 354.35813 -222.300364) (xy 354.306168 -222.288504) (xy 354.256554 -222.269032) (xy 354.210396 -222.242383)
			(xy 354.168725 -222.209152) (xy 354.132473 -222.170081) (xy 354.102449 -222.126044) (xy 354.079323 -222.078023)
			(xy 354.063613 -222.027093) (xy 354.05567 -221.974389) (xy 354.055172 -221.94774) (xy 353.827037 -221.94774)
			(xy 353.827036 -221.975061) (xy 353.818667 -222.029125) (xy 353.802126 -222.081271) (xy 353.777803 -222.130274)
			(xy 353.74627 -222.17498) (xy 353.70827 -222.214336) (xy 353.664697 -222.247416) (xy 353.616577 -222.273441)
			(xy 353.565042 -222.2918) (xy 353.538282 -222.297498) (xy 353.49688 -222.305372) (xy 353.49688 -222.458788)
			(xy 353.497322 -222.472463) (xy 353.504587 -222.498832) (xy 353.518598 -222.522322) (xy 353.538347 -222.541244)
			(xy 353.562414 -222.554238) (xy 353.589068 -222.560369) (xy 353.616394 -222.559197) (xy 353.642426 -222.550806)
			(xy 353.665292 -222.535799) (xy 353.67468 -222.525844) (xy 353.691658 -222.507269) (xy 353.729944 -222.47461)
			(xy 353.772447 -222.447666) (xy 353.81832 -222.426976) (xy 353.86665 -222.412951) (xy 353.916472 -222.40587)
			(xy 353.941634 -222.405448) (xy 353.968285 -222.405948) (xy 354.020991 -222.413897) (xy 354.071924 -222.429612)
			(xy 354.119945 -222.452742) (xy 354.163984 -222.482771) (xy 354.203055 -222.519027) (xy 354.236287 -222.560702)
			(xy 354.262936 -222.606863) (xy 354.282408 -222.656481) (xy 354.294268 -222.708447) (xy 354.298252 -222.7616)
			(xy 354.296258 -222.788205) (xy 354.525824 -222.788205) (xy 354.525824 -222.734907) (xy 354.533767 -222.682203)
			(xy 354.549477 -222.631273) (xy 354.572603 -222.583252) (xy 354.602627 -222.539215) (xy 354.638879 -222.500144)
			(xy 354.68055 -222.466913) (xy 354.726708 -222.440264) (xy 354.776322 -222.420792) (xy 354.828284 -222.408932)
			(xy 354.881434 -222.404949) (xy 354.934584 -222.408932) (xy 354.986546 -222.420792) (xy 355.03616 -222.440264)
			(xy 355.082318 -222.466913) (xy 355.123989 -222.500144) (xy 355.160241 -222.539215) (xy 355.190265 -222.583252)
			(xy 355.213391 -222.631273) (xy 355.229101 -222.682203) (xy 355.237044 -222.734907) (xy 355.237542 -222.761556)
			(xy 355.237044 -222.788205) (xy 355.465624 -222.788205) (xy 355.465624 -222.734907) (xy 355.473567 -222.682203)
			(xy 355.489277 -222.631273) (xy 355.512403 -222.583252) (xy 355.542427 -222.539215) (xy 355.578679 -222.500144)
			(xy 355.62035 -222.466913) (xy 355.666508 -222.440264) (xy 355.716122 -222.420792) (xy 355.768084 -222.408932)
			(xy 355.821234 -222.404949) (xy 355.874384 -222.408932) (xy 355.926346 -222.420792) (xy 355.97596 -222.440264)
			(xy 356.022118 -222.466913) (xy 356.063789 -222.500144) (xy 356.100041 -222.539215) (xy 356.130065 -222.583252)
			(xy 356.153191 -222.631273) (xy 356.168901 -222.682203) (xy 356.176844 -222.734907) (xy 356.177342 -222.761556)
			(xy 356.176844 -222.788205) (xy 356.405424 -222.788205) (xy 356.405424 -222.734907) (xy 356.413367 -222.682203)
			(xy 356.429077 -222.631273) (xy 356.452203 -222.583252) (xy 356.482227 -222.539215) (xy 356.518479 -222.500144)
			(xy 356.56015 -222.466913) (xy 356.606308 -222.440264) (xy 356.655922 -222.420792) (xy 356.707884 -222.408932)
			(xy 356.761034 -222.404949) (xy 356.814184 -222.408932) (xy 356.866146 -222.420792) (xy 356.91576 -222.440264)
			(xy 356.961918 -222.466913) (xy 357.003589 -222.500144) (xy 357.039841 -222.539215) (xy 357.069865 -222.583252)
			(xy 357.092991 -222.631273) (xy 357.108701 -222.682203) (xy 357.116644 -222.734907) (xy 357.117142 -222.761556)
			(xy 357.116644 -222.788205) (xy 357.345224 -222.788205) (xy 357.345224 -222.734907) (xy 357.353167 -222.682203)
			(xy 357.368877 -222.631273) (xy 357.392003 -222.583252) (xy 357.422027 -222.539215) (xy 357.458279 -222.500144)
			(xy 357.49995 -222.466913) (xy 357.546108 -222.440264) (xy 357.595722 -222.420792) (xy 357.647684 -222.408932)
			(xy 357.700834 -222.404949) (xy 357.753984 -222.408932) (xy 357.805946 -222.420792) (xy 357.85556 -222.440264)
			(xy 357.901718 -222.466913) (xy 357.943389 -222.500144) (xy 357.979641 -222.539215) (xy 358.009665 -222.583252)
			(xy 358.032791 -222.631273) (xy 358.048501 -222.682203) (xy 358.056444 -222.734907) (xy 358.056942 -222.761556)
			(xy 358.056444 -222.788205) (xy 358.285024 -222.788205) (xy 358.285024 -222.734907) (xy 358.292967 -222.682203)
			(xy 358.308677 -222.631273) (xy 358.331803 -222.583252) (xy 358.361827 -222.539215) (xy 358.398079 -222.500144)
			(xy 358.43975 -222.466913) (xy 358.485908 -222.440264) (xy 358.535522 -222.420792) (xy 358.587484 -222.408932)
			(xy 358.640634 -222.404949) (xy 358.693784 -222.408932) (xy 358.745746 -222.420792) (xy 358.79536 -222.440264)
			(xy 358.841518 -222.466913) (xy 358.883189 -222.500144) (xy 358.919441 -222.539215) (xy 358.949465 -222.583252)
			(xy 358.972591 -222.631273) (xy 358.988301 -222.682203) (xy 358.996244 -222.734907) (xy 358.996742 -222.761556)
			(xy 358.996244 -222.788205) (xy 359.224824 -222.788205) (xy 359.224824 -222.734907) (xy 359.232767 -222.682203)
			(xy 359.248477 -222.631273) (xy 359.271603 -222.583252) (xy 359.301627 -222.539215) (xy 359.337879 -222.500144)
			(xy 359.37955 -222.466913) (xy 359.425708 -222.440264) (xy 359.475322 -222.420792) (xy 359.527284 -222.408932)
			(xy 359.580434 -222.404949) (xy 359.633584 -222.408932) (xy 359.685546 -222.420792) (xy 359.73516 -222.440264)
			(xy 359.781318 -222.466913) (xy 359.822989 -222.500144) (xy 359.859241 -222.539215) (xy 359.889265 -222.583252)
			(xy 359.912391 -222.631273) (xy 359.928101 -222.682203) (xy 359.936044 -222.734907) (xy 359.936542 -222.761556)
			(xy 359.936044 -222.788205) (xy 360.164624 -222.788205) (xy 360.164624 -222.734907) (xy 360.172567 -222.682203)
			(xy 360.188277 -222.631273) (xy 360.211403 -222.583252) (xy 360.241427 -222.539215) (xy 360.277679 -222.500144)
			(xy 360.31935 -222.466913) (xy 360.365508 -222.440264) (xy 360.415122 -222.420792) (xy 360.467084 -222.408932)
			(xy 360.520234 -222.404949) (xy 360.573384 -222.408932) (xy 360.625346 -222.420792) (xy 360.67496 -222.440264)
			(xy 360.721118 -222.466913) (xy 360.762789 -222.500144) (xy 360.799041 -222.539215) (xy 360.829065 -222.583252)
			(xy 360.852191 -222.631273) (xy 360.867901 -222.682203) (xy 360.875844 -222.734907) (xy 360.876342 -222.761556)
			(xy 360.875844 -222.788205) (xy 361.104424 -222.788205) (xy 361.104424 -222.734907) (xy 361.112367 -222.682203)
			(xy 361.128077 -222.631273) (xy 361.151203 -222.583252) (xy 361.181227 -222.539215) (xy 361.217479 -222.500144)
			(xy 361.25915 -222.466913) (xy 361.305308 -222.440264) (xy 361.354922 -222.420792) (xy 361.406884 -222.408932)
			(xy 361.460034 -222.404949) (xy 361.513184 -222.408932) (xy 361.565146 -222.420792) (xy 361.61476 -222.440264)
			(xy 361.660918 -222.466913) (xy 361.702589 -222.500144) (xy 361.738841 -222.539215) (xy 361.768865 -222.583252)
			(xy 361.791991 -222.631273) (xy 361.807701 -222.682203) (xy 361.815644 -222.734907) (xy 361.816142 -222.761556)
			(xy 361.815644 -222.788205) (xy 362.044224 -222.788205) (xy 362.044224 -222.734907) (xy 362.052167 -222.682203)
			(xy 362.067877 -222.631273) (xy 362.091003 -222.583252) (xy 362.121027 -222.539215) (xy 362.157279 -222.500144)
			(xy 362.19895 -222.466913) (xy 362.245108 -222.440264) (xy 362.294722 -222.420792) (xy 362.346684 -222.408932)
			(xy 362.399834 -222.404949) (xy 362.452984 -222.408932) (xy 362.504946 -222.420792) (xy 362.55456 -222.440264)
			(xy 362.600718 -222.466913) (xy 362.642389 -222.500144) (xy 362.678641 -222.539215) (xy 362.708665 -222.583252)
			(xy 362.731791 -222.631273) (xy 362.747501 -222.682203) (xy 362.755444 -222.734907) (xy 362.755942 -222.761556)
			(xy 362.755444 -222.788205) (xy 362.984024 -222.788205) (xy 362.984024 -222.734907) (xy 362.991967 -222.682203)
			(xy 363.007677 -222.631273) (xy 363.030803 -222.583252) (xy 363.060827 -222.539215) (xy 363.097079 -222.500144)
			(xy 363.13875 -222.466913) (xy 363.184908 -222.440264) (xy 363.234522 -222.420792) (xy 363.286484 -222.408932)
			(xy 363.339634 -222.404949) (xy 363.392784 -222.408932) (xy 363.444746 -222.420792) (xy 363.49436 -222.440264)
			(xy 363.540518 -222.466913) (xy 363.582189 -222.500144) (xy 363.618441 -222.539215) (xy 363.648465 -222.583252)
			(xy 363.671591 -222.631273) (xy 363.687301 -222.682203) (xy 363.695244 -222.734907) (xy 363.695742 -222.761556)
			(xy 363.695244 -222.788205) (xy 363.923824 -222.788205) (xy 363.923824 -222.734907) (xy 363.931767 -222.682203)
			(xy 363.947477 -222.631273) (xy 363.970603 -222.583252) (xy 364.000627 -222.539215) (xy 364.036879 -222.500144)
			(xy 364.07855 -222.466913) (xy 364.124708 -222.440264) (xy 364.174322 -222.420792) (xy 364.226284 -222.408932)
			(xy 364.279434 -222.404949) (xy 364.332584 -222.408932) (xy 364.384546 -222.420792) (xy 364.43416 -222.440264)
			(xy 364.480318 -222.466913) (xy 364.521989 -222.500144) (xy 364.558241 -222.539215) (xy 364.588265 -222.583252)
			(xy 364.611391 -222.631273) (xy 364.627101 -222.682203) (xy 364.635044 -222.734907) (xy 364.635542 -222.761556)
			(xy 364.635044 -222.788205) (xy 364.863624 -222.788205) (xy 364.863624 -222.734907) (xy 364.871567 -222.682203)
			(xy 364.887277 -222.631273) (xy 364.910403 -222.583252) (xy 364.940427 -222.539215) (xy 364.976679 -222.500144)
			(xy 365.01835 -222.466913) (xy 365.064508 -222.440264) (xy 365.114122 -222.420792) (xy 365.166084 -222.408932)
			(xy 365.219234 -222.404949) (xy 365.272384 -222.408932) (xy 365.324346 -222.420792) (xy 365.37396 -222.440264)
			(xy 365.420118 -222.466913) (xy 365.461789 -222.500144) (xy 365.498041 -222.539215) (xy 365.528065 -222.583252)
			(xy 365.551191 -222.631273) (xy 365.566901 -222.682203) (xy 365.574844 -222.734907) (xy 365.575342 -222.761556)
			(xy 365.574844 -222.788205) (xy 365.803424 -222.788205) (xy 365.803424 -222.734907) (xy 365.811367 -222.682203)
			(xy 365.827077 -222.631273) (xy 365.850203 -222.583252) (xy 365.880227 -222.539215) (xy 365.916479 -222.500144)
			(xy 365.95815 -222.466913) (xy 366.004308 -222.440264) (xy 366.053922 -222.420792) (xy 366.105884 -222.408932)
			(xy 366.159034 -222.404949) (xy 366.212184 -222.408932) (xy 366.264146 -222.420792) (xy 366.31376 -222.440264)
			(xy 366.359918 -222.466913) (xy 366.401589 -222.500144) (xy 366.437841 -222.539215) (xy 366.467865 -222.583252)
			(xy 366.490991 -222.631273) (xy 366.506701 -222.682203) (xy 366.514644 -222.734907) (xy 366.515142 -222.761556)
			(xy 366.514644 -222.788205) (xy 366.506701 -222.840909) (xy 366.490991 -222.891839) (xy 366.467865 -222.93986)
			(xy 366.437841 -222.983897) (xy 366.401589 -223.022968) (xy 366.359918 -223.056199) (xy 366.31376 -223.082848)
			(xy 366.264146 -223.10232) (xy 366.212184 -223.11418) (xy 366.159034 -223.118164) (xy 366.105884 -223.11418)
			(xy 366.053922 -223.10232) (xy 366.004308 -223.082848) (xy 365.95815 -223.056199) (xy 365.916479 -223.022968)
			(xy 365.880227 -222.983897) (xy 365.850203 -222.93986) (xy 365.827077 -222.891839) (xy 365.811367 -222.840909)
			(xy 365.803424 -222.788205) (xy 365.574844 -222.788205) (xy 365.566901 -222.840909) (xy 365.551191 -222.891839)
			(xy 365.528065 -222.93986) (xy 365.498041 -222.983897) (xy 365.461789 -223.022968) (xy 365.420118 -223.056199)
			(xy 365.37396 -223.082848) (xy 365.324346 -223.10232) (xy 365.272384 -223.11418) (xy 365.219234 -223.118164)
			(xy 365.166084 -223.11418) (xy 365.114122 -223.10232) (xy 365.064508 -223.082848) (xy 365.01835 -223.056199)
			(xy 364.976679 -223.022968) (xy 364.940427 -222.983897) (xy 364.910403 -222.93986) (xy 364.887277 -222.891839)
			(xy 364.871567 -222.840909) (xy 364.863624 -222.788205) (xy 364.635044 -222.788205) (xy 364.627101 -222.840909)
			(xy 364.611391 -222.891839) (xy 364.588265 -222.93986) (xy 364.558241 -222.983897) (xy 364.521989 -223.022968)
			(xy 364.480318 -223.056199) (xy 364.43416 -223.082848) (xy 364.384546 -223.10232) (xy 364.332584 -223.11418)
			(xy 364.279434 -223.118164) (xy 364.226284 -223.11418) (xy 364.174322 -223.10232) (xy 364.124708 -223.082848)
			(xy 364.07855 -223.056199) (xy 364.036879 -223.022968) (xy 364.000627 -222.983897) (xy 363.970603 -222.93986)
			(xy 363.947477 -222.891839) (xy 363.931767 -222.840909) (xy 363.923824 -222.788205) (xy 363.695244 -222.788205)
			(xy 363.687301 -222.840909) (xy 363.671591 -222.891839) (xy 363.648465 -222.93986) (xy 363.618441 -222.983897)
			(xy 363.582189 -223.022968) (xy 363.540518 -223.056199) (xy 363.49436 -223.082848) (xy 363.444746 -223.10232)
			(xy 363.392784 -223.11418) (xy 363.339634 -223.118164) (xy 363.286484 -223.11418) (xy 363.234522 -223.10232)
			(xy 363.184908 -223.082848) (xy 363.13875 -223.056199) (xy 363.097079 -223.022968) (xy 363.060827 -222.983897)
			(xy 363.030803 -222.93986) (xy 363.007677 -222.891839) (xy 362.991967 -222.840909) (xy 362.984024 -222.788205)
			(xy 362.755444 -222.788205) (xy 362.747501 -222.840909) (xy 362.731791 -222.891839) (xy 362.708665 -222.93986)
			(xy 362.678641 -222.983897) (xy 362.642389 -223.022968) (xy 362.600718 -223.056199) (xy 362.55456 -223.082848)
			(xy 362.504946 -223.10232) (xy 362.452984 -223.11418) (xy 362.399834 -223.118164) (xy 362.346684 -223.11418)
			(xy 362.294722 -223.10232) (xy 362.245108 -223.082848) (xy 362.19895 -223.056199) (xy 362.157279 -223.022968)
			(xy 362.121027 -222.983897) (xy 362.091003 -222.93986) (xy 362.067877 -222.891839) (xy 362.052167 -222.840909)
			(xy 362.044224 -222.788205) (xy 361.815644 -222.788205) (xy 361.807701 -222.840909) (xy 361.791991 -222.891839)
			(xy 361.768865 -222.93986) (xy 361.738841 -222.983897) (xy 361.702589 -223.022968) (xy 361.660918 -223.056199)
			(xy 361.61476 -223.082848) (xy 361.565146 -223.10232) (xy 361.513184 -223.11418) (xy 361.460034 -223.118164)
			(xy 361.406884 -223.11418) (xy 361.354922 -223.10232) (xy 361.305308 -223.082848) (xy 361.25915 -223.056199)
			(xy 361.217479 -223.022968) (xy 361.181227 -222.983897) (xy 361.151203 -222.93986) (xy 361.128077 -222.891839)
			(xy 361.112367 -222.840909) (xy 361.104424 -222.788205) (xy 360.875844 -222.788205) (xy 360.867901 -222.840909)
			(xy 360.852191 -222.891839) (xy 360.829065 -222.93986) (xy 360.799041 -222.983897) (xy 360.762789 -223.022968)
			(xy 360.721118 -223.056199) (xy 360.67496 -223.082848) (xy 360.625346 -223.10232) (xy 360.573384 -223.11418)
			(xy 360.520234 -223.118164) (xy 360.467084 -223.11418) (xy 360.415122 -223.10232) (xy 360.365508 -223.082848)
			(xy 360.31935 -223.056199) (xy 360.277679 -223.022968) (xy 360.241427 -222.983897) (xy 360.211403 -222.93986)
			(xy 360.188277 -222.891839) (xy 360.172567 -222.840909) (xy 360.164624 -222.788205) (xy 359.936044 -222.788205)
			(xy 359.928101 -222.840909) (xy 359.912391 -222.891839) (xy 359.889265 -222.93986) (xy 359.859241 -222.983897)
			(xy 359.822989 -223.022968) (xy 359.781318 -223.056199) (xy 359.73516 -223.082848) (xy 359.685546 -223.10232)
			(xy 359.633584 -223.11418) (xy 359.580434 -223.118164) (xy 359.527284 -223.11418) (xy 359.475322 -223.10232)
			(xy 359.425708 -223.082848) (xy 359.37955 -223.056199) (xy 359.337879 -223.022968) (xy 359.301627 -222.983897)
			(xy 359.271603 -222.93986) (xy 359.248477 -222.891839) (xy 359.232767 -222.840909) (xy 359.224824 -222.788205)
			(xy 358.996244 -222.788205) (xy 358.988301 -222.840909) (xy 358.972591 -222.891839) (xy 358.949465 -222.93986)
			(xy 358.919441 -222.983897) (xy 358.883189 -223.022968) (xy 358.841518 -223.056199) (xy 358.79536 -223.082848)
			(xy 358.745746 -223.10232) (xy 358.693784 -223.11418) (xy 358.640634 -223.118164) (xy 358.587484 -223.11418)
			(xy 358.535522 -223.10232) (xy 358.485908 -223.082848) (xy 358.43975 -223.056199) (xy 358.398079 -223.022968)
			(xy 358.361827 -222.983897) (xy 358.331803 -222.93986) (xy 358.308677 -222.891839) (xy 358.292967 -222.840909)
			(xy 358.285024 -222.788205) (xy 358.056444 -222.788205) (xy 358.048501 -222.840909) (xy 358.032791 -222.891839)
			(xy 358.009665 -222.93986) (xy 357.979641 -222.983897) (xy 357.943389 -223.022968) (xy 357.901718 -223.056199)
			(xy 357.85556 -223.082848) (xy 357.805946 -223.10232) (xy 357.753984 -223.11418) (xy 357.700834 -223.118164)
			(xy 357.647684 -223.11418) (xy 357.595722 -223.10232) (xy 357.546108 -223.082848) (xy 357.49995 -223.056199)
			(xy 357.458279 -223.022968) (xy 357.422027 -222.983897) (xy 357.392003 -222.93986) (xy 357.368877 -222.891839)
			(xy 357.353167 -222.840909) (xy 357.345224 -222.788205) (xy 357.116644 -222.788205) (xy 357.108701 -222.840909)
			(xy 357.092991 -222.891839) (xy 357.069865 -222.93986) (xy 357.039841 -222.983897) (xy 357.003589 -223.022968)
			(xy 356.961918 -223.056199) (xy 356.91576 -223.082848) (xy 356.866146 -223.10232) (xy 356.814184 -223.11418)
			(xy 356.761034 -223.118164) (xy 356.707884 -223.11418) (xy 356.655922 -223.10232) (xy 356.606308 -223.082848)
			(xy 356.56015 -223.056199) (xy 356.518479 -223.022968) (xy 356.482227 -222.983897) (xy 356.452203 -222.93986)
			(xy 356.429077 -222.891839) (xy 356.413367 -222.840909) (xy 356.405424 -222.788205) (xy 356.176844 -222.788205)
			(xy 356.168901 -222.840909) (xy 356.153191 -222.891839) (xy 356.130065 -222.93986) (xy 356.100041 -222.983897)
			(xy 356.063789 -223.022968) (xy 356.022118 -223.056199) (xy 355.97596 -223.082848) (xy 355.926346 -223.10232)
			(xy 355.874384 -223.11418) (xy 355.821234 -223.118164) (xy 355.768084 -223.11418) (xy 355.716122 -223.10232)
			(xy 355.666508 -223.082848) (xy 355.62035 -223.056199) (xy 355.578679 -223.022968) (xy 355.542427 -222.983897)
			(xy 355.512403 -222.93986) (xy 355.489277 -222.891839) (xy 355.473567 -222.840909) (xy 355.465624 -222.788205)
			(xy 355.237044 -222.788205) (xy 355.229101 -222.840909) (xy 355.213391 -222.891839) (xy 355.190265 -222.93986)
			(xy 355.160241 -222.983897) (xy 355.123989 -223.022968) (xy 355.082318 -223.056199) (xy 355.03616 -223.082848)
			(xy 354.986546 -223.10232) (xy 354.934584 -223.11418) (xy 354.881434 -223.118164) (xy 354.828284 -223.11418)
			(xy 354.776322 -223.10232) (xy 354.726708 -223.082848) (xy 354.68055 -223.056199) (xy 354.638879 -223.022968)
			(xy 354.602627 -222.983897) (xy 354.572603 -222.93986) (xy 354.549477 -222.891839) (xy 354.533767 -222.840909)
			(xy 354.525824 -222.788205) (xy 354.296258 -222.788205) (xy 354.294268 -222.814753) (xy 354.282408 -222.866719)
			(xy 354.262936 -222.916337) (xy 354.236287 -222.962498) (xy 354.203055 -223.004173) (xy 354.163984 -223.040429)
			(xy 354.119945 -223.070458) (xy 354.071924 -223.093588) (xy 354.020991 -223.109303) (xy 353.968285 -223.117252)
			(xy 353.941634 -223.117664) (xy 353.916475 -223.117226) (xy 353.866659 -223.110134) (xy 353.818337 -223.096102)
			(xy 353.772471 -223.075409) (xy 353.729974 -223.048466) (xy 353.691692 -223.01581) (xy 353.67468 -222.997268)
			(xy 353.665313 -222.987307) (xy 353.642447 -222.972335) (xy 353.616427 -222.963971) (xy 353.58912 -222.962816)
			(xy 353.562486 -222.968952) (xy 353.538437 -222.981939) (xy 353.5187 -223.000845) (xy 353.50469 -223.024313)
			(xy 353.497414 -223.050659) (xy 353.49688 -223.064324) (xy 353.49688 -223.217994) (xy 353.538282 -223.225868)
			(xy 353.565057 -223.23149) (xy 353.616594 -223.249851) (xy 353.664715 -223.275879) (xy 353.708289 -223.308962)
			(xy 353.746289 -223.348321) (xy 353.777821 -223.393029) (xy 353.802143 -223.442035) (xy 353.818683 -223.494184)
			(xy 353.827051 -223.54825) (xy 353.82705 -223.602275) (xy 354.055924 -223.602275) (xy 354.055924 -223.548977)
			(xy 354.063867 -223.496273) (xy 354.079577 -223.445343) (xy 354.102703 -223.397322) (xy 354.132727 -223.353285)
			(xy 354.168979 -223.314214) (xy 354.21065 -223.280983) (xy 354.256808 -223.254334) (xy 354.306422 -223.234862)
			(xy 354.358384 -223.223002) (xy 354.411534 -223.219019) (xy 354.464684 -223.223002) (xy 354.516646 -223.234862)
			(xy 354.56626 -223.254334) (xy 354.612418 -223.280983) (xy 354.654089 -223.314214) (xy 354.690341 -223.353285)
			(xy 354.720365 -223.397322) (xy 354.743491 -223.445343) (xy 354.759201 -223.496273) (xy 354.767144 -223.548977)
			(xy 354.767642 -223.575626) (xy 354.767144 -223.602275) (xy 354.759201 -223.654979) (xy 354.743491 -223.705909)
			(xy 354.720365 -223.75393) (xy 354.690341 -223.797967) (xy 354.654089 -223.837038) (xy 354.612418 -223.870269)
			(xy 354.56626 -223.896918) (xy 354.516646 -223.91639) (xy 354.464684 -223.92825) (xy 354.411534 -223.932234)
			(xy 354.358384 -223.92825) (xy 354.306422 -223.91639) (xy 354.256808 -223.896918) (xy 354.21065 -223.870269)
			(xy 354.168979 -223.837038) (xy 354.132727 -223.797967) (xy 354.102703 -223.75393) (xy 354.079577 -223.705909)
			(xy 354.063867 -223.654979) (xy 354.055924 -223.602275) (xy 353.82705 -223.602275) (xy 353.82705 -223.60296)
			(xy 353.818681 -223.657025) (xy 353.80214 -223.709174) (xy 353.777816 -223.758179) (xy 353.746283 -223.802887)
			(xy 353.708281 -223.842244) (xy 353.664707 -223.875326) (xy 353.616585 -223.901353) (xy 353.565048 -223.919712)
			(xy 353.538282 -223.925384) (xy 353.49688 -223.933258) (xy 353.49688 -224.086674) (xy 353.497321 -224.100351)
			(xy 353.504583 -224.126723) (xy 353.518593 -224.150216) (xy 353.538343 -224.169141) (xy 353.562412 -224.182137)
			(xy 353.589069 -224.188269) (xy 353.616398 -224.187097) (xy 353.642431 -224.178703) (xy 353.665299 -224.163693)
			(xy 353.67468 -224.15373) (xy 353.691659 -224.135156) (xy 353.729945 -224.102497) (xy 353.772448 -224.075555)
			(xy 353.818321 -224.054866) (xy 353.86665 -224.040841) (xy 353.916473 -224.03376) (xy 353.941634 -224.033334)
			(xy 353.969616 -224.033857) (xy 354.024891 -224.042617) (xy 354.078115 -224.059917) (xy 354.127978 -224.085329)
			(xy 354.173251 -224.118229) (xy 354.21282 -224.157807) (xy 354.24571 -224.203087) (xy 354.271112 -224.252955)
			(xy 354.2884 -224.306183) (xy 354.297149 -224.361459) (xy 354.297742 -224.389442) (xy 354.525326 -224.389442)
			(xy 354.525808 -224.363815) (xy 354.533137 -224.313088) (xy 354.547665 -224.263936) (xy 354.569091 -224.217375)
			(xy 354.596972 -224.174368) (xy 354.630732 -224.135803) (xy 354.669673 -224.102478) (xy 354.71299 -224.075082)
			(xy 354.759788 -224.05418) (xy 354.8091 -224.040204) (xy 354.834444 -224.036382) (xy 354.859082 -224.03308)
			(xy 355.031294 -223.734376) (xy 355.021896 -223.711516) (xy 355.013386 -223.689882) (xy 355.001397 -223.644965)
			(xy 354.995349 -223.598871) (xy 354.994972 -223.575626) (xy 354.99547 -223.548977) (xy 355.003413 -223.496273)
			(xy 355.019123 -223.445343) (xy 355.042249 -223.397322) (xy 355.072273 -223.353285) (xy 355.108525 -223.314214)
			(xy 355.150196 -223.280983) (xy 355.196354 -223.254334) (xy 355.245968 -223.234862) (xy 355.29793 -223.223002)
			(xy 355.35108 -223.219019) (xy 355.40423 -223.223002) (xy 355.456192 -223.234862) (xy 355.505806 -223.254334)
			(xy 355.551964 -223.280983) (xy 355.593635 -223.314214) (xy 355.629887 -223.353285) (xy 355.659911 -223.397322)
			(xy 355.683037 -223.445343) (xy 355.698747 -223.496273) (xy 355.70669 -223.548977) (xy 355.707188 -223.575626)
			(xy 355.706757 -223.601254) (xy 355.706609 -223.602275) (xy 355.935524 -223.602275) (xy 355.935524 -223.548977)
			(xy 355.943467 -223.496273) (xy 355.959177 -223.445343) (xy 355.982303 -223.397322) (xy 356.012327 -223.353285)
			(xy 356.048579 -223.314214) (xy 356.09025 -223.280983) (xy 356.136408 -223.254334) (xy 356.186022 -223.234862)
			(xy 356.237984 -223.223002) (xy 356.291134 -223.219019) (xy 356.344284 -223.223002) (xy 356.396246 -223.234862)
			(xy 356.44586 -223.254334) (xy 356.492018 -223.280983) (xy 356.533689 -223.314214) (xy 356.569941 -223.353285)
			(xy 356.599965 -223.397322) (xy 356.623091 -223.445343) (xy 356.638801 -223.496273) (xy 356.646744 -223.548977)
			(xy 356.647242 -223.575626) (xy 356.646744 -223.602275) (xy 356.638801 -223.654979) (xy 356.623091 -223.705909)
			(xy 356.599965 -223.75393) (xy 356.569941 -223.797967) (xy 356.533689 -223.837038) (xy 356.492018 -223.870269)
			(xy 356.44586 -223.896918) (xy 356.396246 -223.91639) (xy 356.344284 -223.92825) (xy 356.291134 -223.932234)
			(xy 356.237984 -223.92825) (xy 356.186022 -223.91639) (xy 356.136408 -223.896918) (xy 356.09025 -223.870269)
			(xy 356.048579 -223.837038) (xy 356.012327 -223.797967) (xy 355.982303 -223.75393) (xy 355.959177 -223.705909)
			(xy 355.943467 -223.654979) (xy 355.935524 -223.602275) (xy 355.706609 -223.602275) (xy 355.699419 -223.651983)
			(xy 355.684883 -223.701135) (xy 355.66345 -223.747696) (xy 355.635563 -223.790702) (xy 355.601798 -223.829266)
			(xy 355.562852 -223.86259) (xy 355.519531 -223.889986) (xy 355.47273 -223.910888) (xy 355.423416 -223.924864)
			(xy 355.39807 -223.928686) (xy 355.373178 -223.931988) (xy 355.200966 -224.230438) (xy 355.210618 -224.253552)
			(xy 355.219149 -224.275178) (xy 355.23113 -224.320099) (xy 355.237169 -224.366196) (xy 355.237542 -224.389442)
			(xy 355.465126 -224.389442) (xy 355.465624 -224.362793) (xy 355.473567 -224.310089) (xy 355.489277 -224.259159)
			(xy 355.512403 -224.211138) (xy 355.542427 -224.167101) (xy 355.578679 -224.12803) (xy 355.62035 -224.094799)
			(xy 355.666508 -224.06815) (xy 355.716122 -224.048678) (xy 355.768084 -224.036818) (xy 355.821234 -224.032835)
			(xy 355.874384 -224.036818) (xy 355.926346 -224.048678) (xy 355.97596 -224.06815) (xy 356.022118 -224.094799)
			(xy 356.063789 -224.12803) (xy 356.100041 -224.167101) (xy 356.130065 -224.211138) (xy 356.153191 -224.259159)
			(xy 356.168901 -224.310089) (xy 356.176844 -224.362793) (xy 356.177342 -224.389442) (xy 356.404926 -224.389442)
			(xy 356.405408 -224.363815) (xy 356.412737 -224.313088) (xy 356.427265 -224.263936) (xy 356.448691 -224.217375)
			(xy 356.476572 -224.174368) (xy 356.510332 -224.135803) (xy 356.549273 -224.102478) (xy 356.59259 -224.075082)
			(xy 356.639388 -224.05418) (xy 356.6887 -224.040204) (xy 356.714044 -224.036382) (xy 356.738682 -224.03308)
			(xy 356.910894 -223.734376) (xy 356.901496 -223.711516) (xy 356.892986 -223.689882) (xy 356.880997 -223.644965)
			(xy 356.874949 -223.598871) (xy 356.874572 -223.575626) (xy 356.87507 -223.548977) (xy 356.883013 -223.496273)
			(xy 356.898723 -223.445343) (xy 356.921849 -223.397322) (xy 356.951873 -223.353285) (xy 356.988125 -223.314214)
			(xy 357.029796 -223.280983) (xy 357.075954 -223.254334) (xy 357.125568 -223.234862) (xy 357.17753 -223.223002)
			(xy 357.23068 -223.219019) (xy 357.28383 -223.223002) (xy 357.335792 -223.234862) (xy 357.385406 -223.254334)
			(xy 357.431564 -223.280983) (xy 357.473235 -223.314214) (xy 357.509487 -223.353285) (xy 357.539511 -223.397322)
			(xy 357.562637 -223.445343) (xy 357.578347 -223.496273) (xy 357.58629 -223.548977) (xy 357.586788 -223.575626)
			(xy 357.586357 -223.601254) (xy 357.586209 -223.602275) (xy 357.815124 -223.602275) (xy 357.815124 -223.548977)
			(xy 357.823067 -223.496273) (xy 357.838777 -223.445343) (xy 357.861903 -223.397322) (xy 357.891927 -223.353285)
			(xy 357.928179 -223.314214) (xy 357.96985 -223.280983) (xy 358.016008 -223.254334) (xy 358.065622 -223.234862)
			(xy 358.117584 -223.223002) (xy 358.170734 -223.219019) (xy 358.223884 -223.223002) (xy 358.275846 -223.234862)
			(xy 358.32546 -223.254334) (xy 358.371618 -223.280983) (xy 358.413289 -223.314214) (xy 358.449541 -223.353285)
			(xy 358.479565 -223.397322) (xy 358.502691 -223.445343) (xy 358.518401 -223.496273) (xy 358.526344 -223.548977)
			(xy 358.526842 -223.575626) (xy 358.526344 -223.602275) (xy 358.518401 -223.654979) (xy 358.502691 -223.705909)
			(xy 358.479565 -223.75393) (xy 358.449541 -223.797967) (xy 358.413289 -223.837038) (xy 358.371618 -223.870269)
			(xy 358.32546 -223.896918) (xy 358.275846 -223.91639) (xy 358.223884 -223.92825) (xy 358.170734 -223.932234)
			(xy 358.117584 -223.92825) (xy 358.065622 -223.91639) (xy 358.016008 -223.896918) (xy 357.96985 -223.870269)
			(xy 357.928179 -223.837038) (xy 357.891927 -223.797967) (xy 357.861903 -223.75393) (xy 357.838777 -223.705909)
			(xy 357.823067 -223.654979) (xy 357.815124 -223.602275) (xy 357.586209 -223.602275) (xy 357.579019 -223.651983)
			(xy 357.564483 -223.701135) (xy 357.54305 -223.747696) (xy 357.515163 -223.790702) (xy 357.481398 -223.829266)
			(xy 357.442452 -223.86259) (xy 357.399131 -223.889986) (xy 357.35233 -223.910888) (xy 357.303016 -223.924864)
			(xy 357.27767 -223.928686) (xy 357.252778 -223.931988) (xy 357.080566 -224.230438) (xy 357.090218 -224.253552)
			(xy 357.098749 -224.275178) (xy 357.11073 -224.320099) (xy 357.116769 -224.366196) (xy 357.117142 -224.389442)
			(xy 357.344726 -224.389442) (xy 357.345224 -224.362793) (xy 357.353167 -224.310089) (xy 357.368877 -224.259159)
			(xy 357.392003 -224.211138) (xy 357.422027 -224.167101) (xy 357.458279 -224.12803) (xy 357.49995 -224.094799)
			(xy 357.546108 -224.06815) (xy 357.595722 -224.048678) (xy 357.647684 -224.036818) (xy 357.700834 -224.032835)
			(xy 357.753984 -224.036818) (xy 357.805946 -224.048678) (xy 357.85556 -224.06815) (xy 357.901718 -224.094799)
			(xy 357.943389 -224.12803) (xy 357.979641 -224.167101) (xy 358.009665 -224.211138) (xy 358.032791 -224.259159)
			(xy 358.048501 -224.310089) (xy 358.056444 -224.362793) (xy 358.056942 -224.389442) (xy 358.284526 -224.389442)
			(xy 358.285008 -224.363815) (xy 358.292337 -224.313088) (xy 358.306865 -224.263936) (xy 358.328291 -224.217375)
			(xy 358.356172 -224.174368) (xy 358.389932 -224.135803) (xy 358.428873 -224.102478) (xy 358.47219 -224.075082)
			(xy 358.518988 -224.05418) (xy 358.5683 -224.040204) (xy 358.593644 -224.036382) (xy 358.618282 -224.03308)
			(xy 358.790494 -223.734376) (xy 358.781096 -223.711516) (xy 358.772586 -223.689882) (xy 358.760597 -223.644965)
			(xy 358.754549 -223.598871) (xy 358.754172 -223.575626) (xy 358.75467 -223.548977) (xy 358.762613 -223.496273)
			(xy 358.778323 -223.445343) (xy 358.801449 -223.397322) (xy 358.831473 -223.353285) (xy 358.867725 -223.314214)
			(xy 358.909396 -223.280983) (xy 358.955554 -223.254334) (xy 359.005168 -223.234862) (xy 359.05713 -223.223002)
			(xy 359.11028 -223.219019) (xy 359.16343 -223.223002) (xy 359.215392 -223.234862) (xy 359.265006 -223.254334)
			(xy 359.311164 -223.280983) (xy 359.352835 -223.314214) (xy 359.389087 -223.353285) (xy 359.419111 -223.397322)
			(xy 359.442237 -223.445343) (xy 359.457947 -223.496273) (xy 359.46589 -223.548977) (xy 359.466388 -223.575626)
			(xy 359.465957 -223.601254) (xy 359.465809 -223.602275) (xy 359.694724 -223.602275) (xy 359.694724 -223.548977)
			(xy 359.702667 -223.496273) (xy 359.718377 -223.445343) (xy 359.741503 -223.397322) (xy 359.771527 -223.353285)
			(xy 359.807779 -223.314214) (xy 359.84945 -223.280983) (xy 359.895608 -223.254334) (xy 359.945222 -223.234862)
			(xy 359.997184 -223.223002) (xy 360.050334 -223.219019) (xy 360.103484 -223.223002) (xy 360.155446 -223.234862)
			(xy 360.20506 -223.254334) (xy 360.251218 -223.280983) (xy 360.292889 -223.314214) (xy 360.329141 -223.353285)
			(xy 360.359165 -223.397322) (xy 360.382291 -223.445343) (xy 360.398001 -223.496273) (xy 360.405944 -223.548977)
			(xy 360.406442 -223.575626) (xy 360.405944 -223.602275) (xy 360.398001 -223.654979) (xy 360.382291 -223.705909)
			(xy 360.359165 -223.75393) (xy 360.329141 -223.797967) (xy 360.292889 -223.837038) (xy 360.251218 -223.870269)
			(xy 360.20506 -223.896918) (xy 360.155446 -223.91639) (xy 360.103484 -223.92825) (xy 360.050334 -223.932234)
			(xy 359.997184 -223.92825) (xy 359.945222 -223.91639) (xy 359.895608 -223.896918) (xy 359.84945 -223.870269)
			(xy 359.807779 -223.837038) (xy 359.771527 -223.797967) (xy 359.741503 -223.75393) (xy 359.718377 -223.705909)
			(xy 359.702667 -223.654979) (xy 359.694724 -223.602275) (xy 359.465809 -223.602275) (xy 359.458619 -223.651983)
			(xy 359.444083 -223.701135) (xy 359.42265 -223.747696) (xy 359.394763 -223.790702) (xy 359.360998 -223.829266)
			(xy 359.322052 -223.86259) (xy 359.278731 -223.889986) (xy 359.23193 -223.910888) (xy 359.182616 -223.924864)
			(xy 359.15727 -223.928686) (xy 359.132378 -223.931988) (xy 358.960166 -224.230438) (xy 358.969818 -224.253552)
			(xy 358.978349 -224.275178) (xy 358.99033 -224.320099) (xy 358.996369 -224.366196) (xy 358.996742 -224.389442)
			(xy 359.224326 -224.389442) (xy 359.224824 -224.362793) (xy 359.232767 -224.310089) (xy 359.248477 -224.259159)
			(xy 359.271603 -224.211138) (xy 359.301627 -224.167101) (xy 359.337879 -224.12803) (xy 359.37955 -224.094799)
			(xy 359.425708 -224.06815) (xy 359.475322 -224.048678) (xy 359.527284 -224.036818) (xy 359.580434 -224.032835)
			(xy 359.633584 -224.036818) (xy 359.685546 -224.048678) (xy 359.73516 -224.06815) (xy 359.781318 -224.094799)
			(xy 359.822989 -224.12803) (xy 359.859241 -224.167101) (xy 359.889265 -224.211138) (xy 359.912391 -224.259159)
			(xy 359.928101 -224.310089) (xy 359.936044 -224.362793) (xy 359.936542 -224.389442) (xy 360.164126 -224.389442)
			(xy 360.164608 -224.363815) (xy 360.171937 -224.313088) (xy 360.186465 -224.263936) (xy 360.207891 -224.217375)
			(xy 360.235772 -224.174368) (xy 360.269532 -224.135803) (xy 360.308473 -224.102478) (xy 360.35179 -224.075082)
			(xy 360.398588 -224.05418) (xy 360.4479 -224.040204) (xy 360.473244 -224.036382) (xy 360.497882 -224.03308)
			(xy 360.670094 -223.734376) (xy 360.660696 -223.711516) (xy 360.652186 -223.689882) (xy 360.640197 -223.644965)
			(xy 360.634149 -223.598871) (xy 360.633772 -223.575626) (xy 360.63427 -223.548977) (xy 360.642213 -223.496273)
			(xy 360.657923 -223.445343) (xy 360.681049 -223.397322) (xy 360.711073 -223.353285) (xy 360.747325 -223.314214)
			(xy 360.788996 -223.280983) (xy 360.835154 -223.254334) (xy 360.884768 -223.234862) (xy 360.93673 -223.223002)
			(xy 360.98988 -223.219019) (xy 361.04303 -223.223002) (xy 361.094992 -223.234862) (xy 361.144606 -223.254334)
			(xy 361.190764 -223.280983) (xy 361.232435 -223.314214) (xy 361.268687 -223.353285) (xy 361.298711 -223.397322)
			(xy 361.321837 -223.445343) (xy 361.337547 -223.496273) (xy 361.34549 -223.548977) (xy 361.345988 -223.575626)
			(xy 361.345557 -223.601254) (xy 361.345409 -223.602275) (xy 361.574324 -223.602275) (xy 361.574324 -223.548977)
			(xy 361.582267 -223.496273) (xy 361.597977 -223.445343) (xy 361.621103 -223.397322) (xy 361.651127 -223.353285)
			(xy 361.687379 -223.314214) (xy 361.72905 -223.280983) (xy 361.775208 -223.254334) (xy 361.824822 -223.234862)
			(xy 361.876784 -223.223002) (xy 361.929934 -223.219019) (xy 361.983084 -223.223002) (xy 362.035046 -223.234862)
			(xy 362.08466 -223.254334) (xy 362.130818 -223.280983) (xy 362.172489 -223.314214) (xy 362.208741 -223.353285)
			(xy 362.238765 -223.397322) (xy 362.261891 -223.445343) (xy 362.277601 -223.496273) (xy 362.285544 -223.548977)
			(xy 362.286042 -223.575626) (xy 362.285544 -223.602275) (xy 362.277601 -223.654979) (xy 362.261891 -223.705909)
			(xy 362.238765 -223.75393) (xy 362.208741 -223.797967) (xy 362.172489 -223.837038) (xy 362.130818 -223.870269)
			(xy 362.08466 -223.896918) (xy 362.035046 -223.91639) (xy 361.983084 -223.92825) (xy 361.929934 -223.932234)
			(xy 361.876784 -223.92825) (xy 361.824822 -223.91639) (xy 361.775208 -223.896918) (xy 361.72905 -223.870269)
			(xy 361.687379 -223.837038) (xy 361.651127 -223.797967) (xy 361.621103 -223.75393) (xy 361.597977 -223.705909)
			(xy 361.582267 -223.654979) (xy 361.574324 -223.602275) (xy 361.345409 -223.602275) (xy 361.338219 -223.651983)
			(xy 361.323683 -223.701135) (xy 361.30225 -223.747696) (xy 361.274363 -223.790702) (xy 361.240598 -223.829266)
			(xy 361.201652 -223.86259) (xy 361.158331 -223.889986) (xy 361.11153 -223.910888) (xy 361.062216 -223.924864)
			(xy 361.03687 -223.928686) (xy 361.011978 -223.931988) (xy 360.839766 -224.230438) (xy 360.849418 -224.253552)
			(xy 360.857949 -224.275178) (xy 360.86993 -224.320099) (xy 360.875969 -224.366196) (xy 360.876342 -224.389442)
			(xy 361.103926 -224.389442) (xy 361.104424 -224.362793) (xy 361.112367 -224.310089) (xy 361.128077 -224.259159)
			(xy 361.151203 -224.211138) (xy 361.181227 -224.167101) (xy 361.217479 -224.12803) (xy 361.25915 -224.094799)
			(xy 361.305308 -224.06815) (xy 361.354922 -224.048678) (xy 361.406884 -224.036818) (xy 361.460034 -224.032835)
			(xy 361.513184 -224.036818) (xy 361.565146 -224.048678) (xy 361.61476 -224.06815) (xy 361.660918 -224.094799)
			(xy 361.702589 -224.12803) (xy 361.738841 -224.167101) (xy 361.768865 -224.211138) (xy 361.791991 -224.259159)
			(xy 361.807701 -224.310089) (xy 361.815644 -224.362793) (xy 361.816142 -224.389442) (xy 362.043726 -224.389442)
			(xy 362.044208 -224.363815) (xy 362.051537 -224.313088) (xy 362.066065 -224.263936) (xy 362.087491 -224.217375)
			(xy 362.115372 -224.174368) (xy 362.149132 -224.135803) (xy 362.188073 -224.102478) (xy 362.23139 -224.075082)
			(xy 362.278188 -224.05418) (xy 362.3275 -224.040204) (xy 362.352844 -224.036382) (xy 362.377482 -224.03308)
			(xy 362.549948 -223.734376) (xy 362.54055 -223.711262) (xy 362.532055 -223.689667) (xy 362.52008 -223.644835)
			(xy 362.514019 -223.598828) (xy 362.513626 -223.575626) (xy 362.514124 -223.548977) (xy 362.522067 -223.496273)
			(xy 362.537777 -223.445343) (xy 362.560903 -223.397322) (xy 362.590927 -223.353285) (xy 362.627179 -223.314214)
			(xy 362.66885 -223.280983) (xy 362.715008 -223.254334) (xy 362.764622 -223.234862) (xy 362.816584 -223.223002)
			(xy 362.869734 -223.219019) (xy 362.922884 -223.223002) (xy 362.974846 -223.234862) (xy 363.02446 -223.254334)
			(xy 363.070618 -223.280983) (xy 363.112289 -223.314214) (xy 363.148541 -223.353285) (xy 363.178565 -223.397322)
			(xy 363.201691 -223.445343) (xy 363.217401 -223.496273) (xy 363.225344 -223.548977) (xy 363.225842 -223.575626)
			(xy 363.225416 -223.601266) (xy 363.22527 -223.602275) (xy 363.453924 -223.602275) (xy 363.453924 -223.548977)
			(xy 363.461867 -223.496273) (xy 363.477577 -223.445343) (xy 363.500703 -223.397322) (xy 363.530727 -223.353285)
			(xy 363.566979 -223.314214) (xy 363.60865 -223.280983) (xy 363.654808 -223.254334) (xy 363.704422 -223.234862)
			(xy 363.756384 -223.223002) (xy 363.809534 -223.219019) (xy 363.862684 -223.223002) (xy 363.914646 -223.234862)
			(xy 363.96426 -223.254334) (xy 364.010418 -223.280983) (xy 364.052089 -223.314214) (xy 364.088341 -223.353285)
			(xy 364.118365 -223.397322) (xy 364.141491 -223.445343) (xy 364.157201 -223.496273) (xy 364.165144 -223.548977)
			(xy 364.165642 -223.575626) (xy 364.165144 -223.602275) (xy 364.157201 -223.654979) (xy 364.141491 -223.705909)
			(xy 364.118365 -223.75393) (xy 364.088341 -223.797967) (xy 364.052089 -223.837038) (xy 364.010418 -223.870269)
			(xy 363.96426 -223.896918) (xy 363.914646 -223.91639) (xy 363.862684 -223.92825) (xy 363.809534 -223.932234)
			(xy 363.756384 -223.92825) (xy 363.704422 -223.91639) (xy 363.654808 -223.896918) (xy 363.60865 -223.870269)
			(xy 363.566979 -223.837038) (xy 363.530727 -223.797967) (xy 363.500703 -223.75393) (xy 363.477577 -223.705909)
			(xy 363.461867 -223.654979) (xy 363.453924 -223.602275) (xy 363.22527 -223.602275) (xy 363.21807 -223.652018)
			(xy 363.203519 -223.701191) (xy 363.182064 -223.747768) (xy 363.15415 -223.790785) (xy 363.120353 -223.829353)
			(xy 363.081373 -223.862673) (xy 363.038016 -223.890056) (xy 362.991179 -223.910937) (xy 362.94183 -223.924882)
			(xy 362.91647 -223.928686) (xy 362.891578 -223.931988) (xy 362.719366 -224.230438) (xy 362.729018 -224.253552)
			(xy 362.737549 -224.275178) (xy 362.74953 -224.320099) (xy 362.755569 -224.366196) (xy 362.755942 -224.389442)
			(xy 362.983526 -224.389442) (xy 362.984024 -224.362793) (xy 362.991967 -224.310089) (xy 363.007677 -224.259159)
			(xy 363.030803 -224.211138) (xy 363.060827 -224.167101) (xy 363.097079 -224.12803) (xy 363.13875 -224.094799)
			(xy 363.184908 -224.06815) (xy 363.234522 -224.048678) (xy 363.286484 -224.036818) (xy 363.339634 -224.032835)
			(xy 363.392784 -224.036818) (xy 363.444746 -224.048678) (xy 363.49436 -224.06815) (xy 363.540518 -224.094799)
			(xy 363.582189 -224.12803) (xy 363.618441 -224.167101) (xy 363.648465 -224.211138) (xy 363.671591 -224.259159)
			(xy 363.687301 -224.310089) (xy 363.695244 -224.362793) (xy 363.695742 -224.389442) (xy 363.923326 -224.389442)
			(xy 363.923808 -224.363815) (xy 363.931137 -224.313088) (xy 363.945665 -224.263936) (xy 363.967091 -224.217375)
			(xy 363.994972 -224.174368) (xy 364.028732 -224.135803) (xy 364.067673 -224.102478) (xy 364.11099 -224.075082)
			(xy 364.157788 -224.05418) (xy 364.2071 -224.040204) (xy 364.232444 -224.036382) (xy 364.257082 -224.03308)
			(xy 364.429294 -223.734376) (xy 364.419896 -223.711516) (xy 364.411386 -223.689882) (xy 364.399397 -223.644965)
			(xy 364.393349 -223.598871) (xy 364.392972 -223.575626) (xy 364.39347 -223.548977) (xy 364.401413 -223.496273)
			(xy 364.417123 -223.445343) (xy 364.440249 -223.397322) (xy 364.470273 -223.353285) (xy 364.506525 -223.314214)
			(xy 364.548196 -223.280983) (xy 364.594354 -223.254334) (xy 364.643968 -223.234862) (xy 364.69593 -223.223002)
			(xy 364.74908 -223.219019) (xy 364.80223 -223.223002) (xy 364.854192 -223.234862) (xy 364.903806 -223.254334)
			(xy 364.949964 -223.280983) (xy 364.991635 -223.314214) (xy 365.027887 -223.353285) (xy 365.057911 -223.397322)
			(xy 365.081037 -223.445343) (xy 365.096747 -223.496273) (xy 365.10469 -223.548977) (xy 365.105188 -223.575626)
			(xy 365.104757 -223.601254) (xy 365.104609 -223.602275) (xy 365.333524 -223.602275) (xy 365.333524 -223.548977)
			(xy 365.341467 -223.496273) (xy 365.357177 -223.445343) (xy 365.380303 -223.397322) (xy 365.410327 -223.353285)
			(xy 365.446579 -223.314214) (xy 365.48825 -223.280983) (xy 365.534408 -223.254334) (xy 365.584022 -223.234862)
			(xy 365.635984 -223.223002) (xy 365.689134 -223.219019) (xy 365.742284 -223.223002) (xy 365.794246 -223.234862)
			(xy 365.84386 -223.254334) (xy 365.890018 -223.280983) (xy 365.931689 -223.314214) (xy 365.967941 -223.353285)
			(xy 365.997965 -223.397322) (xy 366.021091 -223.445343) (xy 366.036801 -223.496273) (xy 366.044744 -223.548977)
			(xy 366.045242 -223.575626) (xy 366.044744 -223.602275) (xy 366.036801 -223.654979) (xy 366.021091 -223.705909)
			(xy 365.997965 -223.75393) (xy 365.967941 -223.797967) (xy 365.931689 -223.837038) (xy 365.890018 -223.870269)
			(xy 365.84386 -223.896918) (xy 365.794246 -223.91639) (xy 365.742284 -223.92825) (xy 365.689134 -223.932234)
			(xy 365.635984 -223.92825) (xy 365.584022 -223.91639) (xy 365.534408 -223.896918) (xy 365.48825 -223.870269)
			(xy 365.446579 -223.837038) (xy 365.410327 -223.797967) (xy 365.380303 -223.75393) (xy 365.357177 -223.705909)
			(xy 365.341467 -223.654979) (xy 365.333524 -223.602275) (xy 365.104609 -223.602275) (xy 365.097419 -223.651983)
			(xy 365.082883 -223.701135) (xy 365.06145 -223.747696) (xy 365.033563 -223.790702) (xy 364.999798 -223.829266)
			(xy 364.960852 -223.86259) (xy 364.917531 -223.889986) (xy 364.87073 -223.910888) (xy 364.821416 -223.924864)
			(xy 364.79607 -223.928686) (xy 364.771178 -223.931988) (xy 364.598966 -224.230438) (xy 364.608618 -224.253552)
			(xy 364.617149 -224.275178) (xy 364.62913 -224.320099) (xy 364.635169 -224.366196) (xy 364.635542 -224.389442)
			(xy 364.863126 -224.389442) (xy 364.863624 -224.362793) (xy 364.871567 -224.310089) (xy 364.887277 -224.259159)
			(xy 364.910403 -224.211138) (xy 364.940427 -224.167101) (xy 364.976679 -224.12803) (xy 365.01835 -224.094799)
			(xy 365.064508 -224.06815) (xy 365.114122 -224.048678) (xy 365.166084 -224.036818) (xy 365.219234 -224.032835)
			(xy 365.272384 -224.036818) (xy 365.324346 -224.048678) (xy 365.37396 -224.06815) (xy 365.420118 -224.094799)
			(xy 365.461789 -224.12803) (xy 365.498041 -224.167101) (xy 365.528065 -224.211138) (xy 365.551191 -224.259159)
			(xy 365.566901 -224.310089) (xy 365.574844 -224.362793) (xy 365.575342 -224.389442) (xy 365.574952 -224.412686)
			(xy 365.568913 -224.458781) (xy 365.556932 -224.5037) (xy 365.548418 -224.525332) (xy 365.538766 -224.548446)
			(xy 365.711232 -224.846896) (xy 365.73587 -224.850198) (xy 365.761219 -224.853984) (xy 365.810525 -224.86798)
			(xy 365.857317 -224.888897) (xy 365.900629 -224.916303) (xy 365.939566 -224.949633) (xy 365.973326 -224.988198)
			(xy 366.001211 -225.031202) (xy 366.022647 -225.077759) (xy 366.03719 -225.126907) (xy 366.04454 -225.177631)
			(xy 366.044988 -225.203258) (xy 366.04449 -225.229907) (xy 366.036547 -225.282611) (xy 366.020837 -225.333541)
			(xy 365.997711 -225.381562) (xy 365.967687 -225.425599) (xy 365.931435 -225.46467) (xy 365.889764 -225.497901)
			(xy 365.843606 -225.52455) (xy 365.793992 -225.544022) (xy 365.74203 -225.555882) (xy 365.68888 -225.559866)
			(xy 365.63573 -225.555882) (xy 365.583768 -225.544022) (xy 365.534154 -225.52455) (xy 365.487996 -225.497901)
			(xy 365.446325 -225.46467) (xy 365.410073 -225.425599) (xy 365.380049 -225.381562) (xy 365.356923 -225.333541)
			(xy 365.341213 -225.282611) (xy 365.33327 -225.229907) (xy 365.332772 -225.203258) (xy 365.333161 -225.180014)
			(xy 365.3392 -225.133918) (xy 365.351182 -225.089) (xy 365.359696 -225.067368) (xy 365.369348 -225.044254)
			(xy 365.196882 -224.745804) (xy 365.172244 -224.742502) (xy 365.146897 -224.738705) (xy 365.097591 -224.724711)
			(xy 365.050799 -224.703796) (xy 365.007487 -224.676391) (xy 364.968549 -224.643063) (xy 364.934789 -224.604499)
			(xy 364.906903 -224.561495) (xy 364.885468 -224.514939) (xy 364.870925 -224.465792) (xy 364.863574 -224.415069)
			(xy 364.863126 -224.389442) (xy 364.635542 -224.389442) (xy 364.635044 -224.416091) (xy 364.627101 -224.468795)
			(xy 364.611391 -224.519725) (xy 364.588265 -224.567746) (xy 364.558241 -224.611783) (xy 364.521989 -224.650854)
			(xy 364.480318 -224.684085) (xy 364.43416 -224.710734) (xy 364.384546 -224.730206) (xy 364.332584 -224.742066)
			(xy 364.279434 -224.74605) (xy 364.226284 -224.742066) (xy 364.174322 -224.730206) (xy 364.124708 -224.710734)
			(xy 364.07855 -224.684085) (xy 364.036879 -224.650854) (xy 364.000627 -224.611783) (xy 363.970603 -224.567746)
			(xy 363.947477 -224.519725) (xy 363.931767 -224.468795) (xy 363.923824 -224.416091) (xy 363.923326 -224.389442)
			(xy 363.695742 -224.389442) (xy 363.695352 -224.412686) (xy 363.689313 -224.458781) (xy 363.677332 -224.5037)
			(xy 363.668818 -224.525332) (xy 363.659166 -224.548446) (xy 363.831632 -224.846896) (xy 363.85627 -224.850198)
			(xy 363.881619 -224.853984) (xy 363.930925 -224.86798) (xy 363.977717 -224.888897) (xy 364.021029 -224.916303)
			(xy 364.059966 -224.949633) (xy 364.093726 -224.988198) (xy 364.121611 -225.031202) (xy 364.143047 -225.077759)
			(xy 364.15759 -225.126907) (xy 364.16494 -225.177631) (xy 364.165388 -225.203258) (xy 364.16489 -225.229907)
			(xy 364.156947 -225.282611) (xy 364.141237 -225.333541) (xy 364.118111 -225.381562) (xy 364.088087 -225.425599)
			(xy 364.051835 -225.46467) (xy 364.010164 -225.497901) (xy 363.964006 -225.52455) (xy 363.914392 -225.544022)
			(xy 363.86243 -225.555882) (xy 363.80928 -225.559866) (xy 363.75613 -225.555882) (xy 363.704168 -225.544022)
			(xy 363.654554 -225.52455) (xy 363.608396 -225.497901) (xy 363.566725 -225.46467) (xy 363.530473 -225.425599)
			(xy 363.500449 -225.381562) (xy 363.477323 -225.333541) (xy 363.461613 -225.282611) (xy 363.45367 -225.229907)
			(xy 363.453172 -225.203258) (xy 363.453561 -225.180014) (xy 363.4596 -225.133918) (xy 363.471582 -225.089)
			(xy 363.480096 -225.067368) (xy 363.489748 -225.044254) (xy 363.317282 -224.745804) (xy 363.292644 -224.742502)
			(xy 363.267297 -224.738705) (xy 363.217991 -224.724711) (xy 363.171199 -224.703796) (xy 363.127887 -224.676391)
			(xy 363.088949 -224.643063) (xy 363.055189 -224.604499) (xy 363.027303 -224.561495) (xy 363.005868 -224.514939)
			(xy 362.991325 -224.465792) (xy 362.983974 -224.415069) (xy 362.983526 -224.389442) (xy 362.755942 -224.389442)
			(xy 362.755444 -224.416091) (xy 362.747501 -224.468795) (xy 362.731791 -224.519725) (xy 362.708665 -224.567746)
			(xy 362.678641 -224.611783) (xy 362.642389 -224.650854) (xy 362.600718 -224.684085) (xy 362.55456 -224.710734)
			(xy 362.504946 -224.730206) (xy 362.452984 -224.742066) (xy 362.399834 -224.74605) (xy 362.346684 -224.742066)
			(xy 362.294722 -224.730206) (xy 362.245108 -224.710734) (xy 362.19895 -224.684085) (xy 362.157279 -224.650854)
			(xy 362.121027 -224.611783) (xy 362.091003 -224.567746) (xy 362.067877 -224.519725) (xy 362.052167 -224.468795)
			(xy 362.044224 -224.416091) (xy 362.043726 -224.389442) (xy 361.816142 -224.389442) (xy 361.815752 -224.412686)
			(xy 361.809713 -224.458781) (xy 361.797732 -224.5037) (xy 361.789218 -224.525332) (xy 361.779566 -224.548446)
			(xy 361.952032 -224.846896) (xy 361.97667 -224.850198) (xy 362.002019 -224.853984) (xy 362.051325 -224.86798)
			(xy 362.098117 -224.888897) (xy 362.141429 -224.916303) (xy 362.180366 -224.949633) (xy 362.214126 -224.988198)
			(xy 362.242011 -225.031202) (xy 362.263447 -225.077759) (xy 362.27799 -225.126907) (xy 362.28534 -225.177631)
			(xy 362.285788 -225.203258) (xy 362.28529 -225.229907) (xy 362.277347 -225.282611) (xy 362.261637 -225.333541)
			(xy 362.238511 -225.381562) (xy 362.208487 -225.425599) (xy 362.172235 -225.46467) (xy 362.130564 -225.497901)
			(xy 362.084406 -225.52455) (xy 362.034792 -225.544022) (xy 361.98283 -225.555882) (xy 361.92968 -225.559866)
			(xy 361.87653 -225.555882) (xy 361.824568 -225.544022) (xy 361.774954 -225.52455) (xy 361.728796 -225.497901)
			(xy 361.687125 -225.46467) (xy 361.650873 -225.425599) (xy 361.620849 -225.381562) (xy 361.597723 -225.333541)
			(xy 361.582013 -225.282611) (xy 361.57407 -225.229907) (xy 361.573572 -225.203258) (xy 361.573961 -225.180014)
			(xy 361.58 -225.133918) (xy 361.591982 -225.089) (xy 361.600496 -225.067368) (xy 361.610148 -225.044254)
			(xy 361.437682 -224.745804) (xy 361.413044 -224.742502) (xy 361.387697 -224.738705) (xy 361.338391 -224.724711)
			(xy 361.291599 -224.703796) (xy 361.248287 -224.676391) (xy 361.209349 -224.643063) (xy 361.175589 -224.604499)
			(xy 361.147703 -224.561495) (xy 361.126268 -224.514939) (xy 361.111725 -224.465792) (xy 361.104374 -224.415069)
			(xy 361.103926 -224.389442) (xy 360.876342 -224.389442) (xy 360.875844 -224.416091) (xy 360.867901 -224.468795)
			(xy 360.852191 -224.519725) (xy 360.829065 -224.567746) (xy 360.799041 -224.611783) (xy 360.762789 -224.650854)
			(xy 360.721118 -224.684085) (xy 360.67496 -224.710734) (xy 360.625346 -224.730206) (xy 360.573384 -224.742066)
			(xy 360.520234 -224.74605) (xy 360.467084 -224.742066) (xy 360.415122 -224.730206) (xy 360.365508 -224.710734)
			(xy 360.31935 -224.684085) (xy 360.277679 -224.650854) (xy 360.241427 -224.611783) (xy 360.211403 -224.567746)
			(xy 360.188277 -224.519725) (xy 360.172567 -224.468795) (xy 360.164624 -224.416091) (xy 360.164126 -224.389442)
			(xy 359.936542 -224.389442) (xy 359.936152 -224.412686) (xy 359.930113 -224.458781) (xy 359.918132 -224.5037)
			(xy 359.909618 -224.525332) (xy 359.899966 -224.548446) (xy 360.072432 -224.846896) (xy 360.09707 -224.850198)
			(xy 360.122419 -224.853984) (xy 360.171725 -224.86798) (xy 360.218517 -224.888897) (xy 360.261829 -224.916303)
			(xy 360.300766 -224.949633) (xy 360.334526 -224.988198) (xy 360.362411 -225.031202) (xy 360.383847 -225.077759)
			(xy 360.39839 -225.126907) (xy 360.40574 -225.177631) (xy 360.406188 -225.203258) (xy 360.40569 -225.229907)
			(xy 360.397747 -225.282611) (xy 360.382037 -225.333541) (xy 360.358911 -225.381562) (xy 360.328887 -225.425599)
			(xy 360.292635 -225.46467) (xy 360.250964 -225.497901) (xy 360.204806 -225.52455) (xy 360.155192 -225.544022)
			(xy 360.10323 -225.555882) (xy 360.05008 -225.559866) (xy 359.99693 -225.555882) (xy 359.944968 -225.544022)
			(xy 359.895354 -225.52455) (xy 359.849196 -225.497901) (xy 359.807525 -225.46467) (xy 359.771273 -225.425599)
			(xy 359.741249 -225.381562) (xy 359.718123 -225.333541) (xy 359.702413 -225.282611) (xy 359.69447 -225.229907)
			(xy 359.693972 -225.203258) (xy 359.694361 -225.180014) (xy 359.7004 -225.133918) (xy 359.712382 -225.089)
			(xy 359.720896 -225.067368) (xy 359.730548 -225.044254) (xy 359.558082 -224.745804) (xy 359.533444 -224.742502)
			(xy 359.508097 -224.738705) (xy 359.458791 -224.724711) (xy 359.411999 -224.703796) (xy 359.368687 -224.676391)
			(xy 359.329749 -224.643063) (xy 359.295989 -224.604499) (xy 359.268103 -224.561495) (xy 359.246668 -224.514939)
			(xy 359.232125 -224.465792) (xy 359.224774 -224.415069) (xy 359.224326 -224.389442) (xy 358.996742 -224.389442)
			(xy 358.996244 -224.416091) (xy 358.988301 -224.468795) (xy 358.972591 -224.519725) (xy 358.949465 -224.567746)
			(xy 358.919441 -224.611783) (xy 358.883189 -224.650854) (xy 358.841518 -224.684085) (xy 358.79536 -224.710734)
			(xy 358.745746 -224.730206) (xy 358.693784 -224.742066) (xy 358.640634 -224.74605) (xy 358.587484 -224.742066)
			(xy 358.535522 -224.730206) (xy 358.485908 -224.710734) (xy 358.43975 -224.684085) (xy 358.398079 -224.650854)
			(xy 358.361827 -224.611783) (xy 358.331803 -224.567746) (xy 358.308677 -224.519725) (xy 358.292967 -224.468795)
			(xy 358.285024 -224.416091) (xy 358.284526 -224.389442) (xy 358.056942 -224.389442) (xy 358.056552 -224.412686)
			(xy 358.050513 -224.458781) (xy 358.038532 -224.5037) (xy 358.030018 -224.525332) (xy 358.020366 -224.548446)
			(xy 358.192832 -224.846896) (xy 358.21747 -224.850198) (xy 358.242819 -224.853984) (xy 358.292125 -224.86798)
			(xy 358.338917 -224.888897) (xy 358.382229 -224.916303) (xy 358.421166 -224.949633) (xy 358.454926 -224.988198)
			(xy 358.482811 -225.031202) (xy 358.504247 -225.077759) (xy 358.51879 -225.126907) (xy 358.52614 -225.177631)
			(xy 358.526588 -225.203258) (xy 358.52609 -225.229907) (xy 358.75467 -225.229907) (xy 358.75467 -225.176609)
			(xy 358.762613 -225.123905) (xy 358.778323 -225.072975) (xy 358.801449 -225.024954) (xy 358.831473 -224.980917)
			(xy 358.867725 -224.941846) (xy 358.909396 -224.908615) (xy 358.955554 -224.881966) (xy 359.005168 -224.862494)
			(xy 359.05713 -224.850634) (xy 359.11028 -224.846651) (xy 359.16343 -224.850634) (xy 359.215392 -224.862494)
			(xy 359.265006 -224.881966) (xy 359.311164 -224.908615) (xy 359.352835 -224.941846) (xy 359.389087 -224.980917)
			(xy 359.419111 -225.024954) (xy 359.442237 -225.072975) (xy 359.457947 -225.123905) (xy 359.46589 -225.176609)
			(xy 359.466388 -225.203258) (xy 359.46589 -225.229907) (xy 359.457947 -225.282611) (xy 359.442237 -225.333541)
			(xy 359.419111 -225.381562) (xy 359.389087 -225.425599) (xy 359.352835 -225.46467) (xy 359.311164 -225.497901)
			(xy 359.265006 -225.52455) (xy 359.215392 -225.544022) (xy 359.16343 -225.555882) (xy 359.11028 -225.559866)
			(xy 359.05713 -225.555882) (xy 359.005168 -225.544022) (xy 358.955554 -225.52455) (xy 358.909396 -225.497901)
			(xy 358.867725 -225.46467) (xy 358.831473 -225.425599) (xy 358.801449 -225.381562) (xy 358.778323 -225.333541)
			(xy 358.762613 -225.282611) (xy 358.75467 -225.229907) (xy 358.52609 -225.229907) (xy 358.518147 -225.282611)
			(xy 358.502437 -225.333541) (xy 358.479311 -225.381562) (xy 358.449287 -225.425599) (xy 358.413035 -225.46467)
			(xy 358.371364 -225.497901) (xy 358.325206 -225.52455) (xy 358.275592 -225.544022) (xy 358.22363 -225.555882)
			(xy 358.17048 -225.559866) (xy 358.11733 -225.555882) (xy 358.065368 -225.544022) (xy 358.015754 -225.52455)
			(xy 357.969596 -225.497901) (xy 357.927925 -225.46467) (xy 357.891673 -225.425599) (xy 357.861649 -225.381562)
			(xy 357.838523 -225.333541) (xy 357.822813 -225.282611) (xy 357.81487 -225.229907) (xy 357.814372 -225.203258)
			(xy 357.814761 -225.180014) (xy 357.8208 -225.133918) (xy 357.832782 -225.089) (xy 357.841296 -225.067368)
			(xy 357.850948 -225.044254) (xy 357.678482 -224.745804) (xy 357.653844 -224.742502) (xy 357.628497 -224.738705)
			(xy 357.579191 -224.724711) (xy 357.532399 -224.703796) (xy 357.489087 -224.676391) (xy 357.450149 -224.643063)
			(xy 357.416389 -224.604499) (xy 357.388503 -224.561495) (xy 357.367068 -224.514939) (xy 357.352525 -224.465792)
			(xy 357.345174 -224.415069) (xy 357.344726 -224.389442) (xy 357.117142 -224.389442) (xy 357.116644 -224.416091)
			(xy 357.108701 -224.468795) (xy 357.092991 -224.519725) (xy 357.069865 -224.567746) (xy 357.039841 -224.611783)
			(xy 357.003589 -224.650854) (xy 356.961918 -224.684085) (xy 356.91576 -224.710734) (xy 356.866146 -224.730206)
			(xy 356.814184 -224.742066) (xy 356.761034 -224.74605) (xy 356.707884 -224.742066) (xy 356.655922 -224.730206)
			(xy 356.606308 -224.710734) (xy 356.56015 -224.684085) (xy 356.518479 -224.650854) (xy 356.482227 -224.611783)
			(xy 356.452203 -224.567746) (xy 356.429077 -224.519725) (xy 356.413367 -224.468795) (xy 356.405424 -224.416091)
			(xy 356.404926 -224.389442) (xy 356.177342 -224.389442) (xy 356.176952 -224.412686) (xy 356.170913 -224.458781)
			(xy 356.158932 -224.5037) (xy 356.150418 -224.525332) (xy 356.140766 -224.548446) (xy 356.313232 -224.846896)
			(xy 356.33787 -224.850198) (xy 356.363219 -224.853984) (xy 356.412525 -224.86798) (xy 356.459317 -224.888897)
			(xy 356.502629 -224.916303) (xy 356.541566 -224.949633) (xy 356.575326 -224.988198) (xy 356.603211 -225.031202)
			(xy 356.624647 -225.077759) (xy 356.63919 -225.126907) (xy 356.64654 -225.177631) (xy 356.646988 -225.203258)
			(xy 356.64649 -225.229907) (xy 356.638547 -225.282611) (xy 356.622837 -225.333541) (xy 356.599711 -225.381562)
			(xy 356.569687 -225.425599) (xy 356.533435 -225.46467) (xy 356.491764 -225.497901) (xy 356.445606 -225.52455)
			(xy 356.395992 -225.544022) (xy 356.34403 -225.555882) (xy 356.29088 -225.559866) (xy 356.23773 -225.555882)
			(xy 356.185768 -225.544022) (xy 356.136154 -225.52455) (xy 356.089996 -225.497901) (xy 356.048325 -225.46467)
			(xy 356.012073 -225.425599) (xy 355.982049 -225.381562) (xy 355.958923 -225.333541) (xy 355.943213 -225.282611)
			(xy 355.93527 -225.229907) (xy 355.934772 -225.203258) (xy 355.935161 -225.180014) (xy 355.9412 -225.133918)
			(xy 355.953182 -225.089) (xy 355.961696 -225.067368) (xy 355.971348 -225.044254) (xy 355.798882 -224.745804)
			(xy 355.774244 -224.742502) (xy 355.748897 -224.738705) (xy 355.699591 -224.724711) (xy 355.652799 -224.703796)
			(xy 355.609487 -224.676391) (xy 355.570549 -224.643063) (xy 355.536789 -224.604499) (xy 355.508903 -224.561495)
			(xy 355.487468 -224.514939) (xy 355.472925 -224.465792) (xy 355.465574 -224.415069) (xy 355.465126 -224.389442)
			(xy 355.237542 -224.389442) (xy 355.237044 -224.416091) (xy 355.229101 -224.468795) (xy 355.213391 -224.519725)
			(xy 355.190265 -224.567746) (xy 355.160241 -224.611783) (xy 355.123989 -224.650854) (xy 355.082318 -224.684085)
			(xy 355.03616 -224.710734) (xy 354.986546 -224.730206) (xy 354.934584 -224.742066) (xy 354.881434 -224.74605)
			(xy 354.828284 -224.742066) (xy 354.776322 -224.730206) (xy 354.726708 -224.710734) (xy 354.68055 -224.684085)
			(xy 354.638879 -224.650854) (xy 354.602627 -224.611783) (xy 354.572603 -224.567746) (xy 354.549477 -224.519725)
			(xy 354.533767 -224.468795) (xy 354.525824 -224.416091) (xy 354.525326 -224.389442) (xy 354.297742 -224.389442)
			(xy 354.297364 -224.412686) (xy 354.291314 -224.45878) (xy 354.279324 -224.503696) (xy 354.270818 -224.525332)
			(xy 354.261166 -224.548446) (xy 354.433632 -224.846896) (xy 354.45827 -224.850198) (xy 354.483613 -224.854021)
			(xy 354.532922 -224.867998) (xy 354.579718 -224.888902) (xy 354.623032 -224.916299) (xy 354.66197 -224.949625)
			(xy 354.695727 -224.988189) (xy 354.723605 -225.031196) (xy 354.745027 -225.077756) (xy 354.759552 -225.126906)
			(xy 354.766879 -225.177632) (xy 354.767388 -225.203258) (xy 354.76689 -225.229907) (xy 354.758947 -225.282611)
			(xy 354.743237 -225.333541) (xy 354.720111 -225.381562) (xy 354.690087 -225.425599) (xy 354.653835 -225.46467)
			(xy 354.612164 -225.497901) (xy 354.566006 -225.52455) (xy 354.516392 -225.544022) (xy 354.46443 -225.555882)
			(xy 354.41128 -225.559866) (xy 354.35813 -225.555882) (xy 354.306168 -225.544022) (xy 354.256554 -225.52455)
			(xy 354.210396 -225.497901) (xy 354.168725 -225.46467) (xy 354.132473 -225.425599) (xy 354.102449 -225.381562)
			(xy 354.079323 -225.333541) (xy 354.063613 -225.282611) (xy 354.05567 -225.229907) (xy 354.055172 -225.203258)
			(xy 354.05555 -225.180014) (xy 354.0616 -225.13392) (xy 354.073591 -225.089004) (xy 354.082096 -225.067368)
			(xy 354.091748 -225.044254) (xy 353.919282 -224.745804) (xy 353.894644 -224.742502) (xy 353.869439 -224.738713)
			(xy 353.82039 -224.72486) (xy 353.773819 -224.70415) (xy 353.73068 -224.677007) (xy 353.691855 -224.643986)
			(xy 353.67468 -224.625154) (xy 353.665312 -224.615194) (xy 353.642446 -224.600224) (xy 353.616425 -224.591862)
			(xy 353.589118 -224.590707) (xy 353.562484 -224.596843) (xy 353.538435 -224.609829) (xy 353.518697 -224.628734)
			(xy 353.504685 -224.652201) (xy 353.497406 -224.678545) (xy 353.49688 -224.69221) (xy 353.49688 -224.737168)
			(xy 353.412298 -224.82175) (xy 353.42449 -224.852738) (xy 353.432872 -224.874836) (xy 353.442488 -224.873768)
			(xy 353.461805 -224.872625) (xy 353.47148 -224.87255) (xy 353.497474 -224.873032) (xy 353.548821 -224.881162)
			(xy 353.598265 -224.897224) (xy 353.644586 -224.920824) (xy 353.686646 -224.951379) (xy 353.723408 -224.988139)
			(xy 353.753966 -225.030197) (xy 353.777568 -225.076517) (xy 353.793634 -225.125959) (xy 353.801767 -225.177306)
			(xy 353.801767 -225.229294) (xy 353.793634 -225.280641) (xy 353.777568 -225.330083) (xy 353.753966 -225.376403)
			(xy 353.723408 -225.418461) (xy 353.686646 -225.455221) (xy 353.644586 -225.485776) (xy 353.598265 -225.509376)
			(xy 353.548821 -225.525438) (xy 353.497474 -225.533568) (xy 353.47148 -225.533966) (xy 353.461805 -225.533887)
			(xy 353.442489 -225.532743) (xy 353.432872 -225.53168) (xy 353.419327 -225.567696) (xy 353.387253 -225.637648)
			(xy 353.349686 -225.70481) (xy 353.306869 -225.768752) (xy 353.283266 -225.799142) (xy 353.300791 -225.822723)
			(xy 353.328684 -225.874426) (xy 353.347715 -225.930005) (xy 353.357367 -225.987954) (xy 353.357942 -226.017328)
			(xy 353.357417 -226.043977) (xy 353.586024 -226.043977) (xy 353.586024 -225.990679) (xy 353.593967 -225.937975)
			(xy 353.609677 -225.887045) (xy 353.632803 -225.839024) (xy 353.662827 -225.794987) (xy 353.699079 -225.755916)
			(xy 353.74075 -225.722685) (xy 353.786908 -225.696036) (xy 353.836522 -225.676564) (xy 353.888484 -225.664704)
			(xy 353.941634 -225.660721) (xy 353.994784 -225.664704) (xy 354.046746 -225.676564) (xy 354.09636 -225.696036)
			(xy 354.142518 -225.722685) (xy 354.184189 -225.755916) (xy 354.220441 -225.794987) (xy 354.250465 -225.839024)
			(xy 354.273591 -225.887045) (xy 354.289301 -225.937975) (xy 354.297244 -225.990679) (xy 354.297742 -226.017328)
			(xy 354.297244 -226.043977) (xy 354.525824 -226.043977) (xy 354.525824 -225.990679) (xy 354.533767 -225.937975)
			(xy 354.549477 -225.887045) (xy 354.572603 -225.839024) (xy 354.602627 -225.794987) (xy 354.638879 -225.755916)
			(xy 354.68055 -225.722685) (xy 354.726708 -225.696036) (xy 354.776322 -225.676564) (xy 354.828284 -225.664704)
			(xy 354.881434 -225.660721) (xy 354.934584 -225.664704) (xy 354.986546 -225.676564) (xy 355.03616 -225.696036)
			(xy 355.082318 -225.722685) (xy 355.123989 -225.755916) (xy 355.160241 -225.794987) (xy 355.190265 -225.839024)
			(xy 355.213391 -225.887045) (xy 355.229101 -225.937975) (xy 355.237044 -225.990679) (xy 355.237542 -226.017328)
			(xy 355.237044 -226.043977) (xy 355.465624 -226.043977) (xy 355.465624 -225.990679) (xy 355.473567 -225.937975)
			(xy 355.489277 -225.887045) (xy 355.512403 -225.839024) (xy 355.542427 -225.794987) (xy 355.578679 -225.755916)
			(xy 355.62035 -225.722685) (xy 355.666508 -225.696036) (xy 355.716122 -225.676564) (xy 355.768084 -225.664704)
			(xy 355.821234 -225.660721) (xy 355.874384 -225.664704) (xy 355.926346 -225.676564) (xy 355.97596 -225.696036)
			(xy 356.022118 -225.722685) (xy 356.063789 -225.755916) (xy 356.100041 -225.794987) (xy 356.130065 -225.839024)
			(xy 356.153191 -225.887045) (xy 356.168901 -225.937975) (xy 356.176844 -225.990679) (xy 356.177342 -226.017328)
			(xy 356.176844 -226.043977) (xy 356.405424 -226.043977) (xy 356.405424 -225.990679) (xy 356.413367 -225.937975)
			(xy 356.429077 -225.887045) (xy 356.452203 -225.839024) (xy 356.482227 -225.794987) (xy 356.518479 -225.755916)
			(xy 356.56015 -225.722685) (xy 356.606308 -225.696036) (xy 356.655922 -225.676564) (xy 356.707884 -225.664704)
			(xy 356.761034 -225.660721) (xy 356.814184 -225.664704) (xy 356.866146 -225.676564) (xy 356.91576 -225.696036)
			(xy 356.961918 -225.722685) (xy 357.003589 -225.755916) (xy 357.039841 -225.794987) (xy 357.069865 -225.839024)
			(xy 357.092991 -225.887045) (xy 357.108701 -225.937975) (xy 357.116644 -225.990679) (xy 357.117142 -226.017328)
			(xy 357.116644 -226.043977) (xy 357.345224 -226.043977) (xy 357.345224 -225.990679) (xy 357.353167 -225.937975)
			(xy 357.368877 -225.887045) (xy 357.392003 -225.839024) (xy 357.422027 -225.794987) (xy 357.458279 -225.755916)
			(xy 357.49995 -225.722685) (xy 357.546108 -225.696036) (xy 357.595722 -225.676564) (xy 357.647684 -225.664704)
			(xy 357.700834 -225.660721) (xy 357.753984 -225.664704) (xy 357.805946 -225.676564) (xy 357.85556 -225.696036)
			(xy 357.901718 -225.722685) (xy 357.943389 -225.755916) (xy 357.979641 -225.794987) (xy 358.009665 -225.839024)
			(xy 358.032791 -225.887045) (xy 358.048501 -225.937975) (xy 358.056444 -225.990679) (xy 358.056942 -226.017328)
			(xy 358.056444 -226.043977) (xy 358.285024 -226.043977) (xy 358.285024 -225.990679) (xy 358.292967 -225.937975)
			(xy 358.308677 -225.887045) (xy 358.331803 -225.839024) (xy 358.361827 -225.794987) (xy 358.398079 -225.755916)
			(xy 358.43975 -225.722685) (xy 358.485908 -225.696036) (xy 358.535522 -225.676564) (xy 358.587484 -225.664704)
			(xy 358.640634 -225.660721) (xy 358.693784 -225.664704) (xy 358.745746 -225.676564) (xy 358.79536 -225.696036)
			(xy 358.841518 -225.722685) (xy 358.883189 -225.755916) (xy 358.919441 -225.794987) (xy 358.949465 -225.839024)
			(xy 358.972591 -225.887045) (xy 358.988301 -225.937975) (xy 358.996244 -225.990679) (xy 358.996742 -226.017328)
			(xy 358.996244 -226.043977) (xy 359.224824 -226.043977) (xy 359.224824 -225.990679) (xy 359.232767 -225.937975)
			(xy 359.248477 -225.887045) (xy 359.271603 -225.839024) (xy 359.301627 -225.794987) (xy 359.337879 -225.755916)
			(xy 359.37955 -225.722685) (xy 359.425708 -225.696036) (xy 359.475322 -225.676564) (xy 359.527284 -225.664704)
			(xy 359.580434 -225.660721) (xy 359.633584 -225.664704) (xy 359.685546 -225.676564) (xy 359.73516 -225.696036)
			(xy 359.781318 -225.722685) (xy 359.822989 -225.755916) (xy 359.859241 -225.794987) (xy 359.889265 -225.839024)
			(xy 359.912391 -225.887045) (xy 359.928101 -225.937975) (xy 359.936044 -225.990679) (xy 359.936542 -226.017328)
			(xy 359.936044 -226.043977) (xy 360.164624 -226.043977) (xy 360.164624 -225.990679) (xy 360.172567 -225.937975)
			(xy 360.188277 -225.887045) (xy 360.211403 -225.839024) (xy 360.241427 -225.794987) (xy 360.277679 -225.755916)
			(xy 360.31935 -225.722685) (xy 360.365508 -225.696036) (xy 360.415122 -225.676564) (xy 360.467084 -225.664704)
			(xy 360.520234 -225.660721) (xy 360.573384 -225.664704) (xy 360.625346 -225.676564) (xy 360.67496 -225.696036)
			(xy 360.721118 -225.722685) (xy 360.762789 -225.755916) (xy 360.799041 -225.794987) (xy 360.829065 -225.839024)
			(xy 360.852191 -225.887045) (xy 360.867901 -225.937975) (xy 360.875844 -225.990679) (xy 360.876342 -226.017328)
			(xy 360.875844 -226.043977) (xy 361.104424 -226.043977) (xy 361.104424 -225.990679) (xy 361.112367 -225.937975)
			(xy 361.128077 -225.887045) (xy 361.151203 -225.839024) (xy 361.181227 -225.794987) (xy 361.217479 -225.755916)
			(xy 361.25915 -225.722685) (xy 361.305308 -225.696036) (xy 361.354922 -225.676564) (xy 361.406884 -225.664704)
			(xy 361.460034 -225.660721) (xy 361.513184 -225.664704) (xy 361.565146 -225.676564) (xy 361.61476 -225.696036)
			(xy 361.660918 -225.722685) (xy 361.702589 -225.755916) (xy 361.738841 -225.794987) (xy 361.768865 -225.839024)
			(xy 361.791991 -225.887045) (xy 361.807701 -225.937975) (xy 361.815644 -225.990679) (xy 361.816142 -226.017328)
			(xy 361.815644 -226.043977) (xy 362.044224 -226.043977) (xy 362.044224 -225.990679) (xy 362.052167 -225.937975)
			(xy 362.067877 -225.887045) (xy 362.091003 -225.839024) (xy 362.121027 -225.794987) (xy 362.157279 -225.755916)
			(xy 362.19895 -225.722685) (xy 362.245108 -225.696036) (xy 362.294722 -225.676564) (xy 362.346684 -225.664704)
			(xy 362.399834 -225.660721) (xy 362.452984 -225.664704) (xy 362.504946 -225.676564) (xy 362.55456 -225.696036)
			(xy 362.600718 -225.722685) (xy 362.642389 -225.755916) (xy 362.678641 -225.794987) (xy 362.708665 -225.839024)
			(xy 362.731791 -225.887045) (xy 362.747501 -225.937975) (xy 362.755444 -225.990679) (xy 362.755942 -226.017328)
			(xy 362.755444 -226.043977) (xy 362.984024 -226.043977) (xy 362.984024 -225.990679) (xy 362.991967 -225.937975)
			(xy 363.007677 -225.887045) (xy 363.030803 -225.839024) (xy 363.060827 -225.794987) (xy 363.097079 -225.755916)
			(xy 363.13875 -225.722685) (xy 363.184908 -225.696036) (xy 363.234522 -225.676564) (xy 363.286484 -225.664704)
			(xy 363.339634 -225.660721) (xy 363.392784 -225.664704) (xy 363.444746 -225.676564) (xy 363.49436 -225.696036)
			(xy 363.540518 -225.722685) (xy 363.582189 -225.755916) (xy 363.618441 -225.794987) (xy 363.648465 -225.839024)
			(xy 363.671591 -225.887045) (xy 363.687301 -225.937975) (xy 363.695244 -225.990679) (xy 363.695742 -226.017328)
			(xy 363.695244 -226.043977) (xy 363.923824 -226.043977) (xy 363.923824 -225.990679) (xy 363.931767 -225.937975)
			(xy 363.947477 -225.887045) (xy 363.970603 -225.839024) (xy 364.000627 -225.794987) (xy 364.036879 -225.755916)
			(xy 364.07855 -225.722685) (xy 364.124708 -225.696036) (xy 364.174322 -225.676564) (xy 364.226284 -225.664704)
			(xy 364.279434 -225.660721) (xy 364.332584 -225.664704) (xy 364.384546 -225.676564) (xy 364.43416 -225.696036)
			(xy 364.480318 -225.722685) (xy 364.521989 -225.755916) (xy 364.558241 -225.794987) (xy 364.588265 -225.839024)
			(xy 364.611391 -225.887045) (xy 364.627101 -225.937975) (xy 364.635044 -225.990679) (xy 364.635542 -226.017328)
			(xy 364.635044 -226.043977) (xy 364.863624 -226.043977) (xy 364.863624 -225.990679) (xy 364.871567 -225.937975)
			(xy 364.887277 -225.887045) (xy 364.910403 -225.839024) (xy 364.940427 -225.794987) (xy 364.976679 -225.755916)
			(xy 365.01835 -225.722685) (xy 365.064508 -225.696036) (xy 365.114122 -225.676564) (xy 365.166084 -225.664704)
			(xy 365.219234 -225.660721) (xy 365.272384 -225.664704) (xy 365.324346 -225.676564) (xy 365.37396 -225.696036)
			(xy 365.420118 -225.722685) (xy 365.461789 -225.755916) (xy 365.498041 -225.794987) (xy 365.528065 -225.839024)
			(xy 365.551191 -225.887045) (xy 365.566901 -225.937975) (xy 365.574844 -225.990679) (xy 365.575342 -226.017328)
			(xy 365.574844 -226.043977) (xy 365.803424 -226.043977) (xy 365.803424 -225.990679) (xy 365.811367 -225.937975)
			(xy 365.827077 -225.887045) (xy 365.850203 -225.839024) (xy 365.880227 -225.794987) (xy 365.916479 -225.755916)
			(xy 365.95815 -225.722685) (xy 366.004308 -225.696036) (xy 366.053922 -225.676564) (xy 366.105884 -225.664704)
			(xy 366.159034 -225.660721) (xy 366.212184 -225.664704) (xy 366.264146 -225.676564) (xy 366.31376 -225.696036)
			(xy 366.359918 -225.722685) (xy 366.401589 -225.755916) (xy 366.437841 -225.794987) (xy 366.467865 -225.839024)
			(xy 366.490991 -225.887045) (xy 366.506701 -225.937975) (xy 366.514644 -225.990679) (xy 366.515142 -226.017328)
			(xy 366.514644 -226.043977) (xy 366.743224 -226.043977) (xy 366.743224 -225.990679) (xy 366.751167 -225.937975)
			(xy 366.766877 -225.887045) (xy 366.790003 -225.839024) (xy 366.820027 -225.794987) (xy 366.856279 -225.755916)
			(xy 366.89795 -225.722685) (xy 366.944108 -225.696036) (xy 366.993722 -225.676564) (xy 367.045684 -225.664704)
			(xy 367.098834 -225.660721) (xy 367.151984 -225.664704) (xy 367.203946 -225.676564) (xy 367.25356 -225.696036)
			(xy 367.299718 -225.722685) (xy 367.341389 -225.755916) (xy 367.377641 -225.794987) (xy 367.407665 -225.839024)
			(xy 367.430791 -225.887045) (xy 367.446501 -225.937975) (xy 367.454444 -225.990679) (xy 367.454942 -226.017328)
			(xy 367.454444 -226.043977) (xy 367.446501 -226.096681) (xy 367.430791 -226.147611) (xy 367.407665 -226.195632)
			(xy 367.377641 -226.239669) (xy 367.341389 -226.27874) (xy 367.299718 -226.311971) (xy 367.25356 -226.33862)
			(xy 367.203946 -226.358092) (xy 367.151984 -226.369952) (xy 367.098834 -226.373936) (xy 367.045684 -226.369952)
			(xy 366.993722 -226.358092) (xy 366.944108 -226.33862) (xy 366.89795 -226.311971) (xy 366.856279 -226.27874)
			(xy 366.820027 -226.239669) (xy 366.790003 -226.195632) (xy 366.766877 -226.147611) (xy 366.751167 -226.096681)
			(xy 366.743224 -226.043977) (xy 366.514644 -226.043977) (xy 366.506701 -226.096681) (xy 366.490991 -226.147611)
			(xy 366.467865 -226.195632) (xy 366.437841 -226.239669) (xy 366.401589 -226.27874) (xy 366.359918 -226.311971)
			(xy 366.31376 -226.33862) (xy 366.264146 -226.358092) (xy 366.212184 -226.369952) (xy 366.159034 -226.373936)
			(xy 366.105884 -226.369952) (xy 366.053922 -226.358092) (xy 366.004308 -226.33862) (xy 365.95815 -226.311971)
			(xy 365.916479 -226.27874) (xy 365.880227 -226.239669) (xy 365.850203 -226.195632) (xy 365.827077 -226.147611)
			(xy 365.811367 -226.096681) (xy 365.803424 -226.043977) (xy 365.574844 -226.043977) (xy 365.566901 -226.096681)
			(xy 365.551191 -226.147611) (xy 365.528065 -226.195632) (xy 365.498041 -226.239669) (xy 365.461789 -226.27874)
			(xy 365.420118 -226.311971) (xy 365.37396 -226.33862) (xy 365.324346 -226.358092) (xy 365.272384 -226.369952)
			(xy 365.219234 -226.373936) (xy 365.166084 -226.369952) (xy 365.114122 -226.358092) (xy 365.064508 -226.33862)
			(xy 365.01835 -226.311971) (xy 364.976679 -226.27874) (xy 364.940427 -226.239669) (xy 364.910403 -226.195632)
			(xy 364.887277 -226.147611) (xy 364.871567 -226.096681) (xy 364.863624 -226.043977) (xy 364.635044 -226.043977)
			(xy 364.627101 -226.096681) (xy 364.611391 -226.147611) (xy 364.588265 -226.195632) (xy 364.558241 -226.239669)
			(xy 364.521989 -226.27874) (xy 364.480318 -226.311971) (xy 364.43416 -226.33862) (xy 364.384546 -226.358092)
			(xy 364.332584 -226.369952) (xy 364.279434 -226.373936) (xy 364.226284 -226.369952) (xy 364.174322 -226.358092)
			(xy 364.124708 -226.33862) (xy 364.07855 -226.311971) (xy 364.036879 -226.27874) (xy 364.000627 -226.239669)
			(xy 363.970603 -226.195632) (xy 363.947477 -226.147611) (xy 363.931767 -226.096681) (xy 363.923824 -226.043977)
			(xy 363.695244 -226.043977) (xy 363.687301 -226.096681) (xy 363.671591 -226.147611) (xy 363.648465 -226.195632)
			(xy 363.618441 -226.239669) (xy 363.582189 -226.27874) (xy 363.540518 -226.311971) (xy 363.49436 -226.33862)
			(xy 363.444746 -226.358092) (xy 363.392784 -226.369952) (xy 363.339634 -226.373936) (xy 363.286484 -226.369952)
			(xy 363.234522 -226.358092) (xy 363.184908 -226.33862) (xy 363.13875 -226.311971) (xy 363.097079 -226.27874)
			(xy 363.060827 -226.239669) (xy 363.030803 -226.195632) (xy 363.007677 -226.147611) (xy 362.991967 -226.096681)
			(xy 362.984024 -226.043977) (xy 362.755444 -226.043977) (xy 362.747501 -226.096681) (xy 362.731791 -226.147611)
			(xy 362.708665 -226.195632) (xy 362.678641 -226.239669) (xy 362.642389 -226.27874) (xy 362.600718 -226.311971)
			(xy 362.55456 -226.33862) (xy 362.504946 -226.358092) (xy 362.452984 -226.369952) (xy 362.399834 -226.373936)
			(xy 362.346684 -226.369952) (xy 362.294722 -226.358092) (xy 362.245108 -226.33862) (xy 362.19895 -226.311971)
			(xy 362.157279 -226.27874) (xy 362.121027 -226.239669) (xy 362.091003 -226.195632) (xy 362.067877 -226.147611)
			(xy 362.052167 -226.096681) (xy 362.044224 -226.043977) (xy 361.815644 -226.043977) (xy 361.807701 -226.096681)
			(xy 361.791991 -226.147611) (xy 361.768865 -226.195632) (xy 361.738841 -226.239669) (xy 361.702589 -226.27874)
			(xy 361.660918 -226.311971) (xy 361.61476 -226.33862) (xy 361.565146 -226.358092) (xy 361.513184 -226.369952)
			(xy 361.460034 -226.373936) (xy 361.406884 -226.369952) (xy 361.354922 -226.358092) (xy 361.305308 -226.33862)
			(xy 361.25915 -226.311971) (xy 361.217479 -226.27874) (xy 361.181227 -226.239669) (xy 361.151203 -226.195632)
			(xy 361.128077 -226.147611) (xy 361.112367 -226.096681) (xy 361.104424 -226.043977) (xy 360.875844 -226.043977)
			(xy 360.867901 -226.096681) (xy 360.852191 -226.147611) (xy 360.829065 -226.195632) (xy 360.799041 -226.239669)
			(xy 360.762789 -226.27874) (xy 360.721118 -226.311971) (xy 360.67496 -226.33862) (xy 360.625346 -226.358092)
			(xy 360.573384 -226.369952) (xy 360.520234 -226.373936) (xy 360.467084 -226.369952) (xy 360.415122 -226.358092)
			(xy 360.365508 -226.33862) (xy 360.31935 -226.311971) (xy 360.277679 -226.27874) (xy 360.241427 -226.239669)
			(xy 360.211403 -226.195632) (xy 360.188277 -226.147611) (xy 360.172567 -226.096681) (xy 360.164624 -226.043977)
			(xy 359.936044 -226.043977) (xy 359.928101 -226.096681) (xy 359.912391 -226.147611) (xy 359.889265 -226.195632)
			(xy 359.859241 -226.239669) (xy 359.822989 -226.27874) (xy 359.781318 -226.311971) (xy 359.73516 -226.33862)
			(xy 359.685546 -226.358092) (xy 359.633584 -226.369952) (xy 359.580434 -226.373936) (xy 359.527284 -226.369952)
			(xy 359.475322 -226.358092) (xy 359.425708 -226.33862) (xy 359.37955 -226.311971) (xy 359.337879 -226.27874)
			(xy 359.301627 -226.239669) (xy 359.271603 -226.195632) (xy 359.248477 -226.147611) (xy 359.232767 -226.096681)
			(xy 359.224824 -226.043977) (xy 358.996244 -226.043977) (xy 358.988301 -226.096681) (xy 358.972591 -226.147611)
			(xy 358.949465 -226.195632) (xy 358.919441 -226.239669) (xy 358.883189 -226.27874) (xy 358.841518 -226.311971)
			(xy 358.79536 -226.33862) (xy 358.745746 -226.358092) (xy 358.693784 -226.369952) (xy 358.640634 -226.373936)
			(xy 358.587484 -226.369952) (xy 358.535522 -226.358092) (xy 358.485908 -226.33862) (xy 358.43975 -226.311971)
			(xy 358.398079 -226.27874) (xy 358.361827 -226.239669) (xy 358.331803 -226.195632) (xy 358.308677 -226.147611)
			(xy 358.292967 -226.096681) (xy 358.285024 -226.043977) (xy 358.056444 -226.043977) (xy 358.048501 -226.096681)
			(xy 358.032791 -226.147611) (xy 358.009665 -226.195632) (xy 357.979641 -226.239669) (xy 357.943389 -226.27874)
			(xy 357.901718 -226.311971) (xy 357.85556 -226.33862) (xy 357.805946 -226.358092) (xy 357.753984 -226.369952)
			(xy 357.700834 -226.373936) (xy 357.647684 -226.369952) (xy 357.595722 -226.358092) (xy 357.546108 -226.33862)
			(xy 357.49995 -226.311971) (xy 357.458279 -226.27874) (xy 357.422027 -226.239669) (xy 357.392003 -226.195632)
			(xy 357.368877 -226.147611) (xy 357.353167 -226.096681) (xy 357.345224 -226.043977) (xy 357.116644 -226.043977)
			(xy 357.108701 -226.096681) (xy 357.092991 -226.147611) (xy 357.069865 -226.195632) (xy 357.039841 -226.239669)
			(xy 357.003589 -226.27874) (xy 356.961918 -226.311971) (xy 356.91576 -226.33862) (xy 356.866146 -226.358092)
			(xy 356.814184 -226.369952) (xy 356.761034 -226.373936) (xy 356.707884 -226.369952) (xy 356.655922 -226.358092)
			(xy 356.606308 -226.33862) (xy 356.56015 -226.311971) (xy 356.518479 -226.27874) (xy 356.482227 -226.239669)
			(xy 356.452203 -226.195632) (xy 356.429077 -226.147611) (xy 356.413367 -226.096681) (xy 356.405424 -226.043977)
			(xy 356.176844 -226.043977) (xy 356.168901 -226.096681) (xy 356.153191 -226.147611) (xy 356.130065 -226.195632)
			(xy 356.100041 -226.239669) (xy 356.063789 -226.27874) (xy 356.022118 -226.311971) (xy 355.97596 -226.33862)
			(xy 355.926346 -226.358092) (xy 355.874384 -226.369952) (xy 355.821234 -226.373936) (xy 355.768084 -226.369952)
			(xy 355.716122 -226.358092) (xy 355.666508 -226.33862) (xy 355.62035 -226.311971) (xy 355.578679 -226.27874)
			(xy 355.542427 -226.239669) (xy 355.512403 -226.195632) (xy 355.489277 -226.147611) (xy 355.473567 -226.096681)
			(xy 355.465624 -226.043977) (xy 355.237044 -226.043977) (xy 355.229101 -226.096681) (xy 355.213391 -226.147611)
			(xy 355.190265 -226.195632) (xy 355.160241 -226.239669) (xy 355.123989 -226.27874) (xy 355.082318 -226.311971)
			(xy 355.03616 -226.33862) (xy 354.986546 -226.358092) (xy 354.934584 -226.369952) (xy 354.881434 -226.373936)
			(xy 354.828284 -226.369952) (xy 354.776322 -226.358092) (xy 354.726708 -226.33862) (xy 354.68055 -226.311971)
			(xy 354.638879 -226.27874) (xy 354.602627 -226.239669) (xy 354.572603 -226.195632) (xy 354.549477 -226.147611)
			(xy 354.533767 -226.096681) (xy 354.525824 -226.043977) (xy 354.297244 -226.043977) (xy 354.289301 -226.096681)
			(xy 354.273591 -226.147611) (xy 354.250465 -226.195632) (xy 354.220441 -226.239669) (xy 354.184189 -226.27874)
			(xy 354.142518 -226.311971) (xy 354.09636 -226.33862) (xy 354.046746 -226.358092) (xy 353.994784 -226.369952)
			(xy 353.941634 -226.373936) (xy 353.888484 -226.369952) (xy 353.836522 -226.358092) (xy 353.786908 -226.33862)
			(xy 353.74075 -226.311971) (xy 353.699079 -226.27874) (xy 353.662827 -226.239669) (xy 353.632803 -226.195632)
			(xy 353.609677 -226.147611) (xy 353.593967 -226.096681) (xy 353.586024 -226.043977) (xy 353.357417 -226.043977)
			(xy 353.357391 -226.045311) (xy 353.348633 -226.100586) (xy 353.331336 -226.153812) (xy 353.305927 -226.203677)
			(xy 353.273031 -226.248953) (xy 353.233458 -226.288527) (xy 353.188182 -226.321424) (xy 353.138317 -226.346834)
			(xy 353.085092 -226.364131) (xy 353.029817 -226.372891) (xy 353.001834 -226.373436) (xy 352.9755 -226.372965)
			(xy 352.923404 -226.365215) (xy 352.873017 -226.349879) (xy 352.825438 -226.327291) (xy 352.781703 -226.297944)
			(xy 352.742765 -226.262478) (xy 352.709474 -226.221665) (xy 352.682555 -226.176395) (xy 352.672142 -226.152202)
			(xy 352.63723 -226.157064) (xy 352.566927 -226.162274) (xy 352.53168 -226.162616) (xy 352.49656 -226.162264)
			(xy 352.426512 -226.157051) (xy 352.391726 -226.152202) (xy 352.381301 -226.176388) (xy 352.354372 -226.221649)
			(xy 352.321078 -226.262456) (xy 352.282141 -226.297919) (xy 352.23841 -226.327267) (xy 352.190837 -226.349862)
			(xy 352.140457 -226.36521) (xy 352.088367 -226.372979) (xy 352.062034 -226.373436) (xy 352.034046 -226.372919)
			(xy 351.978759 -226.364167) (xy 351.925521 -226.346875) (xy 351.875644 -226.321467) (xy 351.830356 -226.288569)
			(xy 351.790771 -226.248992) (xy 351.757866 -226.203709) (xy 351.732449 -226.153836) (xy 351.715147 -226.100602)
			(xy 351.706386 -226.045316) (xy 351.705926 -226.017328) (xy 351.705926 -226.017074) (xy 351.706276 -225.994471)
			(xy 351.71201 -225.94963) (xy 351.717356 -225.927666) (xy 351.719374 -225.917867) (xy 351.716592 -225.898077)
			(xy 351.706478 -225.880839) (xy 351.69056 -225.868755) (xy 351.681034 -225.86569) (xy 351.66167 -225.860673)
			(xy 351.623184 -225.84975) (xy 351.604072 -225.843846) (xy 351.589737 -225.839829) (xy 351.559982 -225.839369)
			(xy 351.53136 -225.847508) (xy 351.506299 -225.863555) (xy 351.48693 -225.886146) (xy 351.474897 -225.913362)
			(xy 351.471223 -225.942892) (xy 351.473262 -225.957638) (xy 351.475635 -225.972447) (xy 351.478182 -226.002331)
			(xy 351.478342 -226.017328) (xy 351.477791 -226.045311) (xy 351.469033 -226.100586) (xy 351.451736 -226.153812)
			(xy 351.426327 -226.203677) (xy 351.393431 -226.248953) (xy 351.353858 -226.288527) (xy 351.308582 -226.321424)
			(xy 351.258717 -226.346834) (xy 351.205492 -226.364131) (xy 351.150217 -226.372891) (xy 351.122234 -226.373436)
			(xy 351.0959 -226.372965) (xy 351.043804 -226.365215) (xy 350.993417 -226.349879) (xy 350.945838 -226.327291)
			(xy 350.902103 -226.297944) (xy 350.863165 -226.262478) (xy 350.829874 -226.221665) (xy 350.802955 -226.176395)
			(xy 350.792542 -226.152202) (xy 350.75763 -226.157064) (xy 350.687327 -226.162274) (xy 350.65208 -226.162616)
			(xy 350.61696 -226.162264) (xy 350.546912 -226.157051) (xy 350.512126 -226.152202) (xy 350.501701 -226.176388)
			(xy 350.474772 -226.221649) (xy 350.441478 -226.262456) (xy 350.402541 -226.297919) (xy 350.35881 -226.327267)
			(xy 350.311237 -226.349862) (xy 350.260857 -226.36521) (xy 350.208767 -226.372979) (xy 350.182434 -226.373436)
			(xy 350.154446 -226.372919) (xy 350.099159 -226.364167) (xy 350.045921 -226.346875) (xy 349.996044 -226.321467)
			(xy 349.950756 -226.288569) (xy 349.911171 -226.248992) (xy 349.878266 -226.203709) (xy 349.852849 -226.153836)
			(xy 349.835547 -226.100602) (xy 349.826786 -226.045316) (xy 349.826326 -226.017328) (xy 349.826673 -225.994725)
			(xy 349.8324 -225.949882) (xy 349.837756 -225.92792) (xy 349.839858 -225.918093) (xy 349.837053 -225.89821)
			(xy 349.826849 -225.880915) (xy 349.810801 -225.868845) (xy 349.80118 -225.865944) (xy 349.781879 -225.86086)
			(xy 349.74352 -225.849808) (xy 349.724472 -225.843846) (xy 349.710128 -225.83988) (xy 349.680382 -225.839511)
			(xy 349.651788 -225.847715) (xy 349.626763 -225.8638) (xy 349.607424 -225.886403) (xy 349.595406 -225.913615)
			(xy 349.591725 -225.943134) (xy 349.593662 -225.957892) (xy 349.596024 -225.972638) (xy 349.598566 -226.002395)
			(xy 349.598742 -226.017328) (xy 349.598191 -226.045311) (xy 349.589433 -226.100586) (xy 349.572136 -226.153812)
			(xy 349.546727 -226.203677) (xy 349.513831 -226.248953) (xy 349.474258 -226.288527) (xy 349.428982 -226.321424)
			(xy 349.379117 -226.346834) (xy 349.325892 -226.364131) (xy 349.270617 -226.372891) (xy 349.242634 -226.373436)
			(xy 349.2163 -226.372965) (xy 349.164204 -226.365215) (xy 349.113817 -226.349879) (xy 349.066238 -226.327291)
			(xy 349.022503 -226.297944) (xy 348.983565 -226.262478) (xy 348.950274 -226.221665) (xy 348.923355 -226.176395)
			(xy 348.912942 -226.152202) (xy 348.87803 -226.157064) (xy 348.807727 -226.162274) (xy 348.77248 -226.162616)
			(xy 348.73736 -226.162264) (xy 348.667312 -226.157051) (xy 348.632526 -226.152202) (xy 348.622101 -226.176388)
			(xy 348.595172 -226.221649) (xy 348.561878 -226.262456) (xy 348.522941 -226.297919) (xy 348.47921 -226.327267)
			(xy 348.431637 -226.349862) (xy 348.381257 -226.36521) (xy 348.329167 -226.372979) (xy 348.302834 -226.373436)
			(xy 348.274846 -226.372919) (xy 348.219559 -226.364167) (xy 348.166321 -226.346875) (xy 348.116444 -226.321467)
			(xy 348.071156 -226.288569) (xy 348.031571 -226.248992) (xy 347.998666 -226.203709) (xy 347.973249 -226.153836)
			(xy 347.955947 -226.100602) (xy 347.947186 -226.045316) (xy 347.946726 -226.017328) (xy 347.946726 -226.017074)
			(xy 347.947076 -225.994471) (xy 347.95281 -225.94963) (xy 347.958156 -225.927666) (xy 347.960174 -225.917867)
			(xy 347.957392 -225.898077) (xy 347.947278 -225.880839) (xy 347.93136 -225.868755) (xy 347.921834 -225.86569)
			(xy 347.90247 -225.860673) (xy 347.863984 -225.84975) (xy 347.844872 -225.843846) (xy 347.830537 -225.839829)
			(xy 347.800782 -225.839369) (xy 347.77216 -225.847508) (xy 347.747099 -225.863555) (xy 347.72773 -225.886146)
			(xy 347.715697 -225.913362) (xy 347.712023 -225.942892) (xy 347.714062 -225.957638) (xy 347.716435 -225.972447)
			(xy 347.718982 -226.002331) (xy 347.719142 -226.017328) (xy 347.718591 -226.045311) (xy 347.709833 -226.100586)
			(xy 347.692536 -226.153812) (xy 347.667127 -226.203677) (xy 347.634231 -226.248953) (xy 347.594658 -226.288527)
			(xy 347.549382 -226.321424) (xy 347.499517 -226.346834) (xy 347.446292 -226.364131) (xy 347.391017 -226.372891)
			(xy 347.363034 -226.373436) (xy 347.3367 -226.372965) (xy 347.284604 -226.365215) (xy 347.234217 -226.349879)
			(xy 347.186638 -226.327291) (xy 347.142903 -226.297944) (xy 347.103965 -226.262478) (xy 347.070674 -226.221665)
			(xy 347.043755 -226.176395) (xy 347.033342 -226.152202) (xy 346.99843 -226.157064) (xy 346.928127 -226.162274)
			(xy 346.89288 -226.162616) (xy 346.85776 -226.162264) (xy 346.787712 -226.157051) (xy 346.752926 -226.152202)
			(xy 346.742501 -226.176388) (xy 346.715572 -226.221649) (xy 346.682278 -226.262456) (xy 346.643341 -226.297919)
			(xy 346.59961 -226.327267) (xy 346.552037 -226.349862) (xy 346.501657 -226.36521) (xy 346.449567 -226.372979)
			(xy 346.423234 -226.373436) (xy 346.395246 -226.372919) (xy 346.339959 -226.364167) (xy 346.286721 -226.346875)
			(xy 346.236844 -226.321467) (xy 346.191556 -226.288569) (xy 346.151971 -226.248992) (xy 346.119066 -226.203709)
			(xy 346.093649 -226.153836) (xy 346.076347 -226.100602) (xy 346.067586 -226.045316) (xy 346.067126 -226.017328)
			(xy 346.067126 -226.017074) (xy 346.067476 -225.994471) (xy 346.07321 -225.94963) (xy 346.078556 -225.927666)
			(xy 346.080574 -225.917867) (xy 346.077792 -225.898077) (xy 346.067678 -225.880839) (xy 346.05176 -225.868755)
			(xy 346.042234 -225.86569) (xy 346.02287 -225.860673) (xy 345.984384 -225.84975) (xy 345.965272 -225.843846)
			(xy 345.950937 -225.839829) (xy 345.921182 -225.839369) (xy 345.89256 -225.847508) (xy 345.867499 -225.863555)
			(xy 345.84813 -225.886146) (xy 345.836097 -225.913362) (xy 345.832423 -225.942892) (xy 345.834462 -225.957638)
			(xy 345.836835 -225.972447) (xy 345.839382 -226.002331) (xy 345.839542 -226.017328) (xy 345.838991 -226.045311)
			(xy 345.830233 -226.100586) (xy 345.812936 -226.153812) (xy 345.787527 -226.203677) (xy 345.754631 -226.248953)
			(xy 345.715058 -226.288527) (xy 345.669782 -226.321424) (xy 345.619917 -226.346834) (xy 345.566692 -226.364131)
			(xy 345.511417 -226.372891) (xy 345.483434 -226.373436) (xy 345.4571 -226.372965) (xy 345.405004 -226.365215)
			(xy 345.354617 -226.349879) (xy 345.307038 -226.327291) (xy 345.263303 -226.297944) (xy 345.224365 -226.262478)
			(xy 345.191074 -226.221665) (xy 345.164155 -226.176395) (xy 345.153742 -226.152202) (xy 345.11883 -226.157064)
			(xy 345.048527 -226.162274) (xy 345.01328 -226.162616) (xy 344.97816 -226.162264) (xy 344.908112 -226.157051)
			(xy 344.873326 -226.152202) (xy 344.862901 -226.176388) (xy 344.835972 -226.221649) (xy 344.802678 -226.262456)
			(xy 344.763741 -226.297919) (xy 344.72001 -226.327267) (xy 344.672437 -226.349862) (xy 344.622057 -226.36521)
			(xy 344.569967 -226.372979) (xy 344.543634 -226.373436) (xy 344.515646 -226.372919) (xy 344.460359 -226.364167)
			(xy 344.407121 -226.346875) (xy 344.357244 -226.321467) (xy 344.311956 -226.288569) (xy 344.272371 -226.248992)
			(xy 344.239466 -226.203709) (xy 344.214049 -226.153836) (xy 344.196747 -226.100602) (xy 344.187986 -226.045316)
			(xy 344.187526 -226.017328) (xy 344.187873 -225.994725) (xy 344.1936 -225.949882) (xy 344.198956 -225.92792)
			(xy 344.201058 -225.918093) (xy 344.198253 -225.89821) (xy 344.188049 -225.880915) (xy 344.172001 -225.868845)
			(xy 344.16238 -225.865944) (xy 344.143079 -225.86086) (xy 344.10472 -225.849808) (xy 344.085672 -225.843846)
			(xy 344.071328 -225.83988) (xy 344.041582 -225.839511) (xy 344.012988 -225.847715) (xy 343.987963 -225.8638)
			(xy 343.968624 -225.886403) (xy 343.956606 -225.913615) (xy 343.952925 -225.943134) (xy 343.954862 -225.957892)
			(xy 343.957224 -225.972638) (xy 343.959766 -226.002395) (xy 343.959942 -226.017328) (xy 343.959391 -226.045311)
			(xy 343.950633 -226.100586) (xy 343.933336 -226.153812) (xy 343.907927 -226.203677) (xy 343.875031 -226.248953)
			(xy 343.835458 -226.288527) (xy 343.790182 -226.321424) (xy 343.740317 -226.346834) (xy 343.687092 -226.364131)
			(xy 343.631817 -226.372891) (xy 343.603834 -226.373436) (xy 343.5775 -226.372965) (xy 343.525404 -226.365215)
			(xy 343.475017 -226.349879) (xy 343.427438 -226.327291) (xy 343.383703 -226.297944) (xy 343.344765 -226.262478)
			(xy 343.311474 -226.221665) (xy 343.284555 -226.176395) (xy 343.274142 -226.152202) (xy 343.23923 -226.157064)
			(xy 343.168927 -226.162274) (xy 343.13368 -226.162616) (xy 343.09856 -226.162264) (xy 343.028512 -226.157051)
			(xy 342.993726 -226.152202) (xy 342.983301 -226.176388) (xy 342.956372 -226.221649) (xy 342.923078 -226.262456)
			(xy 342.884141 -226.297919) (xy 342.84041 -226.327267) (xy 342.792837 -226.349862) (xy 342.742457 -226.36521)
			(xy 342.690367 -226.372979) (xy 342.664034 -226.373436) (xy 342.636046 -226.372919) (xy 342.580759 -226.364167)
			(xy 342.527521 -226.346875) (xy 342.477644 -226.321467) (xy 342.432356 -226.288569) (xy 342.392771 -226.248992)
			(xy 342.359866 -226.203709) (xy 342.334449 -226.153836) (xy 342.317147 -226.100602) (xy 342.308386 -226.045316)
			(xy 342.307926 -226.017328) (xy 342.307926 -226.017074) (xy 342.308276 -225.994471) (xy 342.31401 -225.94963)
			(xy 342.319356 -225.927666) (xy 342.321374 -225.917867) (xy 342.318592 -225.898077) (xy 342.308478 -225.880839)
			(xy 342.29256 -225.868755) (xy 342.283034 -225.86569) (xy 342.26367 -225.860673) (xy 342.225184 -225.84975)
			(xy 342.206072 -225.843846) (xy 342.191737 -225.839829) (xy 342.161982 -225.839369) (xy 342.13336 -225.847508)
			(xy 342.108299 -225.863555) (xy 342.08893 -225.886146) (xy 342.076897 -225.913362) (xy 342.073223 -225.942892)
			(xy 342.075262 -225.957638) (xy 342.077635 -225.972447) (xy 342.080182 -226.002331) (xy 342.080342 -226.017328)
			(xy 342.079791 -226.045311) (xy 342.071033 -226.100586) (xy 342.053736 -226.153812) (xy 342.028327 -226.203677)
			(xy 341.995431 -226.248953) (xy 341.955858 -226.288527) (xy 341.910582 -226.321424) (xy 341.860717 -226.346834)
			(xy 341.807492 -226.364131) (xy 341.752217 -226.372891) (xy 341.724234 -226.373436) (xy 341.6979 -226.372965)
			(xy 341.645804 -226.365215) (xy 341.595417 -226.349879) (xy 341.547838 -226.327291) (xy 341.504103 -226.297944)
			(xy 341.465165 -226.262478) (xy 341.431874 -226.221665) (xy 341.404955 -226.176395) (xy 341.394542 -226.152202)
			(xy 341.35963 -226.157064) (xy 341.289327 -226.162274) (xy 341.25408 -226.162616) (xy 341.21896 -226.162264)
			(xy 341.148912 -226.157051) (xy 341.114126 -226.152202) (xy 341.103701 -226.176388) (xy 341.076772 -226.221649)
			(xy 341.043478 -226.262456) (xy 341.004541 -226.297919) (xy 340.96081 -226.327267) (xy 340.913237 -226.349862)
			(xy 340.862857 -226.36521) (xy 340.810767 -226.372979) (xy 340.784434 -226.373436) (xy 340.756446 -226.372919)
			(xy 340.701159 -226.364167) (xy 340.647921 -226.346875) (xy 340.598044 -226.321467) (xy 340.552756 -226.288569)
			(xy 340.513171 -226.248992) (xy 340.480266 -226.203709) (xy 340.454849 -226.153836) (xy 340.437547 -226.100602)
			(xy 340.428786 -226.045316) (xy 340.428326 -226.017328) (xy 340.428326 -226.017074) (xy 340.428676 -225.994471)
			(xy 340.43441 -225.94963) (xy 340.439756 -225.927666) (xy 340.441774 -225.917867) (xy 340.438992 -225.898077)
			(xy 340.428878 -225.880839) (xy 340.41296 -225.868755) (xy 340.403434 -225.86569) (xy 340.38407 -225.860673)
			(xy 340.345584 -225.84975) (xy 340.326472 -225.843846) (xy 340.312137 -225.839829) (xy 340.282382 -225.839369)
			(xy 340.25376 -225.847508) (xy 340.228699 -225.863555) (xy 340.20933 -225.886146) (xy 340.197297 -225.913362)
			(xy 340.193623 -225.942892) (xy 340.195662 -225.957638) (xy 340.198035 -225.972447) (xy 340.200582 -226.002331)
			(xy 340.200742 -226.017328) (xy 340.200191 -226.045311) (xy 340.191433 -226.100586) (xy 340.174136 -226.153812)
			(xy 340.148727 -226.203677) (xy 340.115831 -226.248953) (xy 340.076258 -226.288527) (xy 340.030982 -226.321424)
			(xy 339.981117 -226.346834) (xy 339.927892 -226.364131) (xy 339.872617 -226.372891) (xy 339.844634 -226.373436)
			(xy 339.8183 -226.372965) (xy 339.766204 -226.365215) (xy 339.715817 -226.349879) (xy 339.668238 -226.327291)
			(xy 339.624503 -226.297944) (xy 339.585565 -226.262478) (xy 339.552274 -226.221665) (xy 339.525355 -226.176395)
			(xy 339.514942 -226.152202) (xy 339.481286 -226.156838) (xy 339.413531 -226.16192) (xy 339.37956 -226.162362)
			(xy 339.37956 -226.472242) (xy 339.423502 -226.478338) (xy 339.450061 -226.482507) (xy 339.5016 -226.497795)
			(xy 339.550257 -226.520655) (xy 339.594924 -226.550569) (xy 339.634588 -226.586857) (xy 339.668347 -226.628695)
			(xy 339.695433 -226.675131) (xy 339.715233 -226.725111) (xy 339.727295 -226.7775) (xy 339.731346 -226.831106)
			(xy 339.729328 -226.857793) (xy 339.958924 -226.857793) (xy 339.958924 -226.804495) (xy 339.966867 -226.751791)
			(xy 339.982577 -226.700861) (xy 340.005703 -226.65284) (xy 340.035727 -226.608803) (xy 340.071979 -226.569732)
			(xy 340.11365 -226.536501) (xy 340.159808 -226.509852) (xy 340.209422 -226.49038) (xy 340.261384 -226.47852)
			(xy 340.314534 -226.474537) (xy 340.367684 -226.47852) (xy 340.419646 -226.49038) (xy 340.46926 -226.509852)
			(xy 340.515418 -226.536501) (xy 340.557089 -226.569732) (xy 340.593341 -226.608803) (xy 340.623365 -226.65284)
			(xy 340.646491 -226.700861) (xy 340.662201 -226.751791) (xy 340.670144 -226.804495) (xy 340.670642 -226.831144)
			(xy 340.670144 -226.857793) (xy 340.898724 -226.857793) (xy 340.898724 -226.804495) (xy 340.906667 -226.751791)
			(xy 340.922377 -226.700861) (xy 340.945503 -226.65284) (xy 340.975527 -226.608803) (xy 341.011779 -226.569732)
			(xy 341.05345 -226.536501) (xy 341.099608 -226.509852) (xy 341.149222 -226.49038) (xy 341.201184 -226.47852)
			(xy 341.254334 -226.474537) (xy 341.307484 -226.47852) (xy 341.359446 -226.49038) (xy 341.40906 -226.509852)
			(xy 341.455218 -226.536501) (xy 341.496889 -226.569732) (xy 341.533141 -226.608803) (xy 341.563165 -226.65284)
			(xy 341.586291 -226.700861) (xy 341.602001 -226.751791) (xy 341.609944 -226.804495) (xy 341.610442 -226.831144)
			(xy 341.609944 -226.857793) (xy 341.83827 -226.857793) (xy 341.83827 -226.804495) (xy 341.846213 -226.751791)
			(xy 341.861923 -226.700861) (xy 341.885049 -226.65284) (xy 341.915073 -226.608803) (xy 341.951325 -226.569732)
			(xy 341.992996 -226.536501) (xy 342.039154 -226.509852) (xy 342.088768 -226.49038) (xy 342.14073 -226.47852)
			(xy 342.19388 -226.474537) (xy 342.24703 -226.47852) (xy 342.298992 -226.49038) (xy 342.348606 -226.509852)
			(xy 342.394764 -226.536501) (xy 342.436435 -226.569732) (xy 342.472687 -226.608803) (xy 342.502711 -226.65284)
			(xy 342.525837 -226.700861) (xy 342.541547 -226.751791) (xy 342.54949 -226.804495) (xy 342.549988 -226.831144)
			(xy 342.54949 -226.857793) (xy 342.77807 -226.857793) (xy 342.77807 -226.804495) (xy 342.786013 -226.751791)
			(xy 342.801723 -226.700861) (xy 342.824849 -226.65284) (xy 342.854873 -226.608803) (xy 342.891125 -226.569732)
			(xy 342.932796 -226.536501) (xy 342.978954 -226.509852) (xy 343.028568 -226.49038) (xy 343.08053 -226.47852)
			(xy 343.13368 -226.474537) (xy 343.18683 -226.47852) (xy 343.238792 -226.49038) (xy 343.288406 -226.509852)
			(xy 343.334564 -226.536501) (xy 343.376235 -226.569732) (xy 343.412487 -226.608803) (xy 343.442511 -226.65284)
			(xy 343.465637 -226.700861) (xy 343.481347 -226.751791) (xy 343.48929 -226.804495) (xy 343.489788 -226.831144)
			(xy 343.48929 -226.857793) (xy 343.718124 -226.857793) (xy 343.718124 -226.804495) (xy 343.726067 -226.751791)
			(xy 343.741777 -226.700861) (xy 343.764903 -226.65284) (xy 343.794927 -226.608803) (xy 343.831179 -226.569732)
			(xy 343.87285 -226.536501) (xy 343.919008 -226.509852) (xy 343.968622 -226.49038) (xy 344.020584 -226.47852)
			(xy 344.073734 -226.474537) (xy 344.126884 -226.47852) (xy 344.178846 -226.49038) (xy 344.22846 -226.509852)
			(xy 344.274618 -226.536501) (xy 344.316289 -226.569732) (xy 344.352541 -226.608803) (xy 344.382565 -226.65284)
			(xy 344.405691 -226.700861) (xy 344.421401 -226.751791) (xy 344.429344 -226.804495) (xy 344.429842 -226.831144)
			(xy 344.429344 -226.857793) (xy 344.65767 -226.857793) (xy 344.65767 -226.804495) (xy 344.665613 -226.751791)
			(xy 344.681323 -226.700861) (xy 344.704449 -226.65284) (xy 344.734473 -226.608803) (xy 344.770725 -226.569732)
			(xy 344.812396 -226.536501) (xy 344.858554 -226.509852) (xy 344.908168 -226.49038) (xy 344.96013 -226.47852)
			(xy 345.01328 -226.474537) (xy 345.06643 -226.47852) (xy 345.118392 -226.49038) (xy 345.168006 -226.509852)
			(xy 345.214164 -226.536501) (xy 345.255835 -226.569732) (xy 345.292087 -226.608803) (xy 345.322111 -226.65284)
			(xy 345.345237 -226.700861) (xy 345.360947 -226.751791) (xy 345.36889 -226.804495) (xy 345.369388 -226.831144)
			(xy 345.36889 -226.857793) (xy 345.59747 -226.857793) (xy 345.59747 -226.804495) (xy 345.605413 -226.751791)
			(xy 345.621123 -226.700861) (xy 345.644249 -226.65284) (xy 345.674273 -226.608803) (xy 345.710525 -226.569732)
			(xy 345.752196 -226.536501) (xy 345.798354 -226.509852) (xy 345.847968 -226.49038) (xy 345.89993 -226.47852)
			(xy 345.95308 -226.474537) (xy 346.00623 -226.47852) (xy 346.058192 -226.49038) (xy 346.107806 -226.509852)
			(xy 346.153964 -226.536501) (xy 346.195635 -226.569732) (xy 346.231887 -226.608803) (xy 346.261911 -226.65284)
			(xy 346.285037 -226.700861) (xy 346.300747 -226.751791) (xy 346.30869 -226.804495) (xy 346.309188 -226.831144)
			(xy 346.30869 -226.857793) (xy 346.537524 -226.857793) (xy 346.537524 -226.804495) (xy 346.545467 -226.751791)
			(xy 346.561177 -226.700861) (xy 346.584303 -226.65284) (xy 346.614327 -226.608803) (xy 346.650579 -226.569732)
			(xy 346.69225 -226.536501) (xy 346.738408 -226.509852) (xy 346.788022 -226.49038) (xy 346.839984 -226.47852)
			(xy 346.893134 -226.474537) (xy 346.946284 -226.47852) (xy 346.998246 -226.49038) (xy 347.04786 -226.509852)
			(xy 347.094018 -226.536501) (xy 347.135689 -226.569732) (xy 347.171941 -226.608803) (xy 347.201965 -226.65284)
			(xy 347.225091 -226.700861) (xy 347.240801 -226.751791) (xy 347.248744 -226.804495) (xy 347.249242 -226.831144)
			(xy 347.248744 -226.857793) (xy 347.477324 -226.857793) (xy 347.477324 -226.804495) (xy 347.485267 -226.751791)
			(xy 347.500977 -226.700861) (xy 347.524103 -226.65284) (xy 347.554127 -226.608803) (xy 347.590379 -226.569732)
			(xy 347.63205 -226.536501) (xy 347.678208 -226.509852) (xy 347.727822 -226.49038) (xy 347.779784 -226.47852)
			(xy 347.832934 -226.474537) (xy 347.886084 -226.47852) (xy 347.938046 -226.49038) (xy 347.98766 -226.509852)
			(xy 348.033818 -226.536501) (xy 348.075489 -226.569732) (xy 348.111741 -226.608803) (xy 348.141765 -226.65284)
			(xy 348.164891 -226.700861) (xy 348.180601 -226.751791) (xy 348.188544 -226.804495) (xy 348.189042 -226.831144)
			(xy 348.188544 -226.857793) (xy 348.417124 -226.857793) (xy 348.417124 -226.804495) (xy 348.425067 -226.751791)
			(xy 348.440777 -226.700861) (xy 348.463903 -226.65284) (xy 348.493927 -226.608803) (xy 348.530179 -226.569732)
			(xy 348.57185 -226.536501) (xy 348.618008 -226.509852) (xy 348.667622 -226.49038) (xy 348.719584 -226.47852)
			(xy 348.772734 -226.474537) (xy 348.825884 -226.47852) (xy 348.877846 -226.49038) (xy 348.92746 -226.509852)
			(xy 348.973618 -226.536501) (xy 349.015289 -226.569732) (xy 349.051541 -226.608803) (xy 349.081565 -226.65284)
			(xy 349.104691 -226.700861) (xy 349.120401 -226.751791) (xy 349.128344 -226.804495) (xy 349.128842 -226.831144)
			(xy 349.128344 -226.857793) (xy 349.35667 -226.857793) (xy 349.35667 -226.804495) (xy 349.364613 -226.751791)
			(xy 349.380323 -226.700861) (xy 349.403449 -226.65284) (xy 349.433473 -226.608803) (xy 349.469725 -226.569732)
			(xy 349.511396 -226.536501) (xy 349.557554 -226.509852) (xy 349.607168 -226.49038) (xy 349.65913 -226.47852)
			(xy 349.71228 -226.474537) (xy 349.76543 -226.47852) (xy 349.817392 -226.49038) (xy 349.867006 -226.509852)
			(xy 349.913164 -226.536501) (xy 349.954835 -226.569732) (xy 349.991087 -226.608803) (xy 350.021111 -226.65284)
			(xy 350.044237 -226.700861) (xy 350.059947 -226.751791) (xy 350.06789 -226.804495) (xy 350.068388 -226.831144)
			(xy 350.06789 -226.857793) (xy 350.29647 -226.857793) (xy 350.29647 -226.804495) (xy 350.304413 -226.751791)
			(xy 350.320123 -226.700861) (xy 350.343249 -226.65284) (xy 350.373273 -226.608803) (xy 350.409525 -226.569732)
			(xy 350.451196 -226.536501) (xy 350.497354 -226.509852) (xy 350.546968 -226.49038) (xy 350.59893 -226.47852)
			(xy 350.65208 -226.474537) (xy 350.70523 -226.47852) (xy 350.757192 -226.49038) (xy 350.806806 -226.509852)
			(xy 350.852964 -226.536501) (xy 350.894635 -226.569732) (xy 350.930887 -226.608803) (xy 350.960911 -226.65284)
			(xy 350.984037 -226.700861) (xy 350.999747 -226.751791) (xy 351.00769 -226.804495) (xy 351.008188 -226.831144)
			(xy 351.00769 -226.857793) (xy 351.236524 -226.857793) (xy 351.236524 -226.804495) (xy 351.244467 -226.751791)
			(xy 351.260177 -226.700861) (xy 351.283303 -226.65284) (xy 351.313327 -226.608803) (xy 351.349579 -226.569732)
			(xy 351.39125 -226.536501) (xy 351.437408 -226.509852) (xy 351.487022 -226.49038) (xy 351.538984 -226.47852)
			(xy 351.592134 -226.474537) (xy 351.645284 -226.47852) (xy 351.697246 -226.49038) (xy 351.74686 -226.509852)
			(xy 351.793018 -226.536501) (xy 351.834689 -226.569732) (xy 351.870941 -226.608803) (xy 351.900965 -226.65284)
			(xy 351.924091 -226.700861) (xy 351.939801 -226.751791) (xy 351.947744 -226.804495) (xy 351.948242 -226.831144)
			(xy 351.947744 -226.857793) (xy 352.176324 -226.857793) (xy 352.176324 -226.804495) (xy 352.184267 -226.751791)
			(xy 352.199977 -226.700861) (xy 352.223103 -226.65284) (xy 352.253127 -226.608803) (xy 352.289379 -226.569732)
			(xy 352.33105 -226.536501) (xy 352.377208 -226.509852) (xy 352.426822 -226.49038) (xy 352.478784 -226.47852)
			(xy 352.531934 -226.474537) (xy 352.585084 -226.47852) (xy 352.637046 -226.49038) (xy 352.68666 -226.509852)
			(xy 352.732818 -226.536501) (xy 352.774489 -226.569732) (xy 352.810741 -226.608803) (xy 352.840765 -226.65284)
			(xy 352.863891 -226.700861) (xy 352.879601 -226.751791) (xy 352.887544 -226.804495) (xy 352.888042 -226.831144)
			(xy 352.887544 -226.857793) (xy 353.11587 -226.857793) (xy 353.11587 -226.804495) (xy 353.123813 -226.751791)
			(xy 353.139523 -226.700861) (xy 353.162649 -226.65284) (xy 353.192673 -226.608803) (xy 353.228925 -226.569732)
			(xy 353.270596 -226.536501) (xy 353.316754 -226.509852) (xy 353.366368 -226.49038) (xy 353.41833 -226.47852)
			(xy 353.47148 -226.474537) (xy 353.52463 -226.47852) (xy 353.576592 -226.49038) (xy 353.626206 -226.509852)
			(xy 353.672364 -226.536501) (xy 353.714035 -226.569732) (xy 353.750287 -226.608803) (xy 353.780311 -226.65284)
			(xy 353.803437 -226.700861) (xy 353.819147 -226.751791) (xy 353.82709 -226.804495) (xy 353.827588 -226.831144)
			(xy 353.82709 -226.857793) (xy 354.055924 -226.857793) (xy 354.055924 -226.804495) (xy 354.063867 -226.751791)
			(xy 354.079577 -226.700861) (xy 354.102703 -226.65284) (xy 354.132727 -226.608803) (xy 354.168979 -226.569732)
			(xy 354.21065 -226.536501) (xy 354.256808 -226.509852) (xy 354.306422 -226.49038) (xy 354.358384 -226.47852)
			(xy 354.411534 -226.474537) (xy 354.464684 -226.47852) (xy 354.516646 -226.49038) (xy 354.56626 -226.509852)
			(xy 354.612418 -226.536501) (xy 354.654089 -226.569732) (xy 354.690341 -226.608803) (xy 354.720365 -226.65284)
			(xy 354.743491 -226.700861) (xy 354.759201 -226.751791) (xy 354.767144 -226.804495) (xy 354.767642 -226.831144)
			(xy 354.767144 -226.857793) (xy 354.99547 -226.857793) (xy 354.99547 -226.804495) (xy 355.003413 -226.751791)
			(xy 355.019123 -226.700861) (xy 355.042249 -226.65284) (xy 355.072273 -226.608803) (xy 355.108525 -226.569732)
			(xy 355.150196 -226.536501) (xy 355.196354 -226.509852) (xy 355.245968 -226.49038) (xy 355.29793 -226.47852)
			(xy 355.35108 -226.474537) (xy 355.40423 -226.47852) (xy 355.456192 -226.49038) (xy 355.505806 -226.509852)
			(xy 355.551964 -226.536501) (xy 355.593635 -226.569732) (xy 355.629887 -226.608803) (xy 355.659911 -226.65284)
			(xy 355.683037 -226.700861) (xy 355.698747 -226.751791) (xy 355.70669 -226.804495) (xy 355.707188 -226.831144)
			(xy 355.70669 -226.857793) (xy 355.935524 -226.857793) (xy 355.935524 -226.804495) (xy 355.943467 -226.751791)
			(xy 355.959177 -226.700861) (xy 355.982303 -226.65284) (xy 356.012327 -226.608803) (xy 356.048579 -226.569732)
			(xy 356.09025 -226.536501) (xy 356.136408 -226.509852) (xy 356.186022 -226.49038) (xy 356.237984 -226.47852)
			(xy 356.291134 -226.474537) (xy 356.344284 -226.47852) (xy 356.396246 -226.49038) (xy 356.44586 -226.509852)
			(xy 356.492018 -226.536501) (xy 356.533689 -226.569732) (xy 356.569941 -226.608803) (xy 356.599965 -226.65284)
			(xy 356.623091 -226.700861) (xy 356.638801 -226.751791) (xy 356.646744 -226.804495) (xy 356.647242 -226.831144)
			(xy 356.646744 -226.857793) (xy 356.87507 -226.857793) (xy 356.87507 -226.804495) (xy 356.883013 -226.751791)
			(xy 356.898723 -226.700861) (xy 356.921849 -226.65284) (xy 356.951873 -226.608803) (xy 356.988125 -226.569732)
			(xy 357.029796 -226.536501) (xy 357.075954 -226.509852) (xy 357.125568 -226.49038) (xy 357.17753 -226.47852)
			(xy 357.23068 -226.474537) (xy 357.28383 -226.47852) (xy 357.335792 -226.49038) (xy 357.385406 -226.509852)
			(xy 357.431564 -226.536501) (xy 357.473235 -226.569732) (xy 357.509487 -226.608803) (xy 357.539511 -226.65284)
			(xy 357.562637 -226.700861) (xy 357.578347 -226.751791) (xy 357.58629 -226.804495) (xy 357.586788 -226.831144)
			(xy 357.58629 -226.857793) (xy 357.815124 -226.857793) (xy 357.815124 -226.804495) (xy 357.823067 -226.751791)
			(xy 357.838777 -226.700861) (xy 357.861903 -226.65284) (xy 357.891927 -226.608803) (xy 357.928179 -226.569732)
			(xy 357.96985 -226.536501) (xy 358.016008 -226.509852) (xy 358.065622 -226.49038) (xy 358.117584 -226.47852)
			(xy 358.170734 -226.474537) (xy 358.223884 -226.47852) (xy 358.275846 -226.49038) (xy 358.32546 -226.509852)
			(xy 358.371618 -226.536501) (xy 358.413289 -226.569732) (xy 358.449541 -226.608803) (xy 358.479565 -226.65284)
			(xy 358.502691 -226.700861) (xy 358.518401 -226.751791) (xy 358.526344 -226.804495) (xy 358.526842 -226.831144)
			(xy 358.526344 -226.857793) (xy 358.75467 -226.857793) (xy 358.75467 -226.804495) (xy 358.762613 -226.751791)
			(xy 358.778323 -226.700861) (xy 358.801449 -226.65284) (xy 358.831473 -226.608803) (xy 358.867725 -226.569732)
			(xy 358.909396 -226.536501) (xy 358.955554 -226.509852) (xy 359.005168 -226.49038) (xy 359.05713 -226.47852)
			(xy 359.11028 -226.474537) (xy 359.16343 -226.47852) (xy 359.215392 -226.49038) (xy 359.265006 -226.509852)
			(xy 359.311164 -226.536501) (xy 359.352835 -226.569732) (xy 359.389087 -226.608803) (xy 359.419111 -226.65284)
			(xy 359.442237 -226.700861) (xy 359.457947 -226.751791) (xy 359.46589 -226.804495) (xy 359.466388 -226.831144)
			(xy 359.46589 -226.857793) (xy 359.694724 -226.857793) (xy 359.694724 -226.804495) (xy 359.702667 -226.751791)
			(xy 359.718377 -226.700861) (xy 359.741503 -226.65284) (xy 359.771527 -226.608803) (xy 359.807779 -226.569732)
			(xy 359.84945 -226.536501) (xy 359.895608 -226.509852) (xy 359.945222 -226.49038) (xy 359.997184 -226.47852)
			(xy 360.050334 -226.474537) (xy 360.103484 -226.47852) (xy 360.155446 -226.49038) (xy 360.20506 -226.509852)
			(xy 360.251218 -226.536501) (xy 360.292889 -226.569732) (xy 360.329141 -226.608803) (xy 360.359165 -226.65284)
			(xy 360.382291 -226.700861) (xy 360.398001 -226.751791) (xy 360.405944 -226.804495) (xy 360.406442 -226.831144)
			(xy 360.405944 -226.857793) (xy 360.63427 -226.857793) (xy 360.63427 -226.804495) (xy 360.642213 -226.751791)
			(xy 360.657923 -226.700861) (xy 360.681049 -226.65284) (xy 360.711073 -226.608803) (xy 360.747325 -226.569732)
			(xy 360.788996 -226.536501) (xy 360.835154 -226.509852) (xy 360.884768 -226.49038) (xy 360.93673 -226.47852)
			(xy 360.98988 -226.474537) (xy 361.04303 -226.47852) (xy 361.094992 -226.49038) (xy 361.144606 -226.509852)
			(xy 361.190764 -226.536501) (xy 361.232435 -226.569732) (xy 361.268687 -226.608803) (xy 361.298711 -226.65284)
			(xy 361.321837 -226.700861) (xy 361.337547 -226.751791) (xy 361.34549 -226.804495) (xy 361.345988 -226.831144)
			(xy 361.34549 -226.857793) (xy 361.574324 -226.857793) (xy 361.574324 -226.804495) (xy 361.582267 -226.751791)
			(xy 361.597977 -226.700861) (xy 361.621103 -226.65284) (xy 361.651127 -226.608803) (xy 361.687379 -226.569732)
			(xy 361.72905 -226.536501) (xy 361.775208 -226.509852) (xy 361.824822 -226.49038) (xy 361.876784 -226.47852)
			(xy 361.929934 -226.474537) (xy 361.983084 -226.47852) (xy 362.035046 -226.49038) (xy 362.08466 -226.509852)
			(xy 362.130818 -226.536501) (xy 362.172489 -226.569732) (xy 362.208741 -226.608803) (xy 362.238765 -226.65284)
			(xy 362.261891 -226.700861) (xy 362.277601 -226.751791) (xy 362.285544 -226.804495) (xy 362.286042 -226.831144)
			(xy 362.285544 -226.857793) (xy 362.514124 -226.857793) (xy 362.514124 -226.804495) (xy 362.522067 -226.751791)
			(xy 362.537777 -226.700861) (xy 362.560903 -226.65284) (xy 362.590927 -226.608803) (xy 362.627179 -226.569732)
			(xy 362.66885 -226.536501) (xy 362.715008 -226.509852) (xy 362.764622 -226.49038) (xy 362.816584 -226.47852)
			(xy 362.869734 -226.474537) (xy 362.922884 -226.47852) (xy 362.974846 -226.49038) (xy 363.02446 -226.509852)
			(xy 363.070618 -226.536501) (xy 363.112289 -226.569732) (xy 363.148541 -226.608803) (xy 363.178565 -226.65284)
			(xy 363.201691 -226.700861) (xy 363.217401 -226.751791) (xy 363.225344 -226.804495) (xy 363.225842 -226.831144)
			(xy 363.225344 -226.857793) (xy 363.453924 -226.857793) (xy 363.453924 -226.804495) (xy 363.461867 -226.751791)
			(xy 363.477577 -226.700861) (xy 363.500703 -226.65284) (xy 363.530727 -226.608803) (xy 363.566979 -226.569732)
			(xy 363.60865 -226.536501) (xy 363.654808 -226.509852) (xy 363.704422 -226.49038) (xy 363.756384 -226.47852)
			(xy 363.809534 -226.474537) (xy 363.862684 -226.47852) (xy 363.914646 -226.49038) (xy 363.96426 -226.509852)
			(xy 364.010418 -226.536501) (xy 364.052089 -226.569732) (xy 364.088341 -226.608803) (xy 364.118365 -226.65284)
			(xy 364.141491 -226.700861) (xy 364.157201 -226.751791) (xy 364.165144 -226.804495) (xy 364.165642 -226.831144)
			(xy 364.165144 -226.857793) (xy 364.39347 -226.857793) (xy 364.39347 -226.804495) (xy 364.401413 -226.751791)
			(xy 364.417123 -226.700861) (xy 364.440249 -226.65284) (xy 364.470273 -226.608803) (xy 364.506525 -226.569732)
			(xy 364.548196 -226.536501) (xy 364.594354 -226.509852) (xy 364.643968 -226.49038) (xy 364.69593 -226.47852)
			(xy 364.74908 -226.474537) (xy 364.80223 -226.47852) (xy 364.854192 -226.49038) (xy 364.903806 -226.509852)
			(xy 364.949964 -226.536501) (xy 364.991635 -226.569732) (xy 365.027887 -226.608803) (xy 365.057911 -226.65284)
			(xy 365.081037 -226.700861) (xy 365.096747 -226.751791) (xy 365.10469 -226.804495) (xy 365.105188 -226.831144)
			(xy 365.10469 -226.857793) (xy 365.333524 -226.857793) (xy 365.333524 -226.804495) (xy 365.341467 -226.751791)
			(xy 365.357177 -226.700861) (xy 365.380303 -226.65284) (xy 365.410327 -226.608803) (xy 365.446579 -226.569732)
			(xy 365.48825 -226.536501) (xy 365.534408 -226.509852) (xy 365.584022 -226.49038) (xy 365.635984 -226.47852)
			(xy 365.689134 -226.474537) (xy 365.742284 -226.47852) (xy 365.794246 -226.49038) (xy 365.84386 -226.509852)
			(xy 365.890018 -226.536501) (xy 365.931689 -226.569732) (xy 365.967941 -226.608803) (xy 365.997965 -226.65284)
			(xy 366.021091 -226.700861) (xy 366.036801 -226.751791) (xy 366.044744 -226.804495) (xy 366.045242 -226.831144)
			(xy 366.044744 -226.857793) (xy 366.27307 -226.857793) (xy 366.27307 -226.804495) (xy 366.281013 -226.751791)
			(xy 366.296723 -226.700861) (xy 366.319849 -226.65284) (xy 366.349873 -226.608803) (xy 366.386125 -226.569732)
			(xy 366.427796 -226.536501) (xy 366.473954 -226.509852) (xy 366.523568 -226.49038) (xy 366.57553 -226.47852)
			(xy 366.62868 -226.474537) (xy 366.68183 -226.47852) (xy 366.733792 -226.49038) (xy 366.783406 -226.509852)
			(xy 366.829564 -226.536501) (xy 366.871235 -226.569732) (xy 366.907487 -226.608803) (xy 366.937511 -226.65284)
			(xy 366.960637 -226.700861) (xy 366.976347 -226.751791) (xy 366.98429 -226.804495) (xy 366.984788 -226.831144)
			(xy 366.98429 -226.857793) (xy 367.213124 -226.857793) (xy 367.213124 -226.804495) (xy 367.221067 -226.751791)
			(xy 367.236777 -226.700861) (xy 367.259903 -226.65284) (xy 367.289927 -226.608803) (xy 367.326179 -226.569732)
			(xy 367.36785 -226.536501) (xy 367.414008 -226.509852) (xy 367.463622 -226.49038) (xy 367.515584 -226.47852)
			(xy 367.568734 -226.474537) (xy 367.621884 -226.47852) (xy 367.673846 -226.49038) (xy 367.72346 -226.509852)
			(xy 367.769618 -226.536501) (xy 367.811289 -226.569732) (xy 367.847541 -226.608803) (xy 367.877565 -226.65284)
			(xy 367.900691 -226.700861) (xy 367.916401 -226.751791) (xy 367.924344 -226.804495) (xy 367.924842 -226.831144)
			(xy 367.924344 -226.857793) (xy 368.15267 -226.857793) (xy 368.15267 -226.804495) (xy 368.160613 -226.751791)
			(xy 368.176323 -226.700861) (xy 368.199449 -226.65284) (xy 368.229473 -226.608803) (xy 368.265725 -226.569732)
			(xy 368.307396 -226.536501) (xy 368.353554 -226.509852) (xy 368.403168 -226.49038) (xy 368.45513 -226.47852)
			(xy 368.50828 -226.474537) (xy 368.56143 -226.47852) (xy 368.613392 -226.49038) (xy 368.663006 -226.509852)
			(xy 368.709164 -226.536501) (xy 368.750835 -226.569732) (xy 368.787087 -226.608803) (xy 368.817111 -226.65284)
			(xy 368.840237 -226.700861) (xy 368.855947 -226.751791) (xy 368.86389 -226.804495) (xy 368.864388 -226.831144)
			(xy 368.86389 -226.857793) (xy 369.092724 -226.857793) (xy 369.092724 -226.804495) (xy 369.100667 -226.751791)
			(xy 369.116377 -226.700861) (xy 369.139503 -226.65284) (xy 369.169527 -226.608803) (xy 369.205779 -226.569732)
			(xy 369.24745 -226.536501) (xy 369.293608 -226.509852) (xy 369.343222 -226.49038) (xy 369.395184 -226.47852)
			(xy 369.448334 -226.474537) (xy 369.501484 -226.47852) (xy 369.553446 -226.49038) (xy 369.60306 -226.509852)
			(xy 369.649218 -226.536501) (xy 369.690889 -226.569732) (xy 369.727141 -226.608803) (xy 369.757165 -226.65284)
			(xy 369.780291 -226.700861) (xy 369.796001 -226.751791) (xy 369.803944 -226.804495) (xy 369.804442 -226.831144)
			(xy 369.803944 -226.857793) (xy 370.03227 -226.857793) (xy 370.03227 -226.804495) (xy 370.040213 -226.751791)
			(xy 370.055923 -226.700861) (xy 370.079049 -226.65284) (xy 370.109073 -226.608803) (xy 370.145325 -226.569732)
			(xy 370.186996 -226.536501) (xy 370.233154 -226.509852) (xy 370.282768 -226.49038) (xy 370.33473 -226.47852)
			(xy 370.38788 -226.474537) (xy 370.44103 -226.47852) (xy 370.492992 -226.49038) (xy 370.542606 -226.509852)
			(xy 370.588764 -226.536501) (xy 370.630435 -226.569732) (xy 370.666687 -226.608803) (xy 370.696711 -226.65284)
			(xy 370.719837 -226.700861) (xy 370.735547 -226.751791) (xy 370.74349 -226.804495) (xy 370.743988 -226.831144)
			(xy 370.74349 -226.857793) (xy 370.97207 -226.857793) (xy 370.97207 -226.804495) (xy 370.980013 -226.751791)
			(xy 370.995723 -226.700861) (xy 371.018849 -226.65284) (xy 371.048873 -226.608803) (xy 371.085125 -226.569732)
			(xy 371.126796 -226.536501) (xy 371.172954 -226.509852) (xy 371.222568 -226.49038) (xy 371.27453 -226.47852)
			(xy 371.32768 -226.474537) (xy 371.38083 -226.47852) (xy 371.432792 -226.49038) (xy 371.482406 -226.509852)
			(xy 371.528564 -226.536501) (xy 371.570235 -226.569732) (xy 371.606487 -226.608803) (xy 371.636511 -226.65284)
			(xy 371.659637 -226.700861) (xy 371.675347 -226.751791) (xy 371.68329 -226.804495) (xy 371.683788 -226.831144)
			(xy 371.68329 -226.857793) (xy 371.912124 -226.857793) (xy 371.912124 -226.804495) (xy 371.920067 -226.751791)
			(xy 371.935777 -226.700861) (xy 371.958903 -226.65284) (xy 371.988927 -226.608803) (xy 372.025179 -226.569732)
			(xy 372.06685 -226.536501) (xy 372.113008 -226.509852) (xy 372.162622 -226.49038) (xy 372.214584 -226.47852)
			(xy 372.267734 -226.474537) (xy 372.320884 -226.47852) (xy 372.372846 -226.49038) (xy 372.42246 -226.509852)
			(xy 372.468618 -226.536501) (xy 372.510289 -226.569732) (xy 372.546541 -226.608803) (xy 372.576565 -226.65284)
			(xy 372.599691 -226.700861) (xy 372.615401 -226.751791) (xy 372.623344 -226.804495) (xy 372.623842 -226.831144)
			(xy 372.623344 -226.857793) (xy 372.85167 -226.857793) (xy 372.85167 -226.804495) (xy 372.859613 -226.751791)
			(xy 372.875323 -226.700861) (xy 372.898449 -226.65284) (xy 372.928473 -226.608803) (xy 372.964725 -226.569732)
			(xy 373.006396 -226.536501) (xy 373.052554 -226.509852) (xy 373.102168 -226.49038) (xy 373.15413 -226.47852)
			(xy 373.20728 -226.474537) (xy 373.26043 -226.47852) (xy 373.312392 -226.49038) (xy 373.362006 -226.509852)
			(xy 373.408164 -226.536501) (xy 373.449835 -226.569732) (xy 373.486087 -226.608803) (xy 373.516111 -226.65284)
			(xy 373.539237 -226.700861) (xy 373.554947 -226.751791) (xy 373.56289 -226.804495) (xy 373.563388 -226.831144)
			(xy 373.56289 -226.857793) (xy 373.79147 -226.857793) (xy 373.79147 -226.804495) (xy 373.799413 -226.751791)
			(xy 373.815123 -226.700861) (xy 373.838249 -226.65284) (xy 373.868273 -226.608803) (xy 373.904525 -226.569732)
			(xy 373.946196 -226.536501) (xy 373.992354 -226.509852) (xy 374.041968 -226.49038) (xy 374.09393 -226.47852)
			(xy 374.14708 -226.474537) (xy 374.20023 -226.47852) (xy 374.252192 -226.49038) (xy 374.301806 -226.509852)
			(xy 374.347964 -226.536501) (xy 374.389635 -226.569732) (xy 374.425887 -226.608803) (xy 374.455911 -226.65284)
			(xy 374.479037 -226.700861) (xy 374.494747 -226.751791) (xy 374.50269 -226.804495) (xy 374.503188 -226.831144)
			(xy 374.50269 -226.857793) (xy 374.731524 -226.857793) (xy 374.731524 -226.804495) (xy 374.739467 -226.751791)
			(xy 374.755177 -226.700861) (xy 374.778303 -226.65284) (xy 374.808327 -226.608803) (xy 374.844579 -226.569732)
			(xy 374.88625 -226.536501) (xy 374.932408 -226.509852) (xy 374.982022 -226.49038) (xy 375.033984 -226.47852)
			(xy 375.087134 -226.474537) (xy 375.140284 -226.47852) (xy 375.192246 -226.49038) (xy 375.24186 -226.509852)
			(xy 375.288018 -226.536501) (xy 375.329689 -226.569732) (xy 375.365941 -226.608803) (xy 375.395965 -226.65284)
			(xy 375.419091 -226.700861) (xy 375.434801 -226.751791) (xy 375.442744 -226.804495) (xy 375.443242 -226.831144)
			(xy 375.442744 -226.857793) (xy 375.434801 -226.910497) (xy 375.419091 -226.961427) (xy 375.395965 -227.009448)
			(xy 375.365941 -227.053485) (xy 375.329689 -227.092556) (xy 375.288018 -227.125787) (xy 375.24186 -227.152436)
			(xy 375.192246 -227.171908) (xy 375.140284 -227.183768) (xy 375.087134 -227.187752) (xy 375.033984 -227.183768)
			(xy 374.982022 -227.171908) (xy 374.932408 -227.152436) (xy 374.88625 -227.125787) (xy 374.844579 -227.092556)
			(xy 374.808327 -227.053485) (xy 374.778303 -227.009448) (xy 374.755177 -226.961427) (xy 374.739467 -226.910497)
			(xy 374.731524 -226.857793) (xy 374.50269 -226.857793) (xy 374.494747 -226.910497) (xy 374.479037 -226.961427)
			(xy 374.455911 -227.009448) (xy 374.425887 -227.053485) (xy 374.389635 -227.092556) (xy 374.347964 -227.125787)
			(xy 374.301806 -227.152436) (xy 374.252192 -227.171908) (xy 374.20023 -227.183768) (xy 374.14708 -227.187752)
			(xy 374.09393 -227.183768) (xy 374.041968 -227.171908) (xy 373.992354 -227.152436) (xy 373.946196 -227.125787)
			(xy 373.904525 -227.092556) (xy 373.868273 -227.053485) (xy 373.838249 -227.009448) (xy 373.815123 -226.961427)
			(xy 373.799413 -226.910497) (xy 373.79147 -226.857793) (xy 373.56289 -226.857793) (xy 373.554947 -226.910497)
			(xy 373.539237 -226.961427) (xy 373.516111 -227.009448) (xy 373.486087 -227.053485) (xy 373.449835 -227.092556)
			(xy 373.408164 -227.125787) (xy 373.362006 -227.152436) (xy 373.312392 -227.171908) (xy 373.26043 -227.183768)
			(xy 373.20728 -227.187752) (xy 373.15413 -227.183768) (xy 373.102168 -227.171908) (xy 373.052554 -227.152436)
			(xy 373.006396 -227.125787) (xy 372.964725 -227.092556) (xy 372.928473 -227.053485) (xy 372.898449 -227.009448)
			(xy 372.875323 -226.961427) (xy 372.859613 -226.910497) (xy 372.85167 -226.857793) (xy 372.623344 -226.857793)
			(xy 372.615401 -226.910497) (xy 372.599691 -226.961427) (xy 372.576565 -227.009448) (xy 372.546541 -227.053485)
			(xy 372.510289 -227.092556) (xy 372.468618 -227.125787) (xy 372.42246 -227.152436) (xy 372.372846 -227.171908)
			(xy 372.320884 -227.183768) (xy 372.267734 -227.187752) (xy 372.214584 -227.183768) (xy 372.162622 -227.171908)
			(xy 372.113008 -227.152436) (xy 372.06685 -227.125787) (xy 372.025179 -227.092556) (xy 371.988927 -227.053485)
			(xy 371.958903 -227.009448) (xy 371.935777 -226.961427) (xy 371.920067 -226.910497) (xy 371.912124 -226.857793)
			(xy 371.68329 -226.857793) (xy 371.675347 -226.910497) (xy 371.659637 -226.961427) (xy 371.636511 -227.009448)
			(xy 371.606487 -227.053485) (xy 371.570235 -227.092556) (xy 371.528564 -227.125787) (xy 371.482406 -227.152436)
			(xy 371.432792 -227.171908) (xy 371.38083 -227.183768) (xy 371.32768 -227.187752) (xy 371.27453 -227.183768)
			(xy 371.222568 -227.171908) (xy 371.172954 -227.152436) (xy 371.126796 -227.125787) (xy 371.085125 -227.092556)
			(xy 371.048873 -227.053485) (xy 371.018849 -227.009448) (xy 370.995723 -226.961427) (xy 370.980013 -226.910497)
			(xy 370.97207 -226.857793) (xy 370.74349 -226.857793) (xy 370.735547 -226.910497) (xy 370.719837 -226.961427)
			(xy 370.696711 -227.009448) (xy 370.666687 -227.053485) (xy 370.630435 -227.092556) (xy 370.588764 -227.125787)
			(xy 370.542606 -227.152436) (xy 370.492992 -227.171908) (xy 370.44103 -227.183768) (xy 370.38788 -227.187752)
			(xy 370.33473 -227.183768) (xy 370.282768 -227.171908) (xy 370.233154 -227.152436) (xy 370.186996 -227.125787)
			(xy 370.145325 -227.092556) (xy 370.109073 -227.053485) (xy 370.079049 -227.009448) (xy 370.055923 -226.961427)
			(xy 370.040213 -226.910497) (xy 370.03227 -226.857793) (xy 369.803944 -226.857793) (xy 369.796001 -226.910497)
			(xy 369.780291 -226.961427) (xy 369.757165 -227.009448) (xy 369.727141 -227.053485) (xy 369.690889 -227.092556)
			(xy 369.649218 -227.125787) (xy 369.60306 -227.152436) (xy 369.553446 -227.171908) (xy 369.501484 -227.183768)
			(xy 369.448334 -227.187752) (xy 369.395184 -227.183768) (xy 369.343222 -227.171908) (xy 369.293608 -227.152436)
			(xy 369.24745 -227.125787) (xy 369.205779 -227.092556) (xy 369.169527 -227.053485) (xy 369.139503 -227.009448)
			(xy 369.116377 -226.961427) (xy 369.100667 -226.910497) (xy 369.092724 -226.857793) (xy 368.86389 -226.857793)
			(xy 368.855947 -226.910497) (xy 368.840237 -226.961427) (xy 368.817111 -227.009448) (xy 368.787087 -227.053485)
			(xy 368.750835 -227.092556) (xy 368.709164 -227.125787) (xy 368.663006 -227.152436) (xy 368.613392 -227.171908)
			(xy 368.56143 -227.183768) (xy 368.50828 -227.187752) (xy 368.45513 -227.183768) (xy 368.403168 -227.171908)
			(xy 368.353554 -227.152436) (xy 368.307396 -227.125787) (xy 368.265725 -227.092556) (xy 368.229473 -227.053485)
			(xy 368.199449 -227.009448) (xy 368.176323 -226.961427) (xy 368.160613 -226.910497) (xy 368.15267 -226.857793)
			(xy 367.924344 -226.857793) (xy 367.916401 -226.910497) (xy 367.900691 -226.961427) (xy 367.877565 -227.009448)
			(xy 367.847541 -227.053485) (xy 367.811289 -227.092556) (xy 367.769618 -227.125787) (xy 367.72346 -227.152436)
			(xy 367.673846 -227.171908) (xy 367.621884 -227.183768) (xy 367.568734 -227.187752) (xy 367.515584 -227.183768)
			(xy 367.463622 -227.171908) (xy 367.414008 -227.152436) (xy 367.36785 -227.125787) (xy 367.326179 -227.092556)
			(xy 367.289927 -227.053485) (xy 367.259903 -227.009448) (xy 367.236777 -226.961427) (xy 367.221067 -226.910497)
			(xy 367.213124 -226.857793) (xy 366.98429 -226.857793) (xy 366.976347 -226.910497) (xy 366.960637 -226.961427)
			(xy 366.937511 -227.009448) (xy 366.907487 -227.053485) (xy 366.871235 -227.092556) (xy 366.829564 -227.125787)
			(xy 366.783406 -227.152436) (xy 366.733792 -227.171908) (xy 366.68183 -227.183768) (xy 366.62868 -227.187752)
			(xy 366.57553 -227.183768) (xy 366.523568 -227.171908) (xy 366.473954 -227.152436) (xy 366.427796 -227.125787)
			(xy 366.386125 -227.092556) (xy 366.349873 -227.053485) (xy 366.319849 -227.009448) (xy 366.296723 -226.961427)
			(xy 366.281013 -226.910497) (xy 366.27307 -226.857793) (xy 366.044744 -226.857793) (xy 366.036801 -226.910497)
			(xy 366.021091 -226.961427) (xy 365.997965 -227.009448) (xy 365.967941 -227.053485) (xy 365.931689 -227.092556)
			(xy 365.890018 -227.125787) (xy 365.84386 -227.152436) (xy 365.794246 -227.171908) (xy 365.742284 -227.183768)
			(xy 365.689134 -227.187752) (xy 365.635984 -227.183768) (xy 365.584022 -227.171908) (xy 365.534408 -227.152436)
			(xy 365.48825 -227.125787) (xy 365.446579 -227.092556) (xy 365.410327 -227.053485) (xy 365.380303 -227.009448)
			(xy 365.357177 -226.961427) (xy 365.341467 -226.910497) (xy 365.333524 -226.857793) (xy 365.10469 -226.857793)
			(xy 365.096747 -226.910497) (xy 365.081037 -226.961427) (xy 365.057911 -227.009448) (xy 365.027887 -227.053485)
			(xy 364.991635 -227.092556) (xy 364.949964 -227.125787) (xy 364.903806 -227.152436) (xy 364.854192 -227.171908)
			(xy 364.80223 -227.183768) (xy 364.74908 -227.187752) (xy 364.69593 -227.183768) (xy 364.643968 -227.171908)
			(xy 364.594354 -227.152436) (xy 364.548196 -227.125787) (xy 364.506525 -227.092556) (xy 364.470273 -227.053485)
			(xy 364.440249 -227.009448) (xy 364.417123 -226.961427) (xy 364.401413 -226.910497) (xy 364.39347 -226.857793)
			(xy 364.165144 -226.857793) (xy 364.157201 -226.910497) (xy 364.141491 -226.961427) (xy 364.118365 -227.009448)
			(xy 364.088341 -227.053485) (xy 364.052089 -227.092556) (xy 364.010418 -227.125787) (xy 363.96426 -227.152436)
			(xy 363.914646 -227.171908) (xy 363.862684 -227.183768) (xy 363.809534 -227.187752) (xy 363.756384 -227.183768)
			(xy 363.704422 -227.171908) (xy 363.654808 -227.152436) (xy 363.60865 -227.125787) (xy 363.566979 -227.092556)
			(xy 363.530727 -227.053485) (xy 363.500703 -227.009448) (xy 363.477577 -226.961427) (xy 363.461867 -226.910497)
			(xy 363.453924 -226.857793) (xy 363.225344 -226.857793) (xy 363.217401 -226.910497) (xy 363.201691 -226.961427)
			(xy 363.178565 -227.009448) (xy 363.148541 -227.053485) (xy 363.112289 -227.092556) (xy 363.070618 -227.125787)
			(xy 363.02446 -227.152436) (xy 362.974846 -227.171908) (xy 362.922884 -227.183768) (xy 362.869734 -227.187752)
			(xy 362.816584 -227.183768) (xy 362.764622 -227.171908) (xy 362.715008 -227.152436) (xy 362.66885 -227.125787)
			(xy 362.627179 -227.092556) (xy 362.590927 -227.053485) (xy 362.560903 -227.009448) (xy 362.537777 -226.961427)
			(xy 362.522067 -226.910497) (xy 362.514124 -226.857793) (xy 362.285544 -226.857793) (xy 362.277601 -226.910497)
			(xy 362.261891 -226.961427) (xy 362.238765 -227.009448) (xy 362.208741 -227.053485) (xy 362.172489 -227.092556)
			(xy 362.130818 -227.125787) (xy 362.08466 -227.152436) (xy 362.035046 -227.171908) (xy 361.983084 -227.183768)
			(xy 361.929934 -227.187752) (xy 361.876784 -227.183768) (xy 361.824822 -227.171908) (xy 361.775208 -227.152436)
			(xy 361.72905 -227.125787) (xy 361.687379 -227.092556) (xy 361.651127 -227.053485) (xy 361.621103 -227.009448)
			(xy 361.597977 -226.961427) (xy 361.582267 -226.910497) (xy 361.574324 -226.857793) (xy 361.34549 -226.857793)
			(xy 361.337547 -226.910497) (xy 361.321837 -226.961427) (xy 361.298711 -227.009448) (xy 361.268687 -227.053485)
			(xy 361.232435 -227.092556) (xy 361.190764 -227.125787) (xy 361.144606 -227.152436) (xy 361.094992 -227.171908)
			(xy 361.04303 -227.183768) (xy 360.98988 -227.187752) (xy 360.93673 -227.183768) (xy 360.884768 -227.171908)
			(xy 360.835154 -227.152436) (xy 360.788996 -227.125787) (xy 360.747325 -227.092556) (xy 360.711073 -227.053485)
			(xy 360.681049 -227.009448) (xy 360.657923 -226.961427) (xy 360.642213 -226.910497) (xy 360.63427 -226.857793)
			(xy 360.405944 -226.857793) (xy 360.398001 -226.910497) (xy 360.382291 -226.961427) (xy 360.359165 -227.009448)
			(xy 360.329141 -227.053485) (xy 360.292889 -227.092556) (xy 360.251218 -227.125787) (xy 360.20506 -227.152436)
			(xy 360.155446 -227.171908) (xy 360.103484 -227.183768) (xy 360.050334 -227.187752) (xy 359.997184 -227.183768)
			(xy 359.945222 -227.171908) (xy 359.895608 -227.152436) (xy 359.84945 -227.125787) (xy 359.807779 -227.092556)
			(xy 359.771527 -227.053485) (xy 359.741503 -227.009448) (xy 359.718377 -226.961427) (xy 359.702667 -226.910497)
			(xy 359.694724 -226.857793) (xy 359.46589 -226.857793) (xy 359.457947 -226.910497) (xy 359.442237 -226.961427)
			(xy 359.419111 -227.009448) (xy 359.389087 -227.053485) (xy 359.352835 -227.092556) (xy 359.311164 -227.125787)
			(xy 359.265006 -227.152436) (xy 359.215392 -227.171908) (xy 359.16343 -227.183768) (xy 359.11028 -227.187752)
			(xy 359.05713 -227.183768) (xy 359.005168 -227.171908) (xy 358.955554 -227.152436) (xy 358.909396 -227.125787)
			(xy 358.867725 -227.092556) (xy 358.831473 -227.053485) (xy 358.801449 -227.009448) (xy 358.778323 -226.961427)
			(xy 358.762613 -226.910497) (xy 358.75467 -226.857793) (xy 358.526344 -226.857793) (xy 358.518401 -226.910497)
			(xy 358.502691 -226.961427) (xy 358.479565 -227.009448) (xy 358.449541 -227.053485) (xy 358.413289 -227.092556)
			(xy 358.371618 -227.125787) (xy 358.32546 -227.152436) (xy 358.275846 -227.171908) (xy 358.223884 -227.183768)
			(xy 358.170734 -227.187752) (xy 358.117584 -227.183768) (xy 358.065622 -227.171908) (xy 358.016008 -227.152436)
			(xy 357.96985 -227.125787) (xy 357.928179 -227.092556) (xy 357.891927 -227.053485) (xy 357.861903 -227.009448)
			(xy 357.838777 -226.961427) (xy 357.823067 -226.910497) (xy 357.815124 -226.857793) (xy 357.58629 -226.857793)
			(xy 357.578347 -226.910497) (xy 357.562637 -226.961427) (xy 357.539511 -227.009448) (xy 357.509487 -227.053485)
			(xy 357.473235 -227.092556) (xy 357.431564 -227.125787) (xy 357.385406 -227.152436) (xy 357.335792 -227.171908)
			(xy 357.28383 -227.183768) (xy 357.23068 -227.187752) (xy 357.17753 -227.183768) (xy 357.125568 -227.171908)
			(xy 357.075954 -227.152436) (xy 357.029796 -227.125787) (xy 356.988125 -227.092556) (xy 356.951873 -227.053485)
			(xy 356.921849 -227.009448) (xy 356.898723 -226.961427) (xy 356.883013 -226.910497) (xy 356.87507 -226.857793)
			(xy 356.646744 -226.857793) (xy 356.638801 -226.910497) (xy 356.623091 -226.961427) (xy 356.599965 -227.009448)
			(xy 356.569941 -227.053485) (xy 356.533689 -227.092556) (xy 356.492018 -227.125787) (xy 356.44586 -227.152436)
			(xy 356.396246 -227.171908) (xy 356.344284 -227.183768) (xy 356.291134 -227.187752) (xy 356.237984 -227.183768)
			(xy 356.186022 -227.171908) (xy 356.136408 -227.152436) (xy 356.09025 -227.125787) (xy 356.048579 -227.092556)
			(xy 356.012327 -227.053485) (xy 355.982303 -227.009448) (xy 355.959177 -226.961427) (xy 355.943467 -226.910497)
			(xy 355.935524 -226.857793) (xy 355.70669 -226.857793) (xy 355.698747 -226.910497) (xy 355.683037 -226.961427)
			(xy 355.659911 -227.009448) (xy 355.629887 -227.053485) (xy 355.593635 -227.092556) (xy 355.551964 -227.125787)
			(xy 355.505806 -227.152436) (xy 355.456192 -227.171908) (xy 355.40423 -227.183768) (xy 355.35108 -227.187752)
			(xy 355.29793 -227.183768) (xy 355.245968 -227.171908) (xy 355.196354 -227.152436) (xy 355.150196 -227.125787)
			(xy 355.108525 -227.092556) (xy 355.072273 -227.053485) (xy 355.042249 -227.009448) (xy 355.019123 -226.961427)
			(xy 355.003413 -226.910497) (xy 354.99547 -226.857793) (xy 354.767144 -226.857793) (xy 354.759201 -226.910497)
			(xy 354.743491 -226.961427) (xy 354.720365 -227.009448) (xy 354.690341 -227.053485) (xy 354.654089 -227.092556)
			(xy 354.612418 -227.125787) (xy 354.56626 -227.152436) (xy 354.516646 -227.171908) (xy 354.464684 -227.183768)
			(xy 354.411534 -227.187752) (xy 354.358384 -227.183768) (xy 354.306422 -227.171908) (xy 354.256808 -227.152436)
			(xy 354.21065 -227.125787) (xy 354.168979 -227.092556) (xy 354.132727 -227.053485) (xy 354.102703 -227.009448)
			(xy 354.079577 -226.961427) (xy 354.063867 -226.910497) (xy 354.055924 -226.857793) (xy 353.82709 -226.857793)
			(xy 353.819147 -226.910497) (xy 353.803437 -226.961427) (xy 353.780311 -227.009448) (xy 353.750287 -227.053485)
			(xy 353.714035 -227.092556) (xy 353.672364 -227.125787) (xy 353.626206 -227.152436) (xy 353.576592 -227.171908)
			(xy 353.52463 -227.183768) (xy 353.47148 -227.187752) (xy 353.41833 -227.183768) (xy 353.366368 -227.171908)
			(xy 353.316754 -227.152436) (xy 353.270596 -227.125787) (xy 353.228925 -227.092556) (xy 353.192673 -227.053485)
			(xy 353.162649 -227.009448) (xy 353.139523 -226.961427) (xy 353.123813 -226.910497) (xy 353.11587 -226.857793)
			(xy 352.887544 -226.857793) (xy 352.879601 -226.910497) (xy 352.863891 -226.961427) (xy 352.840765 -227.009448)
			(xy 352.810741 -227.053485) (xy 352.774489 -227.092556) (xy 352.732818 -227.125787) (xy 352.68666 -227.152436)
			(xy 352.637046 -227.171908) (xy 352.585084 -227.183768) (xy 352.531934 -227.187752) (xy 352.478784 -227.183768)
			(xy 352.426822 -227.171908) (xy 352.377208 -227.152436) (xy 352.33105 -227.125787) (xy 352.289379 -227.092556)
			(xy 352.253127 -227.053485) (xy 352.223103 -227.009448) (xy 352.199977 -226.961427) (xy 352.184267 -226.910497)
			(xy 352.176324 -226.857793) (xy 351.947744 -226.857793) (xy 351.939801 -226.910497) (xy 351.924091 -226.961427)
			(xy 351.900965 -227.009448) (xy 351.870941 -227.053485) (xy 351.834689 -227.092556) (xy 351.793018 -227.125787)
			(xy 351.74686 -227.152436) (xy 351.697246 -227.171908) (xy 351.645284 -227.183768) (xy 351.592134 -227.187752)
			(xy 351.538984 -227.183768) (xy 351.487022 -227.171908) (xy 351.437408 -227.152436) (xy 351.39125 -227.125787)
			(xy 351.349579 -227.092556) (xy 351.313327 -227.053485) (xy 351.283303 -227.009448) (xy 351.260177 -226.961427)
			(xy 351.244467 -226.910497) (xy 351.236524 -226.857793) (xy 351.00769 -226.857793) (xy 350.999747 -226.910497)
			(xy 350.984037 -226.961427) (xy 350.960911 -227.009448) (xy 350.930887 -227.053485) (xy 350.894635 -227.092556)
			(xy 350.852964 -227.125787) (xy 350.806806 -227.152436) (xy 350.757192 -227.171908) (xy 350.70523 -227.183768)
			(xy 350.65208 -227.187752) (xy 350.59893 -227.183768) (xy 350.546968 -227.171908) (xy 350.497354 -227.152436)
			(xy 350.451196 -227.125787) (xy 350.409525 -227.092556) (xy 350.373273 -227.053485) (xy 350.343249 -227.009448)
			(xy 350.320123 -226.961427) (xy 350.304413 -226.910497) (xy 350.29647 -226.857793) (xy 350.06789 -226.857793)
			(xy 350.059947 -226.910497) (xy 350.044237 -226.961427) (xy 350.021111 -227.009448) (xy 349.991087 -227.053485)
			(xy 349.954835 -227.092556) (xy 349.913164 -227.125787) (xy 349.867006 -227.152436) (xy 349.817392 -227.171908)
			(xy 349.76543 -227.183768) (xy 349.71228 -227.187752) (xy 349.65913 -227.183768) (xy 349.607168 -227.171908)
			(xy 349.557554 -227.152436) (xy 349.511396 -227.125787) (xy 349.469725 -227.092556) (xy 349.433473 -227.053485)
			(xy 349.403449 -227.009448) (xy 349.380323 -226.961427) (xy 349.364613 -226.910497) (xy 349.35667 -226.857793)
			(xy 349.128344 -226.857793) (xy 349.120401 -226.910497) (xy 349.104691 -226.961427) (xy 349.081565 -227.009448)
			(xy 349.051541 -227.053485) (xy 349.015289 -227.092556) (xy 348.973618 -227.125787) (xy 348.92746 -227.152436)
			(xy 348.877846 -227.171908) (xy 348.825884 -227.183768) (xy 348.772734 -227.187752) (xy 348.719584 -227.183768)
			(xy 348.667622 -227.171908) (xy 348.618008 -227.152436) (xy 348.57185 -227.125787) (xy 348.530179 -227.092556)
			(xy 348.493927 -227.053485) (xy 348.463903 -227.009448) (xy 348.440777 -226.961427) (xy 348.425067 -226.910497)
			(xy 348.417124 -226.857793) (xy 348.188544 -226.857793) (xy 348.180601 -226.910497) (xy 348.164891 -226.961427)
			(xy 348.141765 -227.009448) (xy 348.111741 -227.053485) (xy 348.075489 -227.092556) (xy 348.033818 -227.125787)
			(xy 347.98766 -227.152436) (xy 347.938046 -227.171908) (xy 347.886084 -227.183768) (xy 347.832934 -227.187752)
			(xy 347.779784 -227.183768) (xy 347.727822 -227.171908) (xy 347.678208 -227.152436) (xy 347.63205 -227.125787)
			(xy 347.590379 -227.092556) (xy 347.554127 -227.053485) (xy 347.524103 -227.009448) (xy 347.500977 -226.961427)
			(xy 347.485267 -226.910497) (xy 347.477324 -226.857793) (xy 347.248744 -226.857793) (xy 347.240801 -226.910497)
			(xy 347.225091 -226.961427) (xy 347.201965 -227.009448) (xy 347.171941 -227.053485) (xy 347.135689 -227.092556)
			(xy 347.094018 -227.125787) (xy 347.04786 -227.152436) (xy 346.998246 -227.171908) (xy 346.946284 -227.183768)
			(xy 346.893134 -227.187752) (xy 346.839984 -227.183768) (xy 346.788022 -227.171908) (xy 346.738408 -227.152436)
			(xy 346.69225 -227.125787) (xy 346.650579 -227.092556) (xy 346.614327 -227.053485) (xy 346.584303 -227.009448)
			(xy 346.561177 -226.961427) (xy 346.545467 -226.910497) (xy 346.537524 -226.857793) (xy 346.30869 -226.857793)
			(xy 346.300747 -226.910497) (xy 346.285037 -226.961427) (xy 346.261911 -227.009448) (xy 346.231887 -227.053485)
			(xy 346.195635 -227.092556) (xy 346.153964 -227.125787) (xy 346.107806 -227.152436) (xy 346.058192 -227.171908)
			(xy 346.00623 -227.183768) (xy 345.95308 -227.187752) (xy 345.89993 -227.183768) (xy 345.847968 -227.171908)
			(xy 345.798354 -227.152436) (xy 345.752196 -227.125787) (xy 345.710525 -227.092556) (xy 345.674273 -227.053485)
			(xy 345.644249 -227.009448) (xy 345.621123 -226.961427) (xy 345.605413 -226.910497) (xy 345.59747 -226.857793)
			(xy 345.36889 -226.857793) (xy 345.360947 -226.910497) (xy 345.345237 -226.961427) (xy 345.322111 -227.009448)
			(xy 345.292087 -227.053485) (xy 345.255835 -227.092556) (xy 345.214164 -227.125787) (xy 345.168006 -227.152436)
			(xy 345.118392 -227.171908) (xy 345.06643 -227.183768) (xy 345.01328 -227.187752) (xy 344.96013 -227.183768)
			(xy 344.908168 -227.171908) (xy 344.858554 -227.152436) (xy 344.812396 -227.125787) (xy 344.770725 -227.092556)
			(xy 344.734473 -227.053485) (xy 344.704449 -227.009448) (xy 344.681323 -226.961427) (xy 344.665613 -226.910497)
			(xy 344.65767 -226.857793) (xy 344.429344 -226.857793) (xy 344.421401 -226.910497) (xy 344.405691 -226.961427)
			(xy 344.382565 -227.009448) (xy 344.352541 -227.053485) (xy 344.316289 -227.092556) (xy 344.274618 -227.125787)
			(xy 344.22846 -227.152436) (xy 344.178846 -227.171908) (xy 344.126884 -227.183768) (xy 344.073734 -227.187752)
			(xy 344.020584 -227.183768) (xy 343.968622 -227.171908) (xy 343.919008 -227.152436) (xy 343.87285 -227.125787)
			(xy 343.831179 -227.092556) (xy 343.794927 -227.053485) (xy 343.764903 -227.009448) (xy 343.741777 -226.961427)
			(xy 343.726067 -226.910497) (xy 343.718124 -226.857793) (xy 343.48929 -226.857793) (xy 343.481347 -226.910497)
			(xy 343.465637 -226.961427) (xy 343.442511 -227.009448) (xy 343.412487 -227.053485) (xy 343.376235 -227.092556)
			(xy 343.334564 -227.125787) (xy 343.288406 -227.152436) (xy 343.238792 -227.171908) (xy 343.18683 -227.183768)
			(xy 343.13368 -227.187752) (xy 343.08053 -227.183768) (xy 343.028568 -227.171908) (xy 342.978954 -227.152436)
			(xy 342.932796 -227.125787) (xy 342.891125 -227.092556) (xy 342.854873 -227.053485) (xy 342.824849 -227.009448)
			(xy 342.801723 -226.961427) (xy 342.786013 -226.910497) (xy 342.77807 -226.857793) (xy 342.54949 -226.857793)
			(xy 342.541547 -226.910497) (xy 342.525837 -226.961427) (xy 342.502711 -227.009448) (xy 342.472687 -227.053485)
			(xy 342.436435 -227.092556) (xy 342.394764 -227.125787) (xy 342.348606 -227.152436) (xy 342.298992 -227.171908)
			(xy 342.24703 -227.183768) (xy 342.19388 -227.187752) (xy 342.14073 -227.183768) (xy 342.088768 -227.171908)
			(xy 342.039154 -227.152436) (xy 341.992996 -227.125787) (xy 341.951325 -227.092556) (xy 341.915073 -227.053485)
			(xy 341.885049 -227.009448) (xy 341.861923 -226.961427) (xy 341.846213 -226.910497) (xy 341.83827 -226.857793)
			(xy 341.609944 -226.857793) (xy 341.602001 -226.910497) (xy 341.586291 -226.961427) (xy 341.563165 -227.009448)
			(xy 341.533141 -227.053485) (xy 341.496889 -227.092556) (xy 341.455218 -227.125787) (xy 341.40906 -227.152436)
			(xy 341.359446 -227.171908) (xy 341.307484 -227.183768) (xy 341.254334 -227.187752) (xy 341.201184 -227.183768)
			(xy 341.149222 -227.171908) (xy 341.099608 -227.152436) (xy 341.05345 -227.125787) (xy 341.011779 -227.092556)
			(xy 340.975527 -227.053485) (xy 340.945503 -227.009448) (xy 340.922377 -226.961427) (xy 340.906667 -226.910497)
			(xy 340.898724 -226.857793) (xy 340.670144 -226.857793) (xy 340.662201 -226.910497) (xy 340.646491 -226.961427)
			(xy 340.623365 -227.009448) (xy 340.593341 -227.053485) (xy 340.557089 -227.092556) (xy 340.515418 -227.125787)
			(xy 340.46926 -227.152436) (xy 340.419646 -227.171908) (xy 340.367684 -227.183768) (xy 340.314534 -227.187752)
			(xy 340.261384 -227.183768) (xy 340.209422 -227.171908) (xy 340.159808 -227.152436) (xy 340.11365 -227.125787)
			(xy 340.071979 -227.092556) (xy 340.035727 -227.053485) (xy 340.005703 -227.009448) (xy 339.982577 -226.961427)
			(xy 339.966867 -226.910497) (xy 339.958924 -226.857793) (xy 339.729328 -226.857793) (xy 339.727293 -226.884712)
			(xy 339.715229 -226.9371) (xy 339.695428 -226.98708) (xy 339.66834 -227.033515) (xy 339.63458 -227.075351)
			(xy 339.594915 -227.111638) (xy 339.550246 -227.141551) (xy 339.501589 -227.16441) (xy 339.450049 -227.179695)
			(xy 339.423502 -227.18395) (xy 339.37956 -227.190046) (xy 339.37956 -227.671609) (xy 339.48877 -227.671609)
			(xy 339.48877 -227.618311) (xy 339.496713 -227.565607) (xy 339.512423 -227.514677) (xy 339.535549 -227.466656)
			(xy 339.565573 -227.422619) (xy 339.601825 -227.383548) (xy 339.643496 -227.350317) (xy 339.689654 -227.323668)
			(xy 339.739268 -227.304196) (xy 339.79123 -227.292336) (xy 339.84438 -227.288353) (xy 339.89753 -227.292336)
			(xy 339.949492 -227.304196) (xy 339.999106 -227.323668) (xy 340.045264 -227.350317) (xy 340.086935 -227.383548)
			(xy 340.123187 -227.422619) (xy 340.153211 -227.466656) (xy 340.176337 -227.514677) (xy 340.192047 -227.565607)
			(xy 340.19999 -227.618311) (xy 340.200488 -227.64496) (xy 340.19999 -227.671609) (xy 340.428824 -227.671609)
			(xy 340.428824 -227.618311) (xy 340.436767 -227.565607) (xy 340.452477 -227.514677) (xy 340.475603 -227.466656)
			(xy 340.505627 -227.422619) (xy 340.541879 -227.383548) (xy 340.58355 -227.350317) (xy 340.629708 -227.323668)
			(xy 340.679322 -227.304196) (xy 340.731284 -227.292336) (xy 340.784434 -227.288353) (xy 340.837584 -227.292336)
			(xy 340.889546 -227.304196) (xy 340.93916 -227.323668) (xy 340.985318 -227.350317) (xy 341.026989 -227.383548)
			(xy 341.063241 -227.422619) (xy 341.093265 -227.466656) (xy 341.116391 -227.514677) (xy 341.132101 -227.565607)
			(xy 341.140044 -227.618311) (xy 341.140542 -227.64496) (xy 341.140044 -227.671609) (xy 341.368624 -227.671609)
			(xy 341.368624 -227.618311) (xy 341.376567 -227.565607) (xy 341.392277 -227.514677) (xy 341.415403 -227.466656)
			(xy 341.445427 -227.422619) (xy 341.481679 -227.383548) (xy 341.52335 -227.350317) (xy 341.569508 -227.323668)
			(xy 341.619122 -227.304196) (xy 341.671084 -227.292336) (xy 341.724234 -227.288353) (xy 341.777384 -227.292336)
			(xy 341.829346 -227.304196) (xy 341.87896 -227.323668) (xy 341.925118 -227.350317) (xy 341.966789 -227.383548)
			(xy 342.003041 -227.422619) (xy 342.033065 -227.466656) (xy 342.056191 -227.514677) (xy 342.071901 -227.565607)
			(xy 342.079844 -227.618311) (xy 342.080342 -227.64496) (xy 342.079844 -227.671609) (xy 342.308424 -227.671609)
			(xy 342.308424 -227.618311) (xy 342.316367 -227.565607) (xy 342.332077 -227.514677) (xy 342.355203 -227.466656)
			(xy 342.385227 -227.422619) (xy 342.421479 -227.383548) (xy 342.46315 -227.350317) (xy 342.509308 -227.323668)
			(xy 342.558922 -227.304196) (xy 342.610884 -227.292336) (xy 342.664034 -227.288353) (xy 342.717184 -227.292336)
			(xy 342.769146 -227.304196) (xy 342.81876 -227.323668) (xy 342.864918 -227.350317) (xy 342.906589 -227.383548)
			(xy 342.942841 -227.422619) (xy 342.972865 -227.466656) (xy 342.995991 -227.514677) (xy 343.011701 -227.565607)
			(xy 343.019644 -227.618311) (xy 343.020142 -227.64496) (xy 343.019644 -227.671609) (xy 343.248224 -227.671609)
			(xy 343.248224 -227.618311) (xy 343.256167 -227.565607) (xy 343.271877 -227.514677) (xy 343.295003 -227.466656)
			(xy 343.325027 -227.422619) (xy 343.361279 -227.383548) (xy 343.40295 -227.350317) (xy 343.449108 -227.323668)
			(xy 343.498722 -227.304196) (xy 343.550684 -227.292336) (xy 343.603834 -227.288353) (xy 343.656984 -227.292336)
			(xy 343.708946 -227.304196) (xy 343.75856 -227.323668) (xy 343.804718 -227.350317) (xy 343.846389 -227.383548)
			(xy 343.882641 -227.422619) (xy 343.912665 -227.466656) (xy 343.935791 -227.514677) (xy 343.951501 -227.565607)
			(xy 343.959444 -227.618311) (xy 343.959942 -227.64496) (xy 343.959444 -227.671609) (xy 344.188024 -227.671609)
			(xy 344.188024 -227.618311) (xy 344.195967 -227.565607) (xy 344.211677 -227.514677) (xy 344.234803 -227.466656)
			(xy 344.264827 -227.422619) (xy 344.301079 -227.383548) (xy 344.34275 -227.350317) (xy 344.388908 -227.323668)
			(xy 344.438522 -227.304196) (xy 344.490484 -227.292336) (xy 344.543634 -227.288353) (xy 344.596784 -227.292336)
			(xy 344.648746 -227.304196) (xy 344.69836 -227.323668) (xy 344.744518 -227.350317) (xy 344.786189 -227.383548)
			(xy 344.822441 -227.422619) (xy 344.852465 -227.466656) (xy 344.875591 -227.514677) (xy 344.891301 -227.565607)
			(xy 344.899244 -227.618311) (xy 344.899742 -227.64496) (xy 344.899244 -227.671609) (xy 345.127824 -227.671609)
			(xy 345.127824 -227.618311) (xy 345.135767 -227.565607) (xy 345.151477 -227.514677) (xy 345.174603 -227.466656)
			(xy 345.204627 -227.422619) (xy 345.240879 -227.383548) (xy 345.28255 -227.350317) (xy 345.328708 -227.323668)
			(xy 345.378322 -227.304196) (xy 345.430284 -227.292336) (xy 345.483434 -227.288353) (xy 345.536584 -227.292336)
			(xy 345.588546 -227.304196) (xy 345.63816 -227.323668) (xy 345.684318 -227.350317) (xy 345.725989 -227.383548)
			(xy 345.762241 -227.422619) (xy 345.792265 -227.466656) (xy 345.815391 -227.514677) (xy 345.831101 -227.565607)
			(xy 345.839044 -227.618311) (xy 345.839542 -227.64496) (xy 345.839044 -227.671609) (xy 346.067624 -227.671609)
			(xy 346.067624 -227.618311) (xy 346.075567 -227.565607) (xy 346.091277 -227.514677) (xy 346.114403 -227.466656)
			(xy 346.144427 -227.422619) (xy 346.180679 -227.383548) (xy 346.22235 -227.350317) (xy 346.268508 -227.323668)
			(xy 346.318122 -227.304196) (xy 346.370084 -227.292336) (xy 346.423234 -227.288353) (xy 346.476384 -227.292336)
			(xy 346.528346 -227.304196) (xy 346.57796 -227.323668) (xy 346.624118 -227.350317) (xy 346.665789 -227.383548)
			(xy 346.702041 -227.422619) (xy 346.732065 -227.466656) (xy 346.755191 -227.514677) (xy 346.770901 -227.565607)
			(xy 346.778844 -227.618311) (xy 346.779342 -227.64496) (xy 346.778844 -227.671609) (xy 347.00717 -227.671609)
			(xy 347.00717 -227.618311) (xy 347.015113 -227.565607) (xy 347.030823 -227.514677) (xy 347.053949 -227.466656)
			(xy 347.083973 -227.422619) (xy 347.120225 -227.383548) (xy 347.161896 -227.350317) (xy 347.208054 -227.323668)
			(xy 347.257668 -227.304196) (xy 347.30963 -227.292336) (xy 347.36278 -227.288353) (xy 347.41593 -227.292336)
			(xy 347.467892 -227.304196) (xy 347.517506 -227.323668) (xy 347.563664 -227.350317) (xy 347.605335 -227.383548)
			(xy 347.641587 -227.422619) (xy 347.671611 -227.466656) (xy 347.694737 -227.514677) (xy 347.710447 -227.565607)
			(xy 347.71839 -227.618311) (xy 347.718888 -227.64496) (xy 347.71839 -227.671609) (xy 347.947224 -227.671609)
			(xy 347.947224 -227.618311) (xy 347.955167 -227.565607) (xy 347.970877 -227.514677) (xy 347.994003 -227.466656)
			(xy 348.024027 -227.422619) (xy 348.060279 -227.383548) (xy 348.10195 -227.350317) (xy 348.148108 -227.323668)
			(xy 348.197722 -227.304196) (xy 348.249684 -227.292336) (xy 348.302834 -227.288353) (xy 348.355984 -227.292336)
			(xy 348.407946 -227.304196) (xy 348.45756 -227.323668) (xy 348.503718 -227.350317) (xy 348.545389 -227.383548)
			(xy 348.581641 -227.422619) (xy 348.611665 -227.466656) (xy 348.634791 -227.514677) (xy 348.650501 -227.565607)
			(xy 348.658444 -227.618311) (xy 348.658942 -227.64496) (xy 348.658444 -227.671609) (xy 348.887024 -227.671609)
			(xy 348.887024 -227.618311) (xy 348.894967 -227.565607) (xy 348.910677 -227.514677) (xy 348.933803 -227.466656)
			(xy 348.963827 -227.422619) (xy 349.000079 -227.383548) (xy 349.04175 -227.350317) (xy 349.087908 -227.323668)
			(xy 349.137522 -227.304196) (xy 349.189484 -227.292336) (xy 349.242634 -227.288353) (xy 349.295784 -227.292336)
			(xy 349.347746 -227.304196) (xy 349.39736 -227.323668) (xy 349.443518 -227.350317) (xy 349.485189 -227.383548)
			(xy 349.521441 -227.422619) (xy 349.551465 -227.466656) (xy 349.574591 -227.514677) (xy 349.590301 -227.565607)
			(xy 349.598244 -227.618311) (xy 349.598742 -227.64496) (xy 349.598244 -227.671609) (xy 349.826824 -227.671609)
			(xy 349.826824 -227.618311) (xy 349.834767 -227.565607) (xy 349.850477 -227.514677) (xy 349.873603 -227.466656)
			(xy 349.903627 -227.422619) (xy 349.939879 -227.383548) (xy 349.98155 -227.350317) (xy 350.027708 -227.323668)
			(xy 350.077322 -227.304196) (xy 350.129284 -227.292336) (xy 350.182434 -227.288353) (xy 350.235584 -227.292336)
			(xy 350.287546 -227.304196) (xy 350.33716 -227.323668) (xy 350.383318 -227.350317) (xy 350.424989 -227.383548)
			(xy 350.461241 -227.422619) (xy 350.491265 -227.466656) (xy 350.514391 -227.514677) (xy 350.530101 -227.565607)
			(xy 350.538044 -227.618311) (xy 350.538542 -227.64496) (xy 350.538044 -227.671609) (xy 351.706424 -227.671609)
			(xy 351.706424 -227.618311) (xy 351.714367 -227.565607) (xy 351.730077 -227.514677) (xy 351.753203 -227.466656)
			(xy 351.783227 -227.422619) (xy 351.819479 -227.383548) (xy 351.86115 -227.350317) (xy 351.907308 -227.323668)
			(xy 351.956922 -227.304196) (xy 352.008884 -227.292336) (xy 352.062034 -227.288353) (xy 352.115184 -227.292336)
			(xy 352.167146 -227.304196) (xy 352.21676 -227.323668) (xy 352.262918 -227.350317) (xy 352.304589 -227.383548)
			(xy 352.340841 -227.422619) (xy 352.370865 -227.466656) (xy 352.393991 -227.514677) (xy 352.409701 -227.565607)
			(xy 352.417644 -227.618311) (xy 352.418142 -227.64496) (xy 352.417644 -227.671609) (xy 352.646224 -227.671609)
			(xy 352.646224 -227.618311) (xy 352.654167 -227.565607) (xy 352.669877 -227.514677) (xy 352.693003 -227.466656)
			(xy 352.723027 -227.422619) (xy 352.759279 -227.383548) (xy 352.80095 -227.350317) (xy 352.847108 -227.323668)
			(xy 352.896722 -227.304196) (xy 352.948684 -227.292336) (xy 353.001834 -227.288353) (xy 353.054984 -227.292336)
			(xy 353.106946 -227.304196) (xy 353.15656 -227.323668) (xy 353.202718 -227.350317) (xy 353.244389 -227.383548)
			(xy 353.280641 -227.422619) (xy 353.310665 -227.466656) (xy 353.333791 -227.514677) (xy 353.349501 -227.565607)
			(xy 353.357444 -227.618311) (xy 353.357942 -227.64496) (xy 353.357444 -227.671609) (xy 353.586024 -227.671609)
			(xy 353.586024 -227.618311) (xy 353.593967 -227.565607) (xy 353.609677 -227.514677) (xy 353.632803 -227.466656)
			(xy 353.662827 -227.422619) (xy 353.699079 -227.383548) (xy 353.74075 -227.350317) (xy 353.786908 -227.323668)
			(xy 353.836522 -227.304196) (xy 353.888484 -227.292336) (xy 353.941634 -227.288353) (xy 353.994784 -227.292336)
			(xy 354.046746 -227.304196) (xy 354.09636 -227.323668) (xy 354.142518 -227.350317) (xy 354.184189 -227.383548)
			(xy 354.220441 -227.422619) (xy 354.250465 -227.466656) (xy 354.273591 -227.514677) (xy 354.289301 -227.565607)
			(xy 354.297244 -227.618311) (xy 354.297742 -227.64496) (xy 354.297244 -227.671609) (xy 354.525824 -227.671609)
			(xy 354.525824 -227.618311) (xy 354.533767 -227.565607) (xy 354.549477 -227.514677) (xy 354.572603 -227.466656)
			(xy 354.602627 -227.422619) (xy 354.638879 -227.383548) (xy 354.68055 -227.350317) (xy 354.726708 -227.323668)
			(xy 354.776322 -227.304196) (xy 354.828284 -227.292336) (xy 354.881434 -227.288353) (xy 354.934584 -227.292336)
			(xy 354.986546 -227.304196) (xy 355.03616 -227.323668) (xy 355.082318 -227.350317) (xy 355.123989 -227.383548)
			(xy 355.160241 -227.422619) (xy 355.190265 -227.466656) (xy 355.213391 -227.514677) (xy 355.229101 -227.565607)
			(xy 355.237044 -227.618311) (xy 355.237542 -227.64496) (xy 355.237044 -227.671609) (xy 355.465624 -227.671609)
			(xy 355.465624 -227.618311) (xy 355.473567 -227.565607) (xy 355.489277 -227.514677) (xy 355.512403 -227.466656)
			(xy 355.542427 -227.422619) (xy 355.578679 -227.383548) (xy 355.62035 -227.350317) (xy 355.666508 -227.323668)
			(xy 355.716122 -227.304196) (xy 355.768084 -227.292336) (xy 355.821234 -227.288353) (xy 355.874384 -227.292336)
			(xy 355.926346 -227.304196) (xy 355.97596 -227.323668) (xy 356.022118 -227.350317) (xy 356.063789 -227.383548)
			(xy 356.100041 -227.422619) (xy 356.130065 -227.466656) (xy 356.153191 -227.514677) (xy 356.168901 -227.565607)
			(xy 356.176844 -227.618311) (xy 356.177342 -227.64496) (xy 356.176844 -227.671609) (xy 356.405424 -227.671609)
			(xy 356.405424 -227.618311) (xy 356.413367 -227.565607) (xy 356.429077 -227.514677) (xy 356.452203 -227.466656)
			(xy 356.482227 -227.422619) (xy 356.518479 -227.383548) (xy 356.56015 -227.350317) (xy 356.606308 -227.323668)
			(xy 356.655922 -227.304196) (xy 356.707884 -227.292336) (xy 356.761034 -227.288353) (xy 356.814184 -227.292336)
			(xy 356.866146 -227.304196) (xy 356.91576 -227.323668) (xy 356.961918 -227.350317) (xy 357.003589 -227.383548)
			(xy 357.039841 -227.422619) (xy 357.069865 -227.466656) (xy 357.092991 -227.514677) (xy 357.108701 -227.565607)
			(xy 357.116644 -227.618311) (xy 357.117142 -227.64496) (xy 357.116644 -227.671609) (xy 357.345224 -227.671609)
			(xy 357.345224 -227.618311) (xy 357.353167 -227.565607) (xy 357.368877 -227.514677) (xy 357.392003 -227.466656)
			(xy 357.422027 -227.422619) (xy 357.458279 -227.383548) (xy 357.49995 -227.350317) (xy 357.546108 -227.323668)
			(xy 357.595722 -227.304196) (xy 357.647684 -227.292336) (xy 357.700834 -227.288353) (xy 357.753984 -227.292336)
			(xy 357.805946 -227.304196) (xy 357.85556 -227.323668) (xy 357.901718 -227.350317) (xy 357.943389 -227.383548)
			(xy 357.979641 -227.422619) (xy 358.009665 -227.466656) (xy 358.032791 -227.514677) (xy 358.048501 -227.565607)
			(xy 358.056444 -227.618311) (xy 358.056942 -227.64496) (xy 358.056444 -227.671609) (xy 358.285024 -227.671609)
			(xy 358.285024 -227.618311) (xy 358.292967 -227.565607) (xy 358.308677 -227.514677) (xy 358.331803 -227.466656)
			(xy 358.361827 -227.422619) (xy 358.398079 -227.383548) (xy 358.43975 -227.350317) (xy 358.485908 -227.323668)
			(xy 358.535522 -227.304196) (xy 358.587484 -227.292336) (xy 358.640634 -227.288353) (xy 358.693784 -227.292336)
			(xy 358.745746 -227.304196) (xy 358.79536 -227.323668) (xy 358.841518 -227.350317) (xy 358.883189 -227.383548)
			(xy 358.919441 -227.422619) (xy 358.949465 -227.466656) (xy 358.972591 -227.514677) (xy 358.988301 -227.565607)
			(xy 358.996244 -227.618311) (xy 358.996742 -227.64496) (xy 358.996244 -227.671609) (xy 359.224824 -227.671609)
			(xy 359.224824 -227.618311) (xy 359.232767 -227.565607) (xy 359.248477 -227.514677) (xy 359.271603 -227.466656)
			(xy 359.301627 -227.422619) (xy 359.337879 -227.383548) (xy 359.37955 -227.350317) (xy 359.425708 -227.323668)
			(xy 359.475322 -227.304196) (xy 359.527284 -227.292336) (xy 359.580434 -227.288353) (xy 359.633584 -227.292336)
			(xy 359.685546 -227.304196) (xy 359.73516 -227.323668) (xy 359.781318 -227.350317) (xy 359.822989 -227.383548)
			(xy 359.859241 -227.422619) (xy 359.889265 -227.466656) (xy 359.912391 -227.514677) (xy 359.928101 -227.565607)
			(xy 359.936044 -227.618311) (xy 359.936542 -227.64496) (xy 359.936044 -227.671609) (xy 360.164624 -227.671609)
			(xy 360.164624 -227.618311) (xy 360.172567 -227.565607) (xy 360.188277 -227.514677) (xy 360.211403 -227.466656)
			(xy 360.241427 -227.422619) (xy 360.277679 -227.383548) (xy 360.31935 -227.350317) (xy 360.365508 -227.323668)
			(xy 360.415122 -227.304196) (xy 360.467084 -227.292336) (xy 360.520234 -227.288353) (xy 360.573384 -227.292336)
			(xy 360.625346 -227.304196) (xy 360.67496 -227.323668) (xy 360.721118 -227.350317) (xy 360.762789 -227.383548)
			(xy 360.799041 -227.422619) (xy 360.829065 -227.466656) (xy 360.852191 -227.514677) (xy 360.867901 -227.565607)
			(xy 360.875844 -227.618311) (xy 360.876342 -227.64496) (xy 360.875844 -227.671609) (xy 361.104424 -227.671609)
			(xy 361.104424 -227.618311) (xy 361.112367 -227.565607) (xy 361.128077 -227.514677) (xy 361.151203 -227.466656)
			(xy 361.181227 -227.422619) (xy 361.217479 -227.383548) (xy 361.25915 -227.350317) (xy 361.305308 -227.323668)
			(xy 361.354922 -227.304196) (xy 361.406884 -227.292336) (xy 361.460034 -227.288353) (xy 361.513184 -227.292336)
			(xy 361.565146 -227.304196) (xy 361.61476 -227.323668) (xy 361.660918 -227.350317) (xy 361.702589 -227.383548)
			(xy 361.738841 -227.422619) (xy 361.768865 -227.466656) (xy 361.791991 -227.514677) (xy 361.807701 -227.565607)
			(xy 361.815644 -227.618311) (xy 361.816142 -227.64496) (xy 361.815644 -227.671609) (xy 362.044478 -227.671609)
			(xy 362.044478 -227.618311) (xy 362.052421 -227.565607) (xy 362.068131 -227.514677) (xy 362.091257 -227.466656)
			(xy 362.121281 -227.422619) (xy 362.157533 -227.383548) (xy 362.199204 -227.350317) (xy 362.245362 -227.323668)
			(xy 362.294976 -227.304196) (xy 362.346938 -227.292336) (xy 362.400088 -227.288353) (xy 362.453238 -227.292336)
			(xy 362.5052 -227.304196) (xy 362.554814 -227.323668) (xy 362.600972 -227.350317) (xy 362.642643 -227.383548)
			(xy 362.678895 -227.422619) (xy 362.708919 -227.466656) (xy 362.732045 -227.514677) (xy 362.747755 -227.565607)
			(xy 362.755698 -227.618311) (xy 362.756196 -227.64496) (xy 362.755698 -227.671609) (xy 362.984024 -227.671609)
			(xy 362.984024 -227.618311) (xy 362.991967 -227.565607) (xy 363.007677 -227.514677) (xy 363.030803 -227.466656)
			(xy 363.060827 -227.422619) (xy 363.097079 -227.383548) (xy 363.13875 -227.350317) (xy 363.184908 -227.323668)
			(xy 363.234522 -227.304196) (xy 363.286484 -227.292336) (xy 363.339634 -227.288353) (xy 363.392784 -227.292336)
			(xy 363.444746 -227.304196) (xy 363.49436 -227.323668) (xy 363.540518 -227.350317) (xy 363.582189 -227.383548)
			(xy 363.618441 -227.422619) (xy 363.648465 -227.466656) (xy 363.671591 -227.514677) (xy 363.687301 -227.565607)
			(xy 363.695244 -227.618311) (xy 363.695742 -227.64496) (xy 363.695244 -227.671609) (xy 363.923824 -227.671609)
			(xy 363.923824 -227.618311) (xy 363.931767 -227.565607) (xy 363.947477 -227.514677) (xy 363.970603 -227.466656)
			(xy 364.000627 -227.422619) (xy 364.036879 -227.383548) (xy 364.07855 -227.350317) (xy 364.124708 -227.323668)
			(xy 364.174322 -227.304196) (xy 364.226284 -227.292336) (xy 364.279434 -227.288353) (xy 364.332584 -227.292336)
			(xy 364.384546 -227.304196) (xy 364.43416 -227.323668) (xy 364.480318 -227.350317) (xy 364.521989 -227.383548)
			(xy 364.558241 -227.422619) (xy 364.588265 -227.466656) (xy 364.611391 -227.514677) (xy 364.627101 -227.565607)
			(xy 364.635044 -227.618311) (xy 364.635542 -227.64496) (xy 364.635044 -227.671609) (xy 364.863624 -227.671609)
			(xy 364.863624 -227.618311) (xy 364.871567 -227.565607) (xy 364.887277 -227.514677) (xy 364.910403 -227.466656)
			(xy 364.940427 -227.422619) (xy 364.976679 -227.383548) (xy 365.01835 -227.350317) (xy 365.064508 -227.323668)
			(xy 365.114122 -227.304196) (xy 365.166084 -227.292336) (xy 365.219234 -227.288353) (xy 365.272384 -227.292336)
			(xy 365.324346 -227.304196) (xy 365.37396 -227.323668) (xy 365.420118 -227.350317) (xy 365.461789 -227.383548)
			(xy 365.498041 -227.422619) (xy 365.528065 -227.466656) (xy 365.551191 -227.514677) (xy 365.566901 -227.565607)
			(xy 365.574844 -227.618311) (xy 365.575342 -227.64496) (xy 365.574844 -227.671609) (xy 365.803424 -227.671609)
			(xy 365.803424 -227.618311) (xy 365.811367 -227.565607) (xy 365.827077 -227.514677) (xy 365.850203 -227.466656)
			(xy 365.880227 -227.422619) (xy 365.916479 -227.383548) (xy 365.95815 -227.350317) (xy 366.004308 -227.323668)
			(xy 366.053922 -227.304196) (xy 366.105884 -227.292336) (xy 366.159034 -227.288353) (xy 366.212184 -227.292336)
			(xy 366.264146 -227.304196) (xy 366.31376 -227.323668) (xy 366.359918 -227.350317) (xy 366.401589 -227.383548)
			(xy 366.437841 -227.422619) (xy 366.467865 -227.466656) (xy 366.490991 -227.514677) (xy 366.506701 -227.565607)
			(xy 366.514644 -227.618311) (xy 366.515142 -227.64496) (xy 366.514644 -227.671609) (xy 366.743224 -227.671609)
			(xy 366.743224 -227.618311) (xy 366.751167 -227.565607) (xy 366.766877 -227.514677) (xy 366.790003 -227.466656)
			(xy 366.820027 -227.422619) (xy 366.856279 -227.383548) (xy 366.89795 -227.350317) (xy 366.944108 -227.323668)
			(xy 366.993722 -227.304196) (xy 367.045684 -227.292336) (xy 367.098834 -227.288353) (xy 367.151984 -227.292336)
			(xy 367.203946 -227.304196) (xy 367.25356 -227.323668) (xy 367.299718 -227.350317) (xy 367.341389 -227.383548)
			(xy 367.377641 -227.422619) (xy 367.407665 -227.466656) (xy 367.430791 -227.514677) (xy 367.446501 -227.565607)
			(xy 367.454444 -227.618311) (xy 367.454942 -227.64496) (xy 367.454444 -227.671609) (xy 367.683024 -227.671609)
			(xy 367.683024 -227.618311) (xy 367.690967 -227.565607) (xy 367.706677 -227.514677) (xy 367.729803 -227.466656)
			(xy 367.759827 -227.422619) (xy 367.796079 -227.383548) (xy 367.83775 -227.350317) (xy 367.883908 -227.323668)
			(xy 367.933522 -227.304196) (xy 367.985484 -227.292336) (xy 368.038634 -227.288353) (xy 368.091784 -227.292336)
			(xy 368.143746 -227.304196) (xy 368.19336 -227.323668) (xy 368.239518 -227.350317) (xy 368.281189 -227.383548)
			(xy 368.317441 -227.422619) (xy 368.347465 -227.466656) (xy 368.370591 -227.514677) (xy 368.386301 -227.565607)
			(xy 368.394244 -227.618311) (xy 368.394742 -227.64496) (xy 368.394244 -227.671609) (xy 368.622824 -227.671609)
			(xy 368.622824 -227.618311) (xy 368.630767 -227.565607) (xy 368.646477 -227.514677) (xy 368.669603 -227.466656)
			(xy 368.699627 -227.422619) (xy 368.735879 -227.383548) (xy 368.77755 -227.350317) (xy 368.823708 -227.323668)
			(xy 368.873322 -227.304196) (xy 368.925284 -227.292336) (xy 368.978434 -227.288353) (xy 369.031584 -227.292336)
			(xy 369.083546 -227.304196) (xy 369.13316 -227.323668) (xy 369.179318 -227.350317) (xy 369.220989 -227.383548)
			(xy 369.257241 -227.422619) (xy 369.287265 -227.466656) (xy 369.310391 -227.514677) (xy 369.326101 -227.565607)
			(xy 369.334044 -227.618311) (xy 369.334542 -227.64496) (xy 369.334044 -227.671609) (xy 369.56237 -227.671609)
			(xy 369.56237 -227.618311) (xy 369.570313 -227.565607) (xy 369.586023 -227.514677) (xy 369.609149 -227.466656)
			(xy 369.639173 -227.422619) (xy 369.675425 -227.383548) (xy 369.717096 -227.350317) (xy 369.763254 -227.323668)
			(xy 369.812868 -227.304196) (xy 369.86483 -227.292336) (xy 369.91798 -227.288353) (xy 369.97113 -227.292336)
			(xy 370.023092 -227.304196) (xy 370.072706 -227.323668) (xy 370.118864 -227.350317) (xy 370.160535 -227.383548)
			(xy 370.196787 -227.422619) (xy 370.226811 -227.466656) (xy 370.249937 -227.514677) (xy 370.265647 -227.565607)
			(xy 370.27359 -227.618311) (xy 370.274088 -227.64496) (xy 370.27359 -227.671609) (xy 370.502424 -227.671609)
			(xy 370.502424 -227.618311) (xy 370.510367 -227.565607) (xy 370.526077 -227.514677) (xy 370.549203 -227.466656)
			(xy 370.579227 -227.422619) (xy 370.615479 -227.383548) (xy 370.65715 -227.350317) (xy 370.703308 -227.323668)
			(xy 370.752922 -227.304196) (xy 370.804884 -227.292336) (xy 370.858034 -227.288353) (xy 370.911184 -227.292336)
			(xy 370.963146 -227.304196) (xy 371.01276 -227.323668) (xy 371.058918 -227.350317) (xy 371.100589 -227.383548)
			(xy 371.136841 -227.422619) (xy 371.166865 -227.466656) (xy 371.189991 -227.514677) (xy 371.205701 -227.565607)
			(xy 371.213644 -227.618311) (xy 371.214142 -227.64496) (xy 371.213644 -227.671609) (xy 371.442224 -227.671609)
			(xy 371.442224 -227.618311) (xy 371.450167 -227.565607) (xy 371.465877 -227.514677) (xy 371.489003 -227.466656)
			(xy 371.519027 -227.422619) (xy 371.555279 -227.383548) (xy 371.59695 -227.350317) (xy 371.643108 -227.323668)
			(xy 371.692722 -227.304196) (xy 371.744684 -227.292336) (xy 371.797834 -227.288353) (xy 371.850984 -227.292336)
			(xy 371.902946 -227.304196) (xy 371.95256 -227.323668) (xy 371.998718 -227.350317) (xy 372.040389 -227.383548)
			(xy 372.076641 -227.422619) (xy 372.106665 -227.466656) (xy 372.129791 -227.514677) (xy 372.145501 -227.565607)
			(xy 372.153444 -227.618311) (xy 372.153942 -227.64496) (xy 372.153444 -227.671609) (xy 372.382024 -227.671609)
			(xy 372.382024 -227.618311) (xy 372.389967 -227.565607) (xy 372.405677 -227.514677) (xy 372.428803 -227.466656)
			(xy 372.458827 -227.422619) (xy 372.495079 -227.383548) (xy 372.53675 -227.350317) (xy 372.582908 -227.323668)
			(xy 372.632522 -227.304196) (xy 372.684484 -227.292336) (xy 372.737634 -227.288353) (xy 372.790784 -227.292336)
			(xy 372.842746 -227.304196) (xy 372.89236 -227.323668) (xy 372.938518 -227.350317) (xy 372.980189 -227.383548)
			(xy 373.016441 -227.422619) (xy 373.046465 -227.466656) (xy 373.069591 -227.514677) (xy 373.085301 -227.565607)
			(xy 373.093244 -227.618311) (xy 373.093742 -227.64496) (xy 373.093244 -227.671609) (xy 373.321824 -227.671609)
			(xy 373.321824 -227.618311) (xy 373.329767 -227.565607) (xy 373.345477 -227.514677) (xy 373.368603 -227.466656)
			(xy 373.398627 -227.422619) (xy 373.434879 -227.383548) (xy 373.47655 -227.350317) (xy 373.522708 -227.323668)
			(xy 373.572322 -227.304196) (xy 373.624284 -227.292336) (xy 373.677434 -227.288353) (xy 373.730584 -227.292336)
			(xy 373.782546 -227.304196) (xy 373.83216 -227.323668) (xy 373.878318 -227.350317) (xy 373.919989 -227.383548)
			(xy 373.956241 -227.422619) (xy 373.986265 -227.466656) (xy 374.009391 -227.514677) (xy 374.025101 -227.565607)
			(xy 374.033044 -227.618311) (xy 374.033542 -227.64496) (xy 374.033044 -227.671609) (xy 374.261624 -227.671609)
			(xy 374.261624 -227.618311) (xy 374.269567 -227.565607) (xy 374.285277 -227.514677) (xy 374.308403 -227.466656)
			(xy 374.338427 -227.422619) (xy 374.374679 -227.383548) (xy 374.41635 -227.350317) (xy 374.462508 -227.323668)
			(xy 374.512122 -227.304196) (xy 374.564084 -227.292336) (xy 374.617234 -227.288353) (xy 374.670384 -227.292336)
			(xy 374.722346 -227.304196) (xy 374.77196 -227.323668) (xy 374.818118 -227.350317) (xy 374.859789 -227.383548)
			(xy 374.896041 -227.422619) (xy 374.926065 -227.466656) (xy 374.949191 -227.514677) (xy 374.964901 -227.565607)
			(xy 374.972844 -227.618311) (xy 374.973342 -227.64496) (xy 374.972844 -227.671609) (xy 375.20117 -227.671609)
			(xy 375.20117 -227.618311) (xy 375.209113 -227.565607) (xy 375.224823 -227.514677) (xy 375.247949 -227.466656)
			(xy 375.277973 -227.422619) (xy 375.314225 -227.383548) (xy 375.355896 -227.350317) (xy 375.402054 -227.323668)
			(xy 375.451668 -227.304196) (xy 375.50363 -227.292336) (xy 375.55678 -227.288353) (xy 375.60993 -227.292336)
			(xy 375.661892 -227.304196) (xy 375.711506 -227.323668) (xy 375.757664 -227.350317) (xy 375.799335 -227.383548)
			(xy 375.835587 -227.422619) (xy 375.865611 -227.466656) (xy 375.888737 -227.514677) (xy 375.904447 -227.565607)
			(xy 375.91239 -227.618311) (xy 375.912888 -227.64496) (xy 375.91239 -227.671609) (xy 376.14097 -227.671609)
			(xy 376.14097 -227.618311) (xy 376.148913 -227.565607) (xy 376.164623 -227.514677) (xy 376.187749 -227.466656)
			(xy 376.217773 -227.422619) (xy 376.254025 -227.383548) (xy 376.295696 -227.350317) (xy 376.341854 -227.323668)
			(xy 376.391468 -227.304196) (xy 376.44343 -227.292336) (xy 376.49658 -227.288353) (xy 376.54973 -227.292336)
			(xy 376.601692 -227.304196) (xy 376.651306 -227.323668) (xy 376.697464 -227.350317) (xy 376.739135 -227.383548)
			(xy 376.775387 -227.422619) (xy 376.805411 -227.466656) (xy 376.828537 -227.514677) (xy 376.844247 -227.565607)
			(xy 376.85219 -227.618311) (xy 376.852688 -227.64496) (xy 376.85219 -227.671609) (xy 376.844247 -227.724313)
			(xy 376.828537 -227.775243) (xy 376.805411 -227.823264) (xy 376.775387 -227.867301) (xy 376.739135 -227.906372)
			(xy 376.697464 -227.939603) (xy 376.651306 -227.966252) (xy 376.601692 -227.985724) (xy 376.54973 -227.997584)
			(xy 376.49658 -228.001568) (xy 376.44343 -227.997584) (xy 376.391468 -227.985724) (xy 376.341854 -227.966252)
			(xy 376.295696 -227.939603) (xy 376.254025 -227.906372) (xy 376.217773 -227.867301) (xy 376.187749 -227.823264)
			(xy 376.164623 -227.775243) (xy 376.148913 -227.724313) (xy 376.14097 -227.671609) (xy 375.91239 -227.671609)
			(xy 375.904447 -227.724313) (xy 375.888737 -227.775243) (xy 375.865611 -227.823264) (xy 375.835587 -227.867301)
			(xy 375.799335 -227.906372) (xy 375.757664 -227.939603) (xy 375.711506 -227.966252) (xy 375.661892 -227.985724)
			(xy 375.60993 -227.997584) (xy 375.55678 -228.001568) (xy 375.50363 -227.997584) (xy 375.451668 -227.985724)
			(xy 375.402054 -227.966252) (xy 375.355896 -227.939603) (xy 375.314225 -227.906372) (xy 375.277973 -227.867301)
			(xy 375.247949 -227.823264) (xy 375.224823 -227.775243) (xy 375.209113 -227.724313) (xy 375.20117 -227.671609)
			(xy 374.972844 -227.671609) (xy 374.964901 -227.724313) (xy 374.949191 -227.775243) (xy 374.926065 -227.823264)
			(xy 374.896041 -227.867301) (xy 374.859789 -227.906372) (xy 374.818118 -227.939603) (xy 374.77196 -227.966252)
			(xy 374.722346 -227.985724) (xy 374.670384 -227.997584) (xy 374.617234 -228.001568) (xy 374.564084 -227.997584)
			(xy 374.512122 -227.985724) (xy 374.462508 -227.966252) (xy 374.41635 -227.939603) (xy 374.374679 -227.906372)
			(xy 374.338427 -227.867301) (xy 374.308403 -227.823264) (xy 374.285277 -227.775243) (xy 374.269567 -227.724313)
			(xy 374.261624 -227.671609) (xy 374.033044 -227.671609) (xy 374.025101 -227.724313) (xy 374.009391 -227.775243)
			(xy 373.986265 -227.823264) (xy 373.956241 -227.867301) (xy 373.919989 -227.906372) (xy 373.878318 -227.939603)
			(xy 373.83216 -227.966252) (xy 373.782546 -227.985724) (xy 373.730584 -227.997584) (xy 373.677434 -228.001568)
			(xy 373.624284 -227.997584) (xy 373.572322 -227.985724) (xy 373.522708 -227.966252) (xy 373.47655 -227.939603)
			(xy 373.434879 -227.906372) (xy 373.398627 -227.867301) (xy 373.368603 -227.823264) (xy 373.345477 -227.775243)
			(xy 373.329767 -227.724313) (xy 373.321824 -227.671609) (xy 373.093244 -227.671609) (xy 373.085301 -227.724313)
			(xy 373.069591 -227.775243) (xy 373.046465 -227.823264) (xy 373.016441 -227.867301) (xy 372.980189 -227.906372)
			(xy 372.938518 -227.939603) (xy 372.89236 -227.966252) (xy 372.842746 -227.985724) (xy 372.790784 -227.997584)
			(xy 372.737634 -228.001568) (xy 372.684484 -227.997584) (xy 372.632522 -227.985724) (xy 372.582908 -227.966252)
			(xy 372.53675 -227.939603) (xy 372.495079 -227.906372) (xy 372.458827 -227.867301) (xy 372.428803 -227.823264)
			(xy 372.405677 -227.775243) (xy 372.389967 -227.724313) (xy 372.382024 -227.671609) (xy 372.153444 -227.671609)
			(xy 372.145501 -227.724313) (xy 372.129791 -227.775243) (xy 372.106665 -227.823264) (xy 372.076641 -227.867301)
			(xy 372.040389 -227.906372) (xy 371.998718 -227.939603) (xy 371.95256 -227.966252) (xy 371.902946 -227.985724)
			(xy 371.850984 -227.997584) (xy 371.797834 -228.001568) (xy 371.744684 -227.997584) (xy 371.692722 -227.985724)
			(xy 371.643108 -227.966252) (xy 371.59695 -227.939603) (xy 371.555279 -227.906372) (xy 371.519027 -227.867301)
			(xy 371.489003 -227.823264) (xy 371.465877 -227.775243) (xy 371.450167 -227.724313) (xy 371.442224 -227.671609)
			(xy 371.213644 -227.671609) (xy 371.205701 -227.724313) (xy 371.189991 -227.775243) (xy 371.166865 -227.823264)
			(xy 371.136841 -227.867301) (xy 371.100589 -227.906372) (xy 371.058918 -227.939603) (xy 371.01276 -227.966252)
			(xy 370.963146 -227.985724) (xy 370.911184 -227.997584) (xy 370.858034 -228.001568) (xy 370.804884 -227.997584)
			(xy 370.752922 -227.985724) (xy 370.703308 -227.966252) (xy 370.65715 -227.939603) (xy 370.615479 -227.906372)
			(xy 370.579227 -227.867301) (xy 370.549203 -227.823264) (xy 370.526077 -227.775243) (xy 370.510367 -227.724313)
			(xy 370.502424 -227.671609) (xy 370.27359 -227.671609) (xy 370.265647 -227.724313) (xy 370.249937 -227.775243)
			(xy 370.226811 -227.823264) (xy 370.196787 -227.867301) (xy 370.160535 -227.906372) (xy 370.118864 -227.939603)
			(xy 370.072706 -227.966252) (xy 370.023092 -227.985724) (xy 369.97113 -227.997584) (xy 369.91798 -228.001568)
			(xy 369.86483 -227.997584) (xy 369.812868 -227.985724) (xy 369.763254 -227.966252) (xy 369.717096 -227.939603)
			(xy 369.675425 -227.906372) (xy 369.639173 -227.867301) (xy 369.609149 -227.823264) (xy 369.586023 -227.775243)
			(xy 369.570313 -227.724313) (xy 369.56237 -227.671609) (xy 369.334044 -227.671609) (xy 369.326101 -227.724313)
			(xy 369.310391 -227.775243) (xy 369.287265 -227.823264) (xy 369.257241 -227.867301) (xy 369.220989 -227.906372)
			(xy 369.179318 -227.939603) (xy 369.13316 -227.966252) (xy 369.083546 -227.985724) (xy 369.031584 -227.997584)
			(xy 368.978434 -228.001568) (xy 368.925284 -227.997584) (xy 368.873322 -227.985724) (xy 368.823708 -227.966252)
			(xy 368.77755 -227.939603) (xy 368.735879 -227.906372) (xy 368.699627 -227.867301) (xy 368.669603 -227.823264)
			(xy 368.646477 -227.775243) (xy 368.630767 -227.724313) (xy 368.622824 -227.671609) (xy 368.394244 -227.671609)
			(xy 368.386301 -227.724313) (xy 368.370591 -227.775243) (xy 368.347465 -227.823264) (xy 368.317441 -227.867301)
			(xy 368.281189 -227.906372) (xy 368.239518 -227.939603) (xy 368.19336 -227.966252) (xy 368.143746 -227.985724)
			(xy 368.091784 -227.997584) (xy 368.038634 -228.001568) (xy 367.985484 -227.997584) (xy 367.933522 -227.985724)
			(xy 367.883908 -227.966252) (xy 367.83775 -227.939603) (xy 367.796079 -227.906372) (xy 367.759827 -227.867301)
			(xy 367.729803 -227.823264) (xy 367.706677 -227.775243) (xy 367.690967 -227.724313) (xy 367.683024 -227.671609)
			(xy 367.454444 -227.671609) (xy 367.446501 -227.724313) (xy 367.430791 -227.775243) (xy 367.407665 -227.823264)
			(xy 367.377641 -227.867301) (xy 367.341389 -227.906372) (xy 367.299718 -227.939603) (xy 367.25356 -227.966252)
			(xy 367.203946 -227.985724) (xy 367.151984 -227.997584) (xy 367.098834 -228.001568) (xy 367.045684 -227.997584)
			(xy 366.993722 -227.985724) (xy 366.944108 -227.966252) (xy 366.89795 -227.939603) (xy 366.856279 -227.906372)
			(xy 366.820027 -227.867301) (xy 366.790003 -227.823264) (xy 366.766877 -227.775243) (xy 366.751167 -227.724313)
			(xy 366.743224 -227.671609) (xy 366.514644 -227.671609) (xy 366.506701 -227.724313) (xy 366.490991 -227.775243)
			(xy 366.467865 -227.823264) (xy 366.437841 -227.867301) (xy 366.401589 -227.906372) (xy 366.359918 -227.939603)
			(xy 366.31376 -227.966252) (xy 366.264146 -227.985724) (xy 366.212184 -227.997584) (xy 366.159034 -228.001568)
			(xy 366.105884 -227.997584) (xy 366.053922 -227.985724) (xy 366.004308 -227.966252) (xy 365.95815 -227.939603)
			(xy 365.916479 -227.906372) (xy 365.880227 -227.867301) (xy 365.850203 -227.823264) (xy 365.827077 -227.775243)
			(xy 365.811367 -227.724313) (xy 365.803424 -227.671609) (xy 365.574844 -227.671609) (xy 365.566901 -227.724313)
			(xy 365.551191 -227.775243) (xy 365.528065 -227.823264) (xy 365.498041 -227.867301) (xy 365.461789 -227.906372)
			(xy 365.420118 -227.939603) (xy 365.37396 -227.966252) (xy 365.324346 -227.985724) (xy 365.272384 -227.997584)
			(xy 365.219234 -228.001568) (xy 365.166084 -227.997584) (xy 365.114122 -227.985724) (xy 365.064508 -227.966252)
			(xy 365.01835 -227.939603) (xy 364.976679 -227.906372) (xy 364.940427 -227.867301) (xy 364.910403 -227.823264)
			(xy 364.887277 -227.775243) (xy 364.871567 -227.724313) (xy 364.863624 -227.671609) (xy 364.635044 -227.671609)
			(xy 364.627101 -227.724313) (xy 364.611391 -227.775243) (xy 364.588265 -227.823264) (xy 364.558241 -227.867301)
			(xy 364.521989 -227.906372) (xy 364.480318 -227.939603) (xy 364.43416 -227.966252) (xy 364.384546 -227.985724)
			(xy 364.332584 -227.997584) (xy 364.279434 -228.001568) (xy 364.226284 -227.997584) (xy 364.174322 -227.985724)
			(xy 364.124708 -227.966252) (xy 364.07855 -227.939603) (xy 364.036879 -227.906372) (xy 364.000627 -227.867301)
			(xy 363.970603 -227.823264) (xy 363.947477 -227.775243) (xy 363.931767 -227.724313) (xy 363.923824 -227.671609)
			(xy 363.695244 -227.671609) (xy 363.687301 -227.724313) (xy 363.671591 -227.775243) (xy 363.648465 -227.823264)
			(xy 363.618441 -227.867301) (xy 363.582189 -227.906372) (xy 363.540518 -227.939603) (xy 363.49436 -227.966252)
			(xy 363.444746 -227.985724) (xy 363.392784 -227.997584) (xy 363.339634 -228.001568) (xy 363.286484 -227.997584)
			(xy 363.234522 -227.985724) (xy 363.184908 -227.966252) (xy 363.13875 -227.939603) (xy 363.097079 -227.906372)
			(xy 363.060827 -227.867301) (xy 363.030803 -227.823264) (xy 363.007677 -227.775243) (xy 362.991967 -227.724313)
			(xy 362.984024 -227.671609) (xy 362.755698 -227.671609) (xy 362.747755 -227.724313) (xy 362.732045 -227.775243)
			(xy 362.708919 -227.823264) (xy 362.678895 -227.867301) (xy 362.642643 -227.906372) (xy 362.600972 -227.939603)
			(xy 362.554814 -227.966252) (xy 362.5052 -227.985724) (xy 362.453238 -227.997584) (xy 362.400088 -228.001568)
			(xy 362.346938 -227.997584) (xy 362.294976 -227.985724) (xy 362.245362 -227.966252) (xy 362.199204 -227.939603)
			(xy 362.157533 -227.906372) (xy 362.121281 -227.867301) (xy 362.091257 -227.823264) (xy 362.068131 -227.775243)
			(xy 362.052421 -227.724313) (xy 362.044478 -227.671609) (xy 361.815644 -227.671609) (xy 361.807701 -227.724313)
			(xy 361.791991 -227.775243) (xy 361.768865 -227.823264) (xy 361.738841 -227.867301) (xy 361.702589 -227.906372)
			(xy 361.660918 -227.939603) (xy 361.61476 -227.966252) (xy 361.565146 -227.985724) (xy 361.513184 -227.997584)
			(xy 361.460034 -228.001568) (xy 361.406884 -227.997584) (xy 361.354922 -227.985724) (xy 361.305308 -227.966252)
			(xy 361.25915 -227.939603) (xy 361.217479 -227.906372) (xy 361.181227 -227.867301) (xy 361.151203 -227.823264)
			(xy 361.128077 -227.775243) (xy 361.112367 -227.724313) (xy 361.104424 -227.671609) (xy 360.875844 -227.671609)
			(xy 360.867901 -227.724313) (xy 360.852191 -227.775243) (xy 360.829065 -227.823264) (xy 360.799041 -227.867301)
			(xy 360.762789 -227.906372) (xy 360.721118 -227.939603) (xy 360.67496 -227.966252) (xy 360.625346 -227.985724)
			(xy 360.573384 -227.997584) (xy 360.520234 -228.001568) (xy 360.467084 -227.997584) (xy 360.415122 -227.985724)
			(xy 360.365508 -227.966252) (xy 360.31935 -227.939603) (xy 360.277679 -227.906372) (xy 360.241427 -227.867301)
			(xy 360.211403 -227.823264) (xy 360.188277 -227.775243) (xy 360.172567 -227.724313) (xy 360.164624 -227.671609)
			(xy 359.936044 -227.671609) (xy 359.928101 -227.724313) (xy 359.912391 -227.775243) (xy 359.889265 -227.823264)
			(xy 359.859241 -227.867301) (xy 359.822989 -227.906372) (xy 359.781318 -227.939603) (xy 359.73516 -227.966252)
			(xy 359.685546 -227.985724) (xy 359.633584 -227.997584) (xy 359.580434 -228.001568) (xy 359.527284 -227.997584)
			(xy 359.475322 -227.985724) (xy 359.425708 -227.966252) (xy 359.37955 -227.939603) (xy 359.337879 -227.906372)
			(xy 359.301627 -227.867301) (xy 359.271603 -227.823264) (xy 359.248477 -227.775243) (xy 359.232767 -227.724313)
			(xy 359.224824 -227.671609) (xy 358.996244 -227.671609) (xy 358.988301 -227.724313) (xy 358.972591 -227.775243)
			(xy 358.949465 -227.823264) (xy 358.919441 -227.867301) (xy 358.883189 -227.906372) (xy 358.841518 -227.939603)
			(xy 358.79536 -227.966252) (xy 358.745746 -227.985724) (xy 358.693784 -227.997584) (xy 358.640634 -228.001568)
			(xy 358.587484 -227.997584) (xy 358.535522 -227.985724) (xy 358.485908 -227.966252) (xy 358.43975 -227.939603)
			(xy 358.398079 -227.906372) (xy 358.361827 -227.867301) (xy 358.331803 -227.823264) (xy 358.308677 -227.775243)
			(xy 358.292967 -227.724313) (xy 358.285024 -227.671609) (xy 358.056444 -227.671609) (xy 358.048501 -227.724313)
			(xy 358.032791 -227.775243) (xy 358.009665 -227.823264) (xy 357.979641 -227.867301) (xy 357.943389 -227.906372)
			(xy 357.901718 -227.939603) (xy 357.85556 -227.966252) (xy 357.805946 -227.985724) (xy 357.753984 -227.997584)
			(xy 357.700834 -228.001568) (xy 357.647684 -227.997584) (xy 357.595722 -227.985724) (xy 357.546108 -227.966252)
			(xy 357.49995 -227.939603) (xy 357.458279 -227.906372) (xy 357.422027 -227.867301) (xy 357.392003 -227.823264)
			(xy 357.368877 -227.775243) (xy 357.353167 -227.724313) (xy 357.345224 -227.671609) (xy 357.116644 -227.671609)
			(xy 357.108701 -227.724313) (xy 357.092991 -227.775243) (xy 357.069865 -227.823264) (xy 357.039841 -227.867301)
			(xy 357.003589 -227.906372) (xy 356.961918 -227.939603) (xy 356.91576 -227.966252) (xy 356.866146 -227.985724)
			(xy 356.814184 -227.997584) (xy 356.761034 -228.001568) (xy 356.707884 -227.997584) (xy 356.655922 -227.985724)
			(xy 356.606308 -227.966252) (xy 356.56015 -227.939603) (xy 356.518479 -227.906372) (xy 356.482227 -227.867301)
			(xy 356.452203 -227.823264) (xy 356.429077 -227.775243) (xy 356.413367 -227.724313) (xy 356.405424 -227.671609)
			(xy 356.176844 -227.671609) (xy 356.168901 -227.724313) (xy 356.153191 -227.775243) (xy 356.130065 -227.823264)
			(xy 356.100041 -227.867301) (xy 356.063789 -227.906372) (xy 356.022118 -227.939603) (xy 355.97596 -227.966252)
			(xy 355.926346 -227.985724) (xy 355.874384 -227.997584) (xy 355.821234 -228.001568) (xy 355.768084 -227.997584)
			(xy 355.716122 -227.985724) (xy 355.666508 -227.966252) (xy 355.62035 -227.939603) (xy 355.578679 -227.906372)
			(xy 355.542427 -227.867301) (xy 355.512403 -227.823264) (xy 355.489277 -227.775243) (xy 355.473567 -227.724313)
			(xy 355.465624 -227.671609) (xy 355.237044 -227.671609) (xy 355.229101 -227.724313) (xy 355.213391 -227.775243)
			(xy 355.190265 -227.823264) (xy 355.160241 -227.867301) (xy 355.123989 -227.906372) (xy 355.082318 -227.939603)
			(xy 355.03616 -227.966252) (xy 354.986546 -227.985724) (xy 354.934584 -227.997584) (xy 354.881434 -228.001568)
			(xy 354.828284 -227.997584) (xy 354.776322 -227.985724) (xy 354.726708 -227.966252) (xy 354.68055 -227.939603)
			(xy 354.638879 -227.906372) (xy 354.602627 -227.867301) (xy 354.572603 -227.823264) (xy 354.549477 -227.775243)
			(xy 354.533767 -227.724313) (xy 354.525824 -227.671609) (xy 354.297244 -227.671609) (xy 354.289301 -227.724313)
			(xy 354.273591 -227.775243) (xy 354.250465 -227.823264) (xy 354.220441 -227.867301) (xy 354.184189 -227.906372)
			(xy 354.142518 -227.939603) (xy 354.09636 -227.966252) (xy 354.046746 -227.985724) (xy 353.994784 -227.997584)
			(xy 353.941634 -228.001568) (xy 353.888484 -227.997584) (xy 353.836522 -227.985724) (xy 353.786908 -227.966252)
			(xy 353.74075 -227.939603) (xy 353.699079 -227.906372) (xy 353.662827 -227.867301) (xy 353.632803 -227.823264)
			(xy 353.609677 -227.775243) (xy 353.593967 -227.724313) (xy 353.586024 -227.671609) (xy 353.357444 -227.671609)
			(xy 353.349501 -227.724313) (xy 353.333791 -227.775243) (xy 353.310665 -227.823264) (xy 353.280641 -227.867301)
			(xy 353.244389 -227.906372) (xy 353.202718 -227.939603) (xy 353.15656 -227.966252) (xy 353.106946 -227.985724)
			(xy 353.054984 -227.997584) (xy 353.001834 -228.001568) (xy 352.948684 -227.997584) (xy 352.896722 -227.985724)
			(xy 352.847108 -227.966252) (xy 352.80095 -227.939603) (xy 352.759279 -227.906372) (xy 352.723027 -227.867301)
			(xy 352.693003 -227.823264) (xy 352.669877 -227.775243) (xy 352.654167 -227.724313) (xy 352.646224 -227.671609)
			(xy 352.417644 -227.671609) (xy 352.409701 -227.724313) (xy 352.393991 -227.775243) (xy 352.370865 -227.823264)
			(xy 352.340841 -227.867301) (xy 352.304589 -227.906372) (xy 352.262918 -227.939603) (xy 352.21676 -227.966252)
			(xy 352.167146 -227.985724) (xy 352.115184 -227.997584) (xy 352.062034 -228.001568) (xy 352.008884 -227.997584)
			(xy 351.956922 -227.985724) (xy 351.907308 -227.966252) (xy 351.86115 -227.939603) (xy 351.819479 -227.906372)
			(xy 351.783227 -227.867301) (xy 351.753203 -227.823264) (xy 351.730077 -227.775243) (xy 351.714367 -227.724313)
			(xy 351.706424 -227.671609) (xy 350.538044 -227.671609) (xy 350.530101 -227.724313) (xy 350.514391 -227.775243)
			(xy 350.491265 -227.823264) (xy 350.461241 -227.867301) (xy 350.424989 -227.906372) (xy 350.383318 -227.939603)
			(xy 350.33716 -227.966252) (xy 350.287546 -227.985724) (xy 350.235584 -227.997584) (xy 350.182434 -228.001568)
			(xy 350.129284 -227.997584) (xy 350.077322 -227.985724) (xy 350.027708 -227.966252) (xy 349.98155 -227.939603)
			(xy 349.939879 -227.906372) (xy 349.903627 -227.867301) (xy 349.873603 -227.823264) (xy 349.850477 -227.775243)
			(xy 349.834767 -227.724313) (xy 349.826824 -227.671609) (xy 349.598244 -227.671609) (xy 349.590301 -227.724313)
			(xy 349.574591 -227.775243) (xy 349.551465 -227.823264) (xy 349.521441 -227.867301) (xy 349.485189 -227.906372)
			(xy 349.443518 -227.939603) (xy 349.39736 -227.966252) (xy 349.347746 -227.985724) (xy 349.295784 -227.997584)
			(xy 349.242634 -228.001568) (xy 349.189484 -227.997584) (xy 349.137522 -227.985724) (xy 349.087908 -227.966252)
			(xy 349.04175 -227.939603) (xy 349.000079 -227.906372) (xy 348.963827 -227.867301) (xy 348.933803 -227.823264)
			(xy 348.910677 -227.775243) (xy 348.894967 -227.724313) (xy 348.887024 -227.671609) (xy 348.658444 -227.671609)
			(xy 348.650501 -227.724313) (xy 348.634791 -227.775243) (xy 348.611665 -227.823264) (xy 348.581641 -227.867301)
			(xy 348.545389 -227.906372) (xy 348.503718 -227.939603) (xy 348.45756 -227.966252) (xy 348.407946 -227.985724)
			(xy 348.355984 -227.997584) (xy 348.302834 -228.001568) (xy 348.249684 -227.997584) (xy 348.197722 -227.985724)
			(xy 348.148108 -227.966252) (xy 348.10195 -227.939603) (xy 348.060279 -227.906372) (xy 348.024027 -227.867301)
			(xy 347.994003 -227.823264) (xy 347.970877 -227.775243) (xy 347.955167 -227.724313) (xy 347.947224 -227.671609)
			(xy 347.71839 -227.671609) (xy 347.710447 -227.724313) (xy 347.694737 -227.775243) (xy 347.671611 -227.823264)
			(xy 347.641587 -227.867301) (xy 347.605335 -227.906372) (xy 347.563664 -227.939603) (xy 347.517506 -227.966252)
			(xy 347.467892 -227.985724) (xy 347.41593 -227.997584) (xy 347.36278 -228.001568) (xy 347.30963 -227.997584)
			(xy 347.257668 -227.985724) (xy 347.208054 -227.966252) (xy 347.161896 -227.939603) (xy 347.120225 -227.906372)
			(xy 347.083973 -227.867301) (xy 347.053949 -227.823264) (xy 347.030823 -227.775243) (xy 347.015113 -227.724313)
			(xy 347.00717 -227.671609) (xy 346.778844 -227.671609) (xy 346.770901 -227.724313) (xy 346.755191 -227.775243)
			(xy 346.732065 -227.823264) (xy 346.702041 -227.867301) (xy 346.665789 -227.906372) (xy 346.624118 -227.939603)
			(xy 346.57796 -227.966252) (xy 346.528346 -227.985724) (xy 346.476384 -227.997584) (xy 346.423234 -228.001568)
			(xy 346.370084 -227.997584) (xy 346.318122 -227.985724) (xy 346.268508 -227.966252) (xy 346.22235 -227.939603)
			(xy 346.180679 -227.906372) (xy 346.144427 -227.867301) (xy 346.114403 -227.823264) (xy 346.091277 -227.775243)
			(xy 346.075567 -227.724313) (xy 346.067624 -227.671609) (xy 345.839044 -227.671609) (xy 345.831101 -227.724313)
			(xy 345.815391 -227.775243) (xy 345.792265 -227.823264) (xy 345.762241 -227.867301) (xy 345.725989 -227.906372)
			(xy 345.684318 -227.939603) (xy 345.63816 -227.966252) (xy 345.588546 -227.985724) (xy 345.536584 -227.997584)
			(xy 345.483434 -228.001568) (xy 345.430284 -227.997584) (xy 345.378322 -227.985724) (xy 345.328708 -227.966252)
			(xy 345.28255 -227.939603) (xy 345.240879 -227.906372) (xy 345.204627 -227.867301) (xy 345.174603 -227.823264)
			(xy 345.151477 -227.775243) (xy 345.135767 -227.724313) (xy 345.127824 -227.671609) (xy 344.899244 -227.671609)
			(xy 344.891301 -227.724313) (xy 344.875591 -227.775243) (xy 344.852465 -227.823264) (xy 344.822441 -227.867301)
			(xy 344.786189 -227.906372) (xy 344.744518 -227.939603) (xy 344.69836 -227.966252) (xy 344.648746 -227.985724)
			(xy 344.596784 -227.997584) (xy 344.543634 -228.001568) (xy 344.490484 -227.997584) (xy 344.438522 -227.985724)
			(xy 344.388908 -227.966252) (xy 344.34275 -227.939603) (xy 344.301079 -227.906372) (xy 344.264827 -227.867301)
			(xy 344.234803 -227.823264) (xy 344.211677 -227.775243) (xy 344.195967 -227.724313) (xy 344.188024 -227.671609)
			(xy 343.959444 -227.671609) (xy 343.951501 -227.724313) (xy 343.935791 -227.775243) (xy 343.912665 -227.823264)
			(xy 343.882641 -227.867301) (xy 343.846389 -227.906372) (xy 343.804718 -227.939603) (xy 343.75856 -227.966252)
			(xy 343.708946 -227.985724) (xy 343.656984 -227.997584) (xy 343.603834 -228.001568) (xy 343.550684 -227.997584)
			(xy 343.498722 -227.985724) (xy 343.449108 -227.966252) (xy 343.40295 -227.939603) (xy 343.361279 -227.906372)
			(xy 343.325027 -227.867301) (xy 343.295003 -227.823264) (xy 343.271877 -227.775243) (xy 343.256167 -227.724313)
			(xy 343.248224 -227.671609) (xy 343.019644 -227.671609) (xy 343.011701 -227.724313) (xy 342.995991 -227.775243)
			(xy 342.972865 -227.823264) (xy 342.942841 -227.867301) (xy 342.906589 -227.906372) (xy 342.864918 -227.939603)
			(xy 342.81876 -227.966252) (xy 342.769146 -227.985724) (xy 342.717184 -227.997584) (xy 342.664034 -228.001568)
			(xy 342.610884 -227.997584) (xy 342.558922 -227.985724) (xy 342.509308 -227.966252) (xy 342.46315 -227.939603)
			(xy 342.421479 -227.906372) (xy 342.385227 -227.867301) (xy 342.355203 -227.823264) (xy 342.332077 -227.775243)
			(xy 342.316367 -227.724313) (xy 342.308424 -227.671609) (xy 342.079844 -227.671609) (xy 342.071901 -227.724313)
			(xy 342.056191 -227.775243) (xy 342.033065 -227.823264) (xy 342.003041 -227.867301) (xy 341.966789 -227.906372)
			(xy 341.925118 -227.939603) (xy 341.87896 -227.966252) (xy 341.829346 -227.985724) (xy 341.777384 -227.997584)
			(xy 341.724234 -228.001568) (xy 341.671084 -227.997584) (xy 341.619122 -227.985724) (xy 341.569508 -227.966252)
			(xy 341.52335 -227.939603) (xy 341.481679 -227.906372) (xy 341.445427 -227.867301) (xy 341.415403 -227.823264)
			(xy 341.392277 -227.775243) (xy 341.376567 -227.724313) (xy 341.368624 -227.671609) (xy 341.140044 -227.671609)
			(xy 341.132101 -227.724313) (xy 341.116391 -227.775243) (xy 341.093265 -227.823264) (xy 341.063241 -227.867301)
			(xy 341.026989 -227.906372) (xy 340.985318 -227.939603) (xy 340.93916 -227.966252) (xy 340.889546 -227.985724)
			(xy 340.837584 -227.997584) (xy 340.784434 -228.001568) (xy 340.731284 -227.997584) (xy 340.679322 -227.985724)
			(xy 340.629708 -227.966252) (xy 340.58355 -227.939603) (xy 340.541879 -227.906372) (xy 340.505627 -227.867301)
			(xy 340.475603 -227.823264) (xy 340.452477 -227.775243) (xy 340.436767 -227.724313) (xy 340.428824 -227.671609)
			(xy 340.19999 -227.671609) (xy 340.192047 -227.724313) (xy 340.176337 -227.775243) (xy 340.153211 -227.823264)
			(xy 340.123187 -227.867301) (xy 340.086935 -227.906372) (xy 340.045264 -227.939603) (xy 339.999106 -227.966252)
			(xy 339.949492 -227.985724) (xy 339.89753 -227.997584) (xy 339.84438 -228.001568) (xy 339.79123 -227.997584)
			(xy 339.739268 -227.985724) (xy 339.689654 -227.966252) (xy 339.643496 -227.939603) (xy 339.601825 -227.906372)
			(xy 339.565573 -227.867301) (xy 339.535549 -227.823264) (xy 339.512423 -227.775243) (xy 339.496713 -227.724313)
			(xy 339.48877 -227.671609) (xy 339.37956 -227.671609) (xy 339.37956 -228.100128) (xy 339.423502 -228.106224)
			(xy 339.450062 -228.110393) (xy 339.501603 -228.125681) (xy 339.550262 -228.148542) (xy 339.594931 -228.178457)
			(xy 339.634597 -228.214746) (xy 339.668357 -228.256585) (xy 339.695445 -228.303023) (xy 339.715245 -228.353006)
			(xy 339.727308 -228.405396) (xy 339.73136 -228.459004) (xy 339.729343 -228.485679) (xy 339.95867 -228.485679)
			(xy 339.95867 -228.432381) (xy 339.966613 -228.379677) (xy 339.982323 -228.328747) (xy 340.005449 -228.280726)
			(xy 340.035473 -228.236689) (xy 340.071725 -228.197618) (xy 340.113396 -228.164387) (xy 340.159554 -228.137738)
			(xy 340.209168 -228.118266) (xy 340.26113 -228.106406) (xy 340.31428 -228.102423) (xy 340.36743 -228.106406)
			(xy 340.419392 -228.118266) (xy 340.469006 -228.137738) (xy 340.515164 -228.164387) (xy 340.556835 -228.197618)
			(xy 340.593087 -228.236689) (xy 340.623111 -228.280726) (xy 340.646237 -228.328747) (xy 340.661947 -228.379677)
			(xy 340.66989 -228.432381) (xy 340.670388 -228.45903) (xy 340.66989 -228.485679) (xy 340.89847 -228.485679)
			(xy 340.89847 -228.432381) (xy 340.906413 -228.379677) (xy 340.922123 -228.328747) (xy 340.945249 -228.280726)
			(xy 340.975273 -228.236689) (xy 341.011525 -228.197618) (xy 341.053196 -228.164387) (xy 341.099354 -228.137738)
			(xy 341.148968 -228.118266) (xy 341.20093 -228.106406) (xy 341.25408 -228.102423) (xy 341.30723 -228.106406)
			(xy 341.359192 -228.118266) (xy 341.408806 -228.137738) (xy 341.454964 -228.164387) (xy 341.496635 -228.197618)
			(xy 341.532887 -228.236689) (xy 341.562911 -228.280726) (xy 341.586037 -228.328747) (xy 341.601747 -228.379677)
			(xy 341.60969 -228.432381) (xy 341.610188 -228.45903) (xy 341.60969 -228.485679) (xy 341.83827 -228.485679)
			(xy 341.83827 -228.432381) (xy 341.846213 -228.379677) (xy 341.861923 -228.328747) (xy 341.885049 -228.280726)
			(xy 341.915073 -228.236689) (xy 341.951325 -228.197618) (xy 341.992996 -228.164387) (xy 342.039154 -228.137738)
			(xy 342.088768 -228.118266) (xy 342.14073 -228.106406) (xy 342.19388 -228.102423) (xy 342.24703 -228.106406)
			(xy 342.298992 -228.118266) (xy 342.348606 -228.137738) (xy 342.394764 -228.164387) (xy 342.436435 -228.197618)
			(xy 342.472687 -228.236689) (xy 342.502711 -228.280726) (xy 342.525837 -228.328747) (xy 342.541547 -228.379677)
			(xy 342.54949 -228.432381) (xy 342.549988 -228.45903) (xy 342.54949 -228.485679) (xy 342.77807 -228.485679)
			(xy 342.77807 -228.432381) (xy 342.786013 -228.379677) (xy 342.801723 -228.328747) (xy 342.824849 -228.280726)
			(xy 342.854873 -228.236689) (xy 342.891125 -228.197618) (xy 342.932796 -228.164387) (xy 342.978954 -228.137738)
			(xy 343.028568 -228.118266) (xy 343.08053 -228.106406) (xy 343.13368 -228.102423) (xy 343.18683 -228.106406)
			(xy 343.238792 -228.118266) (xy 343.288406 -228.137738) (xy 343.334564 -228.164387) (xy 343.376235 -228.197618)
			(xy 343.412487 -228.236689) (xy 343.442511 -228.280726) (xy 343.465637 -228.328747) (xy 343.481347 -228.379677)
			(xy 343.48929 -228.432381) (xy 343.489788 -228.45903) (xy 343.48929 -228.485679) (xy 343.71787 -228.485679)
			(xy 343.71787 -228.432381) (xy 343.725813 -228.379677) (xy 343.741523 -228.328747) (xy 343.764649 -228.280726)
			(xy 343.794673 -228.236689) (xy 343.830925 -228.197618) (xy 343.872596 -228.164387) (xy 343.918754 -228.137738)
			(xy 343.968368 -228.118266) (xy 344.02033 -228.106406) (xy 344.07348 -228.102423) (xy 344.12663 -228.106406)
			(xy 344.178592 -228.118266) (xy 344.228206 -228.137738) (xy 344.274364 -228.164387) (xy 344.316035 -228.197618)
			(xy 344.352287 -228.236689) (xy 344.382311 -228.280726) (xy 344.405437 -228.328747) (xy 344.421147 -228.379677)
			(xy 344.42909 -228.432381) (xy 344.429588 -228.45903) (xy 344.42909 -228.485679) (xy 344.65767 -228.485679)
			(xy 344.65767 -228.432381) (xy 344.665613 -228.379677) (xy 344.681323 -228.328747) (xy 344.704449 -228.280726)
			(xy 344.734473 -228.236689) (xy 344.770725 -228.197618) (xy 344.812396 -228.164387) (xy 344.858554 -228.137738)
			(xy 344.908168 -228.118266) (xy 344.96013 -228.106406) (xy 345.01328 -228.102423) (xy 345.06643 -228.106406)
			(xy 345.118392 -228.118266) (xy 345.168006 -228.137738) (xy 345.214164 -228.164387) (xy 345.255835 -228.197618)
			(xy 345.292087 -228.236689) (xy 345.322111 -228.280726) (xy 345.345237 -228.328747) (xy 345.360947 -228.379677)
			(xy 345.36889 -228.432381) (xy 345.369388 -228.45903) (xy 345.36889 -228.485679) (xy 345.597724 -228.485679)
			(xy 345.597724 -228.432381) (xy 345.605667 -228.379677) (xy 345.621377 -228.328747) (xy 345.644503 -228.280726)
			(xy 345.674527 -228.236689) (xy 345.710779 -228.197618) (xy 345.75245 -228.164387) (xy 345.798608 -228.137738)
			(xy 345.848222 -228.118266) (xy 345.900184 -228.106406) (xy 345.953334 -228.102423) (xy 346.006484 -228.106406)
			(xy 346.058446 -228.118266) (xy 346.10806 -228.137738) (xy 346.154218 -228.164387) (xy 346.195889 -228.197618)
			(xy 346.232141 -228.236689) (xy 346.262165 -228.280726) (xy 346.285291 -228.328747) (xy 346.301001 -228.379677)
			(xy 346.308944 -228.432381) (xy 346.309442 -228.45903) (xy 346.308944 -228.485679) (xy 346.53727 -228.485679)
			(xy 346.53727 -228.432381) (xy 346.545213 -228.379677) (xy 346.560923 -228.328747) (xy 346.584049 -228.280726)
			(xy 346.614073 -228.236689) (xy 346.650325 -228.197618) (xy 346.691996 -228.164387) (xy 346.738154 -228.137738)
			(xy 346.787768 -228.118266) (xy 346.83973 -228.106406) (xy 346.89288 -228.102423) (xy 346.94603 -228.106406)
			(xy 346.997992 -228.118266) (xy 347.047606 -228.137738) (xy 347.093764 -228.164387) (xy 347.135435 -228.197618)
			(xy 347.171687 -228.236689) (xy 347.201711 -228.280726) (xy 347.224837 -228.328747) (xy 347.240547 -228.379677)
			(xy 347.24849 -228.432381) (xy 347.248988 -228.45903) (xy 347.24849 -228.485679) (xy 347.47707 -228.485679)
			(xy 347.47707 -228.432381) (xy 347.485013 -228.379677) (xy 347.500723 -228.328747) (xy 347.523849 -228.280726)
			(xy 347.553873 -228.236689) (xy 347.590125 -228.197618) (xy 347.631796 -228.164387) (xy 347.677954 -228.137738)
			(xy 347.727568 -228.118266) (xy 347.77953 -228.106406) (xy 347.83268 -228.102423) (xy 347.88583 -228.106406)
			(xy 347.937792 -228.118266) (xy 347.987406 -228.137738) (xy 348.033564 -228.164387) (xy 348.075235 -228.197618)
			(xy 348.111487 -228.236689) (xy 348.141511 -228.280726) (xy 348.164637 -228.328747) (xy 348.180347 -228.379677)
			(xy 348.18829 -228.432381) (xy 348.188788 -228.45903) (xy 348.18829 -228.485679) (xy 348.41687 -228.485679)
			(xy 348.41687 -228.432381) (xy 348.424813 -228.379677) (xy 348.440523 -228.328747) (xy 348.463649 -228.280726)
			(xy 348.493673 -228.236689) (xy 348.529925 -228.197618) (xy 348.571596 -228.164387) (xy 348.617754 -228.137738)
			(xy 348.667368 -228.118266) (xy 348.71933 -228.106406) (xy 348.77248 -228.102423) (xy 348.82563 -228.106406)
			(xy 348.877592 -228.118266) (xy 348.927206 -228.137738) (xy 348.973364 -228.164387) (xy 349.015035 -228.197618)
			(xy 349.051287 -228.236689) (xy 349.081311 -228.280726) (xy 349.104437 -228.328747) (xy 349.120147 -228.379677)
			(xy 349.12809 -228.432381) (xy 349.128588 -228.45903) (xy 349.12809 -228.485679) (xy 349.35667 -228.485679)
			(xy 349.35667 -228.432381) (xy 349.364613 -228.379677) (xy 349.380323 -228.328747) (xy 349.403449 -228.280726)
			(xy 349.433473 -228.236689) (xy 349.469725 -228.197618) (xy 349.511396 -228.164387) (xy 349.557554 -228.137738)
			(xy 349.607168 -228.118266) (xy 349.65913 -228.106406) (xy 349.71228 -228.102423) (xy 349.76543 -228.106406)
			(xy 349.817392 -228.118266) (xy 349.867006 -228.137738) (xy 349.913164 -228.164387) (xy 349.954835 -228.197618)
			(xy 349.991087 -228.236689) (xy 350.021111 -228.280726) (xy 350.044237 -228.328747) (xy 350.059947 -228.379677)
			(xy 350.06789 -228.432381) (xy 350.068388 -228.45903) (xy 350.06789 -228.485679) (xy 350.29647 -228.485679)
			(xy 350.29647 -228.432381) (xy 350.304413 -228.379677) (xy 350.320123 -228.328747) (xy 350.343249 -228.280726)
			(xy 350.373273 -228.236689) (xy 350.409525 -228.197618) (xy 350.451196 -228.164387) (xy 350.497354 -228.137738)
			(xy 350.546968 -228.118266) (xy 350.59893 -228.106406) (xy 350.65208 -228.102423) (xy 350.70523 -228.106406)
			(xy 350.757192 -228.118266) (xy 350.806806 -228.137738) (xy 350.852964 -228.164387) (xy 350.894635 -228.197618)
			(xy 350.930887 -228.236689) (xy 350.960911 -228.280726) (xy 350.984037 -228.328747) (xy 350.999747 -228.379677)
			(xy 351.00769 -228.432381) (xy 351.008188 -228.45903) (xy 351.00769 -228.485679) (xy 351.007652 -228.485933)
			(xy 351.236524 -228.485933) (xy 351.236524 -228.432635) (xy 351.244467 -228.379931) (xy 351.260177 -228.329001)
			(xy 351.283303 -228.28098) (xy 351.313327 -228.236943) (xy 351.349579 -228.197872) (xy 351.39125 -228.164641)
			(xy 351.437408 -228.137992) (xy 351.487022 -228.11852) (xy 351.538984 -228.10666) (xy 351.592134 -228.102677)
			(xy 351.645284 -228.10666) (xy 351.697246 -228.11852) (xy 351.74686 -228.137992) (xy 351.793018 -228.164641)
			(xy 351.834689 -228.197872) (xy 351.870941 -228.236943) (xy 351.900965 -228.28098) (xy 351.924091 -228.329001)
			(xy 351.939801 -228.379931) (xy 351.947744 -228.432635) (xy 351.948242 -228.459284) (xy 351.947749 -228.485679)
			(xy 352.17607 -228.485679) (xy 352.17607 -228.432381) (xy 352.184013 -228.379677) (xy 352.199723 -228.328747)
			(xy 352.222849 -228.280726) (xy 352.252873 -228.236689) (xy 352.289125 -228.197618) (xy 352.330796 -228.164387)
			(xy 352.376954 -228.137738) (xy 352.426568 -228.118266) (xy 352.47853 -228.106406) (xy 352.53168 -228.102423)
			(xy 352.58483 -228.106406) (xy 352.636792 -228.118266) (xy 352.686406 -228.137738) (xy 352.732564 -228.164387)
			(xy 352.774235 -228.197618) (xy 352.810487 -228.236689) (xy 352.840511 -228.280726) (xy 352.863637 -228.328747)
			(xy 352.879347 -228.379677) (xy 352.88729 -228.432381) (xy 352.887788 -228.45903) (xy 352.88729 -228.485679)
			(xy 353.11587 -228.485679) (xy 353.11587 -228.432381) (xy 353.123813 -228.379677) (xy 353.139523 -228.328747)
			(xy 353.162649 -228.280726) (xy 353.192673 -228.236689) (xy 353.228925 -228.197618) (xy 353.270596 -228.164387)
			(xy 353.316754 -228.137738) (xy 353.366368 -228.118266) (xy 353.41833 -228.106406) (xy 353.47148 -228.102423)
			(xy 353.52463 -228.106406) (xy 353.576592 -228.118266) (xy 353.626206 -228.137738) (xy 353.672364 -228.164387)
			(xy 353.714035 -228.197618) (xy 353.750287 -228.236689) (xy 353.780311 -228.280726) (xy 353.803437 -228.328747)
			(xy 353.819147 -228.379677) (xy 353.82709 -228.432381) (xy 353.827588 -228.45903) (xy 353.82709 -228.485679)
			(xy 354.05567 -228.485679) (xy 354.05567 -228.432381) (xy 354.063613 -228.379677) (xy 354.079323 -228.328747)
			(xy 354.102449 -228.280726) (xy 354.132473 -228.236689) (xy 354.168725 -228.197618) (xy 354.210396 -228.164387)
			(xy 354.256554 -228.137738) (xy 354.306168 -228.118266) (xy 354.35813 -228.106406) (xy 354.41128 -228.102423)
			(xy 354.46443 -228.106406) (xy 354.516392 -228.118266) (xy 354.566006 -228.137738) (xy 354.612164 -228.164387)
			(xy 354.653835 -228.197618) (xy 354.690087 -228.236689) (xy 354.720111 -228.280726) (xy 354.743237 -228.328747)
			(xy 354.758947 -228.379677) (xy 354.76689 -228.432381) (xy 354.767388 -228.45903) (xy 354.76689 -228.485679)
			(xy 354.99547 -228.485679) (xy 354.99547 -228.432381) (xy 355.003413 -228.379677) (xy 355.019123 -228.328747)
			(xy 355.042249 -228.280726) (xy 355.072273 -228.236689) (xy 355.108525 -228.197618) (xy 355.150196 -228.164387)
			(xy 355.196354 -228.137738) (xy 355.245968 -228.118266) (xy 355.29793 -228.106406) (xy 355.35108 -228.102423)
			(xy 355.40423 -228.106406) (xy 355.456192 -228.118266) (xy 355.505806 -228.137738) (xy 355.551964 -228.164387)
			(xy 355.593635 -228.197618) (xy 355.629887 -228.236689) (xy 355.659911 -228.280726) (xy 355.683037 -228.328747)
			(xy 355.698747 -228.379677) (xy 355.70669 -228.432381) (xy 355.707188 -228.45903) (xy 355.70669 -228.485679)
			(xy 355.93527 -228.485679) (xy 355.93527 -228.432381) (xy 355.943213 -228.379677) (xy 355.958923 -228.328747)
			(xy 355.982049 -228.280726) (xy 356.012073 -228.236689) (xy 356.048325 -228.197618) (xy 356.089996 -228.164387)
			(xy 356.136154 -228.137738) (xy 356.185768 -228.118266) (xy 356.23773 -228.106406) (xy 356.29088 -228.102423)
			(xy 356.34403 -228.106406) (xy 356.395992 -228.118266) (xy 356.445606 -228.137738) (xy 356.491764 -228.164387)
			(xy 356.533435 -228.197618) (xy 356.569687 -228.236689) (xy 356.599711 -228.280726) (xy 356.622837 -228.328747)
			(xy 356.638547 -228.379677) (xy 356.64649 -228.432381) (xy 356.646988 -228.45903) (xy 356.64649 -228.485679)
			(xy 356.87507 -228.485679) (xy 356.87507 -228.432381) (xy 356.883013 -228.379677) (xy 356.898723 -228.328747)
			(xy 356.921849 -228.280726) (xy 356.951873 -228.236689) (xy 356.988125 -228.197618) (xy 357.029796 -228.164387)
			(xy 357.075954 -228.137738) (xy 357.125568 -228.118266) (xy 357.17753 -228.106406) (xy 357.23068 -228.102423)
			(xy 357.28383 -228.106406) (xy 357.335792 -228.118266) (xy 357.385406 -228.137738) (xy 357.431564 -228.164387)
			(xy 357.473235 -228.197618) (xy 357.509487 -228.236689) (xy 357.539511 -228.280726) (xy 357.562637 -228.328747)
			(xy 357.578347 -228.379677) (xy 357.58629 -228.432381) (xy 357.586788 -228.45903) (xy 357.58629 -228.485679)
			(xy 357.81487 -228.485679) (xy 357.81487 -228.432381) (xy 357.822813 -228.379677) (xy 357.838523 -228.328747)
			(xy 357.861649 -228.280726) (xy 357.891673 -228.236689) (xy 357.927925 -228.197618) (xy 357.969596 -228.164387)
			(xy 358.015754 -228.137738) (xy 358.065368 -228.118266) (xy 358.11733 -228.106406) (xy 358.17048 -228.102423)
			(xy 358.22363 -228.106406) (xy 358.275592 -228.118266) (xy 358.325206 -228.137738) (xy 358.371364 -228.164387)
			(xy 358.413035 -228.197618) (xy 358.449287 -228.236689) (xy 358.479311 -228.280726) (xy 358.502437 -228.328747)
			(xy 358.518147 -228.379677) (xy 358.52609 -228.432381) (xy 358.526588 -228.45903) (xy 358.52609 -228.485679)
			(xy 358.754924 -228.485679) (xy 358.754924 -228.432381) (xy 358.762867 -228.379677) (xy 358.778577 -228.328747)
			(xy 358.801703 -228.280726) (xy 358.831727 -228.236689) (xy 358.867979 -228.197618) (xy 358.90965 -228.164387)
			(xy 358.955808 -228.137738) (xy 359.005422 -228.118266) (xy 359.057384 -228.106406) (xy 359.110534 -228.102423)
			(xy 359.163684 -228.106406) (xy 359.215646 -228.118266) (xy 359.26526 -228.137738) (xy 359.311418 -228.164387)
			(xy 359.353089 -228.197618) (xy 359.389341 -228.236689) (xy 359.419365 -228.280726) (xy 359.442491 -228.328747)
			(xy 359.458201 -228.379677) (xy 359.466144 -228.432381) (xy 359.466642 -228.45903) (xy 359.466144 -228.485679)
			(xy 359.69447 -228.485679) (xy 359.69447 -228.432381) (xy 359.702413 -228.379677) (xy 359.718123 -228.328747)
			(xy 359.741249 -228.280726) (xy 359.771273 -228.236689) (xy 359.807525 -228.197618) (xy 359.849196 -228.164387)
			(xy 359.895354 -228.137738) (xy 359.944968 -228.118266) (xy 359.99693 -228.106406) (xy 360.05008 -228.102423)
			(xy 360.10323 -228.106406) (xy 360.155192 -228.118266) (xy 360.204806 -228.137738) (xy 360.250964 -228.164387)
			(xy 360.292635 -228.197618) (xy 360.328887 -228.236689) (xy 360.358911 -228.280726) (xy 360.382037 -228.328747)
			(xy 360.397747 -228.379677) (xy 360.40569 -228.432381) (xy 360.406188 -228.45903) (xy 360.40569 -228.485679)
			(xy 360.63427 -228.485679) (xy 360.63427 -228.432381) (xy 360.642213 -228.379677) (xy 360.657923 -228.328747)
			(xy 360.681049 -228.280726) (xy 360.711073 -228.236689) (xy 360.747325 -228.197618) (xy 360.788996 -228.164387)
			(xy 360.835154 -228.137738) (xy 360.884768 -228.118266) (xy 360.93673 -228.106406) (xy 360.98988 -228.102423)
			(xy 361.04303 -228.106406) (xy 361.094992 -228.118266) (xy 361.144606 -228.137738) (xy 361.190764 -228.164387)
			(xy 361.232435 -228.197618) (xy 361.268687 -228.236689) (xy 361.298711 -228.280726) (xy 361.321837 -228.328747)
			(xy 361.337547 -228.379677) (xy 361.34549 -228.432381) (xy 361.345988 -228.45903) (xy 361.34549 -228.485679)
			(xy 361.57407 -228.485679) (xy 361.57407 -228.432381) (xy 361.582013 -228.379677) (xy 361.597723 -228.328747)
			(xy 361.620849 -228.280726) (xy 361.650873 -228.236689) (xy 361.687125 -228.197618) (xy 361.728796 -228.164387)
			(xy 361.774954 -228.137738) (xy 361.824568 -228.118266) (xy 361.87653 -228.106406) (xy 361.92968 -228.102423)
			(xy 361.98283 -228.106406) (xy 362.034792 -228.118266) (xy 362.084406 -228.137738) (xy 362.130564 -228.164387)
			(xy 362.172235 -228.197618) (xy 362.208487 -228.236689) (xy 362.238511 -228.280726) (xy 362.261637 -228.328747)
			(xy 362.277347 -228.379677) (xy 362.28529 -228.432381) (xy 362.285788 -228.45903) (xy 362.28529 -228.485679)
			(xy 363.45367 -228.485679) (xy 363.45367 -228.432381) (xy 363.461613 -228.379677) (xy 363.477323 -228.328747)
			(xy 363.500449 -228.280726) (xy 363.530473 -228.236689) (xy 363.566725 -228.197618) (xy 363.608396 -228.164387)
			(xy 363.654554 -228.137738) (xy 363.704168 -228.118266) (xy 363.75613 -228.106406) (xy 363.80928 -228.102423)
			(xy 363.86243 -228.106406) (xy 363.914392 -228.118266) (xy 363.964006 -228.137738) (xy 364.010164 -228.164387)
			(xy 364.051835 -228.197618) (xy 364.088087 -228.236689) (xy 364.118111 -228.280726) (xy 364.141237 -228.328747)
			(xy 364.156947 -228.379677) (xy 364.16489 -228.432381) (xy 364.165388 -228.45903) (xy 364.16489 -228.485679)
			(xy 365.33327 -228.485679) (xy 365.33327 -228.432381) (xy 365.341213 -228.379677) (xy 365.356923 -228.328747)
			(xy 365.380049 -228.280726) (xy 365.410073 -228.236689) (xy 365.446325 -228.197618) (xy 365.487996 -228.164387)
			(xy 365.534154 -228.137738) (xy 365.583768 -228.118266) (xy 365.63573 -228.106406) (xy 365.68888 -228.102423)
			(xy 365.74203 -228.106406) (xy 365.793992 -228.118266) (xy 365.843606 -228.137738) (xy 365.889764 -228.164387)
			(xy 365.931435 -228.197618) (xy 365.967687 -228.236689) (xy 365.997711 -228.280726) (xy 366.020837 -228.328747)
			(xy 366.036547 -228.379677) (xy 366.04449 -228.432381) (xy 366.044988 -228.45903) (xy 366.04449 -228.485679)
			(xy 367.21287 -228.485679) (xy 367.21287 -228.432381) (xy 367.220813 -228.379677) (xy 367.236523 -228.328747)
			(xy 367.259649 -228.280726) (xy 367.289673 -228.236689) (xy 367.325925 -228.197618) (xy 367.367596 -228.164387)
			(xy 367.413754 -228.137738) (xy 367.463368 -228.118266) (xy 367.51533 -228.106406) (xy 367.56848 -228.102423)
			(xy 367.62163 -228.106406) (xy 367.673592 -228.118266) (xy 367.723206 -228.137738) (xy 367.769364 -228.164387)
			(xy 367.811035 -228.197618) (xy 367.847287 -228.236689) (xy 367.877311 -228.280726) (xy 367.900437 -228.328747)
			(xy 367.916147 -228.379677) (xy 367.92409 -228.432381) (xy 367.924588 -228.45903) (xy 367.92409 -228.485679)
			(xy 368.15267 -228.485679) (xy 368.15267 -228.432381) (xy 368.160613 -228.379677) (xy 368.176323 -228.328747)
			(xy 368.199449 -228.280726) (xy 368.229473 -228.236689) (xy 368.265725 -228.197618) (xy 368.307396 -228.164387)
			(xy 368.353554 -228.137738) (xy 368.403168 -228.118266) (xy 368.45513 -228.106406) (xy 368.50828 -228.102423)
			(xy 368.56143 -228.106406) (xy 368.613392 -228.118266) (xy 368.663006 -228.137738) (xy 368.709164 -228.164387)
			(xy 368.750835 -228.197618) (xy 368.787087 -228.236689) (xy 368.817111 -228.280726) (xy 368.840237 -228.328747)
			(xy 368.855947 -228.379677) (xy 368.86389 -228.432381) (xy 368.864388 -228.45903) (xy 368.86389 -228.485679)
			(xy 369.09247 -228.485679) (xy 369.09247 -228.432381) (xy 369.100413 -228.379677) (xy 369.116123 -228.328747)
			(xy 369.139249 -228.280726) (xy 369.169273 -228.236689) (xy 369.205525 -228.197618) (xy 369.247196 -228.164387)
			(xy 369.293354 -228.137738) (xy 369.342968 -228.118266) (xy 369.39493 -228.106406) (xy 369.44808 -228.102423)
			(xy 369.50123 -228.106406) (xy 369.553192 -228.118266) (xy 369.602806 -228.137738) (xy 369.648964 -228.164387)
			(xy 369.690635 -228.197618) (xy 369.726887 -228.236689) (xy 369.756911 -228.280726) (xy 369.780037 -228.328747)
			(xy 369.795747 -228.379677) (xy 369.80369 -228.432381) (xy 369.804188 -228.45903) (xy 369.80369 -228.485679)
			(xy 370.03227 -228.485679) (xy 370.03227 -228.432381) (xy 370.040213 -228.379677) (xy 370.055923 -228.328747)
			(xy 370.079049 -228.280726) (xy 370.109073 -228.236689) (xy 370.145325 -228.197618) (xy 370.186996 -228.164387)
			(xy 370.233154 -228.137738) (xy 370.282768 -228.118266) (xy 370.33473 -228.106406) (xy 370.38788 -228.102423)
			(xy 370.44103 -228.106406) (xy 370.492992 -228.118266) (xy 370.542606 -228.137738) (xy 370.588764 -228.164387)
			(xy 370.630435 -228.197618) (xy 370.666687 -228.236689) (xy 370.696711 -228.280726) (xy 370.719837 -228.328747)
			(xy 370.735547 -228.379677) (xy 370.74349 -228.432381) (xy 370.743988 -228.45903) (xy 370.74349 -228.485679)
			(xy 370.97207 -228.485679) (xy 370.97207 -228.432381) (xy 370.980013 -228.379677) (xy 370.995723 -228.328747)
			(xy 371.018849 -228.280726) (xy 371.048873 -228.236689) (xy 371.085125 -228.197618) (xy 371.126796 -228.164387)
			(xy 371.172954 -228.137738) (xy 371.222568 -228.118266) (xy 371.27453 -228.106406) (xy 371.32768 -228.102423)
			(xy 371.38083 -228.106406) (xy 371.432792 -228.118266) (xy 371.482406 -228.137738) (xy 371.528564 -228.164387)
			(xy 371.570235 -228.197618) (xy 371.606487 -228.236689) (xy 371.636511 -228.280726) (xy 371.659637 -228.328747)
			(xy 371.675347 -228.379677) (xy 371.68329 -228.432381) (xy 371.683788 -228.45903) (xy 371.68329 -228.485679)
			(xy 371.91187 -228.485679) (xy 371.91187 -228.432381) (xy 371.919813 -228.379677) (xy 371.935523 -228.328747)
			(xy 371.958649 -228.280726) (xy 371.988673 -228.236689) (xy 372.024925 -228.197618) (xy 372.066596 -228.164387)
			(xy 372.112754 -228.137738) (xy 372.162368 -228.118266) (xy 372.21433 -228.106406) (xy 372.26748 -228.102423)
			(xy 372.32063 -228.106406) (xy 372.372592 -228.118266) (xy 372.422206 -228.137738) (xy 372.468364 -228.164387)
			(xy 372.510035 -228.197618) (xy 372.546287 -228.236689) (xy 372.576311 -228.280726) (xy 372.599437 -228.328747)
			(xy 372.615147 -228.379677) (xy 372.62309 -228.432381) (xy 372.623588 -228.45903) (xy 372.62309 -228.485679)
			(xy 372.85167 -228.485679) (xy 372.85167 -228.432381) (xy 372.859613 -228.379677) (xy 372.875323 -228.328747)
			(xy 372.898449 -228.280726) (xy 372.928473 -228.236689) (xy 372.964725 -228.197618) (xy 373.006396 -228.164387)
			(xy 373.052554 -228.137738) (xy 373.102168 -228.118266) (xy 373.15413 -228.106406) (xy 373.20728 -228.102423)
			(xy 373.26043 -228.106406) (xy 373.312392 -228.118266) (xy 373.362006 -228.137738) (xy 373.408164 -228.164387)
			(xy 373.449835 -228.197618) (xy 373.486087 -228.236689) (xy 373.516111 -228.280726) (xy 373.539237 -228.328747)
			(xy 373.554947 -228.379677) (xy 373.56289 -228.432381) (xy 373.563388 -228.45903) (xy 373.56289 -228.485679)
			(xy 373.791724 -228.485679) (xy 373.791724 -228.432381) (xy 373.799667 -228.379677) (xy 373.815377 -228.328747)
			(xy 373.838503 -228.280726) (xy 373.868527 -228.236689) (xy 373.904779 -228.197618) (xy 373.94645 -228.164387)
			(xy 373.992608 -228.137738) (xy 374.042222 -228.118266) (xy 374.094184 -228.106406) (xy 374.147334 -228.102423)
			(xy 374.200484 -228.106406) (xy 374.252446 -228.118266) (xy 374.30206 -228.137738) (xy 374.348218 -228.164387)
			(xy 374.389889 -228.197618) (xy 374.426141 -228.236689) (xy 374.456165 -228.280726) (xy 374.479291 -228.328747)
			(xy 374.495001 -228.379677) (xy 374.502944 -228.432381) (xy 374.503442 -228.45903) (xy 374.502944 -228.485679)
			(xy 374.73127 -228.485679) (xy 374.73127 -228.432381) (xy 374.739213 -228.379677) (xy 374.754923 -228.328747)
			(xy 374.778049 -228.280726) (xy 374.808073 -228.236689) (xy 374.844325 -228.197618) (xy 374.885996 -228.164387)
			(xy 374.932154 -228.137738) (xy 374.981768 -228.118266) (xy 375.03373 -228.106406) (xy 375.08688 -228.102423)
			(xy 375.14003 -228.106406) (xy 375.191992 -228.118266) (xy 375.241606 -228.137738) (xy 375.287764 -228.164387)
			(xy 375.329435 -228.197618) (xy 375.365687 -228.236689) (xy 375.395711 -228.280726) (xy 375.418837 -228.328747)
			(xy 375.434547 -228.379677) (xy 375.44249 -228.432381) (xy 375.442988 -228.45903) (xy 375.44249 -228.485679)
			(xy 375.67107 -228.485679) (xy 375.67107 -228.432381) (xy 375.679013 -228.379677) (xy 375.694723 -228.328747)
			(xy 375.717849 -228.280726) (xy 375.747873 -228.236689) (xy 375.784125 -228.197618) (xy 375.825796 -228.164387)
			(xy 375.871954 -228.137738) (xy 375.921568 -228.118266) (xy 375.97353 -228.106406) (xy 376.02668 -228.102423)
			(xy 376.07983 -228.106406) (xy 376.131792 -228.118266) (xy 376.181406 -228.137738) (xy 376.227564 -228.164387)
			(xy 376.269235 -228.197618) (xy 376.305487 -228.236689) (xy 376.335511 -228.280726) (xy 376.358637 -228.328747)
			(xy 376.374347 -228.379677) (xy 376.38229 -228.432381) (xy 376.382788 -228.45903) (xy 376.38229 -228.485679)
			(xy 376.61087 -228.485679) (xy 376.61087 -228.432381) (xy 376.618813 -228.379677) (xy 376.634523 -228.328747)
			(xy 376.657649 -228.280726) (xy 376.687673 -228.236689) (xy 376.723925 -228.197618) (xy 376.765596 -228.164387)
			(xy 376.811754 -228.137738) (xy 376.861368 -228.118266) (xy 376.91333 -228.106406) (xy 376.96648 -228.102423)
			(xy 377.01963 -228.106406) (xy 377.071592 -228.118266) (xy 377.121206 -228.137738) (xy 377.167364 -228.164387)
			(xy 377.209035 -228.197618) (xy 377.245287 -228.236689) (xy 377.275311 -228.280726) (xy 377.298437 -228.328747)
			(xy 377.314147 -228.379677) (xy 377.32209 -228.432381) (xy 377.322588 -228.45903) (xy 377.32209 -228.485679)
			(xy 377.314147 -228.538383) (xy 377.298437 -228.589313) (xy 377.275311 -228.637334) (xy 377.245287 -228.681371)
			(xy 377.209035 -228.720442) (xy 377.167364 -228.753673) (xy 377.121206 -228.780322) (xy 377.071592 -228.799794)
			(xy 377.01963 -228.811654) (xy 376.96648 -228.815638) (xy 376.91333 -228.811654) (xy 376.861368 -228.799794)
			(xy 376.811754 -228.780322) (xy 376.765596 -228.753673) (xy 376.723925 -228.720442) (xy 376.687673 -228.681371)
			(xy 376.657649 -228.637334) (xy 376.634523 -228.589313) (xy 376.618813 -228.538383) (xy 376.61087 -228.485679)
			(xy 376.38229 -228.485679) (xy 376.374347 -228.538383) (xy 376.358637 -228.589313) (xy 376.335511 -228.637334)
			(xy 376.305487 -228.681371) (xy 376.269235 -228.720442) (xy 376.227564 -228.753673) (xy 376.181406 -228.780322)
			(xy 376.131792 -228.799794) (xy 376.07983 -228.811654) (xy 376.02668 -228.815638) (xy 375.97353 -228.811654)
			(xy 375.921568 -228.799794) (xy 375.871954 -228.780322) (xy 375.825796 -228.753673) (xy 375.784125 -228.720442)
			(xy 375.747873 -228.681371) (xy 375.717849 -228.637334) (xy 375.694723 -228.589313) (xy 375.679013 -228.538383)
			(xy 375.67107 -228.485679) (xy 375.44249 -228.485679) (xy 375.434547 -228.538383) (xy 375.418837 -228.589313)
			(xy 375.395711 -228.637334) (xy 375.365687 -228.681371) (xy 375.329435 -228.720442) (xy 375.287764 -228.753673)
			(xy 375.241606 -228.780322) (xy 375.191992 -228.799794) (xy 375.14003 -228.811654) (xy 375.08688 -228.815638)
			(xy 375.03373 -228.811654) (xy 374.981768 -228.799794) (xy 374.932154 -228.780322) (xy 374.885996 -228.753673)
			(xy 374.844325 -228.720442) (xy 374.808073 -228.681371) (xy 374.778049 -228.637334) (xy 374.754923 -228.589313)
			(xy 374.739213 -228.538383) (xy 374.73127 -228.485679) (xy 374.502944 -228.485679) (xy 374.495001 -228.538383)
			(xy 374.479291 -228.589313) (xy 374.456165 -228.637334) (xy 374.426141 -228.681371) (xy 374.389889 -228.720442)
			(xy 374.348218 -228.753673) (xy 374.30206 -228.780322) (xy 374.252446 -228.799794) (xy 374.200484 -228.811654)
			(xy 374.147334 -228.815638) (xy 374.094184 -228.811654) (xy 374.042222 -228.799794) (xy 373.992608 -228.780322)
			(xy 373.94645 -228.753673) (xy 373.904779 -228.720442) (xy 373.868527 -228.681371) (xy 373.838503 -228.637334)
			(xy 373.815377 -228.589313) (xy 373.799667 -228.538383) (xy 373.791724 -228.485679) (xy 373.56289 -228.485679)
			(xy 373.554947 -228.538383) (xy 373.539237 -228.589313) (xy 373.516111 -228.637334) (xy 373.486087 -228.681371)
			(xy 373.449835 -228.720442) (xy 373.408164 -228.753673) (xy 373.362006 -228.780322) (xy 373.312392 -228.799794)
			(xy 373.26043 -228.811654) (xy 373.20728 -228.815638) (xy 373.15413 -228.811654) (xy 373.102168 -228.799794)
			(xy 373.052554 -228.780322) (xy 373.006396 -228.753673) (xy 372.964725 -228.720442) (xy 372.928473 -228.681371)
			(xy 372.898449 -228.637334) (xy 372.875323 -228.589313) (xy 372.859613 -228.538383) (xy 372.85167 -228.485679)
			(xy 372.62309 -228.485679) (xy 372.615147 -228.538383) (xy 372.599437 -228.589313) (xy 372.576311 -228.637334)
			(xy 372.546287 -228.681371) (xy 372.510035 -228.720442) (xy 372.468364 -228.753673) (xy 372.422206 -228.780322)
			(xy 372.372592 -228.799794) (xy 372.32063 -228.811654) (xy 372.26748 -228.815638) (xy 372.21433 -228.811654)
			(xy 372.162368 -228.799794) (xy 372.112754 -228.780322) (xy 372.066596 -228.753673) (xy 372.024925 -228.720442)
			(xy 371.988673 -228.681371) (xy 371.958649 -228.637334) (xy 371.935523 -228.589313) (xy 371.919813 -228.538383)
			(xy 371.91187 -228.485679) (xy 371.68329 -228.485679) (xy 371.675347 -228.538383) (xy 371.659637 -228.589313)
			(xy 371.636511 -228.637334) (xy 371.606487 -228.681371) (xy 371.570235 -228.720442) (xy 371.528564 -228.753673)
			(xy 371.482406 -228.780322) (xy 371.432792 -228.799794) (xy 371.38083 -228.811654) (xy 371.32768 -228.815638)
			(xy 371.27453 -228.811654) (xy 371.222568 -228.799794) (xy 371.172954 -228.780322) (xy 371.126796 -228.753673)
			(xy 371.085125 -228.720442) (xy 371.048873 -228.681371) (xy 371.018849 -228.637334) (xy 370.995723 -228.589313)
			(xy 370.980013 -228.538383) (xy 370.97207 -228.485679) (xy 370.74349 -228.485679) (xy 370.735547 -228.538383)
			(xy 370.719837 -228.589313) (xy 370.696711 -228.637334) (xy 370.666687 -228.681371) (xy 370.630435 -228.720442)
			(xy 370.588764 -228.753673) (xy 370.542606 -228.780322) (xy 370.492992 -228.799794) (xy 370.44103 -228.811654)
			(xy 370.38788 -228.815638) (xy 370.33473 -228.811654) (xy 370.282768 -228.799794) (xy 370.233154 -228.780322)
			(xy 370.186996 -228.753673) (xy 370.145325 -228.720442) (xy 370.109073 -228.681371) (xy 370.079049 -228.637334)
			(xy 370.055923 -228.589313) (xy 370.040213 -228.538383) (xy 370.03227 -228.485679) (xy 369.80369 -228.485679)
			(xy 369.795747 -228.538383) (xy 369.780037 -228.589313) (xy 369.756911 -228.637334) (xy 369.726887 -228.681371)
			(xy 369.690635 -228.720442) (xy 369.648964 -228.753673) (xy 369.602806 -228.780322) (xy 369.553192 -228.799794)
			(xy 369.50123 -228.811654) (xy 369.44808 -228.815638) (xy 369.39493 -228.811654) (xy 369.342968 -228.799794)
			(xy 369.293354 -228.780322) (xy 369.247196 -228.753673) (xy 369.205525 -228.720442) (xy 369.169273 -228.681371)
			(xy 369.139249 -228.637334) (xy 369.116123 -228.589313) (xy 369.100413 -228.538383) (xy 369.09247 -228.485679)
			(xy 368.86389 -228.485679) (xy 368.855947 -228.538383) (xy 368.840237 -228.589313) (xy 368.817111 -228.637334)
			(xy 368.787087 -228.681371) (xy 368.750835 -228.720442) (xy 368.709164 -228.753673) (xy 368.663006 -228.780322)
			(xy 368.613392 -228.799794) (xy 368.56143 -228.811654) (xy 368.50828 -228.815638) (xy 368.45513 -228.811654)
			(xy 368.403168 -228.799794) (xy 368.353554 -228.780322) (xy 368.307396 -228.753673) (xy 368.265725 -228.720442)
			(xy 368.229473 -228.681371) (xy 368.199449 -228.637334) (xy 368.176323 -228.589313) (xy 368.160613 -228.538383)
			(xy 368.15267 -228.485679) (xy 367.92409 -228.485679) (xy 367.916147 -228.538383) (xy 367.900437 -228.589313)
			(xy 367.877311 -228.637334) (xy 367.847287 -228.681371) (xy 367.811035 -228.720442) (xy 367.769364 -228.753673)
			(xy 367.723206 -228.780322) (xy 367.673592 -228.799794) (xy 367.62163 -228.811654) (xy 367.56848 -228.815638)
			(xy 367.51533 -228.811654) (xy 367.463368 -228.799794) (xy 367.413754 -228.780322) (xy 367.367596 -228.753673)
			(xy 367.325925 -228.720442) (xy 367.289673 -228.681371) (xy 367.259649 -228.637334) (xy 367.236523 -228.589313)
			(xy 367.220813 -228.538383) (xy 367.21287 -228.485679) (xy 366.04449 -228.485679) (xy 366.036547 -228.538383)
			(xy 366.020837 -228.589313) (xy 365.997711 -228.637334) (xy 365.967687 -228.681371) (xy 365.931435 -228.720442)
			(xy 365.889764 -228.753673) (xy 365.843606 -228.780322) (xy 365.793992 -228.799794) (xy 365.74203 -228.811654)
			(xy 365.68888 -228.815638) (xy 365.63573 -228.811654) (xy 365.583768 -228.799794) (xy 365.534154 -228.780322)
			(xy 365.487996 -228.753673) (xy 365.446325 -228.720442) (xy 365.410073 -228.681371) (xy 365.380049 -228.637334)
			(xy 365.356923 -228.589313) (xy 365.341213 -228.538383) (xy 365.33327 -228.485679) (xy 364.16489 -228.485679)
			(xy 364.156947 -228.538383) (xy 364.141237 -228.589313) (xy 364.118111 -228.637334) (xy 364.088087 -228.681371)
			(xy 364.051835 -228.720442) (xy 364.010164 -228.753673) (xy 363.964006 -228.780322) (xy 363.914392 -228.799794)
			(xy 363.86243 -228.811654) (xy 363.80928 -228.815638) (xy 363.75613 -228.811654) (xy 363.704168 -228.799794)
			(xy 363.654554 -228.780322) (xy 363.608396 -228.753673) (xy 363.566725 -228.720442) (xy 363.530473 -228.681371)
			(xy 363.500449 -228.637334) (xy 363.477323 -228.589313) (xy 363.461613 -228.538383) (xy 363.45367 -228.485679)
			(xy 362.28529 -228.485679) (xy 362.277347 -228.538383) (xy 362.261637 -228.589313) (xy 362.238511 -228.637334)
			(xy 362.208487 -228.681371) (xy 362.172235 -228.720442) (xy 362.130564 -228.753673) (xy 362.084406 -228.780322)
			(xy 362.034792 -228.799794) (xy 361.98283 -228.811654) (xy 361.92968 -228.815638) (xy 361.87653 -228.811654)
			(xy 361.824568 -228.799794) (xy 361.774954 -228.780322) (xy 361.728796 -228.753673) (xy 361.687125 -228.720442)
			(xy 361.650873 -228.681371) (xy 361.620849 -228.637334) (xy 361.597723 -228.589313) (xy 361.582013 -228.538383)
			(xy 361.57407 -228.485679) (xy 361.34549 -228.485679) (xy 361.337547 -228.538383) (xy 361.321837 -228.589313)
			(xy 361.298711 -228.637334) (xy 361.268687 -228.681371) (xy 361.232435 -228.720442) (xy 361.190764 -228.753673)
			(xy 361.144606 -228.780322) (xy 361.094992 -228.799794) (xy 361.04303 -228.811654) (xy 360.98988 -228.815638)
			(xy 360.93673 -228.811654) (xy 360.884768 -228.799794) (xy 360.835154 -228.780322) (xy 360.788996 -228.753673)
			(xy 360.747325 -228.720442) (xy 360.711073 -228.681371) (xy 360.681049 -228.637334) (xy 360.657923 -228.589313)
			(xy 360.642213 -228.538383) (xy 360.63427 -228.485679) (xy 360.40569 -228.485679) (xy 360.397747 -228.538383)
			(xy 360.382037 -228.589313) (xy 360.358911 -228.637334) (xy 360.328887 -228.681371) (xy 360.292635 -228.720442)
			(xy 360.250964 -228.753673) (xy 360.204806 -228.780322) (xy 360.155192 -228.799794) (xy 360.10323 -228.811654)
			(xy 360.05008 -228.815638) (xy 359.99693 -228.811654) (xy 359.944968 -228.799794) (xy 359.895354 -228.780322)
			(xy 359.849196 -228.753673) (xy 359.807525 -228.720442) (xy 359.771273 -228.681371) (xy 359.741249 -228.637334)
			(xy 359.718123 -228.589313) (xy 359.702413 -228.538383) (xy 359.69447 -228.485679) (xy 359.466144 -228.485679)
			(xy 359.458201 -228.538383) (xy 359.442491 -228.589313) (xy 359.419365 -228.637334) (xy 359.389341 -228.681371)
			(xy 359.353089 -228.720442) (xy 359.311418 -228.753673) (xy 359.26526 -228.780322) (xy 359.215646 -228.799794)
			(xy 359.163684 -228.811654) (xy 359.110534 -228.815638) (xy 359.057384 -228.811654) (xy 359.005422 -228.799794)
			(xy 358.955808 -228.780322) (xy 358.90965 -228.753673) (xy 358.867979 -228.720442) (xy 358.831727 -228.681371)
			(xy 358.801703 -228.637334) (xy 358.778577 -228.589313) (xy 358.762867 -228.538383) (xy 358.754924 -228.485679)
			(xy 358.52609 -228.485679) (xy 358.518147 -228.538383) (xy 358.502437 -228.589313) (xy 358.479311 -228.637334)
			(xy 358.449287 -228.681371) (xy 358.413035 -228.720442) (xy 358.371364 -228.753673) (xy 358.325206 -228.780322)
			(xy 358.275592 -228.799794) (xy 358.22363 -228.811654) (xy 358.17048 -228.815638) (xy 358.11733 -228.811654)
			(xy 358.065368 -228.799794) (xy 358.015754 -228.780322) (xy 357.969596 -228.753673) (xy 357.927925 -228.720442)
			(xy 357.891673 -228.681371) (xy 357.861649 -228.637334) (xy 357.838523 -228.589313) (xy 357.822813 -228.538383)
			(xy 357.81487 -228.485679) (xy 357.58629 -228.485679) (xy 357.578347 -228.538383) (xy 357.562637 -228.589313)
			(xy 357.539511 -228.637334) (xy 357.509487 -228.681371) (xy 357.473235 -228.720442) (xy 357.431564 -228.753673)
			(xy 357.385406 -228.780322) (xy 357.335792 -228.799794) (xy 357.28383 -228.811654) (xy 357.23068 -228.815638)
			(xy 357.17753 -228.811654) (xy 357.125568 -228.799794) (xy 357.075954 -228.780322) (xy 357.029796 -228.753673)
			(xy 356.988125 -228.720442) (xy 356.951873 -228.681371) (xy 356.921849 -228.637334) (xy 356.898723 -228.589313)
			(xy 356.883013 -228.538383) (xy 356.87507 -228.485679) (xy 356.64649 -228.485679) (xy 356.638547 -228.538383)
			(xy 356.622837 -228.589313) (xy 356.599711 -228.637334) (xy 356.569687 -228.681371) (xy 356.533435 -228.720442)
			(xy 356.491764 -228.753673) (xy 356.445606 -228.780322) (xy 356.395992 -228.799794) (xy 356.34403 -228.811654)
			(xy 356.29088 -228.815638) (xy 356.23773 -228.811654) (xy 356.185768 -228.799794) (xy 356.136154 -228.780322)
			(xy 356.089996 -228.753673) (xy 356.048325 -228.720442) (xy 356.012073 -228.681371) (xy 355.982049 -228.637334)
			(xy 355.958923 -228.589313) (xy 355.943213 -228.538383) (xy 355.93527 -228.485679) (xy 355.70669 -228.485679)
			(xy 355.698747 -228.538383) (xy 355.683037 -228.589313) (xy 355.659911 -228.637334) (xy 355.629887 -228.681371)
			(xy 355.593635 -228.720442) (xy 355.551964 -228.753673) (xy 355.505806 -228.780322) (xy 355.456192 -228.799794)
			(xy 355.40423 -228.811654) (xy 355.35108 -228.815638) (xy 355.29793 -228.811654) (xy 355.245968 -228.799794)
			(xy 355.196354 -228.780322) (xy 355.150196 -228.753673) (xy 355.108525 -228.720442) (xy 355.072273 -228.681371)
			(xy 355.042249 -228.637334) (xy 355.019123 -228.589313) (xy 355.003413 -228.538383) (xy 354.99547 -228.485679)
			(xy 354.76689 -228.485679) (xy 354.758947 -228.538383) (xy 354.743237 -228.589313) (xy 354.720111 -228.637334)
			(xy 354.690087 -228.681371) (xy 354.653835 -228.720442) (xy 354.612164 -228.753673) (xy 354.566006 -228.780322)
			(xy 354.516392 -228.799794) (xy 354.46443 -228.811654) (xy 354.41128 -228.815638) (xy 354.35813 -228.811654)
			(xy 354.306168 -228.799794) (xy 354.256554 -228.780322) (xy 354.210396 -228.753673) (xy 354.168725 -228.720442)
			(xy 354.132473 -228.681371) (xy 354.102449 -228.637334) (xy 354.079323 -228.589313) (xy 354.063613 -228.538383)
			(xy 354.05567 -228.485679) (xy 353.82709 -228.485679) (xy 353.819147 -228.538383) (xy 353.803437 -228.589313)
			(xy 353.780311 -228.637334) (xy 353.750287 -228.681371) (xy 353.714035 -228.720442) (xy 353.672364 -228.753673)
			(xy 353.626206 -228.780322) (xy 353.576592 -228.799794) (xy 353.52463 -228.811654) (xy 353.47148 -228.815638)
			(xy 353.41833 -228.811654) (xy 353.366368 -228.799794) (xy 353.316754 -228.780322) (xy 353.270596 -228.753673)
			(xy 353.228925 -228.720442) (xy 353.192673 -228.681371) (xy 353.162649 -228.637334) (xy 353.139523 -228.589313)
			(xy 353.123813 -228.538383) (xy 353.11587 -228.485679) (xy 352.88729 -228.485679) (xy 352.879347 -228.538383)
			(xy 352.863637 -228.589313) (xy 352.840511 -228.637334) (xy 352.810487 -228.681371) (xy 352.774235 -228.720442)
			(xy 352.732564 -228.753673) (xy 352.686406 -228.780322) (xy 352.636792 -228.799794) (xy 352.58483 -228.811654)
			(xy 352.53168 -228.815638) (xy 352.47853 -228.811654) (xy 352.426568 -228.799794) (xy 352.376954 -228.780322)
			(xy 352.330796 -228.753673) (xy 352.289125 -228.720442) (xy 352.252873 -228.681371) (xy 352.222849 -228.637334)
			(xy 352.199723 -228.589313) (xy 352.184013 -228.538383) (xy 352.17607 -228.485679) (xy 351.947749 -228.485679)
			(xy 351.947744 -228.485933) (xy 351.939801 -228.538637) (xy 351.924091 -228.589567) (xy 351.900965 -228.637588)
			(xy 351.870941 -228.681625) (xy 351.834689 -228.720696) (xy 351.793018 -228.753927) (xy 351.74686 -228.780576)
			(xy 351.697246 -228.800048) (xy 351.645284 -228.811908) (xy 351.592134 -228.815892) (xy 351.538984 -228.811908)
			(xy 351.487022 -228.800048) (xy 351.437408 -228.780576) (xy 351.39125 -228.753927) (xy 351.349579 -228.720696)
			(xy 351.313327 -228.681625) (xy 351.283303 -228.637588) (xy 351.260177 -228.589567) (xy 351.244467 -228.538637)
			(xy 351.236524 -228.485933) (xy 351.007652 -228.485933) (xy 350.999747 -228.538383) (xy 350.984037 -228.589313)
			(xy 350.960911 -228.637334) (xy 350.930887 -228.681371) (xy 350.894635 -228.720442) (xy 350.852964 -228.753673)
			(xy 350.806806 -228.780322) (xy 350.757192 -228.799794) (xy 350.70523 -228.811654) (xy 350.65208 -228.815638)
			(xy 350.59893 -228.811654) (xy 350.546968 -228.799794) (xy 350.497354 -228.780322) (xy 350.451196 -228.753673)
			(xy 350.409525 -228.720442) (xy 350.373273 -228.681371) (xy 350.343249 -228.637334) (xy 350.320123 -228.589313)
			(xy 350.304413 -228.538383) (xy 350.29647 -228.485679) (xy 350.06789 -228.485679) (xy 350.059947 -228.538383)
			(xy 350.044237 -228.589313) (xy 350.021111 -228.637334) (xy 349.991087 -228.681371) (xy 349.954835 -228.720442)
			(xy 349.913164 -228.753673) (xy 349.867006 -228.780322) (xy 349.817392 -228.799794) (xy 349.76543 -228.811654)
			(xy 349.71228 -228.815638) (xy 349.65913 -228.811654) (xy 349.607168 -228.799794) (xy 349.557554 -228.780322)
			(xy 349.511396 -228.753673) (xy 349.469725 -228.720442) (xy 349.433473 -228.681371) (xy 349.403449 -228.637334)
			(xy 349.380323 -228.589313) (xy 349.364613 -228.538383) (xy 349.35667 -228.485679) (xy 349.12809 -228.485679)
			(xy 349.120147 -228.538383) (xy 349.104437 -228.589313) (xy 349.081311 -228.637334) (xy 349.051287 -228.681371)
			(xy 349.015035 -228.720442) (xy 348.973364 -228.753673) (xy 348.927206 -228.780322) (xy 348.877592 -228.799794)
			(xy 348.82563 -228.811654) (xy 348.77248 -228.815638) (xy 348.71933 -228.811654) (xy 348.667368 -228.799794)
			(xy 348.617754 -228.780322) (xy 348.571596 -228.753673) (xy 348.529925 -228.720442) (xy 348.493673 -228.681371)
			(xy 348.463649 -228.637334) (xy 348.440523 -228.589313) (xy 348.424813 -228.538383) (xy 348.41687 -228.485679)
			(xy 348.18829 -228.485679) (xy 348.180347 -228.538383) (xy 348.164637 -228.589313) (xy 348.141511 -228.637334)
			(xy 348.111487 -228.681371) (xy 348.075235 -228.720442) (xy 348.033564 -228.753673) (xy 347.987406 -228.780322)
			(xy 347.937792 -228.799794) (xy 347.88583 -228.811654) (xy 347.83268 -228.815638) (xy 347.77953 -228.811654)
			(xy 347.727568 -228.799794) (xy 347.677954 -228.780322) (xy 347.631796 -228.753673) (xy 347.590125 -228.720442)
			(xy 347.553873 -228.681371) (xy 347.523849 -228.637334) (xy 347.500723 -228.589313) (xy 347.485013 -228.538383)
			(xy 347.47707 -228.485679) (xy 347.24849 -228.485679) (xy 347.240547 -228.538383) (xy 347.224837 -228.589313)
			(xy 347.201711 -228.637334) (xy 347.171687 -228.681371) (xy 347.135435 -228.720442) (xy 347.093764 -228.753673)
			(xy 347.047606 -228.780322) (xy 346.997992 -228.799794) (xy 346.94603 -228.811654) (xy 346.89288 -228.815638)
			(xy 346.83973 -228.811654) (xy 346.787768 -228.799794) (xy 346.738154 -228.780322) (xy 346.691996 -228.753673)
			(xy 346.650325 -228.720442) (xy 346.614073 -228.681371) (xy 346.584049 -228.637334) (xy 346.560923 -228.589313)
			(xy 346.545213 -228.538383) (xy 346.53727 -228.485679) (xy 346.308944 -228.485679) (xy 346.301001 -228.538383)
			(xy 346.285291 -228.589313) (xy 346.262165 -228.637334) (xy 346.232141 -228.681371) (xy 346.195889 -228.720442)
			(xy 346.154218 -228.753673) (xy 346.10806 -228.780322) (xy 346.058446 -228.799794) (xy 346.006484 -228.811654)
			(xy 345.953334 -228.815638) (xy 345.900184 -228.811654) (xy 345.848222 -228.799794) (xy 345.798608 -228.780322)
			(xy 345.75245 -228.753673) (xy 345.710779 -228.720442) (xy 345.674527 -228.681371) (xy 345.644503 -228.637334)
			(xy 345.621377 -228.589313) (xy 345.605667 -228.538383) (xy 345.597724 -228.485679) (xy 345.36889 -228.485679)
			(xy 345.360947 -228.538383) (xy 345.345237 -228.589313) (xy 345.322111 -228.637334) (xy 345.292087 -228.681371)
			(xy 345.255835 -228.720442) (xy 345.214164 -228.753673) (xy 345.168006 -228.780322) (xy 345.118392 -228.799794)
			(xy 345.06643 -228.811654) (xy 345.01328 -228.815638) (xy 344.96013 -228.811654) (xy 344.908168 -228.799794)
			(xy 344.858554 -228.780322) (xy 344.812396 -228.753673) (xy 344.770725 -228.720442) (xy 344.734473 -228.681371)
			(xy 344.704449 -228.637334) (xy 344.681323 -228.589313) (xy 344.665613 -228.538383) (xy 344.65767 -228.485679)
			(xy 344.42909 -228.485679) (xy 344.421147 -228.538383) (xy 344.405437 -228.589313) (xy 344.382311 -228.637334)
			(xy 344.352287 -228.681371) (xy 344.316035 -228.720442) (xy 344.274364 -228.753673) (xy 344.228206 -228.780322)
			(xy 344.178592 -228.799794) (xy 344.12663 -228.811654) (xy 344.07348 -228.815638) (xy 344.02033 -228.811654)
			(xy 343.968368 -228.799794) (xy 343.918754 -228.780322) (xy 343.872596 -228.753673) (xy 343.830925 -228.720442)
			(xy 343.794673 -228.681371) (xy 343.764649 -228.637334) (xy 343.741523 -228.589313) (xy 343.725813 -228.538383)
			(xy 343.71787 -228.485679) (xy 343.48929 -228.485679) (xy 343.481347 -228.538383) (xy 343.465637 -228.589313)
			(xy 343.442511 -228.637334) (xy 343.412487 -228.681371) (xy 343.376235 -228.720442) (xy 343.334564 -228.753673)
			(xy 343.288406 -228.780322) (xy 343.238792 -228.799794) (xy 343.18683 -228.811654) (xy 343.13368 -228.815638)
			(xy 343.08053 -228.811654) (xy 343.028568 -228.799794) (xy 342.978954 -228.780322) (xy 342.932796 -228.753673)
			(xy 342.891125 -228.720442) (xy 342.854873 -228.681371) (xy 342.824849 -228.637334) (xy 342.801723 -228.589313)
			(xy 342.786013 -228.538383) (xy 342.77807 -228.485679) (xy 342.54949 -228.485679) (xy 342.541547 -228.538383)
			(xy 342.525837 -228.589313) (xy 342.502711 -228.637334) (xy 342.472687 -228.681371) (xy 342.436435 -228.720442)
			(xy 342.394764 -228.753673) (xy 342.348606 -228.780322) (xy 342.298992 -228.799794) (xy 342.24703 -228.811654)
			(xy 342.19388 -228.815638) (xy 342.14073 -228.811654) (xy 342.088768 -228.799794) (xy 342.039154 -228.780322)
			(xy 341.992996 -228.753673) (xy 341.951325 -228.720442) (xy 341.915073 -228.681371) (xy 341.885049 -228.637334)
			(xy 341.861923 -228.589313) (xy 341.846213 -228.538383) (xy 341.83827 -228.485679) (xy 341.60969 -228.485679)
			(xy 341.601747 -228.538383) (xy 341.586037 -228.589313) (xy 341.562911 -228.637334) (xy 341.532887 -228.681371)
			(xy 341.496635 -228.720442) (xy 341.454964 -228.753673) (xy 341.408806 -228.780322) (xy 341.359192 -228.799794)
			(xy 341.30723 -228.811654) (xy 341.25408 -228.815638) (xy 341.20093 -228.811654) (xy 341.148968 -228.799794)
			(xy 341.099354 -228.780322) (xy 341.053196 -228.753673) (xy 341.011525 -228.720442) (xy 340.975273 -228.681371)
			(xy 340.945249 -228.637334) (xy 340.922123 -228.589313) (xy 340.906413 -228.538383) (xy 340.89847 -228.485679)
			(xy 340.66989 -228.485679) (xy 340.661947 -228.538383) (xy 340.646237 -228.589313) (xy 340.623111 -228.637334)
			(xy 340.593087 -228.681371) (xy 340.556835 -228.720442) (xy 340.515164 -228.753673) (xy 340.469006 -228.780322)
			(xy 340.419392 -228.799794) (xy 340.36743 -228.811654) (xy 340.31428 -228.815638) (xy 340.26113 -228.811654)
			(xy 340.209168 -228.799794) (xy 340.159554 -228.780322) (xy 340.113396 -228.753673) (xy 340.071725 -228.720442)
			(xy 340.035473 -228.681371) (xy 340.005449 -228.637334) (xy 339.982323 -228.589313) (xy 339.966613 -228.538383)
			(xy 339.95867 -228.485679) (xy 339.729343 -228.485679) (xy 339.727307 -228.512612) (xy 339.715243 -228.565002)
			(xy 339.695441 -228.614984) (xy 339.668352 -228.661421) (xy 339.634591 -228.70326) (xy 339.594925 -228.739548)
			(xy 339.550255 -228.769462) (xy 339.501596 -228.792322) (xy 339.450054 -228.807608) (xy 339.423502 -228.811836)
			(xy 339.37956 -228.817932) (xy 339.37956 -229.299495) (xy 339.489024 -229.299495) (xy 339.489024 -229.246197)
			(xy 339.496967 -229.193493) (xy 339.512677 -229.142563) (xy 339.535803 -229.094542) (xy 339.565827 -229.050505)
			(xy 339.602079 -229.011434) (xy 339.64375 -228.978203) (xy 339.689908 -228.951554) (xy 339.739522 -228.932082)
			(xy 339.791484 -228.920222) (xy 339.844634 -228.916239) (xy 339.897784 -228.920222) (xy 339.949746 -228.932082)
			(xy 339.99936 -228.951554) (xy 340.045518 -228.978203) (xy 340.087189 -229.011434) (xy 340.123441 -229.050505)
			(xy 340.153465 -229.094542) (xy 340.176591 -229.142563) (xy 340.192301 -229.193493) (xy 340.200244 -229.246197)
			(xy 340.200742 -229.272846) (xy 340.200244 -229.299495) (xy 340.428824 -229.299495) (xy 340.428824 -229.246197)
			(xy 340.436767 -229.193493) (xy 340.452477 -229.142563) (xy 340.475603 -229.094542) (xy 340.505627 -229.050505)
			(xy 340.541879 -229.011434) (xy 340.58355 -228.978203) (xy 340.629708 -228.951554) (xy 340.679322 -228.932082)
			(xy 340.731284 -228.920222) (xy 340.784434 -228.916239) (xy 340.837584 -228.920222) (xy 340.889546 -228.932082)
			(xy 340.93916 -228.951554) (xy 340.985318 -228.978203) (xy 341.026989 -229.011434) (xy 341.063241 -229.050505)
			(xy 341.093265 -229.094542) (xy 341.116391 -229.142563) (xy 341.132101 -229.193493) (xy 341.140044 -229.246197)
			(xy 341.140542 -229.272846) (xy 341.140044 -229.299495) (xy 341.368624 -229.299495) (xy 341.368624 -229.246197)
			(xy 341.376567 -229.193493) (xy 341.392277 -229.142563) (xy 341.415403 -229.094542) (xy 341.445427 -229.050505)
			(xy 341.481679 -229.011434) (xy 341.52335 -228.978203) (xy 341.569508 -228.951554) (xy 341.619122 -228.932082)
			(xy 341.671084 -228.920222) (xy 341.724234 -228.916239) (xy 341.777384 -228.920222) (xy 341.829346 -228.932082)
			(xy 341.87896 -228.951554) (xy 341.925118 -228.978203) (xy 341.966789 -229.011434) (xy 342.003041 -229.050505)
			(xy 342.033065 -229.094542) (xy 342.056191 -229.142563) (xy 342.071901 -229.193493) (xy 342.079844 -229.246197)
			(xy 342.080342 -229.272846) (xy 342.079844 -229.299495) (xy 342.30817 -229.299495) (xy 342.30817 -229.246197)
			(xy 342.316113 -229.193493) (xy 342.331823 -229.142563) (xy 342.354949 -229.094542) (xy 342.384973 -229.050505)
			(xy 342.421225 -229.011434) (xy 342.462896 -228.978203) (xy 342.509054 -228.951554) (xy 342.558668 -228.932082)
			(xy 342.61063 -228.920222) (xy 342.66378 -228.916239) (xy 342.71693 -228.920222) (xy 342.768892 -228.932082)
			(xy 342.818506 -228.951554) (xy 342.864664 -228.978203) (xy 342.906335 -229.011434) (xy 342.942587 -229.050505)
			(xy 342.972611 -229.094542) (xy 342.995737 -229.142563) (xy 343.011447 -229.193493) (xy 343.01939 -229.246197)
			(xy 343.019888 -229.272846) (xy 343.01939 -229.299495) (xy 343.248224 -229.299495) (xy 343.248224 -229.246197)
			(xy 343.256167 -229.193493) (xy 343.271877 -229.142563) (xy 343.295003 -229.094542) (xy 343.325027 -229.050505)
			(xy 343.361279 -229.011434) (xy 343.40295 -228.978203) (xy 343.449108 -228.951554) (xy 343.498722 -228.932082)
			(xy 343.550684 -228.920222) (xy 343.603834 -228.916239) (xy 343.656984 -228.920222) (xy 343.708946 -228.932082)
			(xy 343.75856 -228.951554) (xy 343.804718 -228.978203) (xy 343.846389 -229.011434) (xy 343.882641 -229.050505)
			(xy 343.912665 -229.094542) (xy 343.935791 -229.142563) (xy 343.951501 -229.193493) (xy 343.959444 -229.246197)
			(xy 343.959942 -229.272846) (xy 343.959444 -229.299495) (xy 344.188024 -229.299495) (xy 344.188024 -229.246197)
			(xy 344.195967 -229.193493) (xy 344.211677 -229.142563) (xy 344.234803 -229.094542) (xy 344.264827 -229.050505)
			(xy 344.301079 -229.011434) (xy 344.34275 -228.978203) (xy 344.388908 -228.951554) (xy 344.438522 -228.932082)
			(xy 344.490484 -228.920222) (xy 344.543634 -228.916239) (xy 344.596784 -228.920222) (xy 344.648746 -228.932082)
			(xy 344.69836 -228.951554) (xy 344.744518 -228.978203) (xy 344.786189 -229.011434) (xy 344.822441 -229.050505)
			(xy 344.852465 -229.094542) (xy 344.875591 -229.142563) (xy 344.891301 -229.193493) (xy 344.899244 -229.246197)
			(xy 344.899742 -229.272846) (xy 344.899244 -229.299495) (xy 345.127824 -229.299495) (xy 345.127824 -229.246197)
			(xy 345.135767 -229.193493) (xy 345.151477 -229.142563) (xy 345.174603 -229.094542) (xy 345.204627 -229.050505)
			(xy 345.240879 -229.011434) (xy 345.28255 -228.978203) (xy 345.328708 -228.951554) (xy 345.378322 -228.932082)
			(xy 345.430284 -228.920222) (xy 345.483434 -228.916239) (xy 345.536584 -228.920222) (xy 345.588546 -228.932082)
			(xy 345.63816 -228.951554) (xy 345.684318 -228.978203) (xy 345.725989 -229.011434) (xy 345.762241 -229.050505)
			(xy 345.792265 -229.094542) (xy 345.815391 -229.142563) (xy 345.831101 -229.193493) (xy 345.839044 -229.246197)
			(xy 345.839542 -229.272846) (xy 345.839044 -229.299495) (xy 346.067624 -229.299495) (xy 346.067624 -229.246197)
			(xy 346.075567 -229.193493) (xy 346.091277 -229.142563) (xy 346.114403 -229.094542) (xy 346.144427 -229.050505)
			(xy 346.180679 -229.011434) (xy 346.22235 -228.978203) (xy 346.268508 -228.951554) (xy 346.318122 -228.932082)
			(xy 346.370084 -228.920222) (xy 346.423234 -228.916239) (xy 346.476384 -228.920222) (xy 346.528346 -228.932082)
			(xy 346.57796 -228.951554) (xy 346.624118 -228.978203) (xy 346.665789 -229.011434) (xy 346.702041 -229.050505)
			(xy 346.732065 -229.094542) (xy 346.755191 -229.142563) (xy 346.770901 -229.193493) (xy 346.778844 -229.246197)
			(xy 346.779342 -229.272846) (xy 346.778844 -229.299495) (xy 347.007424 -229.299495) (xy 347.007424 -229.246197)
			(xy 347.015367 -229.193493) (xy 347.031077 -229.142563) (xy 347.054203 -229.094542) (xy 347.084227 -229.050505)
			(xy 347.120479 -229.011434) (xy 347.16215 -228.978203) (xy 347.208308 -228.951554) (xy 347.257922 -228.932082)
			(xy 347.309884 -228.920222) (xy 347.363034 -228.916239) (xy 347.416184 -228.920222) (xy 347.468146 -228.932082)
			(xy 347.51776 -228.951554) (xy 347.563918 -228.978203) (xy 347.605589 -229.011434) (xy 347.641841 -229.050505)
			(xy 347.671865 -229.094542) (xy 347.694991 -229.142563) (xy 347.710701 -229.193493) (xy 347.718644 -229.246197)
			(xy 347.719142 -229.272846) (xy 347.718644 -229.299495) (xy 347.947224 -229.299495) (xy 347.947224 -229.246197)
			(xy 347.955167 -229.193493) (xy 347.970877 -229.142563) (xy 347.994003 -229.094542) (xy 348.024027 -229.050505)
			(xy 348.060279 -229.011434) (xy 348.10195 -228.978203) (xy 348.148108 -228.951554) (xy 348.197722 -228.932082)
			(xy 348.249684 -228.920222) (xy 348.302834 -228.916239) (xy 348.355984 -228.920222) (xy 348.407946 -228.932082)
			(xy 348.45756 -228.951554) (xy 348.503718 -228.978203) (xy 348.545389 -229.011434) (xy 348.581641 -229.050505)
			(xy 348.611665 -229.094542) (xy 348.634791 -229.142563) (xy 348.650501 -229.193493) (xy 348.658444 -229.246197)
			(xy 348.658942 -229.272846) (xy 348.658444 -229.299495) (xy 348.88677 -229.299495) (xy 348.88677 -229.246197)
			(xy 348.894713 -229.193493) (xy 348.910423 -229.142563) (xy 348.933549 -229.094542) (xy 348.963573 -229.050505)
			(xy 348.999825 -229.011434) (xy 349.041496 -228.978203) (xy 349.087654 -228.951554) (xy 349.137268 -228.932082)
			(xy 349.18923 -228.920222) (xy 349.24238 -228.916239) (xy 349.29553 -228.920222) (xy 349.347492 -228.932082)
			(xy 349.397106 -228.951554) (xy 349.443264 -228.978203) (xy 349.484935 -229.011434) (xy 349.521187 -229.050505)
			(xy 349.551211 -229.094542) (xy 349.574337 -229.142563) (xy 349.590047 -229.193493) (xy 349.59799 -229.246197)
			(xy 349.598488 -229.272846) (xy 349.59799 -229.299495) (xy 349.826824 -229.299495) (xy 349.826824 -229.246197)
			(xy 349.834767 -229.193493) (xy 349.850477 -229.142563) (xy 349.873603 -229.094542) (xy 349.903627 -229.050505)
			(xy 349.939879 -229.011434) (xy 349.98155 -228.978203) (xy 350.027708 -228.951554) (xy 350.077322 -228.932082)
			(xy 350.129284 -228.920222) (xy 350.182434 -228.916239) (xy 350.235584 -228.920222) (xy 350.287546 -228.932082)
			(xy 350.33716 -228.951554) (xy 350.383318 -228.978203) (xy 350.424989 -229.011434) (xy 350.461241 -229.050505)
			(xy 350.491265 -229.094542) (xy 350.514391 -229.142563) (xy 350.530101 -229.193493) (xy 350.538044 -229.246197)
			(xy 350.538542 -229.272846) (xy 350.538044 -229.299495) (xy 350.766624 -229.299495) (xy 350.766624 -229.246197)
			(xy 350.774567 -229.193493) (xy 350.790277 -229.142563) (xy 350.813403 -229.094542) (xy 350.843427 -229.050505)
			(xy 350.879679 -229.011434) (xy 350.92135 -228.978203) (xy 350.967508 -228.951554) (xy 351.017122 -228.932082)
			(xy 351.069084 -228.920222) (xy 351.122234 -228.916239) (xy 351.175384 -228.920222) (xy 351.227346 -228.932082)
			(xy 351.27696 -228.951554) (xy 351.323118 -228.978203) (xy 351.364789 -229.011434) (xy 351.401041 -229.050505)
			(xy 351.431065 -229.094542) (xy 351.454191 -229.142563) (xy 351.469901 -229.193493) (xy 351.477844 -229.246197)
			(xy 351.478342 -229.272846) (xy 351.477844 -229.299495) (xy 351.706424 -229.299495) (xy 351.706424 -229.246197)
			(xy 351.714367 -229.193493) (xy 351.730077 -229.142563) (xy 351.753203 -229.094542) (xy 351.783227 -229.050505)
			(xy 351.819479 -229.011434) (xy 351.86115 -228.978203) (xy 351.907308 -228.951554) (xy 351.956922 -228.932082)
			(xy 352.008884 -228.920222) (xy 352.062034 -228.916239) (xy 352.115184 -228.920222) (xy 352.167146 -228.932082)
			(xy 352.21676 -228.951554) (xy 352.262918 -228.978203) (xy 352.304589 -229.011434) (xy 352.340841 -229.050505)
			(xy 352.370865 -229.094542) (xy 352.393991 -229.142563) (xy 352.409701 -229.193493) (xy 352.417644 -229.246197)
			(xy 352.418142 -229.272846) (xy 352.417644 -229.299495) (xy 352.646224 -229.299495) (xy 352.646224 -229.246197)
			(xy 352.654167 -229.193493) (xy 352.669877 -229.142563) (xy 352.693003 -229.094542) (xy 352.723027 -229.050505)
			(xy 352.759279 -229.011434) (xy 352.80095 -228.978203) (xy 352.847108 -228.951554) (xy 352.896722 -228.932082)
			(xy 352.948684 -228.920222) (xy 353.001834 -228.916239) (xy 353.054984 -228.920222) (xy 353.106946 -228.932082)
			(xy 353.15656 -228.951554) (xy 353.202718 -228.978203) (xy 353.244389 -229.011434) (xy 353.280641 -229.050505)
			(xy 353.310665 -229.094542) (xy 353.333791 -229.142563) (xy 353.349501 -229.193493) (xy 353.357444 -229.246197)
			(xy 353.357942 -229.272846) (xy 353.357444 -229.299495) (xy 353.586024 -229.299495) (xy 353.586024 -229.246197)
			(xy 353.593967 -229.193493) (xy 353.609677 -229.142563) (xy 353.632803 -229.094542) (xy 353.662827 -229.050505)
			(xy 353.699079 -229.011434) (xy 353.74075 -228.978203) (xy 353.786908 -228.951554) (xy 353.836522 -228.932082)
			(xy 353.888484 -228.920222) (xy 353.941634 -228.916239) (xy 353.994784 -228.920222) (xy 354.046746 -228.932082)
			(xy 354.09636 -228.951554) (xy 354.142518 -228.978203) (xy 354.184189 -229.011434) (xy 354.220441 -229.050505)
			(xy 354.250465 -229.094542) (xy 354.273591 -229.142563) (xy 354.289301 -229.193493) (xy 354.297244 -229.246197)
			(xy 354.297742 -229.272846) (xy 354.297244 -229.299495) (xy 354.525824 -229.299495) (xy 354.525824 -229.246197)
			(xy 354.533767 -229.193493) (xy 354.549477 -229.142563) (xy 354.572603 -229.094542) (xy 354.602627 -229.050505)
			(xy 354.638879 -229.011434) (xy 354.68055 -228.978203) (xy 354.726708 -228.951554) (xy 354.776322 -228.932082)
			(xy 354.828284 -228.920222) (xy 354.881434 -228.916239) (xy 354.934584 -228.920222) (xy 354.986546 -228.932082)
			(xy 355.03616 -228.951554) (xy 355.082318 -228.978203) (xy 355.123989 -229.011434) (xy 355.160241 -229.050505)
			(xy 355.190265 -229.094542) (xy 355.213391 -229.142563) (xy 355.229101 -229.193493) (xy 355.237044 -229.246197)
			(xy 355.237542 -229.272846) (xy 355.237044 -229.299495) (xy 355.465624 -229.299495) (xy 355.465624 -229.246197)
			(xy 355.473567 -229.193493) (xy 355.489277 -229.142563) (xy 355.512403 -229.094542) (xy 355.542427 -229.050505)
			(xy 355.578679 -229.011434) (xy 355.62035 -228.978203) (xy 355.666508 -228.951554) (xy 355.716122 -228.932082)
			(xy 355.768084 -228.920222) (xy 355.821234 -228.916239) (xy 355.874384 -228.920222) (xy 355.926346 -228.932082)
			(xy 355.97596 -228.951554) (xy 356.022118 -228.978203) (xy 356.063789 -229.011434) (xy 356.100041 -229.050505)
			(xy 356.130065 -229.094542) (xy 356.153191 -229.142563) (xy 356.168901 -229.193493) (xy 356.176844 -229.246197)
			(xy 356.177342 -229.272846) (xy 356.176844 -229.299495) (xy 356.405424 -229.299495) (xy 356.405424 -229.246197)
			(xy 356.413367 -229.193493) (xy 356.429077 -229.142563) (xy 356.452203 -229.094542) (xy 356.482227 -229.050505)
			(xy 356.518479 -229.011434) (xy 356.56015 -228.978203) (xy 356.606308 -228.951554) (xy 356.655922 -228.932082)
			(xy 356.707884 -228.920222) (xy 356.761034 -228.916239) (xy 356.814184 -228.920222) (xy 356.866146 -228.932082)
			(xy 356.91576 -228.951554) (xy 356.961918 -228.978203) (xy 357.003589 -229.011434) (xy 357.039841 -229.050505)
			(xy 357.069865 -229.094542) (xy 357.092991 -229.142563) (xy 357.108701 -229.193493) (xy 357.116644 -229.246197)
			(xy 357.117142 -229.272846) (xy 357.116644 -229.299495) (xy 357.345224 -229.299495) (xy 357.345224 -229.246197)
			(xy 357.353167 -229.193493) (xy 357.368877 -229.142563) (xy 357.392003 -229.094542) (xy 357.422027 -229.050505)
			(xy 357.458279 -229.011434) (xy 357.49995 -228.978203) (xy 357.546108 -228.951554) (xy 357.595722 -228.932082)
			(xy 357.647684 -228.920222) (xy 357.700834 -228.916239) (xy 357.753984 -228.920222) (xy 357.805946 -228.932082)
			(xy 357.85556 -228.951554) (xy 357.901718 -228.978203) (xy 357.943389 -229.011434) (xy 357.979641 -229.050505)
			(xy 358.009665 -229.094542) (xy 358.032791 -229.142563) (xy 358.048501 -229.193493) (xy 358.056444 -229.246197)
			(xy 358.056942 -229.272846) (xy 358.056444 -229.299495) (xy 358.285024 -229.299495) (xy 358.285024 -229.246197)
			(xy 358.292967 -229.193493) (xy 358.308677 -229.142563) (xy 358.331803 -229.094542) (xy 358.361827 -229.050505)
			(xy 358.398079 -229.011434) (xy 358.43975 -228.978203) (xy 358.485908 -228.951554) (xy 358.535522 -228.932082)
			(xy 358.587484 -228.920222) (xy 358.640634 -228.916239) (xy 358.693784 -228.920222) (xy 358.745746 -228.932082)
			(xy 358.79536 -228.951554) (xy 358.841518 -228.978203) (xy 358.883189 -229.011434) (xy 358.919441 -229.050505)
			(xy 358.949465 -229.094542) (xy 358.972591 -229.142563) (xy 358.988301 -229.193493) (xy 358.996244 -229.246197)
			(xy 358.996742 -229.272846) (xy 358.996244 -229.299495) (xy 359.22457 -229.299495) (xy 359.22457 -229.246197)
			(xy 359.232513 -229.193493) (xy 359.248223 -229.142563) (xy 359.271349 -229.094542) (xy 359.301373 -229.050505)
			(xy 359.337625 -229.011434) (xy 359.379296 -228.978203) (xy 359.425454 -228.951554) (xy 359.475068 -228.932082)
			(xy 359.52703 -228.920222) (xy 359.58018 -228.916239) (xy 359.63333 -228.920222) (xy 359.685292 -228.932082)
			(xy 359.734906 -228.951554) (xy 359.781064 -228.978203) (xy 359.822735 -229.011434) (xy 359.858987 -229.050505)
			(xy 359.889011 -229.094542) (xy 359.912137 -229.142563) (xy 359.927847 -229.193493) (xy 359.93579 -229.246197)
			(xy 359.936288 -229.272846) (xy 359.93579 -229.299495) (xy 360.164624 -229.299495) (xy 360.164624 -229.246197)
			(xy 360.172567 -229.193493) (xy 360.188277 -229.142563) (xy 360.211403 -229.094542) (xy 360.241427 -229.050505)
			(xy 360.277679 -229.011434) (xy 360.31935 -228.978203) (xy 360.365508 -228.951554) (xy 360.415122 -228.932082)
			(xy 360.467084 -228.920222) (xy 360.520234 -228.916239) (xy 360.573384 -228.920222) (xy 360.625346 -228.932082)
			(xy 360.67496 -228.951554) (xy 360.721118 -228.978203) (xy 360.762789 -229.011434) (xy 360.799041 -229.050505)
			(xy 360.829065 -229.094542) (xy 360.852191 -229.142563) (xy 360.867901 -229.193493) (xy 360.875844 -229.246197)
			(xy 360.876342 -229.272846) (xy 360.875844 -229.299495) (xy 361.104424 -229.299495) (xy 361.104424 -229.246197)
			(xy 361.112367 -229.193493) (xy 361.128077 -229.142563) (xy 361.151203 -229.094542) (xy 361.181227 -229.050505)
			(xy 361.217479 -229.011434) (xy 361.25915 -228.978203) (xy 361.305308 -228.951554) (xy 361.354922 -228.932082)
			(xy 361.406884 -228.920222) (xy 361.460034 -228.916239) (xy 361.513184 -228.920222) (xy 361.565146 -228.932082)
			(xy 361.61476 -228.951554) (xy 361.660918 -228.978203) (xy 361.702589 -229.011434) (xy 361.738841 -229.050505)
			(xy 361.768865 -229.094542) (xy 361.791991 -229.142563) (xy 361.807701 -229.193493) (xy 361.815644 -229.246197)
			(xy 361.816142 -229.272846) (xy 361.815644 -229.299495) (xy 362.044224 -229.299495) (xy 362.044224 -229.246197)
			(xy 362.052167 -229.193493) (xy 362.067877 -229.142563) (xy 362.091003 -229.094542) (xy 362.121027 -229.050505)
			(xy 362.157279 -229.011434) (xy 362.19895 -228.978203) (xy 362.245108 -228.951554) (xy 362.294722 -228.932082)
			(xy 362.346684 -228.920222) (xy 362.399834 -228.916239) (xy 362.452984 -228.920222) (xy 362.504946 -228.932082)
			(xy 362.55456 -228.951554) (xy 362.600718 -228.978203) (xy 362.642389 -229.011434) (xy 362.678641 -229.050505)
			(xy 362.708665 -229.094542) (xy 362.731791 -229.142563) (xy 362.747501 -229.193493) (xy 362.755444 -229.246197)
			(xy 362.755942 -229.272846) (xy 362.755444 -229.299495) (xy 362.984024 -229.299495) (xy 362.984024 -229.246197)
			(xy 362.991967 -229.193493) (xy 363.007677 -229.142563) (xy 363.030803 -229.094542) (xy 363.060827 -229.050505)
			(xy 363.097079 -229.011434) (xy 363.13875 -228.978203) (xy 363.184908 -228.951554) (xy 363.234522 -228.932082)
			(xy 363.286484 -228.920222) (xy 363.339634 -228.916239) (xy 363.392784 -228.920222) (xy 363.444746 -228.932082)
			(xy 363.49436 -228.951554) (xy 363.540518 -228.978203) (xy 363.582189 -229.011434) (xy 363.618441 -229.050505)
			(xy 363.648465 -229.094542) (xy 363.671591 -229.142563) (xy 363.687301 -229.193493) (xy 363.695244 -229.246197)
			(xy 363.695742 -229.272846) (xy 363.695244 -229.299495) (xy 363.923824 -229.299495) (xy 363.923824 -229.246197)
			(xy 363.931767 -229.193493) (xy 363.947477 -229.142563) (xy 363.970603 -229.094542) (xy 364.000627 -229.050505)
			(xy 364.036879 -229.011434) (xy 364.07855 -228.978203) (xy 364.124708 -228.951554) (xy 364.174322 -228.932082)
			(xy 364.226284 -228.920222) (xy 364.279434 -228.916239) (xy 364.332584 -228.920222) (xy 364.384546 -228.932082)
			(xy 364.43416 -228.951554) (xy 364.480318 -228.978203) (xy 364.521989 -229.011434) (xy 364.558241 -229.050505)
			(xy 364.588265 -229.094542) (xy 364.611391 -229.142563) (xy 364.627101 -229.193493) (xy 364.635044 -229.246197)
			(xy 364.635542 -229.272846) (xy 364.635044 -229.299495) (xy 364.863624 -229.299495) (xy 364.863624 -229.246197)
			(xy 364.871567 -229.193493) (xy 364.887277 -229.142563) (xy 364.910403 -229.094542) (xy 364.940427 -229.050505)
			(xy 364.976679 -229.011434) (xy 365.01835 -228.978203) (xy 365.064508 -228.951554) (xy 365.114122 -228.932082)
			(xy 365.166084 -228.920222) (xy 365.219234 -228.916239) (xy 365.272384 -228.920222) (xy 365.324346 -228.932082)
			(xy 365.37396 -228.951554) (xy 365.420118 -228.978203) (xy 365.461789 -229.011434) (xy 365.498041 -229.050505)
			(xy 365.528065 -229.094542) (xy 365.551191 -229.142563) (xy 365.566901 -229.193493) (xy 365.574844 -229.246197)
			(xy 365.575342 -229.272846) (xy 365.574844 -229.299495) (xy 365.803424 -229.299495) (xy 365.803424 -229.246197)
			(xy 365.811367 -229.193493) (xy 365.827077 -229.142563) (xy 365.850203 -229.094542) (xy 365.880227 -229.050505)
			(xy 365.916479 -229.011434) (xy 365.95815 -228.978203) (xy 366.004308 -228.951554) (xy 366.053922 -228.932082)
			(xy 366.105884 -228.920222) (xy 366.159034 -228.916239) (xy 366.212184 -228.920222) (xy 366.264146 -228.932082)
			(xy 366.31376 -228.951554) (xy 366.359918 -228.978203) (xy 366.401589 -229.011434) (xy 366.437841 -229.050505)
			(xy 366.467865 -229.094542) (xy 366.490991 -229.142563) (xy 366.506701 -229.193493) (xy 366.514644 -229.246197)
			(xy 366.515142 -229.272846) (xy 366.514644 -229.299495) (xy 366.743224 -229.299495) (xy 366.743224 -229.246197)
			(xy 366.751167 -229.193493) (xy 366.766877 -229.142563) (xy 366.790003 -229.094542) (xy 366.820027 -229.050505)
			(xy 366.856279 -229.011434) (xy 366.89795 -228.978203) (xy 366.944108 -228.951554) (xy 366.993722 -228.932082)
			(xy 367.045684 -228.920222) (xy 367.098834 -228.916239) (xy 367.151984 -228.920222) (xy 367.203946 -228.932082)
			(xy 367.25356 -228.951554) (xy 367.299718 -228.978203) (xy 367.341389 -229.011434) (xy 367.377641 -229.050505)
			(xy 367.407665 -229.094542) (xy 367.430791 -229.142563) (xy 367.446501 -229.193493) (xy 367.454444 -229.246197)
			(xy 367.454942 -229.272846) (xy 367.454444 -229.299495) (xy 367.683024 -229.299495) (xy 367.683024 -229.246197)
			(xy 367.690967 -229.193493) (xy 367.706677 -229.142563) (xy 367.729803 -229.094542) (xy 367.759827 -229.050505)
			(xy 367.796079 -229.011434) (xy 367.83775 -228.978203) (xy 367.883908 -228.951554) (xy 367.933522 -228.932082)
			(xy 367.985484 -228.920222) (xy 368.038634 -228.916239) (xy 368.091784 -228.920222) (xy 368.143746 -228.932082)
			(xy 368.19336 -228.951554) (xy 368.239518 -228.978203) (xy 368.281189 -229.011434) (xy 368.317441 -229.050505)
			(xy 368.347465 -229.094542) (xy 368.370591 -229.142563) (xy 368.386301 -229.193493) (xy 368.394244 -229.246197)
			(xy 368.394742 -229.272846) (xy 368.394244 -229.299495) (xy 368.622824 -229.299495) (xy 368.622824 -229.246197)
			(xy 368.630767 -229.193493) (xy 368.646477 -229.142563) (xy 368.669603 -229.094542) (xy 368.699627 -229.050505)
			(xy 368.735879 -229.011434) (xy 368.77755 -228.978203) (xy 368.823708 -228.951554) (xy 368.873322 -228.932082)
			(xy 368.925284 -228.920222) (xy 368.978434 -228.916239) (xy 369.031584 -228.920222) (xy 369.083546 -228.932082)
			(xy 369.13316 -228.951554) (xy 369.179318 -228.978203) (xy 369.220989 -229.011434) (xy 369.257241 -229.050505)
			(xy 369.287265 -229.094542) (xy 369.310391 -229.142563) (xy 369.326101 -229.193493) (xy 369.334044 -229.246197)
			(xy 369.334542 -229.272846) (xy 369.334044 -229.299495) (xy 369.562624 -229.299495) (xy 369.562624 -229.246197)
			(xy 369.570567 -229.193493) (xy 369.586277 -229.142563) (xy 369.609403 -229.094542) (xy 369.639427 -229.050505)
			(xy 369.675679 -229.011434) (xy 369.71735 -228.978203) (xy 369.763508 -228.951554) (xy 369.813122 -228.932082)
			(xy 369.865084 -228.920222) (xy 369.918234 -228.916239) (xy 369.971384 -228.920222) (xy 370.023346 -228.932082)
			(xy 370.07296 -228.951554) (xy 370.119118 -228.978203) (xy 370.160789 -229.011434) (xy 370.197041 -229.050505)
			(xy 370.227065 -229.094542) (xy 370.250191 -229.142563) (xy 370.265901 -229.193493) (xy 370.273844 -229.246197)
			(xy 370.274342 -229.272846) (xy 370.273844 -229.299495) (xy 370.50217 -229.299495) (xy 370.50217 -229.246197)
			(xy 370.510113 -229.193493) (xy 370.525823 -229.142563) (xy 370.548949 -229.094542) (xy 370.578973 -229.050505)
			(xy 370.615225 -229.011434) (xy 370.656896 -228.978203) (xy 370.703054 -228.951554) (xy 370.752668 -228.932082)
			(xy 370.80463 -228.920222) (xy 370.85778 -228.916239) (xy 370.91093 -228.920222) (xy 370.962892 -228.932082)
			(xy 371.012506 -228.951554) (xy 371.058664 -228.978203) (xy 371.100335 -229.011434) (xy 371.136587 -229.050505)
			(xy 371.166611 -229.094542) (xy 371.189737 -229.142563) (xy 371.205447 -229.193493) (xy 371.21339 -229.246197)
			(xy 371.213888 -229.272846) (xy 371.21339 -229.299495) (xy 371.442224 -229.299495) (xy 371.442224 -229.246197)
			(xy 371.450167 -229.193493) (xy 371.465877 -229.142563) (xy 371.489003 -229.094542) (xy 371.519027 -229.050505)
			(xy 371.555279 -229.011434) (xy 371.59695 -228.978203) (xy 371.643108 -228.951554) (xy 371.692722 -228.932082)
			(xy 371.744684 -228.920222) (xy 371.797834 -228.916239) (xy 371.850984 -228.920222) (xy 371.902946 -228.932082)
			(xy 371.95256 -228.951554) (xy 371.998718 -228.978203) (xy 372.040389 -229.011434) (xy 372.076641 -229.050505)
			(xy 372.106665 -229.094542) (xy 372.129791 -229.142563) (xy 372.145501 -229.193493) (xy 372.153444 -229.246197)
			(xy 372.153942 -229.272846) (xy 372.153444 -229.299495) (xy 372.382024 -229.299495) (xy 372.382024 -229.246197)
			(xy 372.389967 -229.193493) (xy 372.405677 -229.142563) (xy 372.428803 -229.094542) (xy 372.458827 -229.050505)
			(xy 372.495079 -229.011434) (xy 372.53675 -228.978203) (xy 372.582908 -228.951554) (xy 372.632522 -228.932082)
			(xy 372.684484 -228.920222) (xy 372.737634 -228.916239) (xy 372.790784 -228.920222) (xy 372.842746 -228.932082)
			(xy 372.89236 -228.951554) (xy 372.938518 -228.978203) (xy 372.980189 -229.011434) (xy 373.016441 -229.050505)
			(xy 373.046465 -229.094542) (xy 373.069591 -229.142563) (xy 373.085301 -229.193493) (xy 373.093244 -229.246197)
			(xy 373.093742 -229.272846) (xy 373.093244 -229.299495) (xy 373.321824 -229.299495) (xy 373.321824 -229.246197)
			(xy 373.329767 -229.193493) (xy 373.345477 -229.142563) (xy 373.368603 -229.094542) (xy 373.398627 -229.050505)
			(xy 373.434879 -229.011434) (xy 373.47655 -228.978203) (xy 373.522708 -228.951554) (xy 373.572322 -228.932082)
			(xy 373.624284 -228.920222) (xy 373.677434 -228.916239) (xy 373.730584 -228.920222) (xy 373.782546 -228.932082)
			(xy 373.83216 -228.951554) (xy 373.878318 -228.978203) (xy 373.919989 -229.011434) (xy 373.956241 -229.050505)
			(xy 373.986265 -229.094542) (xy 374.009391 -229.142563) (xy 374.025101 -229.193493) (xy 374.033044 -229.246197)
			(xy 374.033542 -229.272846) (xy 374.033044 -229.299495) (xy 374.261624 -229.299495) (xy 374.261624 -229.246197)
			(xy 374.269567 -229.193493) (xy 374.285277 -229.142563) (xy 374.308403 -229.094542) (xy 374.338427 -229.050505)
			(xy 374.374679 -229.011434) (xy 374.41635 -228.978203) (xy 374.462508 -228.951554) (xy 374.512122 -228.932082)
			(xy 374.564084 -228.920222) (xy 374.617234 -228.916239) (xy 374.670384 -228.920222) (xy 374.722346 -228.932082)
			(xy 374.77196 -228.951554) (xy 374.818118 -228.978203) (xy 374.859789 -229.011434) (xy 374.896041 -229.050505)
			(xy 374.926065 -229.094542) (xy 374.949191 -229.142563) (xy 374.964901 -229.193493) (xy 374.972844 -229.246197)
			(xy 374.973342 -229.272846) (xy 374.972844 -229.299495) (xy 375.201424 -229.299495) (xy 375.201424 -229.246197)
			(xy 375.209367 -229.193493) (xy 375.225077 -229.142563) (xy 375.248203 -229.094542) (xy 375.278227 -229.050505)
			(xy 375.314479 -229.011434) (xy 375.35615 -228.978203) (xy 375.402308 -228.951554) (xy 375.451922 -228.932082)
			(xy 375.503884 -228.920222) (xy 375.557034 -228.916239) (xy 375.610184 -228.920222) (xy 375.662146 -228.932082)
			(xy 375.71176 -228.951554) (xy 375.757918 -228.978203) (xy 375.799589 -229.011434) (xy 375.835841 -229.050505)
			(xy 375.865865 -229.094542) (xy 375.888991 -229.142563) (xy 375.904701 -229.193493) (xy 375.912644 -229.246197)
			(xy 375.913142 -229.272846) (xy 375.912644 -229.299495) (xy 376.141224 -229.299495) (xy 376.141224 -229.246197)
			(xy 376.149167 -229.193493) (xy 376.164877 -229.142563) (xy 376.188003 -229.094542) (xy 376.218027 -229.050505)
			(xy 376.254279 -229.011434) (xy 376.29595 -228.978203) (xy 376.342108 -228.951554) (xy 376.391722 -228.932082)
			(xy 376.443684 -228.920222) (xy 376.496834 -228.916239) (xy 376.549984 -228.920222) (xy 376.601946 -228.932082)
			(xy 376.65156 -228.951554) (xy 376.697718 -228.978203) (xy 376.739389 -229.011434) (xy 376.775641 -229.050505)
			(xy 376.805665 -229.094542) (xy 376.828791 -229.142563) (xy 376.844501 -229.193493) (xy 376.852444 -229.246197)
			(xy 376.852942 -229.272846) (xy 376.852444 -229.299495) (xy 377.08077 -229.299495) (xy 377.08077 -229.246197)
			(xy 377.088713 -229.193493) (xy 377.104423 -229.142563) (xy 377.127549 -229.094542) (xy 377.157573 -229.050505)
			(xy 377.193825 -229.011434) (xy 377.235496 -228.978203) (xy 377.281654 -228.951554) (xy 377.331268 -228.932082)
			(xy 377.38323 -228.920222) (xy 377.43638 -228.916239) (xy 377.48953 -228.920222) (xy 377.541492 -228.932082)
			(xy 377.591106 -228.951554) (xy 377.637264 -228.978203) (xy 377.678935 -229.011434) (xy 377.715187 -229.050505)
			(xy 377.745211 -229.094542) (xy 377.768337 -229.142563) (xy 377.784047 -229.193493) (xy 377.79199 -229.246197)
			(xy 377.792488 -229.272846) (xy 377.79199 -229.299495) (xy 377.784047 -229.352199) (xy 377.768337 -229.403129)
			(xy 377.745211 -229.45115) (xy 377.715187 -229.495187) (xy 377.678935 -229.534258) (xy 377.637264 -229.567489)
			(xy 377.591106 -229.594138) (xy 377.541492 -229.61361) (xy 377.48953 -229.62547) (xy 377.43638 -229.629454)
			(xy 377.38323 -229.62547) (xy 377.331268 -229.61361) (xy 377.281654 -229.594138) (xy 377.235496 -229.567489)
			(xy 377.193825 -229.534258) (xy 377.157573 -229.495187) (xy 377.127549 -229.45115) (xy 377.104423 -229.403129)
			(xy 377.088713 -229.352199) (xy 377.08077 -229.299495) (xy 376.852444 -229.299495) (xy 376.844501 -229.352199)
			(xy 376.828791 -229.403129) (xy 376.805665 -229.45115) (xy 376.775641 -229.495187) (xy 376.739389 -229.534258)
			(xy 376.697718 -229.567489) (xy 376.65156 -229.594138) (xy 376.601946 -229.61361) (xy 376.549984 -229.62547)
			(xy 376.496834 -229.629454) (xy 376.443684 -229.62547) (xy 376.391722 -229.61361) (xy 376.342108 -229.594138)
			(xy 376.29595 -229.567489) (xy 376.254279 -229.534258) (xy 376.218027 -229.495187) (xy 376.188003 -229.45115)
			(xy 376.164877 -229.403129) (xy 376.149167 -229.352199) (xy 376.141224 -229.299495) (xy 375.912644 -229.299495)
			(xy 375.904701 -229.352199) (xy 375.888991 -229.403129) (xy 375.865865 -229.45115) (xy 375.835841 -229.495187)
			(xy 375.799589 -229.534258) (xy 375.757918 -229.567489) (xy 375.71176 -229.594138) (xy 375.662146 -229.61361)
			(xy 375.610184 -229.62547) (xy 375.557034 -229.629454) (xy 375.503884 -229.62547) (xy 375.451922 -229.61361)
			(xy 375.402308 -229.594138) (xy 375.35615 -229.567489) (xy 375.314479 -229.534258) (xy 375.278227 -229.495187)
			(xy 375.248203 -229.45115) (xy 375.225077 -229.403129) (xy 375.209367 -229.352199) (xy 375.201424 -229.299495)
			(xy 374.972844 -229.299495) (xy 374.964901 -229.352199) (xy 374.949191 -229.403129) (xy 374.926065 -229.45115)
			(xy 374.896041 -229.495187) (xy 374.859789 -229.534258) (xy 374.818118 -229.567489) (xy 374.77196 -229.594138)
			(xy 374.722346 -229.61361) (xy 374.670384 -229.62547) (xy 374.617234 -229.629454) (xy 374.564084 -229.62547)
			(xy 374.512122 -229.61361) (xy 374.462508 -229.594138) (xy 374.41635 -229.567489) (xy 374.374679 -229.534258)
			(xy 374.338427 -229.495187) (xy 374.308403 -229.45115) (xy 374.285277 -229.403129) (xy 374.269567 -229.352199)
			(xy 374.261624 -229.299495) (xy 374.033044 -229.299495) (xy 374.025101 -229.352199) (xy 374.009391 -229.403129)
			(xy 373.986265 -229.45115) (xy 373.956241 -229.495187) (xy 373.919989 -229.534258) (xy 373.878318 -229.567489)
			(xy 373.83216 -229.594138) (xy 373.782546 -229.61361) (xy 373.730584 -229.62547) (xy 373.677434 -229.629454)
			(xy 373.624284 -229.62547) (xy 373.572322 -229.61361) (xy 373.522708 -229.594138) (xy 373.47655 -229.567489)
			(xy 373.434879 -229.534258) (xy 373.398627 -229.495187) (xy 373.368603 -229.45115) (xy 373.345477 -229.403129)
			(xy 373.329767 -229.352199) (xy 373.321824 -229.299495) (xy 373.093244 -229.299495) (xy 373.085301 -229.352199)
			(xy 373.069591 -229.403129) (xy 373.046465 -229.45115) (xy 373.016441 -229.495187) (xy 372.980189 -229.534258)
			(xy 372.938518 -229.567489) (xy 372.89236 -229.594138) (xy 372.842746 -229.61361) (xy 372.790784 -229.62547)
			(xy 372.737634 -229.629454) (xy 372.684484 -229.62547) (xy 372.632522 -229.61361) (xy 372.582908 -229.594138)
			(xy 372.53675 -229.567489) (xy 372.495079 -229.534258) (xy 372.458827 -229.495187) (xy 372.428803 -229.45115)
			(xy 372.405677 -229.403129) (xy 372.389967 -229.352199) (xy 372.382024 -229.299495) (xy 372.153444 -229.299495)
			(xy 372.145501 -229.352199) (xy 372.129791 -229.403129) (xy 372.106665 -229.45115) (xy 372.076641 -229.495187)
			(xy 372.040389 -229.534258) (xy 371.998718 -229.567489) (xy 371.95256 -229.594138) (xy 371.902946 -229.61361)
			(xy 371.850984 -229.62547) (xy 371.797834 -229.629454) (xy 371.744684 -229.62547) (xy 371.692722 -229.61361)
			(xy 371.643108 -229.594138) (xy 371.59695 -229.567489) (xy 371.555279 -229.534258) (xy 371.519027 -229.495187)
			(xy 371.489003 -229.45115) (xy 371.465877 -229.403129) (xy 371.450167 -229.352199) (xy 371.442224 -229.299495)
			(xy 371.21339 -229.299495) (xy 371.205447 -229.352199) (xy 371.189737 -229.403129) (xy 371.166611 -229.45115)
			(xy 371.136587 -229.495187) (xy 371.100335 -229.534258) (xy 371.058664 -229.567489) (xy 371.012506 -229.594138)
			(xy 370.962892 -229.61361) (xy 370.91093 -229.62547) (xy 370.85778 -229.629454) (xy 370.80463 -229.62547)
			(xy 370.752668 -229.61361) (xy 370.703054 -229.594138) (xy 370.656896 -229.567489) (xy 370.615225 -229.534258)
			(xy 370.578973 -229.495187) (xy 370.548949 -229.45115) (xy 370.525823 -229.403129) (xy 370.510113 -229.352199)
			(xy 370.50217 -229.299495) (xy 370.273844 -229.299495) (xy 370.265901 -229.352199) (xy 370.250191 -229.403129)
			(xy 370.227065 -229.45115) (xy 370.197041 -229.495187) (xy 370.160789 -229.534258) (xy 370.119118 -229.567489)
			(xy 370.07296 -229.594138) (xy 370.023346 -229.61361) (xy 369.971384 -229.62547) (xy 369.918234 -229.629454)
			(xy 369.865084 -229.62547) (xy 369.813122 -229.61361) (xy 369.763508 -229.594138) (xy 369.71735 -229.567489)
			(xy 369.675679 -229.534258) (xy 369.639427 -229.495187) (xy 369.609403 -229.45115) (xy 369.586277 -229.403129)
			(xy 369.570567 -229.352199) (xy 369.562624 -229.299495) (xy 369.334044 -229.299495) (xy 369.326101 -229.352199)
			(xy 369.310391 -229.403129) (xy 369.287265 -229.45115) (xy 369.257241 -229.495187) (xy 369.220989 -229.534258)
			(xy 369.179318 -229.567489) (xy 369.13316 -229.594138) (xy 369.083546 -229.61361) (xy 369.031584 -229.62547)
			(xy 368.978434 -229.629454) (xy 368.925284 -229.62547) (xy 368.873322 -229.61361) (xy 368.823708 -229.594138)
			(xy 368.77755 -229.567489) (xy 368.735879 -229.534258) (xy 368.699627 -229.495187) (xy 368.669603 -229.45115)
			(xy 368.646477 -229.403129) (xy 368.630767 -229.352199) (xy 368.622824 -229.299495) (xy 368.394244 -229.299495)
			(xy 368.386301 -229.352199) (xy 368.370591 -229.403129) (xy 368.347465 -229.45115) (xy 368.317441 -229.495187)
			(xy 368.281189 -229.534258) (xy 368.239518 -229.567489) (xy 368.19336 -229.594138) (xy 368.143746 -229.61361)
			(xy 368.091784 -229.62547) (xy 368.038634 -229.629454) (xy 367.985484 -229.62547) (xy 367.933522 -229.61361)
			(xy 367.883908 -229.594138) (xy 367.83775 -229.567489) (xy 367.796079 -229.534258) (xy 367.759827 -229.495187)
			(xy 367.729803 -229.45115) (xy 367.706677 -229.403129) (xy 367.690967 -229.352199) (xy 367.683024 -229.299495)
			(xy 367.454444 -229.299495) (xy 367.446501 -229.352199) (xy 367.430791 -229.403129) (xy 367.407665 -229.45115)
			(xy 367.377641 -229.495187) (xy 367.341389 -229.534258) (xy 367.299718 -229.567489) (xy 367.25356 -229.594138)
			(xy 367.203946 -229.61361) (xy 367.151984 -229.62547) (xy 367.098834 -229.629454) (xy 367.045684 -229.62547)
			(xy 366.993722 -229.61361) (xy 366.944108 -229.594138) (xy 366.89795 -229.567489) (xy 366.856279 -229.534258)
			(xy 366.820027 -229.495187) (xy 366.790003 -229.45115) (xy 366.766877 -229.403129) (xy 366.751167 -229.352199)
			(xy 366.743224 -229.299495) (xy 366.514644 -229.299495) (xy 366.506701 -229.352199) (xy 366.490991 -229.403129)
			(xy 366.467865 -229.45115) (xy 366.437841 -229.495187) (xy 366.401589 -229.534258) (xy 366.359918 -229.567489)
			(xy 366.31376 -229.594138) (xy 366.264146 -229.61361) (xy 366.212184 -229.62547) (xy 366.159034 -229.629454)
			(xy 366.105884 -229.62547) (xy 366.053922 -229.61361) (xy 366.004308 -229.594138) (xy 365.95815 -229.567489)
			(xy 365.916479 -229.534258) (xy 365.880227 -229.495187) (xy 365.850203 -229.45115) (xy 365.827077 -229.403129)
			(xy 365.811367 -229.352199) (xy 365.803424 -229.299495) (xy 365.574844 -229.299495) (xy 365.566901 -229.352199)
			(xy 365.551191 -229.403129) (xy 365.528065 -229.45115) (xy 365.498041 -229.495187) (xy 365.461789 -229.534258)
			(xy 365.420118 -229.567489) (xy 365.37396 -229.594138) (xy 365.324346 -229.61361) (xy 365.272384 -229.62547)
			(xy 365.219234 -229.629454) (xy 365.166084 -229.62547) (xy 365.114122 -229.61361) (xy 365.064508 -229.594138)
			(xy 365.01835 -229.567489) (xy 364.976679 -229.534258) (xy 364.940427 -229.495187) (xy 364.910403 -229.45115)
			(xy 364.887277 -229.403129) (xy 364.871567 -229.352199) (xy 364.863624 -229.299495) (xy 364.635044 -229.299495)
			(xy 364.627101 -229.352199) (xy 364.611391 -229.403129) (xy 364.588265 -229.45115) (xy 364.558241 -229.495187)
			(xy 364.521989 -229.534258) (xy 364.480318 -229.567489) (xy 364.43416 -229.594138) (xy 364.384546 -229.61361)
			(xy 364.332584 -229.62547) (xy 364.279434 -229.629454) (xy 364.226284 -229.62547) (xy 364.174322 -229.61361)
			(xy 364.124708 -229.594138) (xy 364.07855 -229.567489) (xy 364.036879 -229.534258) (xy 364.000627 -229.495187)
			(xy 363.970603 -229.45115) (xy 363.947477 -229.403129) (xy 363.931767 -229.352199) (xy 363.923824 -229.299495)
			(xy 363.695244 -229.299495) (xy 363.687301 -229.352199) (xy 363.671591 -229.403129) (xy 363.648465 -229.45115)
			(xy 363.618441 -229.495187) (xy 363.582189 -229.534258) (xy 363.540518 -229.567489) (xy 363.49436 -229.594138)
			(xy 363.444746 -229.61361) (xy 363.392784 -229.62547) (xy 363.339634 -229.629454) (xy 363.286484 -229.62547)
			(xy 363.234522 -229.61361) (xy 363.184908 -229.594138) (xy 363.13875 -229.567489) (xy 363.097079 -229.534258)
			(xy 363.060827 -229.495187) (xy 363.030803 -229.45115) (xy 363.007677 -229.403129) (xy 362.991967 -229.352199)
			(xy 362.984024 -229.299495) (xy 362.755444 -229.299495) (xy 362.747501 -229.352199) (xy 362.731791 -229.403129)
			(xy 362.708665 -229.45115) (xy 362.678641 -229.495187) (xy 362.642389 -229.534258) (xy 362.600718 -229.567489)
			(xy 362.55456 -229.594138) (xy 362.504946 -229.61361) (xy 362.452984 -229.62547) (xy 362.399834 -229.629454)
			(xy 362.346684 -229.62547) (xy 362.294722 -229.61361) (xy 362.245108 -229.594138) (xy 362.19895 -229.567489)
			(xy 362.157279 -229.534258) (xy 362.121027 -229.495187) (xy 362.091003 -229.45115) (xy 362.067877 -229.403129)
			(xy 362.052167 -229.352199) (xy 362.044224 -229.299495) (xy 361.815644 -229.299495) (xy 361.807701 -229.352199)
			(xy 361.791991 -229.403129) (xy 361.768865 -229.45115) (xy 361.738841 -229.495187) (xy 361.702589 -229.534258)
			(xy 361.660918 -229.567489) (xy 361.61476 -229.594138) (xy 361.565146 -229.61361) (xy 361.513184 -229.62547)
			(xy 361.460034 -229.629454) (xy 361.406884 -229.62547) (xy 361.354922 -229.61361) (xy 361.305308 -229.594138)
			(xy 361.25915 -229.567489) (xy 361.217479 -229.534258) (xy 361.181227 -229.495187) (xy 361.151203 -229.45115)
			(xy 361.128077 -229.403129) (xy 361.112367 -229.352199) (xy 361.104424 -229.299495) (xy 360.875844 -229.299495)
			(xy 360.867901 -229.352199) (xy 360.852191 -229.403129) (xy 360.829065 -229.45115) (xy 360.799041 -229.495187)
			(xy 360.762789 -229.534258) (xy 360.721118 -229.567489) (xy 360.67496 -229.594138) (xy 360.625346 -229.61361)
			(xy 360.573384 -229.62547) (xy 360.520234 -229.629454) (xy 360.467084 -229.62547) (xy 360.415122 -229.61361)
			(xy 360.365508 -229.594138) (xy 360.31935 -229.567489) (xy 360.277679 -229.534258) (xy 360.241427 -229.495187)
			(xy 360.211403 -229.45115) (xy 360.188277 -229.403129) (xy 360.172567 -229.352199) (xy 360.164624 -229.299495)
			(xy 359.93579 -229.299495) (xy 359.927847 -229.352199) (xy 359.912137 -229.403129) (xy 359.889011 -229.45115)
			(xy 359.858987 -229.495187) (xy 359.822735 -229.534258) (xy 359.781064 -229.567489) (xy 359.734906 -229.594138)
			(xy 359.685292 -229.61361) (xy 359.63333 -229.62547) (xy 359.58018 -229.629454) (xy 359.52703 -229.62547)
			(xy 359.475068 -229.61361) (xy 359.425454 -229.594138) (xy 359.379296 -229.567489) (xy 359.337625 -229.534258)
			(xy 359.301373 -229.495187) (xy 359.271349 -229.45115) (xy 359.248223 -229.403129) (xy 359.232513 -229.352199)
			(xy 359.22457 -229.299495) (xy 358.996244 -229.299495) (xy 358.988301 -229.352199) (xy 358.972591 -229.403129)
			(xy 358.949465 -229.45115) (xy 358.919441 -229.495187) (xy 358.883189 -229.534258) (xy 358.841518 -229.567489)
			(xy 358.79536 -229.594138) (xy 358.745746 -229.61361) (xy 358.693784 -229.62547) (xy 358.640634 -229.629454)
			(xy 358.587484 -229.62547) (xy 358.535522 -229.61361) (xy 358.485908 -229.594138) (xy 358.43975 -229.567489)
			(xy 358.398079 -229.534258) (xy 358.361827 -229.495187) (xy 358.331803 -229.45115) (xy 358.308677 -229.403129)
			(xy 358.292967 -229.352199) (xy 358.285024 -229.299495) (xy 358.056444 -229.299495) (xy 358.048501 -229.352199)
			(xy 358.032791 -229.403129) (xy 358.009665 -229.45115) (xy 357.979641 -229.495187) (xy 357.943389 -229.534258)
			(xy 357.901718 -229.567489) (xy 357.85556 -229.594138) (xy 357.805946 -229.61361) (xy 357.753984 -229.62547)
			(xy 357.700834 -229.629454) (xy 357.647684 -229.62547) (xy 357.595722 -229.61361) (xy 357.546108 -229.594138)
			(xy 357.49995 -229.567489) (xy 357.458279 -229.534258) (xy 357.422027 -229.495187) (xy 357.392003 -229.45115)
			(xy 357.368877 -229.403129) (xy 357.353167 -229.352199) (xy 357.345224 -229.299495) (xy 357.116644 -229.299495)
			(xy 357.108701 -229.352199) (xy 357.092991 -229.403129) (xy 357.069865 -229.45115) (xy 357.039841 -229.495187)
			(xy 357.003589 -229.534258) (xy 356.961918 -229.567489) (xy 356.91576 -229.594138) (xy 356.866146 -229.61361)
			(xy 356.814184 -229.62547) (xy 356.761034 -229.629454) (xy 356.707884 -229.62547) (xy 356.655922 -229.61361)
			(xy 356.606308 -229.594138) (xy 356.56015 -229.567489) (xy 356.518479 -229.534258) (xy 356.482227 -229.495187)
			(xy 356.452203 -229.45115) (xy 356.429077 -229.403129) (xy 356.413367 -229.352199) (xy 356.405424 -229.299495)
			(xy 356.176844 -229.299495) (xy 356.168901 -229.352199) (xy 356.153191 -229.403129) (xy 356.130065 -229.45115)
			(xy 356.100041 -229.495187) (xy 356.063789 -229.534258) (xy 356.022118 -229.567489) (xy 355.97596 -229.594138)
			(xy 355.926346 -229.61361) (xy 355.874384 -229.62547) (xy 355.821234 -229.629454) (xy 355.768084 -229.62547)
			(xy 355.716122 -229.61361) (xy 355.666508 -229.594138) (xy 355.62035 -229.567489) (xy 355.578679 -229.534258)
			(xy 355.542427 -229.495187) (xy 355.512403 -229.45115) (xy 355.489277 -229.403129) (xy 355.473567 -229.352199)
			(xy 355.465624 -229.299495) (xy 355.237044 -229.299495) (xy 355.229101 -229.352199) (xy 355.213391 -229.403129)
			(xy 355.190265 -229.45115) (xy 355.160241 -229.495187) (xy 355.123989 -229.534258) (xy 355.082318 -229.567489)
			(xy 355.03616 -229.594138) (xy 354.986546 -229.61361) (xy 354.934584 -229.62547) (xy 354.881434 -229.629454)
			(xy 354.828284 -229.62547) (xy 354.776322 -229.61361) (xy 354.726708 -229.594138) (xy 354.68055 -229.567489)
			(xy 354.638879 -229.534258) (xy 354.602627 -229.495187) (xy 354.572603 -229.45115) (xy 354.549477 -229.403129)
			(xy 354.533767 -229.352199) (xy 354.525824 -229.299495) (xy 354.297244 -229.299495) (xy 354.289301 -229.352199)
			(xy 354.273591 -229.403129) (xy 354.250465 -229.45115) (xy 354.220441 -229.495187) (xy 354.184189 -229.534258)
			(xy 354.142518 -229.567489) (xy 354.09636 -229.594138) (xy 354.046746 -229.61361) (xy 353.994784 -229.62547)
			(xy 353.941634 -229.629454) (xy 353.888484 -229.62547) (xy 353.836522 -229.61361) (xy 353.786908 -229.594138)
			(xy 353.74075 -229.567489) (xy 353.699079 -229.534258) (xy 353.662827 -229.495187) (xy 353.632803 -229.45115)
			(xy 353.609677 -229.403129) (xy 353.593967 -229.352199) (xy 353.586024 -229.299495) (xy 353.357444 -229.299495)
			(xy 353.349501 -229.352199) (xy 353.333791 -229.403129) (xy 353.310665 -229.45115) (xy 353.280641 -229.495187)
			(xy 353.244389 -229.534258) (xy 353.202718 -229.567489) (xy 353.15656 -229.594138) (xy 353.106946 -229.61361)
			(xy 353.054984 -229.62547) (xy 353.001834 -229.629454) (xy 352.948684 -229.62547) (xy 352.896722 -229.61361)
			(xy 352.847108 -229.594138) (xy 352.80095 -229.567489) (xy 352.759279 -229.534258) (xy 352.723027 -229.495187)
			(xy 352.693003 -229.45115) (xy 352.669877 -229.403129) (xy 352.654167 -229.352199) (xy 352.646224 -229.299495)
			(xy 352.417644 -229.299495) (xy 352.409701 -229.352199) (xy 352.393991 -229.403129) (xy 352.370865 -229.45115)
			(xy 352.340841 -229.495187) (xy 352.304589 -229.534258) (xy 352.262918 -229.567489) (xy 352.21676 -229.594138)
			(xy 352.167146 -229.61361) (xy 352.115184 -229.62547) (xy 352.062034 -229.629454) (xy 352.008884 -229.62547)
			(xy 351.956922 -229.61361) (xy 351.907308 -229.594138) (xy 351.86115 -229.567489) (xy 351.819479 -229.534258)
			(xy 351.783227 -229.495187) (xy 351.753203 -229.45115) (xy 351.730077 -229.403129) (xy 351.714367 -229.352199)
			(xy 351.706424 -229.299495) (xy 351.477844 -229.299495) (xy 351.469901 -229.352199) (xy 351.454191 -229.403129)
			(xy 351.431065 -229.45115) (xy 351.401041 -229.495187) (xy 351.364789 -229.534258) (xy 351.323118 -229.567489)
			(xy 351.27696 -229.594138) (xy 351.227346 -229.61361) (xy 351.175384 -229.62547) (xy 351.122234 -229.629454)
			(xy 351.069084 -229.62547) (xy 351.017122 -229.61361) (xy 350.967508 -229.594138) (xy 350.92135 -229.567489)
			(xy 350.879679 -229.534258) (xy 350.843427 -229.495187) (xy 350.813403 -229.45115) (xy 350.790277 -229.403129)
			(xy 350.774567 -229.352199) (xy 350.766624 -229.299495) (xy 350.538044 -229.299495) (xy 350.530101 -229.352199)
			(xy 350.514391 -229.403129) (xy 350.491265 -229.45115) (xy 350.461241 -229.495187) (xy 350.424989 -229.534258)
			(xy 350.383318 -229.567489) (xy 350.33716 -229.594138) (xy 350.287546 -229.61361) (xy 350.235584 -229.62547)
			(xy 350.182434 -229.629454) (xy 350.129284 -229.62547) (xy 350.077322 -229.61361) (xy 350.027708 -229.594138)
			(xy 349.98155 -229.567489) (xy 349.939879 -229.534258) (xy 349.903627 -229.495187) (xy 349.873603 -229.45115)
			(xy 349.850477 -229.403129) (xy 349.834767 -229.352199) (xy 349.826824 -229.299495) (xy 349.59799 -229.299495)
			(xy 349.590047 -229.352199) (xy 349.574337 -229.403129) (xy 349.551211 -229.45115) (xy 349.521187 -229.495187)
			(xy 349.484935 -229.534258) (xy 349.443264 -229.567489) (xy 349.397106 -229.594138) (xy 349.347492 -229.61361)
			(xy 349.29553 -229.62547) (xy 349.24238 -229.629454) (xy 349.18923 -229.62547) (xy 349.137268 -229.61361)
			(xy 349.087654 -229.594138) (xy 349.041496 -229.567489) (xy 348.999825 -229.534258) (xy 348.963573 -229.495187)
			(xy 348.933549 -229.45115) (xy 348.910423 -229.403129) (xy 348.894713 -229.352199) (xy 348.88677 -229.299495)
			(xy 348.658444 -229.299495) (xy 348.650501 -229.352199) (xy 348.634791 -229.403129) (xy 348.611665 -229.45115)
			(xy 348.581641 -229.495187) (xy 348.545389 -229.534258) (xy 348.503718 -229.567489) (xy 348.45756 -229.594138)
			(xy 348.407946 -229.61361) (xy 348.355984 -229.62547) (xy 348.302834 -229.629454) (xy 348.249684 -229.62547)
			(xy 348.197722 -229.61361) (xy 348.148108 -229.594138) (xy 348.10195 -229.567489) (xy 348.060279 -229.534258)
			(xy 348.024027 -229.495187) (xy 347.994003 -229.45115) (xy 347.970877 -229.403129) (xy 347.955167 -229.352199)
			(xy 347.947224 -229.299495) (xy 347.718644 -229.299495) (xy 347.710701 -229.352199) (xy 347.694991 -229.403129)
			(xy 347.671865 -229.45115) (xy 347.641841 -229.495187) (xy 347.605589 -229.534258) (xy 347.563918 -229.567489)
			(xy 347.51776 -229.594138) (xy 347.468146 -229.61361) (xy 347.416184 -229.62547) (xy 347.363034 -229.629454)
			(xy 347.309884 -229.62547) (xy 347.257922 -229.61361) (xy 347.208308 -229.594138) (xy 347.16215 -229.567489)
			(xy 347.120479 -229.534258) (xy 347.084227 -229.495187) (xy 347.054203 -229.45115) (xy 347.031077 -229.403129)
			(xy 347.015367 -229.352199) (xy 347.007424 -229.299495) (xy 346.778844 -229.299495) (xy 346.770901 -229.352199)
			(xy 346.755191 -229.403129) (xy 346.732065 -229.45115) (xy 346.702041 -229.495187) (xy 346.665789 -229.534258)
			(xy 346.624118 -229.567489) (xy 346.57796 -229.594138) (xy 346.528346 -229.61361) (xy 346.476384 -229.62547)
			(xy 346.423234 -229.629454) (xy 346.370084 -229.62547) (xy 346.318122 -229.61361) (xy 346.268508 -229.594138)
			(xy 346.22235 -229.567489) (xy 346.180679 -229.534258) (xy 346.144427 -229.495187) (xy 346.114403 -229.45115)
			(xy 346.091277 -229.403129) (xy 346.075567 -229.352199) (xy 346.067624 -229.299495) (xy 345.839044 -229.299495)
			(xy 345.831101 -229.352199) (xy 345.815391 -229.403129) (xy 345.792265 -229.45115) (xy 345.762241 -229.495187)
			(xy 345.725989 -229.534258) (xy 345.684318 -229.567489) (xy 345.63816 -229.594138) (xy 345.588546 -229.61361)
			(xy 345.536584 -229.62547) (xy 345.483434 -229.629454) (xy 345.430284 -229.62547) (xy 345.378322 -229.61361)
			(xy 345.328708 -229.594138) (xy 345.28255 -229.567489) (xy 345.240879 -229.534258) (xy 345.204627 -229.495187)
			(xy 345.174603 -229.45115) (xy 345.151477 -229.403129) (xy 345.135767 -229.352199) (xy 345.127824 -229.299495)
			(xy 344.899244 -229.299495) (xy 344.891301 -229.352199) (xy 344.875591 -229.403129) (xy 344.852465 -229.45115)
			(xy 344.822441 -229.495187) (xy 344.786189 -229.534258) (xy 344.744518 -229.567489) (xy 344.69836 -229.594138)
			(xy 344.648746 -229.61361) (xy 344.596784 -229.62547) (xy 344.543634 -229.629454) (xy 344.490484 -229.62547)
			(xy 344.438522 -229.61361) (xy 344.388908 -229.594138) (xy 344.34275 -229.567489) (xy 344.301079 -229.534258)
			(xy 344.264827 -229.495187) (xy 344.234803 -229.45115) (xy 344.211677 -229.403129) (xy 344.195967 -229.352199)
			(xy 344.188024 -229.299495) (xy 343.959444 -229.299495) (xy 343.951501 -229.352199) (xy 343.935791 -229.403129)
			(xy 343.912665 -229.45115) (xy 343.882641 -229.495187) (xy 343.846389 -229.534258) (xy 343.804718 -229.567489)
			(xy 343.75856 -229.594138) (xy 343.708946 -229.61361) (xy 343.656984 -229.62547) (xy 343.603834 -229.629454)
			(xy 343.550684 -229.62547) (xy 343.498722 -229.61361) (xy 343.449108 -229.594138) (xy 343.40295 -229.567489)
			(xy 343.361279 -229.534258) (xy 343.325027 -229.495187) (xy 343.295003 -229.45115) (xy 343.271877 -229.403129)
			(xy 343.256167 -229.352199) (xy 343.248224 -229.299495) (xy 343.01939 -229.299495) (xy 343.011447 -229.352199)
			(xy 342.995737 -229.403129) (xy 342.972611 -229.45115) (xy 342.942587 -229.495187) (xy 342.906335 -229.534258)
			(xy 342.864664 -229.567489) (xy 342.818506 -229.594138) (xy 342.768892 -229.61361) (xy 342.71693 -229.62547)
			(xy 342.66378 -229.629454) (xy 342.61063 -229.62547) (xy 342.558668 -229.61361) (xy 342.509054 -229.594138)
			(xy 342.462896 -229.567489) (xy 342.421225 -229.534258) (xy 342.384973 -229.495187) (xy 342.354949 -229.45115)
			(xy 342.331823 -229.403129) (xy 342.316113 -229.352199) (xy 342.30817 -229.299495) (xy 342.079844 -229.299495)
			(xy 342.071901 -229.352199) (xy 342.056191 -229.403129) (xy 342.033065 -229.45115) (xy 342.003041 -229.495187)
			(xy 341.966789 -229.534258) (xy 341.925118 -229.567489) (xy 341.87896 -229.594138) (xy 341.829346 -229.61361)
			(xy 341.777384 -229.62547) (xy 341.724234 -229.629454) (xy 341.671084 -229.62547) (xy 341.619122 -229.61361)
			(xy 341.569508 -229.594138) (xy 341.52335 -229.567489) (xy 341.481679 -229.534258) (xy 341.445427 -229.495187)
			(xy 341.415403 -229.45115) (xy 341.392277 -229.403129) (xy 341.376567 -229.352199) (xy 341.368624 -229.299495)
			(xy 341.140044 -229.299495) (xy 341.132101 -229.352199) (xy 341.116391 -229.403129) (xy 341.093265 -229.45115)
			(xy 341.063241 -229.495187) (xy 341.026989 -229.534258) (xy 340.985318 -229.567489) (xy 340.93916 -229.594138)
			(xy 340.889546 -229.61361) (xy 340.837584 -229.62547) (xy 340.784434 -229.629454) (xy 340.731284 -229.62547)
			(xy 340.679322 -229.61361) (xy 340.629708 -229.594138) (xy 340.58355 -229.567489) (xy 340.541879 -229.534258)
			(xy 340.505627 -229.495187) (xy 340.475603 -229.45115) (xy 340.452477 -229.403129) (xy 340.436767 -229.352199)
			(xy 340.428824 -229.299495) (xy 340.200244 -229.299495) (xy 340.192301 -229.352199) (xy 340.176591 -229.403129)
			(xy 340.153465 -229.45115) (xy 340.123441 -229.495187) (xy 340.087189 -229.534258) (xy 340.045518 -229.567489)
			(xy 339.99936 -229.594138) (xy 339.949746 -229.61361) (xy 339.897784 -229.62547) (xy 339.844634 -229.629454)
			(xy 339.791484 -229.62547) (xy 339.739522 -229.61361) (xy 339.689908 -229.594138) (xy 339.64375 -229.567489)
			(xy 339.602079 -229.534258) (xy 339.565827 -229.495187) (xy 339.535803 -229.45115) (xy 339.512677 -229.403129)
			(xy 339.496967 -229.352199) (xy 339.489024 -229.299495) (xy 339.37956 -229.299495) (xy 339.37956 -229.72776)
			(xy 339.423502 -229.733856) (xy 339.450056 -229.738038) (xy 339.501585 -229.753349) (xy 339.550228 -229.776227)
			(xy 339.594881 -229.806154) (xy 339.634531 -229.842451) (xy 339.668277 -229.884293) (xy 339.695354 -229.93073)
			(xy 339.715146 -229.980708) (xy 339.727204 -230.033093) (xy 339.731254 -230.086695) (xy 339.729243 -230.113311)
			(xy 339.95867 -230.113311) (xy 339.95867 -230.060013) (xy 339.966613 -230.007309) (xy 339.982323 -229.956379)
			(xy 340.005449 -229.908358) (xy 340.035473 -229.864321) (xy 340.071725 -229.82525) (xy 340.113396 -229.792019)
			(xy 340.159554 -229.76537) (xy 340.209168 -229.745898) (xy 340.26113 -229.734038) (xy 340.31428 -229.730055)
			(xy 340.36743 -229.734038) (xy 340.419392 -229.745898) (xy 340.469006 -229.76537) (xy 340.515164 -229.792019)
			(xy 340.556835 -229.82525) (xy 340.593087 -229.864321) (xy 340.623111 -229.908358) (xy 340.646237 -229.956379)
			(xy 340.661947 -230.007309) (xy 340.66989 -230.060013) (xy 340.670388 -230.086662) (xy 340.66989 -230.113311)
			(xy 340.89847 -230.113311) (xy 340.89847 -230.060013) (xy 340.906413 -230.007309) (xy 340.922123 -229.956379)
			(xy 340.945249 -229.908358) (xy 340.975273 -229.864321) (xy 341.011525 -229.82525) (xy 341.053196 -229.792019)
			(xy 341.099354 -229.76537) (xy 341.148968 -229.745898) (xy 341.20093 -229.734038) (xy 341.25408 -229.730055)
			(xy 341.30723 -229.734038) (xy 341.359192 -229.745898) (xy 341.408806 -229.76537) (xy 341.454964 -229.792019)
			(xy 341.496635 -229.82525) (xy 341.532887 -229.864321) (xy 341.562911 -229.908358) (xy 341.586037 -229.956379)
			(xy 341.601747 -230.007309) (xy 341.60969 -230.060013) (xy 341.610188 -230.086662) (xy 341.60969 -230.113311)
			(xy 341.83827 -230.113311) (xy 341.83827 -230.060013) (xy 341.846213 -230.007309) (xy 341.861923 -229.956379)
			(xy 341.885049 -229.908358) (xy 341.915073 -229.864321) (xy 341.951325 -229.82525) (xy 341.992996 -229.792019)
			(xy 342.039154 -229.76537) (xy 342.088768 -229.745898) (xy 342.14073 -229.734038) (xy 342.19388 -229.730055)
			(xy 342.24703 -229.734038) (xy 342.298992 -229.745898) (xy 342.348606 -229.76537) (xy 342.394764 -229.792019)
			(xy 342.436435 -229.82525) (xy 342.472687 -229.864321) (xy 342.502711 -229.908358) (xy 342.525837 -229.956379)
			(xy 342.541547 -230.007309) (xy 342.54949 -230.060013) (xy 342.549988 -230.086662) (xy 342.54949 -230.113311)
			(xy 342.77807 -230.113311) (xy 342.77807 -230.060013) (xy 342.786013 -230.007309) (xy 342.801723 -229.956379)
			(xy 342.824849 -229.908358) (xy 342.854873 -229.864321) (xy 342.891125 -229.82525) (xy 342.932796 -229.792019)
			(xy 342.978954 -229.76537) (xy 343.028568 -229.745898) (xy 343.08053 -229.734038) (xy 343.13368 -229.730055)
			(xy 343.18683 -229.734038) (xy 343.238792 -229.745898) (xy 343.288406 -229.76537) (xy 343.334564 -229.792019)
			(xy 343.376235 -229.82525) (xy 343.412487 -229.864321) (xy 343.442511 -229.908358) (xy 343.465637 -229.956379)
			(xy 343.481347 -230.007309) (xy 343.48929 -230.060013) (xy 343.489788 -230.086662) (xy 343.48929 -230.113311)
			(xy 343.71787 -230.113311) (xy 343.71787 -230.060013) (xy 343.725813 -230.007309) (xy 343.741523 -229.956379)
			(xy 343.764649 -229.908358) (xy 343.794673 -229.864321) (xy 343.830925 -229.82525) (xy 343.872596 -229.792019)
			(xy 343.918754 -229.76537) (xy 343.968368 -229.745898) (xy 344.02033 -229.734038) (xy 344.07348 -229.730055)
			(xy 344.12663 -229.734038) (xy 344.178592 -229.745898) (xy 344.228206 -229.76537) (xy 344.274364 -229.792019)
			(xy 344.316035 -229.82525) (xy 344.352287 -229.864321) (xy 344.382311 -229.908358) (xy 344.405437 -229.956379)
			(xy 344.421147 -230.007309) (xy 344.42909 -230.060013) (xy 344.429588 -230.086662) (xy 344.42909 -230.113311)
			(xy 344.657924 -230.113311) (xy 344.657924 -230.060013) (xy 344.665867 -230.007309) (xy 344.681577 -229.956379)
			(xy 344.704703 -229.908358) (xy 344.734727 -229.864321) (xy 344.770979 -229.82525) (xy 344.81265 -229.792019)
			(xy 344.858808 -229.76537) (xy 344.908422 -229.745898) (xy 344.960384 -229.734038) (xy 345.013534 -229.730055)
			(xy 345.066684 -229.734038) (xy 345.118646 -229.745898) (xy 345.16826 -229.76537) (xy 345.214418 -229.792019)
			(xy 345.256089 -229.82525) (xy 345.292341 -229.864321) (xy 345.322365 -229.908358) (xy 345.345491 -229.956379)
			(xy 345.361201 -230.007309) (xy 345.369144 -230.060013) (xy 345.369642 -230.086662) (xy 345.369144 -230.113311)
			(xy 345.59747 -230.113311) (xy 345.59747 -230.060013) (xy 345.605413 -230.007309) (xy 345.621123 -229.956379)
			(xy 345.644249 -229.908358) (xy 345.674273 -229.864321) (xy 345.710525 -229.82525) (xy 345.752196 -229.792019)
			(xy 345.798354 -229.76537) (xy 345.847968 -229.745898) (xy 345.89993 -229.734038) (xy 345.95308 -229.730055)
			(xy 346.00623 -229.734038) (xy 346.058192 -229.745898) (xy 346.107806 -229.76537) (xy 346.153964 -229.792019)
			(xy 346.195635 -229.82525) (xy 346.231887 -229.864321) (xy 346.261911 -229.908358) (xy 346.285037 -229.956379)
			(xy 346.300747 -230.007309) (xy 346.30869 -230.060013) (xy 346.309188 -230.086662) (xy 346.30869 -230.113311)
			(xy 346.53727 -230.113311) (xy 346.53727 -230.060013) (xy 346.545213 -230.007309) (xy 346.560923 -229.956379)
			(xy 346.584049 -229.908358) (xy 346.614073 -229.864321) (xy 346.650325 -229.82525) (xy 346.691996 -229.792019)
			(xy 346.738154 -229.76537) (xy 346.787768 -229.745898) (xy 346.83973 -229.734038) (xy 346.89288 -229.730055)
			(xy 346.94603 -229.734038) (xy 346.997992 -229.745898) (xy 347.047606 -229.76537) (xy 347.093764 -229.792019)
			(xy 347.135435 -229.82525) (xy 347.171687 -229.864321) (xy 347.201711 -229.908358) (xy 347.224837 -229.956379)
			(xy 347.240547 -230.007309) (xy 347.24849 -230.060013) (xy 347.248988 -230.086662) (xy 347.24849 -230.113311)
			(xy 347.47707 -230.113311) (xy 347.47707 -230.060013) (xy 347.485013 -230.007309) (xy 347.500723 -229.956379)
			(xy 347.523849 -229.908358) (xy 347.553873 -229.864321) (xy 347.590125 -229.82525) (xy 347.631796 -229.792019)
			(xy 347.677954 -229.76537) (xy 347.727568 -229.745898) (xy 347.77953 -229.734038) (xy 347.83268 -229.730055)
			(xy 347.88583 -229.734038) (xy 347.937792 -229.745898) (xy 347.987406 -229.76537) (xy 348.033564 -229.792019)
			(xy 348.075235 -229.82525) (xy 348.111487 -229.864321) (xy 348.141511 -229.908358) (xy 348.164637 -229.956379)
			(xy 348.180347 -230.007309) (xy 348.18829 -230.060013) (xy 348.188788 -230.086662) (xy 348.18829 -230.113311)
			(xy 348.41687 -230.113311) (xy 348.41687 -230.060013) (xy 348.424813 -230.007309) (xy 348.440523 -229.956379)
			(xy 348.463649 -229.908358) (xy 348.493673 -229.864321) (xy 348.529925 -229.82525) (xy 348.571596 -229.792019)
			(xy 348.617754 -229.76537) (xy 348.667368 -229.745898) (xy 348.71933 -229.734038) (xy 348.77248 -229.730055)
			(xy 348.82563 -229.734038) (xy 348.877592 -229.745898) (xy 348.927206 -229.76537) (xy 348.973364 -229.792019)
			(xy 349.015035 -229.82525) (xy 349.051287 -229.864321) (xy 349.081311 -229.908358) (xy 349.104437 -229.956379)
			(xy 349.120147 -230.007309) (xy 349.12809 -230.060013) (xy 349.128588 -230.086662) (xy 349.12809 -230.113311)
			(xy 349.35667 -230.113311) (xy 349.35667 -230.060013) (xy 349.364613 -230.007309) (xy 349.380323 -229.956379)
			(xy 349.403449 -229.908358) (xy 349.433473 -229.864321) (xy 349.469725 -229.82525) (xy 349.511396 -229.792019)
			(xy 349.557554 -229.76537) (xy 349.607168 -229.745898) (xy 349.65913 -229.734038) (xy 349.71228 -229.730055)
			(xy 349.76543 -229.734038) (xy 349.817392 -229.745898) (xy 349.867006 -229.76537) (xy 349.913164 -229.792019)
			(xy 349.954835 -229.82525) (xy 349.991087 -229.864321) (xy 350.021111 -229.908358) (xy 350.044237 -229.956379)
			(xy 350.059947 -230.007309) (xy 350.06789 -230.060013) (xy 350.068388 -230.086662) (xy 350.06789 -230.113311)
			(xy 350.29647 -230.113311) (xy 350.29647 -230.060013) (xy 350.304413 -230.007309) (xy 350.320123 -229.956379)
			(xy 350.343249 -229.908358) (xy 350.373273 -229.864321) (xy 350.409525 -229.82525) (xy 350.451196 -229.792019)
			(xy 350.497354 -229.76537) (xy 350.546968 -229.745898) (xy 350.59893 -229.734038) (xy 350.65208 -229.730055)
			(xy 350.70523 -229.734038) (xy 350.757192 -229.745898) (xy 350.806806 -229.76537) (xy 350.852964 -229.792019)
			(xy 350.894635 -229.82525) (xy 350.930887 -229.864321) (xy 350.960911 -229.908358) (xy 350.984037 -229.956379)
			(xy 350.999747 -230.007309) (xy 351.00769 -230.060013) (xy 351.008188 -230.086662) (xy 351.00769 -230.113311)
			(xy 351.23627 -230.113311) (xy 351.23627 -230.060013) (xy 351.244213 -230.007309) (xy 351.259923 -229.956379)
			(xy 351.283049 -229.908358) (xy 351.313073 -229.864321) (xy 351.349325 -229.82525) (xy 351.390996 -229.792019)
			(xy 351.437154 -229.76537) (xy 351.486768 -229.745898) (xy 351.53873 -229.734038) (xy 351.59188 -229.730055)
			(xy 351.64503 -229.734038) (xy 351.696992 -229.745898) (xy 351.746606 -229.76537) (xy 351.792764 -229.792019)
			(xy 351.834435 -229.82525) (xy 351.870687 -229.864321) (xy 351.900711 -229.908358) (xy 351.923837 -229.956379)
			(xy 351.939547 -230.007309) (xy 351.94749 -230.060013) (xy 351.947988 -230.086662) (xy 351.94749 -230.113311)
			(xy 352.17607 -230.113311) (xy 352.17607 -230.060013) (xy 352.184013 -230.007309) (xy 352.199723 -229.956379)
			(xy 352.222849 -229.908358) (xy 352.252873 -229.864321) (xy 352.289125 -229.82525) (xy 352.330796 -229.792019)
			(xy 352.376954 -229.76537) (xy 352.426568 -229.745898) (xy 352.47853 -229.734038) (xy 352.53168 -229.730055)
			(xy 352.58483 -229.734038) (xy 352.636792 -229.745898) (xy 352.686406 -229.76537) (xy 352.732564 -229.792019)
			(xy 352.774235 -229.82525) (xy 352.810487 -229.864321) (xy 352.840511 -229.908358) (xy 352.863637 -229.956379)
			(xy 352.879347 -230.007309) (xy 352.88729 -230.060013) (xy 352.887788 -230.086662) (xy 352.88729 -230.113311)
			(xy 353.11587 -230.113311) (xy 353.11587 -230.060013) (xy 353.123813 -230.007309) (xy 353.139523 -229.956379)
			(xy 353.162649 -229.908358) (xy 353.192673 -229.864321) (xy 353.228925 -229.82525) (xy 353.270596 -229.792019)
			(xy 353.316754 -229.76537) (xy 353.366368 -229.745898) (xy 353.41833 -229.734038) (xy 353.47148 -229.730055)
			(xy 353.52463 -229.734038) (xy 353.576592 -229.745898) (xy 353.626206 -229.76537) (xy 353.672364 -229.792019)
			(xy 353.714035 -229.82525) (xy 353.750287 -229.864321) (xy 353.780311 -229.908358) (xy 353.803437 -229.956379)
			(xy 353.819147 -230.007309) (xy 353.82709 -230.060013) (xy 353.827588 -230.086662) (xy 353.82709 -230.113311)
			(xy 354.055924 -230.113311) (xy 354.055924 -230.060013) (xy 354.063867 -230.007309) (xy 354.079577 -229.956379)
			(xy 354.102703 -229.908358) (xy 354.132727 -229.864321) (xy 354.168979 -229.82525) (xy 354.21065 -229.792019)
			(xy 354.256808 -229.76537) (xy 354.306422 -229.745898) (xy 354.358384 -229.734038) (xy 354.411534 -229.730055)
			(xy 354.464684 -229.734038) (xy 354.516646 -229.745898) (xy 354.56626 -229.76537) (xy 354.612418 -229.792019)
			(xy 354.654089 -229.82525) (xy 354.690341 -229.864321) (xy 354.720365 -229.908358) (xy 354.743491 -229.956379)
			(xy 354.759201 -230.007309) (xy 354.767144 -230.060013) (xy 354.767642 -230.086662) (xy 354.767144 -230.113311)
			(xy 354.99547 -230.113311) (xy 354.99547 -230.060013) (xy 355.003413 -230.007309) (xy 355.019123 -229.956379)
			(xy 355.042249 -229.908358) (xy 355.072273 -229.864321) (xy 355.108525 -229.82525) (xy 355.150196 -229.792019)
			(xy 355.196354 -229.76537) (xy 355.245968 -229.745898) (xy 355.29793 -229.734038) (xy 355.35108 -229.730055)
			(xy 355.40423 -229.734038) (xy 355.456192 -229.745898) (xy 355.505806 -229.76537) (xy 355.551964 -229.792019)
			(xy 355.593635 -229.82525) (xy 355.629887 -229.864321) (xy 355.659911 -229.908358) (xy 355.683037 -229.956379)
			(xy 355.698747 -230.007309) (xy 355.70669 -230.060013) (xy 355.707188 -230.086662) (xy 355.70669 -230.113311)
			(xy 355.93527 -230.113311) (xy 355.93527 -230.060013) (xy 355.943213 -230.007309) (xy 355.958923 -229.956379)
			(xy 355.982049 -229.908358) (xy 356.012073 -229.864321) (xy 356.048325 -229.82525) (xy 356.089996 -229.792019)
			(xy 356.136154 -229.76537) (xy 356.185768 -229.745898) (xy 356.23773 -229.734038) (xy 356.29088 -229.730055)
			(xy 356.34403 -229.734038) (xy 356.395992 -229.745898) (xy 356.445606 -229.76537) (xy 356.491764 -229.792019)
			(xy 356.533435 -229.82525) (xy 356.569687 -229.864321) (xy 356.599711 -229.908358) (xy 356.622837 -229.956379)
			(xy 356.638547 -230.007309) (xy 356.64649 -230.060013) (xy 356.646988 -230.086662) (xy 356.64649 -230.113311)
			(xy 356.87507 -230.113311) (xy 356.87507 -230.060013) (xy 356.883013 -230.007309) (xy 356.898723 -229.956379)
			(xy 356.921849 -229.908358) (xy 356.951873 -229.864321) (xy 356.988125 -229.82525) (xy 357.029796 -229.792019)
			(xy 357.075954 -229.76537) (xy 357.125568 -229.745898) (xy 357.17753 -229.734038) (xy 357.23068 -229.730055)
			(xy 357.28383 -229.734038) (xy 357.335792 -229.745898) (xy 357.385406 -229.76537) (xy 357.431564 -229.792019)
			(xy 357.473235 -229.82525) (xy 357.509487 -229.864321) (xy 357.539511 -229.908358) (xy 357.562637 -229.956379)
			(xy 357.578347 -230.007309) (xy 357.58629 -230.060013) (xy 357.586788 -230.086662) (xy 357.58629 -230.113311)
			(xy 357.81487 -230.113311) (xy 357.81487 -230.060013) (xy 357.822813 -230.007309) (xy 357.838523 -229.956379)
			(xy 357.861649 -229.908358) (xy 357.891673 -229.864321) (xy 357.927925 -229.82525) (xy 357.969596 -229.792019)
			(xy 358.015754 -229.76537) (xy 358.065368 -229.745898) (xy 358.11733 -229.734038) (xy 358.17048 -229.730055)
			(xy 358.22363 -229.734038) (xy 358.275592 -229.745898) (xy 358.325206 -229.76537) (xy 358.371364 -229.792019)
			(xy 358.413035 -229.82525) (xy 358.449287 -229.864321) (xy 358.479311 -229.908358) (xy 358.502437 -229.956379)
			(xy 358.518147 -230.007309) (xy 358.52609 -230.060013) (xy 358.526588 -230.086662) (xy 358.52609 -230.113311)
			(xy 358.754924 -230.113311) (xy 358.754924 -230.060013) (xy 358.762867 -230.007309) (xy 358.778577 -229.956379)
			(xy 358.801703 -229.908358) (xy 358.831727 -229.864321) (xy 358.867979 -229.82525) (xy 358.90965 -229.792019)
			(xy 358.955808 -229.76537) (xy 359.005422 -229.745898) (xy 359.057384 -229.734038) (xy 359.110534 -229.730055)
			(xy 359.163684 -229.734038) (xy 359.215646 -229.745898) (xy 359.26526 -229.76537) (xy 359.311418 -229.792019)
			(xy 359.353089 -229.82525) (xy 359.389341 -229.864321) (xy 359.419365 -229.908358) (xy 359.442491 -229.956379)
			(xy 359.458201 -230.007309) (xy 359.466144 -230.060013) (xy 359.466642 -230.086662) (xy 359.466144 -230.113311)
			(xy 359.694724 -230.113311) (xy 359.694724 -230.060013) (xy 359.702667 -230.007309) (xy 359.718377 -229.956379)
			(xy 359.741503 -229.908358) (xy 359.771527 -229.864321) (xy 359.807779 -229.82525) (xy 359.84945 -229.792019)
			(xy 359.895608 -229.76537) (xy 359.945222 -229.745898) (xy 359.997184 -229.734038) (xy 360.050334 -229.730055)
			(xy 360.103484 -229.734038) (xy 360.155446 -229.745898) (xy 360.20506 -229.76537) (xy 360.251218 -229.792019)
			(xy 360.292889 -229.82525) (xy 360.329141 -229.864321) (xy 360.359165 -229.908358) (xy 360.382291 -229.956379)
			(xy 360.398001 -230.007309) (xy 360.405944 -230.060013) (xy 360.406442 -230.086662) (xy 360.405944 -230.113311)
			(xy 360.634524 -230.113311) (xy 360.634524 -230.060013) (xy 360.642467 -230.007309) (xy 360.658177 -229.956379)
			(xy 360.681303 -229.908358) (xy 360.711327 -229.864321) (xy 360.747579 -229.82525) (xy 360.78925 -229.792019)
			(xy 360.835408 -229.76537) (xy 360.885022 -229.745898) (xy 360.936984 -229.734038) (xy 360.990134 -229.730055)
			(xy 361.043284 -229.734038) (xy 361.095246 -229.745898) (xy 361.14486 -229.76537) (xy 361.191018 -229.792019)
			(xy 361.232689 -229.82525) (xy 361.268941 -229.864321) (xy 361.298965 -229.908358) (xy 361.322091 -229.956379)
			(xy 361.337801 -230.007309) (xy 361.345744 -230.060013) (xy 361.346242 -230.086662) (xy 361.345744 -230.113311)
			(xy 361.574324 -230.113311) (xy 361.574324 -230.060013) (xy 361.582267 -230.007309) (xy 361.597977 -229.956379)
			(xy 361.621103 -229.908358) (xy 361.651127 -229.864321) (xy 361.687379 -229.82525) (xy 361.72905 -229.792019)
			(xy 361.775208 -229.76537) (xy 361.824822 -229.745898) (xy 361.876784 -229.734038) (xy 361.929934 -229.730055)
			(xy 361.983084 -229.734038) (xy 362.035046 -229.745898) (xy 362.08466 -229.76537) (xy 362.130818 -229.792019)
			(xy 362.172489 -229.82525) (xy 362.208741 -229.864321) (xy 362.238765 -229.908358) (xy 362.261891 -229.956379)
			(xy 362.277601 -230.007309) (xy 362.285544 -230.060013) (xy 362.286042 -230.086662) (xy 362.285544 -230.113311)
			(xy 362.514124 -230.113311) (xy 362.514124 -230.060013) (xy 362.522067 -230.007309) (xy 362.537777 -229.956379)
			(xy 362.560903 -229.908358) (xy 362.590927 -229.864321) (xy 362.627179 -229.82525) (xy 362.66885 -229.792019)
			(xy 362.715008 -229.76537) (xy 362.764622 -229.745898) (xy 362.816584 -229.734038) (xy 362.869734 -229.730055)
			(xy 362.922884 -229.734038) (xy 362.974846 -229.745898) (xy 363.02446 -229.76537) (xy 363.070618 -229.792019)
			(xy 363.112289 -229.82525) (xy 363.148541 -229.864321) (xy 363.178565 -229.908358) (xy 363.201691 -229.956379)
			(xy 363.217401 -230.007309) (xy 363.225344 -230.060013) (xy 363.225842 -230.086662) (xy 363.225344 -230.113311)
			(xy 363.45367 -230.113311) (xy 363.45367 -230.060013) (xy 363.461613 -230.007309) (xy 363.477323 -229.956379)
			(xy 363.500449 -229.908358) (xy 363.530473 -229.864321) (xy 363.566725 -229.82525) (xy 363.608396 -229.792019)
			(xy 363.654554 -229.76537) (xy 363.704168 -229.745898) (xy 363.75613 -229.734038) (xy 363.80928 -229.730055)
			(xy 363.86243 -229.734038) (xy 363.914392 -229.745898) (xy 363.964006 -229.76537) (xy 364.010164 -229.792019)
			(xy 364.051835 -229.82525) (xy 364.088087 -229.864321) (xy 364.118111 -229.908358) (xy 364.141237 -229.956379)
			(xy 364.156947 -230.007309) (xy 364.16489 -230.060013) (xy 364.165388 -230.086662) (xy 364.16489 -230.113311)
			(xy 364.39347 -230.113311) (xy 364.39347 -230.060013) (xy 364.401413 -230.007309) (xy 364.417123 -229.956379)
			(xy 364.440249 -229.908358) (xy 364.470273 -229.864321) (xy 364.506525 -229.82525) (xy 364.548196 -229.792019)
			(xy 364.594354 -229.76537) (xy 364.643968 -229.745898) (xy 364.69593 -229.734038) (xy 364.74908 -229.730055)
			(xy 364.80223 -229.734038) (xy 364.854192 -229.745898) (xy 364.903806 -229.76537) (xy 364.949964 -229.792019)
			(xy 364.991635 -229.82525) (xy 365.027887 -229.864321) (xy 365.057911 -229.908358) (xy 365.081037 -229.956379)
			(xy 365.096747 -230.007309) (xy 365.10469 -230.060013) (xy 365.105188 -230.086662) (xy 365.10469 -230.113311)
			(xy 365.33327 -230.113311) (xy 365.33327 -230.060013) (xy 365.341213 -230.007309) (xy 365.356923 -229.956379)
			(xy 365.380049 -229.908358) (xy 365.410073 -229.864321) (xy 365.446325 -229.82525) (xy 365.487996 -229.792019)
			(xy 365.534154 -229.76537) (xy 365.583768 -229.745898) (xy 365.63573 -229.734038) (xy 365.68888 -229.730055)
			(xy 365.74203 -229.734038) (xy 365.793992 -229.745898) (xy 365.843606 -229.76537) (xy 365.889764 -229.792019)
			(xy 365.931435 -229.82525) (xy 365.967687 -229.864321) (xy 365.997711 -229.908358) (xy 366.020837 -229.956379)
			(xy 366.036547 -230.007309) (xy 366.04449 -230.060013) (xy 366.044988 -230.086662) (xy 366.04449 -230.113311)
			(xy 366.27307 -230.113311) (xy 366.27307 -230.060013) (xy 366.281013 -230.007309) (xy 366.296723 -229.956379)
			(xy 366.319849 -229.908358) (xy 366.349873 -229.864321) (xy 366.386125 -229.82525) (xy 366.427796 -229.792019)
			(xy 366.473954 -229.76537) (xy 366.523568 -229.745898) (xy 366.57553 -229.734038) (xy 366.62868 -229.730055)
			(xy 366.68183 -229.734038) (xy 366.733792 -229.745898) (xy 366.783406 -229.76537) (xy 366.829564 -229.792019)
			(xy 366.871235 -229.82525) (xy 366.907487 -229.864321) (xy 366.937511 -229.908358) (xy 366.960637 -229.956379)
			(xy 366.976347 -230.007309) (xy 366.98429 -230.060013) (xy 366.984788 -230.086662) (xy 366.98429 -230.113311)
			(xy 367.21287 -230.113311) (xy 367.21287 -230.060013) (xy 367.220813 -230.007309) (xy 367.236523 -229.956379)
			(xy 367.259649 -229.908358) (xy 367.289673 -229.864321) (xy 367.325925 -229.82525) (xy 367.367596 -229.792019)
			(xy 367.413754 -229.76537) (xy 367.463368 -229.745898) (xy 367.51533 -229.734038) (xy 367.56848 -229.730055)
			(xy 367.62163 -229.734038) (xy 367.673592 -229.745898) (xy 367.723206 -229.76537) (xy 367.769364 -229.792019)
			(xy 367.811035 -229.82525) (xy 367.847287 -229.864321) (xy 367.877311 -229.908358) (xy 367.900437 -229.956379)
			(xy 367.916147 -230.007309) (xy 367.92409 -230.060013) (xy 367.924588 -230.086662) (xy 367.92409 -230.113311)
			(xy 368.15267 -230.113311) (xy 368.15267 -230.060013) (xy 368.160613 -230.007309) (xy 368.176323 -229.956379)
			(xy 368.199449 -229.908358) (xy 368.229473 -229.864321) (xy 368.265725 -229.82525) (xy 368.307396 -229.792019)
			(xy 368.353554 -229.76537) (xy 368.403168 -229.745898) (xy 368.45513 -229.734038) (xy 368.50828 -229.730055)
			(xy 368.56143 -229.734038) (xy 368.613392 -229.745898) (xy 368.663006 -229.76537) (xy 368.709164 -229.792019)
			(xy 368.750835 -229.82525) (xy 368.787087 -229.864321) (xy 368.817111 -229.908358) (xy 368.840237 -229.956379)
			(xy 368.855947 -230.007309) (xy 368.86389 -230.060013) (xy 368.864388 -230.086662) (xy 368.86389 -230.113311)
			(xy 369.09247 -230.113311) (xy 369.09247 -230.060013) (xy 369.100413 -230.007309) (xy 369.116123 -229.956379)
			(xy 369.139249 -229.908358) (xy 369.169273 -229.864321) (xy 369.205525 -229.82525) (xy 369.247196 -229.792019)
			(xy 369.293354 -229.76537) (xy 369.342968 -229.745898) (xy 369.39493 -229.734038) (xy 369.44808 -229.730055)
			(xy 369.50123 -229.734038) (xy 369.553192 -229.745898) (xy 369.602806 -229.76537) (xy 369.648964 -229.792019)
			(xy 369.690635 -229.82525) (xy 369.726887 -229.864321) (xy 369.756911 -229.908358) (xy 369.780037 -229.956379)
			(xy 369.795747 -230.007309) (xy 369.80369 -230.060013) (xy 369.804188 -230.086662) (xy 369.80369 -230.113311)
			(xy 370.97207 -230.113311) (xy 370.97207 -230.060013) (xy 370.980013 -230.007309) (xy 370.995723 -229.956379)
			(xy 371.018849 -229.908358) (xy 371.048873 -229.864321) (xy 371.085125 -229.82525) (xy 371.126796 -229.792019)
			(xy 371.172954 -229.76537) (xy 371.222568 -229.745898) (xy 371.27453 -229.734038) (xy 371.32768 -229.730055)
			(xy 371.38083 -229.734038) (xy 371.432792 -229.745898) (xy 371.482406 -229.76537) (xy 371.528564 -229.792019)
			(xy 371.570235 -229.82525) (xy 371.606487 -229.864321) (xy 371.636511 -229.908358) (xy 371.659637 -229.956379)
			(xy 371.675347 -230.007309) (xy 371.68329 -230.060013) (xy 371.683788 -230.086662) (xy 371.68329 -230.113311)
			(xy 371.91187 -230.113311) (xy 371.91187 -230.060013) (xy 371.919813 -230.007309) (xy 371.935523 -229.956379)
			(xy 371.958649 -229.908358) (xy 371.988673 -229.864321) (xy 372.024925 -229.82525) (xy 372.066596 -229.792019)
			(xy 372.112754 -229.76537) (xy 372.162368 -229.745898) (xy 372.21433 -229.734038) (xy 372.26748 -229.730055)
			(xy 372.32063 -229.734038) (xy 372.372592 -229.745898) (xy 372.422206 -229.76537) (xy 372.468364 -229.792019)
			(xy 372.510035 -229.82525) (xy 372.546287 -229.864321) (xy 372.576311 -229.908358) (xy 372.599437 -229.956379)
			(xy 372.615147 -230.007309) (xy 372.62309 -230.060013) (xy 372.623588 -230.086662) (xy 372.62309 -230.113311)
			(xy 372.851924 -230.113311) (xy 372.851924 -230.060013) (xy 372.859867 -230.007309) (xy 372.875577 -229.956379)
			(xy 372.898703 -229.908358) (xy 372.928727 -229.864321) (xy 372.964979 -229.82525) (xy 373.00665 -229.792019)
			(xy 373.052808 -229.76537) (xy 373.102422 -229.745898) (xy 373.154384 -229.734038) (xy 373.207534 -229.730055)
			(xy 373.260684 -229.734038) (xy 373.312646 -229.745898) (xy 373.36226 -229.76537) (xy 373.408418 -229.792019)
			(xy 373.450089 -229.82525) (xy 373.486341 -229.864321) (xy 373.516365 -229.908358) (xy 373.539491 -229.956379)
			(xy 373.555201 -230.007309) (xy 373.563144 -230.060013) (xy 373.563642 -230.086662) (xy 373.563144 -230.113311)
			(xy 373.79147 -230.113311) (xy 373.79147 -230.060013) (xy 373.799413 -230.007309) (xy 373.815123 -229.956379)
			(xy 373.838249 -229.908358) (xy 373.868273 -229.864321) (xy 373.904525 -229.82525) (xy 373.946196 -229.792019)
			(xy 373.992354 -229.76537) (xy 374.041968 -229.745898) (xy 374.09393 -229.734038) (xy 374.14708 -229.730055)
			(xy 374.20023 -229.734038) (xy 374.252192 -229.745898) (xy 374.301806 -229.76537) (xy 374.347964 -229.792019)
			(xy 374.389635 -229.82525) (xy 374.425887 -229.864321) (xy 374.455911 -229.908358) (xy 374.479037 -229.956379)
			(xy 374.494747 -230.007309) (xy 374.50269 -230.060013) (xy 374.503188 -230.086662) (xy 374.50269 -230.113311)
			(xy 374.73127 -230.113311) (xy 374.73127 -230.060013) (xy 374.739213 -230.007309) (xy 374.754923 -229.956379)
			(xy 374.778049 -229.908358) (xy 374.808073 -229.864321) (xy 374.844325 -229.82525) (xy 374.885996 -229.792019)
			(xy 374.932154 -229.76537) (xy 374.981768 -229.745898) (xy 375.03373 -229.734038) (xy 375.08688 -229.730055)
			(xy 375.14003 -229.734038) (xy 375.191992 -229.745898) (xy 375.241606 -229.76537) (xy 375.287764 -229.792019)
			(xy 375.329435 -229.82525) (xy 375.365687 -229.864321) (xy 375.395711 -229.908358) (xy 375.418837 -229.956379)
			(xy 375.434547 -230.007309) (xy 375.44249 -230.060013) (xy 375.442988 -230.086662) (xy 375.44249 -230.113311)
			(xy 375.67107 -230.113311) (xy 375.67107 -230.060013) (xy 375.679013 -230.007309) (xy 375.694723 -229.956379)
			(xy 375.717849 -229.908358) (xy 375.747873 -229.864321) (xy 375.784125 -229.82525) (xy 375.825796 -229.792019)
			(xy 375.871954 -229.76537) (xy 375.921568 -229.745898) (xy 375.97353 -229.734038) (xy 376.02668 -229.730055)
			(xy 376.07983 -229.734038) (xy 376.131792 -229.745898) (xy 376.181406 -229.76537) (xy 376.227564 -229.792019)
			(xy 376.269235 -229.82525) (xy 376.305487 -229.864321) (xy 376.335511 -229.908358) (xy 376.358637 -229.956379)
			(xy 376.374347 -230.007309) (xy 376.38229 -230.060013) (xy 376.382788 -230.086662) (xy 376.38229 -230.113311)
			(xy 376.61087 -230.113311) (xy 376.61087 -230.060013) (xy 376.618813 -230.007309) (xy 376.634523 -229.956379)
			(xy 376.657649 -229.908358) (xy 376.687673 -229.864321) (xy 376.723925 -229.82525) (xy 376.765596 -229.792019)
			(xy 376.811754 -229.76537) (xy 376.861368 -229.745898) (xy 376.91333 -229.734038) (xy 376.96648 -229.730055)
			(xy 377.01963 -229.734038) (xy 377.071592 -229.745898) (xy 377.121206 -229.76537) (xy 377.167364 -229.792019)
			(xy 377.209035 -229.82525) (xy 377.245287 -229.864321) (xy 377.275311 -229.908358) (xy 377.298437 -229.956379)
			(xy 377.314147 -230.007309) (xy 377.32209 -230.060013) (xy 377.322588 -230.086662) (xy 377.32209 -230.113311)
			(xy 377.55067 -230.113311) (xy 377.55067 -230.060013) (xy 377.558613 -230.007309) (xy 377.574323 -229.956379)
			(xy 377.597449 -229.908358) (xy 377.627473 -229.864321) (xy 377.663725 -229.82525) (xy 377.705396 -229.792019)
			(xy 377.751554 -229.76537) (xy 377.801168 -229.745898) (xy 377.85313 -229.734038) (xy 377.90628 -229.730055)
			(xy 377.95943 -229.734038) (xy 378.011392 -229.745898) (xy 378.061006 -229.76537) (xy 378.107164 -229.792019)
			(xy 378.148835 -229.82525) (xy 378.185087 -229.864321) (xy 378.215111 -229.908358) (xy 378.238237 -229.956379)
			(xy 378.253947 -230.007309) (xy 378.26189 -230.060013) (xy 378.262388 -230.086662) (xy 378.26189 -230.113311)
			(xy 378.49047 -230.113311) (xy 378.49047 -230.060013) (xy 378.498413 -230.007309) (xy 378.514123 -229.956379)
			(xy 378.537249 -229.908358) (xy 378.567273 -229.864321) (xy 378.603525 -229.82525) (xy 378.645196 -229.792019)
			(xy 378.691354 -229.76537) (xy 378.740968 -229.745898) (xy 378.79293 -229.734038) (xy 378.84608 -229.730055)
			(xy 378.89923 -229.734038) (xy 378.951192 -229.745898) (xy 379.000806 -229.76537) (xy 379.046964 -229.792019)
			(xy 379.088635 -229.82525) (xy 379.124887 -229.864321) (xy 379.154911 -229.908358) (xy 379.178037 -229.956379)
			(xy 379.193747 -230.007309) (xy 379.20169 -230.060013) (xy 379.202188 -230.086662) (xy 379.20169 -230.113311)
			(xy 379.193747 -230.166015) (xy 379.178037 -230.216945) (xy 379.154911 -230.264966) (xy 379.124887 -230.309003)
			(xy 379.088635 -230.348074) (xy 379.046964 -230.381305) (xy 379.000806 -230.407954) (xy 378.951192 -230.427426)
			(xy 378.89923 -230.439286) (xy 378.84608 -230.44327) (xy 378.79293 -230.439286) (xy 378.740968 -230.427426)
			(xy 378.691354 -230.407954) (xy 378.645196 -230.381305) (xy 378.603525 -230.348074) (xy 378.567273 -230.309003)
			(xy 378.537249 -230.264966) (xy 378.514123 -230.216945) (xy 378.498413 -230.166015) (xy 378.49047 -230.113311)
			(xy 378.26189 -230.113311) (xy 378.253947 -230.166015) (xy 378.238237 -230.216945) (xy 378.215111 -230.264966)
			(xy 378.185087 -230.309003) (xy 378.148835 -230.348074) (xy 378.107164 -230.381305) (xy 378.061006 -230.407954)
			(xy 378.011392 -230.427426) (xy 377.95943 -230.439286) (xy 377.90628 -230.44327) (xy 377.85313 -230.439286)
			(xy 377.801168 -230.427426) (xy 377.751554 -230.407954) (xy 377.705396 -230.381305) (xy 377.663725 -230.348074)
			(xy 377.627473 -230.309003) (xy 377.597449 -230.264966) (xy 377.574323 -230.216945) (xy 377.558613 -230.166015)
			(xy 377.55067 -230.113311) (xy 377.32209 -230.113311) (xy 377.314147 -230.166015) (xy 377.298437 -230.216945)
			(xy 377.275311 -230.264966) (xy 377.245287 -230.309003) (xy 377.209035 -230.348074) (xy 377.167364 -230.381305)
			(xy 377.121206 -230.407954) (xy 377.071592 -230.427426) (xy 377.01963 -230.439286) (xy 376.96648 -230.44327)
			(xy 376.91333 -230.439286) (xy 376.861368 -230.427426) (xy 376.811754 -230.407954) (xy 376.765596 -230.381305)
			(xy 376.723925 -230.348074) (xy 376.687673 -230.309003) (xy 376.657649 -230.264966) (xy 376.634523 -230.216945)
			(xy 376.618813 -230.166015) (xy 376.61087 -230.113311) (xy 376.38229 -230.113311) (xy 376.374347 -230.166015)
			(xy 376.358637 -230.216945) (xy 376.335511 -230.264966) (xy 376.305487 -230.309003) (xy 376.269235 -230.348074)
			(xy 376.227564 -230.381305) (xy 376.181406 -230.407954) (xy 376.131792 -230.427426) (xy 376.07983 -230.439286)
			(xy 376.02668 -230.44327) (xy 375.97353 -230.439286) (xy 375.921568 -230.427426) (xy 375.871954 -230.407954)
			(xy 375.825796 -230.381305) (xy 375.784125 -230.348074) (xy 375.747873 -230.309003) (xy 375.717849 -230.264966)
			(xy 375.694723 -230.216945) (xy 375.679013 -230.166015) (xy 375.67107 -230.113311) (xy 375.44249 -230.113311)
			(xy 375.434547 -230.166015) (xy 375.418837 -230.216945) (xy 375.395711 -230.264966) (xy 375.365687 -230.309003)
			(xy 375.329435 -230.348074) (xy 375.287764 -230.381305) (xy 375.241606 -230.407954) (xy 375.191992 -230.427426)
			(xy 375.14003 -230.439286) (xy 375.08688 -230.44327) (xy 375.03373 -230.439286) (xy 374.981768 -230.427426)
			(xy 374.932154 -230.407954) (xy 374.885996 -230.381305) (xy 374.844325 -230.348074) (xy 374.808073 -230.309003)
			(xy 374.778049 -230.264966) (xy 374.754923 -230.216945) (xy 374.739213 -230.166015) (xy 374.73127 -230.113311)
			(xy 374.50269 -230.113311) (xy 374.494747 -230.166015) (xy 374.479037 -230.216945) (xy 374.455911 -230.264966)
			(xy 374.425887 -230.309003) (xy 374.389635 -230.348074) (xy 374.347964 -230.381305) (xy 374.301806 -230.407954)
			(xy 374.252192 -230.427426) (xy 374.20023 -230.439286) (xy 374.14708 -230.44327) (xy 374.09393 -230.439286)
			(xy 374.041968 -230.427426) (xy 373.992354 -230.407954) (xy 373.946196 -230.381305) (xy 373.904525 -230.348074)
			(xy 373.868273 -230.309003) (xy 373.838249 -230.264966) (xy 373.815123 -230.216945) (xy 373.799413 -230.166015)
			(xy 373.79147 -230.113311) (xy 373.563144 -230.113311) (xy 373.555201 -230.166015) (xy 373.539491 -230.216945)
			(xy 373.516365 -230.264966) (xy 373.486341 -230.309003) (xy 373.450089 -230.348074) (xy 373.408418 -230.381305)
			(xy 373.36226 -230.407954) (xy 373.312646 -230.427426) (xy 373.260684 -230.439286) (xy 373.207534 -230.44327)
			(xy 373.154384 -230.439286) (xy 373.102422 -230.427426) (xy 373.052808 -230.407954) (xy 373.00665 -230.381305)
			(xy 372.964979 -230.348074) (xy 372.928727 -230.309003) (xy 372.898703 -230.264966) (xy 372.875577 -230.216945)
			(xy 372.859867 -230.166015) (xy 372.851924 -230.113311) (xy 372.62309 -230.113311) (xy 372.615147 -230.166015)
			(xy 372.599437 -230.216945) (xy 372.576311 -230.264966) (xy 372.546287 -230.309003) (xy 372.510035 -230.348074)
			(xy 372.468364 -230.381305) (xy 372.422206 -230.407954) (xy 372.372592 -230.427426) (xy 372.32063 -230.439286)
			(xy 372.26748 -230.44327) (xy 372.21433 -230.439286) (xy 372.162368 -230.427426) (xy 372.112754 -230.407954)
			(xy 372.066596 -230.381305) (xy 372.024925 -230.348074) (xy 371.988673 -230.309003) (xy 371.958649 -230.264966)
			(xy 371.935523 -230.216945) (xy 371.919813 -230.166015) (xy 371.91187 -230.113311) (xy 371.68329 -230.113311)
			(xy 371.675347 -230.166015) (xy 371.659637 -230.216945) (xy 371.636511 -230.264966) (xy 371.606487 -230.309003)
			(xy 371.570235 -230.348074) (xy 371.528564 -230.381305) (xy 371.482406 -230.407954) (xy 371.432792 -230.427426)
			(xy 371.38083 -230.439286) (xy 371.32768 -230.44327) (xy 371.27453 -230.439286) (xy 371.222568 -230.427426)
			(xy 371.172954 -230.407954) (xy 371.126796 -230.381305) (xy 371.085125 -230.348074) (xy 371.048873 -230.309003)
			(xy 371.018849 -230.264966) (xy 370.995723 -230.216945) (xy 370.980013 -230.166015) (xy 370.97207 -230.113311)
			(xy 369.80369 -230.113311) (xy 369.795747 -230.166015) (xy 369.780037 -230.216945) (xy 369.756911 -230.264966)
			(xy 369.726887 -230.309003) (xy 369.690635 -230.348074) (xy 369.648964 -230.381305) (xy 369.602806 -230.407954)
			(xy 369.553192 -230.427426) (xy 369.50123 -230.439286) (xy 369.44808 -230.44327) (xy 369.39493 -230.439286)
			(xy 369.342968 -230.427426) (xy 369.293354 -230.407954) (xy 369.247196 -230.381305) (xy 369.205525 -230.348074)
			(xy 369.169273 -230.309003) (xy 369.139249 -230.264966) (xy 369.116123 -230.216945) (xy 369.100413 -230.166015)
			(xy 369.09247 -230.113311) (xy 368.86389 -230.113311) (xy 368.855947 -230.166015) (xy 368.840237 -230.216945)
			(xy 368.817111 -230.264966) (xy 368.787087 -230.309003) (xy 368.750835 -230.348074) (xy 368.709164 -230.381305)
			(xy 368.663006 -230.407954) (xy 368.613392 -230.427426) (xy 368.56143 -230.439286) (xy 368.50828 -230.44327)
			(xy 368.45513 -230.439286) (xy 368.403168 -230.427426) (xy 368.353554 -230.407954) (xy 368.307396 -230.381305)
			(xy 368.265725 -230.348074) (xy 368.229473 -230.309003) (xy 368.199449 -230.264966) (xy 368.176323 -230.216945)
			(xy 368.160613 -230.166015) (xy 368.15267 -230.113311) (xy 367.92409 -230.113311) (xy 367.916147 -230.166015)
			(xy 367.900437 -230.216945) (xy 367.877311 -230.264966) (xy 367.847287 -230.309003) (xy 367.811035 -230.348074)
			(xy 367.769364 -230.381305) (xy 367.723206 -230.407954) (xy 367.673592 -230.427426) (xy 367.62163 -230.439286)
			(xy 367.56848 -230.44327) (xy 367.51533 -230.439286) (xy 367.463368 -230.427426) (xy 367.413754 -230.407954)
			(xy 367.367596 -230.381305) (xy 367.325925 -230.348074) (xy 367.289673 -230.309003) (xy 367.259649 -230.264966)
			(xy 367.236523 -230.216945) (xy 367.220813 -230.166015) (xy 367.21287 -230.113311) (xy 366.98429 -230.113311)
			(xy 366.976347 -230.166015) (xy 366.960637 -230.216945) (xy 366.937511 -230.264966) (xy 366.907487 -230.309003)
			(xy 366.871235 -230.348074) (xy 366.829564 -230.381305) (xy 366.783406 -230.407954) (xy 366.733792 -230.427426)
			(xy 366.68183 -230.439286) (xy 366.62868 -230.44327) (xy 366.57553 -230.439286) (xy 366.523568 -230.427426)
			(xy 366.473954 -230.407954) (xy 366.427796 -230.381305) (xy 366.386125 -230.348074) (xy 366.349873 -230.309003)
			(xy 366.319849 -230.264966) (xy 366.296723 -230.216945) (xy 366.281013 -230.166015) (xy 366.27307 -230.113311)
			(xy 366.04449 -230.113311) (xy 366.036547 -230.166015) (xy 366.020837 -230.216945) (xy 365.997711 -230.264966)
			(xy 365.967687 -230.309003) (xy 365.931435 -230.348074) (xy 365.889764 -230.381305) (xy 365.843606 -230.407954)
			(xy 365.793992 -230.427426) (xy 365.74203 -230.439286) (xy 365.68888 -230.44327) (xy 365.63573 -230.439286)
			(xy 365.583768 -230.427426) (xy 365.534154 -230.407954) (xy 365.487996 -230.381305) (xy 365.446325 -230.348074)
			(xy 365.410073 -230.309003) (xy 365.380049 -230.264966) (xy 365.356923 -230.216945) (xy 365.341213 -230.166015)
			(xy 365.33327 -230.113311) (xy 365.10469 -230.113311) (xy 365.096747 -230.166015) (xy 365.081037 -230.216945)
			(xy 365.057911 -230.264966) (xy 365.027887 -230.309003) (xy 364.991635 -230.348074) (xy 364.949964 -230.381305)
			(xy 364.903806 -230.407954) (xy 364.854192 -230.427426) (xy 364.80223 -230.439286) (xy 364.74908 -230.44327)
			(xy 364.69593 -230.439286) (xy 364.643968 -230.427426) (xy 364.594354 -230.407954) (xy 364.548196 -230.381305)
			(xy 364.506525 -230.348074) (xy 364.470273 -230.309003) (xy 364.440249 -230.264966) (xy 364.417123 -230.216945)
			(xy 364.401413 -230.166015) (xy 364.39347 -230.113311) (xy 364.16489 -230.113311) (xy 364.156947 -230.166015)
			(xy 364.141237 -230.216945) (xy 364.118111 -230.264966) (xy 364.088087 -230.309003) (xy 364.051835 -230.348074)
			(xy 364.010164 -230.381305) (xy 363.964006 -230.407954) (xy 363.914392 -230.427426) (xy 363.86243 -230.439286)
			(xy 363.80928 -230.44327) (xy 363.75613 -230.439286) (xy 363.704168 -230.427426) (xy 363.654554 -230.407954)
			(xy 363.608396 -230.381305) (xy 363.566725 -230.348074) (xy 363.530473 -230.309003) (xy 363.500449 -230.264966)
			(xy 363.477323 -230.216945) (xy 363.461613 -230.166015) (xy 363.45367 -230.113311) (xy 363.225344 -230.113311)
			(xy 363.217401 -230.166015) (xy 363.201691 -230.216945) (xy 363.178565 -230.264966) (xy 363.148541 -230.309003)
			(xy 363.112289 -230.348074) (xy 363.070618 -230.381305) (xy 363.02446 -230.407954) (xy 362.974846 -230.427426)
			(xy 362.922884 -230.439286) (xy 362.869734 -230.44327) (xy 362.816584 -230.439286) (xy 362.764622 -230.427426)
			(xy 362.715008 -230.407954) (xy 362.66885 -230.381305) (xy 362.627179 -230.348074) (xy 362.590927 -230.309003)
			(xy 362.560903 -230.264966) (xy 362.537777 -230.216945) (xy 362.522067 -230.166015) (xy 362.514124 -230.113311)
			(xy 362.285544 -230.113311) (xy 362.277601 -230.166015) (xy 362.261891 -230.216945) (xy 362.238765 -230.264966)
			(xy 362.208741 -230.309003) (xy 362.172489 -230.348074) (xy 362.130818 -230.381305) (xy 362.08466 -230.407954)
			(xy 362.035046 -230.427426) (xy 361.983084 -230.439286) (xy 361.929934 -230.44327) (xy 361.876784 -230.439286)
			(xy 361.824822 -230.427426) (xy 361.775208 -230.407954) (xy 361.72905 -230.381305) (xy 361.687379 -230.348074)
			(xy 361.651127 -230.309003) (xy 361.621103 -230.264966) (xy 361.597977 -230.216945) (xy 361.582267 -230.166015)
			(xy 361.574324 -230.113311) (xy 361.345744 -230.113311) (xy 361.337801 -230.166015) (xy 361.322091 -230.216945)
			(xy 361.298965 -230.264966) (xy 361.268941 -230.309003) (xy 361.232689 -230.348074) (xy 361.191018 -230.381305)
			(xy 361.14486 -230.407954) (xy 361.095246 -230.427426) (xy 361.043284 -230.439286) (xy 360.990134 -230.44327)
			(xy 360.936984 -230.439286) (xy 360.885022 -230.427426) (xy 360.835408 -230.407954) (xy 360.78925 -230.381305)
			(xy 360.747579 -230.348074) (xy 360.711327 -230.309003) (xy 360.681303 -230.264966) (xy 360.658177 -230.216945)
			(xy 360.642467 -230.166015) (xy 360.634524 -230.113311) (xy 360.405944 -230.113311) (xy 360.398001 -230.166015)
			(xy 360.382291 -230.216945) (xy 360.359165 -230.264966) (xy 360.329141 -230.309003) (xy 360.292889 -230.348074)
			(xy 360.251218 -230.381305) (xy 360.20506 -230.407954) (xy 360.155446 -230.427426) (xy 360.103484 -230.439286)
			(xy 360.050334 -230.44327) (xy 359.997184 -230.439286) (xy 359.945222 -230.427426) (xy 359.895608 -230.407954)
			(xy 359.84945 -230.381305) (xy 359.807779 -230.348074) (xy 359.771527 -230.309003) (xy 359.741503 -230.264966)
			(xy 359.718377 -230.216945) (xy 359.702667 -230.166015) (xy 359.694724 -230.113311) (xy 359.466144 -230.113311)
			(xy 359.458201 -230.166015) (xy 359.442491 -230.216945) (xy 359.419365 -230.264966) (xy 359.389341 -230.309003)
			(xy 359.353089 -230.348074) (xy 359.311418 -230.381305) (xy 359.26526 -230.407954) (xy 359.215646 -230.427426)
			(xy 359.163684 -230.439286) (xy 359.110534 -230.44327) (xy 359.057384 -230.439286) (xy 359.005422 -230.427426)
			(xy 358.955808 -230.407954) (xy 358.90965 -230.381305) (xy 358.867979 -230.348074) (xy 358.831727 -230.309003)
			(xy 358.801703 -230.264966) (xy 358.778577 -230.216945) (xy 358.762867 -230.166015) (xy 358.754924 -230.113311)
			(xy 358.52609 -230.113311) (xy 358.518147 -230.166015) (xy 358.502437 -230.216945) (xy 358.479311 -230.264966)
			(xy 358.449287 -230.309003) (xy 358.413035 -230.348074) (xy 358.371364 -230.381305) (xy 358.325206 -230.407954)
			(xy 358.275592 -230.427426) (xy 358.22363 -230.439286) (xy 358.17048 -230.44327) (xy 358.11733 -230.439286)
			(xy 358.065368 -230.427426) (xy 358.015754 -230.407954) (xy 357.969596 -230.381305) (xy 357.927925 -230.348074)
			(xy 357.891673 -230.309003) (xy 357.861649 -230.264966) (xy 357.838523 -230.216945) (xy 357.822813 -230.166015)
			(xy 357.81487 -230.113311) (xy 357.58629 -230.113311) (xy 357.578347 -230.166015) (xy 357.562637 -230.216945)
			(xy 357.539511 -230.264966) (xy 357.509487 -230.309003) (xy 357.473235 -230.348074) (xy 357.431564 -230.381305)
			(xy 357.385406 -230.407954) (xy 357.335792 -230.427426) (xy 357.28383 -230.439286) (xy 357.23068 -230.44327)
			(xy 357.17753 -230.439286) (xy 357.125568 -230.427426) (xy 357.075954 -230.407954) (xy 357.029796 -230.381305)
			(xy 356.988125 -230.348074) (xy 356.951873 -230.309003) (xy 356.921849 -230.264966) (xy 356.898723 -230.216945)
			(xy 356.883013 -230.166015) (xy 356.87507 -230.113311) (xy 356.64649 -230.113311) (xy 356.638547 -230.166015)
			(xy 356.622837 -230.216945) (xy 356.599711 -230.264966) (xy 356.569687 -230.309003) (xy 356.533435 -230.348074)
			(xy 356.491764 -230.381305) (xy 356.445606 -230.407954) (xy 356.395992 -230.427426) (xy 356.34403 -230.439286)
			(xy 356.29088 -230.44327) (xy 356.23773 -230.439286) (xy 356.185768 -230.427426) (xy 356.136154 -230.407954)
			(xy 356.089996 -230.381305) (xy 356.048325 -230.348074) (xy 356.012073 -230.309003) (xy 355.982049 -230.264966)
			(xy 355.958923 -230.216945) (xy 355.943213 -230.166015) (xy 355.93527 -230.113311) (xy 355.70669 -230.113311)
			(xy 355.698747 -230.166015) (xy 355.683037 -230.216945) (xy 355.659911 -230.264966) (xy 355.629887 -230.309003)
			(xy 355.593635 -230.348074) (xy 355.551964 -230.381305) (xy 355.505806 -230.407954) (xy 355.456192 -230.427426)
			(xy 355.40423 -230.439286) (xy 355.35108 -230.44327) (xy 355.29793 -230.439286) (xy 355.245968 -230.427426)
			(xy 355.196354 -230.407954) (xy 355.150196 -230.381305) (xy 355.108525 -230.348074) (xy 355.072273 -230.309003)
			(xy 355.042249 -230.264966) (xy 355.019123 -230.216945) (xy 355.003413 -230.166015) (xy 354.99547 -230.113311)
			(xy 354.767144 -230.113311) (xy 354.759201 -230.166015) (xy 354.743491 -230.216945) (xy 354.720365 -230.264966)
			(xy 354.690341 -230.309003) (xy 354.654089 -230.348074) (xy 354.612418 -230.381305) (xy 354.56626 -230.407954)
			(xy 354.516646 -230.427426) (xy 354.464684 -230.439286) (xy 354.411534 -230.44327) (xy 354.358384 -230.439286)
			(xy 354.306422 -230.427426) (xy 354.256808 -230.407954) (xy 354.21065 -230.381305) (xy 354.168979 -230.348074)
			(xy 354.132727 -230.309003) (xy 354.102703 -230.264966) (xy 354.079577 -230.216945) (xy 354.063867 -230.166015)
			(xy 354.055924 -230.113311) (xy 353.82709 -230.113311) (xy 353.819147 -230.166015) (xy 353.803437 -230.216945)
			(xy 353.780311 -230.264966) (xy 353.750287 -230.309003) (xy 353.714035 -230.348074) (xy 353.672364 -230.381305)
			(xy 353.626206 -230.407954) (xy 353.576592 -230.427426) (xy 353.52463 -230.439286) (xy 353.47148 -230.44327)
			(xy 353.41833 -230.439286) (xy 353.366368 -230.427426) (xy 353.316754 -230.407954) (xy 353.270596 -230.381305)
			(xy 353.228925 -230.348074) (xy 353.192673 -230.309003) (xy 353.162649 -230.264966) (xy 353.139523 -230.216945)
			(xy 353.123813 -230.166015) (xy 353.11587 -230.113311) (xy 352.88729 -230.113311) (xy 352.879347 -230.166015)
			(xy 352.863637 -230.216945) (xy 352.840511 -230.264966) (xy 352.810487 -230.309003) (xy 352.774235 -230.348074)
			(xy 352.732564 -230.381305) (xy 352.686406 -230.407954) (xy 352.636792 -230.427426) (xy 352.58483 -230.439286)
			(xy 352.53168 -230.44327) (xy 352.47853 -230.439286) (xy 352.426568 -230.427426) (xy 352.376954 -230.407954)
			(xy 352.330796 -230.381305) (xy 352.289125 -230.348074) (xy 352.252873 -230.309003) (xy 352.222849 -230.264966)
			(xy 352.199723 -230.216945) (xy 352.184013 -230.166015) (xy 352.17607 -230.113311) (xy 351.94749 -230.113311)
			(xy 351.939547 -230.166015) (xy 351.923837 -230.216945) (xy 351.900711 -230.264966) (xy 351.870687 -230.309003)
			(xy 351.834435 -230.348074) (xy 351.792764 -230.381305) (xy 351.746606 -230.407954) (xy 351.696992 -230.427426)
			(xy 351.64503 -230.439286) (xy 351.59188 -230.44327) (xy 351.53873 -230.439286) (xy 351.486768 -230.427426)
			(xy 351.437154 -230.407954) (xy 351.390996 -230.381305) (xy 351.349325 -230.348074) (xy 351.313073 -230.309003)
			(xy 351.283049 -230.264966) (xy 351.259923 -230.216945) (xy 351.244213 -230.166015) (xy 351.23627 -230.113311)
			(xy 351.00769 -230.113311) (xy 350.999747 -230.166015) (xy 350.984037 -230.216945) (xy 350.960911 -230.264966)
			(xy 350.930887 -230.309003) (xy 350.894635 -230.348074) (xy 350.852964 -230.381305) (xy 350.806806 -230.407954)
			(xy 350.757192 -230.427426) (xy 350.70523 -230.439286) (xy 350.65208 -230.44327) (xy 350.59893 -230.439286)
			(xy 350.546968 -230.427426) (xy 350.497354 -230.407954) (xy 350.451196 -230.381305) (xy 350.409525 -230.348074)
			(xy 350.373273 -230.309003) (xy 350.343249 -230.264966) (xy 350.320123 -230.216945) (xy 350.304413 -230.166015)
			(xy 350.29647 -230.113311) (xy 350.06789 -230.113311) (xy 350.059947 -230.166015) (xy 350.044237 -230.216945)
			(xy 350.021111 -230.264966) (xy 349.991087 -230.309003) (xy 349.954835 -230.348074) (xy 349.913164 -230.381305)
			(xy 349.867006 -230.407954) (xy 349.817392 -230.427426) (xy 349.76543 -230.439286) (xy 349.71228 -230.44327)
			(xy 349.65913 -230.439286) (xy 349.607168 -230.427426) (xy 349.557554 -230.407954) (xy 349.511396 -230.381305)
			(xy 349.469725 -230.348074) (xy 349.433473 -230.309003) (xy 349.403449 -230.264966) (xy 349.380323 -230.216945)
			(xy 349.364613 -230.166015) (xy 349.35667 -230.113311) (xy 349.12809 -230.113311) (xy 349.120147 -230.166015)
			(xy 349.104437 -230.216945) (xy 349.081311 -230.264966) (xy 349.051287 -230.309003) (xy 349.015035 -230.348074)
			(xy 348.973364 -230.381305) (xy 348.927206 -230.407954) (xy 348.877592 -230.427426) (xy 348.82563 -230.439286)
			(xy 348.77248 -230.44327) (xy 348.71933 -230.439286) (xy 348.667368 -230.427426) (xy 348.617754 -230.407954)
			(xy 348.571596 -230.381305) (xy 348.529925 -230.348074) (xy 348.493673 -230.309003) (xy 348.463649 -230.264966)
			(xy 348.440523 -230.216945) (xy 348.424813 -230.166015) (xy 348.41687 -230.113311) (xy 348.18829 -230.113311)
			(xy 348.180347 -230.166015) (xy 348.164637 -230.216945) (xy 348.141511 -230.264966) (xy 348.111487 -230.309003)
			(xy 348.075235 -230.348074) (xy 348.033564 -230.381305) (xy 347.987406 -230.407954) (xy 347.937792 -230.427426)
			(xy 347.88583 -230.439286) (xy 347.83268 -230.44327) (xy 347.77953 -230.439286) (xy 347.727568 -230.427426)
			(xy 347.677954 -230.407954) (xy 347.631796 -230.381305) (xy 347.590125 -230.348074) (xy 347.553873 -230.309003)
			(xy 347.523849 -230.264966) (xy 347.500723 -230.216945) (xy 347.485013 -230.166015) (xy 347.47707 -230.113311)
			(xy 347.24849 -230.113311) (xy 347.240547 -230.166015) (xy 347.224837 -230.216945) (xy 347.201711 -230.264966)
			(xy 347.171687 -230.309003) (xy 347.135435 -230.348074) (xy 347.093764 -230.381305) (xy 347.047606 -230.407954)
			(xy 346.997992 -230.427426) (xy 346.94603 -230.439286) (xy 346.89288 -230.44327) (xy 346.83973 -230.439286)
			(xy 346.787768 -230.427426) (xy 346.738154 -230.407954) (xy 346.691996 -230.381305) (xy 346.650325 -230.348074)
			(xy 346.614073 -230.309003) (xy 346.584049 -230.264966) (xy 346.560923 -230.216945) (xy 346.545213 -230.166015)
			(xy 346.53727 -230.113311) (xy 346.30869 -230.113311) (xy 346.300747 -230.166015) (xy 346.285037 -230.216945)
			(xy 346.261911 -230.264966) (xy 346.231887 -230.309003) (xy 346.195635 -230.348074) (xy 346.153964 -230.381305)
			(xy 346.107806 -230.407954) (xy 346.058192 -230.427426) (xy 346.00623 -230.439286) (xy 345.95308 -230.44327)
			(xy 345.89993 -230.439286) (xy 345.847968 -230.427426) (xy 345.798354 -230.407954) (xy 345.752196 -230.381305)
			(xy 345.710525 -230.348074) (xy 345.674273 -230.309003) (xy 345.644249 -230.264966) (xy 345.621123 -230.216945)
			(xy 345.605413 -230.166015) (xy 345.59747 -230.113311) (xy 345.369144 -230.113311) (xy 345.361201 -230.166015)
			(xy 345.345491 -230.216945) (xy 345.322365 -230.264966) (xy 345.292341 -230.309003) (xy 345.256089 -230.348074)
			(xy 345.214418 -230.381305) (xy 345.16826 -230.407954) (xy 345.118646 -230.427426) (xy 345.066684 -230.439286)
			(xy 345.013534 -230.44327) (xy 344.960384 -230.439286) (xy 344.908422 -230.427426) (xy 344.858808 -230.407954)
			(xy 344.81265 -230.381305) (xy 344.770979 -230.348074) (xy 344.734727 -230.309003) (xy 344.704703 -230.264966)
			(xy 344.681577 -230.216945) (xy 344.665867 -230.166015) (xy 344.657924 -230.113311) (xy 344.42909 -230.113311)
			(xy 344.421147 -230.166015) (xy 344.405437 -230.216945) (xy 344.382311 -230.264966) (xy 344.352287 -230.309003)
			(xy 344.316035 -230.348074) (xy 344.274364 -230.381305) (xy 344.228206 -230.407954) (xy 344.178592 -230.427426)
			(xy 344.12663 -230.439286) (xy 344.07348 -230.44327) (xy 344.02033 -230.439286) (xy 343.968368 -230.427426)
			(xy 343.918754 -230.407954) (xy 343.872596 -230.381305) (xy 343.830925 -230.348074) (xy 343.794673 -230.309003)
			(xy 343.764649 -230.264966) (xy 343.741523 -230.216945) (xy 343.725813 -230.166015) (xy 343.71787 -230.113311)
			(xy 343.48929 -230.113311) (xy 343.481347 -230.166015) (xy 343.465637 -230.216945) (xy 343.442511 -230.264966)
			(xy 343.412487 -230.309003) (xy 343.376235 -230.348074) (xy 343.334564 -230.381305) (xy 343.288406 -230.407954)
			(xy 343.238792 -230.427426) (xy 343.18683 -230.439286) (xy 343.13368 -230.44327) (xy 343.08053 -230.439286)
			(xy 343.028568 -230.427426) (xy 342.978954 -230.407954) (xy 342.932796 -230.381305) (xy 342.891125 -230.348074)
			(xy 342.854873 -230.309003) (xy 342.824849 -230.264966) (xy 342.801723 -230.216945) (xy 342.786013 -230.166015)
			(xy 342.77807 -230.113311) (xy 342.54949 -230.113311) (xy 342.541547 -230.166015) (xy 342.525837 -230.216945)
			(xy 342.502711 -230.264966) (xy 342.472687 -230.309003) (xy 342.436435 -230.348074) (xy 342.394764 -230.381305)
			(xy 342.348606 -230.407954) (xy 342.298992 -230.427426) (xy 342.24703 -230.439286) (xy 342.19388 -230.44327)
			(xy 342.14073 -230.439286) (xy 342.088768 -230.427426) (xy 342.039154 -230.407954) (xy 341.992996 -230.381305)
			(xy 341.951325 -230.348074) (xy 341.915073 -230.309003) (xy 341.885049 -230.264966) (xy 341.861923 -230.216945)
			(xy 341.846213 -230.166015) (xy 341.83827 -230.113311) (xy 341.60969 -230.113311) (xy 341.601747 -230.166015)
			(xy 341.586037 -230.216945) (xy 341.562911 -230.264966) (xy 341.532887 -230.309003) (xy 341.496635 -230.348074)
			(xy 341.454964 -230.381305) (xy 341.408806 -230.407954) (xy 341.359192 -230.427426) (xy 341.30723 -230.439286)
			(xy 341.25408 -230.44327) (xy 341.20093 -230.439286) (xy 341.148968 -230.427426) (xy 341.099354 -230.407954)
			(xy 341.053196 -230.381305) (xy 341.011525 -230.348074) (xy 340.975273 -230.309003) (xy 340.945249 -230.264966)
			(xy 340.922123 -230.216945) (xy 340.906413 -230.166015) (xy 340.89847 -230.113311) (xy 340.66989 -230.113311)
			(xy 340.661947 -230.166015) (xy 340.646237 -230.216945) (xy 340.623111 -230.264966) (xy 340.593087 -230.309003)
			(xy 340.556835 -230.348074) (xy 340.515164 -230.381305) (xy 340.469006 -230.407954) (xy 340.419392 -230.427426)
			(xy 340.36743 -230.439286) (xy 340.31428 -230.44327) (xy 340.26113 -230.439286) (xy 340.209168 -230.427426)
			(xy 340.159554 -230.407954) (xy 340.113396 -230.381305) (xy 340.071725 -230.348074) (xy 340.035473 -230.309003)
			(xy 340.005449 -230.264966) (xy 339.982323 -230.216945) (xy 339.966613 -230.166015) (xy 339.95867 -230.113311)
			(xy 339.729243 -230.113311) (xy 339.727205 -230.140297) (xy 339.715149 -230.192682) (xy 339.695358 -230.242661)
			(xy 339.668283 -230.289099) (xy 339.634538 -230.330942) (xy 339.594889 -230.367239) (xy 339.550237 -230.397168)
			(xy 339.501594 -230.420048) (xy 339.450067 -230.435359) (xy 339.423502 -230.439468) (xy 339.37956 -230.445564)
			(xy 339.37956 -230.927127) (xy 339.489024 -230.927127) (xy 339.489024 -230.873829) (xy 339.496967 -230.821125)
			(xy 339.512677 -230.770195) (xy 339.535803 -230.722174) (xy 339.565827 -230.678137) (xy 339.602079 -230.639066)
			(xy 339.64375 -230.605835) (xy 339.689908 -230.579186) (xy 339.739522 -230.559714) (xy 339.791484 -230.547854)
			(xy 339.844634 -230.543871) (xy 339.897784 -230.547854) (xy 339.949746 -230.559714) (xy 339.99936 -230.579186)
			(xy 340.045518 -230.605835) (xy 340.087189 -230.639066) (xy 340.123441 -230.678137) (xy 340.153465 -230.722174)
			(xy 340.176591 -230.770195) (xy 340.192301 -230.821125) (xy 340.200244 -230.873829) (xy 340.200742 -230.900478)
			(xy 340.200244 -230.927127) (xy 340.428824 -230.927127) (xy 340.428824 -230.873829) (xy 340.436767 -230.821125)
			(xy 340.452477 -230.770195) (xy 340.475603 -230.722174) (xy 340.505627 -230.678137) (xy 340.541879 -230.639066)
			(xy 340.58355 -230.605835) (xy 340.629708 -230.579186) (xy 340.679322 -230.559714) (xy 340.731284 -230.547854)
			(xy 340.784434 -230.543871) (xy 340.837584 -230.547854) (xy 340.889546 -230.559714) (xy 340.93916 -230.579186)
			(xy 340.985318 -230.605835) (xy 341.026989 -230.639066) (xy 341.063241 -230.678137) (xy 341.093265 -230.722174)
			(xy 341.116391 -230.770195) (xy 341.132101 -230.821125) (xy 341.140044 -230.873829) (xy 341.140542 -230.900478)
			(xy 341.140044 -230.927127) (xy 341.368624 -230.927127) (xy 341.368624 -230.873829) (xy 341.376567 -230.821125)
			(xy 341.392277 -230.770195) (xy 341.415403 -230.722174) (xy 341.445427 -230.678137) (xy 341.481679 -230.639066)
			(xy 341.52335 -230.605835) (xy 341.569508 -230.579186) (xy 341.619122 -230.559714) (xy 341.671084 -230.547854)
			(xy 341.724234 -230.543871) (xy 341.777384 -230.547854) (xy 341.829346 -230.559714) (xy 341.87896 -230.579186)
			(xy 341.925118 -230.605835) (xy 341.966789 -230.639066) (xy 342.003041 -230.678137) (xy 342.033065 -230.722174)
			(xy 342.056191 -230.770195) (xy 342.071901 -230.821125) (xy 342.079844 -230.873829) (xy 342.080342 -230.900478)
			(xy 342.079844 -230.927127) (xy 342.308424 -230.927127) (xy 342.308424 -230.873829) (xy 342.316367 -230.821125)
			(xy 342.332077 -230.770195) (xy 342.355203 -230.722174) (xy 342.385227 -230.678137) (xy 342.421479 -230.639066)
			(xy 342.46315 -230.605835) (xy 342.509308 -230.579186) (xy 342.558922 -230.559714) (xy 342.610884 -230.547854)
			(xy 342.664034 -230.543871) (xy 342.717184 -230.547854) (xy 342.769146 -230.559714) (xy 342.81876 -230.579186)
			(xy 342.864918 -230.605835) (xy 342.906589 -230.639066) (xy 342.942841 -230.678137) (xy 342.972865 -230.722174)
			(xy 342.995991 -230.770195) (xy 343.011701 -230.821125) (xy 343.019644 -230.873829) (xy 343.020142 -230.900478)
			(xy 343.019644 -230.927127) (xy 343.248224 -230.927127) (xy 343.248224 -230.873829) (xy 343.256167 -230.821125)
			(xy 343.271877 -230.770195) (xy 343.295003 -230.722174) (xy 343.325027 -230.678137) (xy 343.361279 -230.639066)
			(xy 343.40295 -230.605835) (xy 343.449108 -230.579186) (xy 343.498722 -230.559714) (xy 343.550684 -230.547854)
			(xy 343.603834 -230.543871) (xy 343.656984 -230.547854) (xy 343.708946 -230.559714) (xy 343.75856 -230.579186)
			(xy 343.804718 -230.605835) (xy 343.846389 -230.639066) (xy 343.882641 -230.678137) (xy 343.912665 -230.722174)
			(xy 343.935791 -230.770195) (xy 343.951501 -230.821125) (xy 343.959444 -230.873829) (xy 343.959942 -230.900478)
			(xy 343.959444 -230.927127) (xy 344.188024 -230.927127) (xy 344.188024 -230.873829) (xy 344.195967 -230.821125)
			(xy 344.211677 -230.770195) (xy 344.234803 -230.722174) (xy 344.264827 -230.678137) (xy 344.301079 -230.639066)
			(xy 344.34275 -230.605835) (xy 344.388908 -230.579186) (xy 344.438522 -230.559714) (xy 344.490484 -230.547854)
			(xy 344.543634 -230.543871) (xy 344.596784 -230.547854) (xy 344.648746 -230.559714) (xy 344.69836 -230.579186)
			(xy 344.744518 -230.605835) (xy 344.786189 -230.639066) (xy 344.822441 -230.678137) (xy 344.852465 -230.722174)
			(xy 344.875591 -230.770195) (xy 344.891301 -230.821125) (xy 344.899244 -230.873829) (xy 344.899742 -230.900478)
			(xy 344.899244 -230.927127) (xy 345.12757 -230.927127) (xy 345.12757 -230.873829) (xy 345.135513 -230.821125)
			(xy 345.151223 -230.770195) (xy 345.174349 -230.722174) (xy 345.204373 -230.678137) (xy 345.240625 -230.639066)
			(xy 345.282296 -230.605835) (xy 345.328454 -230.579186) (xy 345.378068 -230.559714) (xy 345.43003 -230.547854)
			(xy 345.48318 -230.543871) (xy 345.53633 -230.547854) (xy 345.588292 -230.559714) (xy 345.637906 -230.579186)
			(xy 345.684064 -230.605835) (xy 345.725735 -230.639066) (xy 345.761987 -230.678137) (xy 345.792011 -230.722174)
			(xy 345.815137 -230.770195) (xy 345.830847 -230.821125) (xy 345.83879 -230.873829) (xy 345.839288 -230.900478)
			(xy 345.83879 -230.927127) (xy 346.067624 -230.927127) (xy 346.067624 -230.873829) (xy 346.075567 -230.821125)
			(xy 346.091277 -230.770195) (xy 346.114403 -230.722174) (xy 346.144427 -230.678137) (xy 346.180679 -230.639066)
			(xy 346.22235 -230.605835) (xy 346.268508 -230.579186) (xy 346.318122 -230.559714) (xy 346.370084 -230.547854)
			(xy 346.423234 -230.543871) (xy 346.476384 -230.547854) (xy 346.528346 -230.559714) (xy 346.57796 -230.579186)
			(xy 346.624118 -230.605835) (xy 346.665789 -230.639066) (xy 346.702041 -230.678137) (xy 346.732065 -230.722174)
			(xy 346.755191 -230.770195) (xy 346.770901 -230.821125) (xy 346.778844 -230.873829) (xy 346.779342 -230.900478)
			(xy 346.778844 -230.927127) (xy 347.007424 -230.927127) (xy 347.007424 -230.873829) (xy 347.015367 -230.821125)
			(xy 347.031077 -230.770195) (xy 347.054203 -230.722174) (xy 347.084227 -230.678137) (xy 347.120479 -230.639066)
			(xy 347.16215 -230.605835) (xy 347.208308 -230.579186) (xy 347.257922 -230.559714) (xy 347.309884 -230.547854)
			(xy 347.363034 -230.543871) (xy 347.416184 -230.547854) (xy 347.468146 -230.559714) (xy 347.51776 -230.579186)
			(xy 347.563918 -230.605835) (xy 347.605589 -230.639066) (xy 347.641841 -230.678137) (xy 347.671865 -230.722174)
			(xy 347.694991 -230.770195) (xy 347.710701 -230.821125) (xy 347.718644 -230.873829) (xy 347.719142 -230.900478)
			(xy 347.718644 -230.927127) (xy 347.947224 -230.927127) (xy 347.947224 -230.873829) (xy 347.955167 -230.821125)
			(xy 347.970877 -230.770195) (xy 347.994003 -230.722174) (xy 348.024027 -230.678137) (xy 348.060279 -230.639066)
			(xy 348.10195 -230.605835) (xy 348.148108 -230.579186) (xy 348.197722 -230.559714) (xy 348.249684 -230.547854)
			(xy 348.302834 -230.543871) (xy 348.355984 -230.547854) (xy 348.407946 -230.559714) (xy 348.45756 -230.579186)
			(xy 348.503718 -230.605835) (xy 348.545389 -230.639066) (xy 348.581641 -230.678137) (xy 348.611665 -230.722174)
			(xy 348.634791 -230.770195) (xy 348.650501 -230.821125) (xy 348.658444 -230.873829) (xy 348.658942 -230.900478)
			(xy 348.658444 -230.927127) (xy 348.887024 -230.927127) (xy 348.887024 -230.873829) (xy 348.894967 -230.821125)
			(xy 348.910677 -230.770195) (xy 348.933803 -230.722174) (xy 348.963827 -230.678137) (xy 349.000079 -230.639066)
			(xy 349.04175 -230.605835) (xy 349.087908 -230.579186) (xy 349.137522 -230.559714) (xy 349.189484 -230.547854)
			(xy 349.242634 -230.543871) (xy 349.295784 -230.547854) (xy 349.347746 -230.559714) (xy 349.39736 -230.579186)
			(xy 349.443518 -230.605835) (xy 349.485189 -230.639066) (xy 349.521441 -230.678137) (xy 349.551465 -230.722174)
			(xy 349.574591 -230.770195) (xy 349.590301 -230.821125) (xy 349.598244 -230.873829) (xy 349.598742 -230.900478)
			(xy 349.598244 -230.927127) (xy 349.826824 -230.927127) (xy 349.826824 -230.873829) (xy 349.834767 -230.821125)
			(xy 349.850477 -230.770195) (xy 349.873603 -230.722174) (xy 349.903627 -230.678137) (xy 349.939879 -230.639066)
			(xy 349.98155 -230.605835) (xy 350.027708 -230.579186) (xy 350.077322 -230.559714) (xy 350.129284 -230.547854)
			(xy 350.182434 -230.543871) (xy 350.235584 -230.547854) (xy 350.287546 -230.559714) (xy 350.33716 -230.579186)
			(xy 350.383318 -230.605835) (xy 350.424989 -230.639066) (xy 350.461241 -230.678137) (xy 350.491265 -230.722174)
			(xy 350.514391 -230.770195) (xy 350.530101 -230.821125) (xy 350.538044 -230.873829) (xy 350.538542 -230.900478)
			(xy 350.538044 -230.927127) (xy 350.766624 -230.927127) (xy 350.766624 -230.873829) (xy 350.774567 -230.821125)
			(xy 350.790277 -230.770195) (xy 350.813403 -230.722174) (xy 350.843427 -230.678137) (xy 350.879679 -230.639066)
			(xy 350.92135 -230.605835) (xy 350.967508 -230.579186) (xy 351.017122 -230.559714) (xy 351.069084 -230.547854)
			(xy 351.122234 -230.543871) (xy 351.175384 -230.547854) (xy 351.227346 -230.559714) (xy 351.27696 -230.579186)
			(xy 351.323118 -230.605835) (xy 351.364789 -230.639066) (xy 351.401041 -230.678137) (xy 351.431065 -230.722174)
			(xy 351.454191 -230.770195) (xy 351.469901 -230.821125) (xy 351.477844 -230.873829) (xy 351.478342 -230.900478)
			(xy 351.477844 -230.927127) (xy 351.706424 -230.927127) (xy 351.706424 -230.873829) (xy 351.714367 -230.821125)
			(xy 351.730077 -230.770195) (xy 351.753203 -230.722174) (xy 351.783227 -230.678137) (xy 351.819479 -230.639066)
			(xy 351.86115 -230.605835) (xy 351.907308 -230.579186) (xy 351.956922 -230.559714) (xy 352.008884 -230.547854)
			(xy 352.062034 -230.543871) (xy 352.115184 -230.547854) (xy 352.167146 -230.559714) (xy 352.21676 -230.579186)
			(xy 352.262918 -230.605835) (xy 352.304589 -230.639066) (xy 352.340841 -230.678137) (xy 352.370865 -230.722174)
			(xy 352.393991 -230.770195) (xy 352.409701 -230.821125) (xy 352.417644 -230.873829) (xy 352.418142 -230.900478)
			(xy 352.417644 -230.927127) (xy 352.646224 -230.927127) (xy 352.646224 -230.873829) (xy 352.654167 -230.821125)
			(xy 352.669877 -230.770195) (xy 352.693003 -230.722174) (xy 352.723027 -230.678137) (xy 352.759279 -230.639066)
			(xy 352.80095 -230.605835) (xy 352.847108 -230.579186) (xy 352.896722 -230.559714) (xy 352.948684 -230.547854)
			(xy 353.001834 -230.543871) (xy 353.054984 -230.547854) (xy 353.106946 -230.559714) (xy 353.15656 -230.579186)
			(xy 353.202718 -230.605835) (xy 353.244389 -230.639066) (xy 353.280641 -230.678137) (xy 353.310665 -230.722174)
			(xy 353.333791 -230.770195) (xy 353.349501 -230.821125) (xy 353.357444 -230.873829) (xy 353.357942 -230.900478)
			(xy 353.357444 -230.927127) (xy 353.586024 -230.927127) (xy 353.586024 -230.873829) (xy 353.593967 -230.821125)
			(xy 353.609677 -230.770195) (xy 353.632803 -230.722174) (xy 353.662827 -230.678137) (xy 353.699079 -230.639066)
			(xy 353.74075 -230.605835) (xy 353.786908 -230.579186) (xy 353.836522 -230.559714) (xy 353.888484 -230.547854)
			(xy 353.941634 -230.543871) (xy 353.994784 -230.547854) (xy 354.046746 -230.559714) (xy 354.09636 -230.579186)
			(xy 354.142518 -230.605835) (xy 354.184189 -230.639066) (xy 354.220441 -230.678137) (xy 354.250465 -230.722174)
			(xy 354.273591 -230.770195) (xy 354.289301 -230.821125) (xy 354.297244 -230.873829) (xy 354.297742 -230.900478)
			(xy 354.297244 -230.927127) (xy 354.525824 -230.927127) (xy 354.525824 -230.873829) (xy 354.533767 -230.821125)
			(xy 354.549477 -230.770195) (xy 354.572603 -230.722174) (xy 354.602627 -230.678137) (xy 354.638879 -230.639066)
			(xy 354.68055 -230.605835) (xy 354.726708 -230.579186) (xy 354.776322 -230.559714) (xy 354.828284 -230.547854)
			(xy 354.881434 -230.543871) (xy 354.934584 -230.547854) (xy 354.986546 -230.559714) (xy 355.03616 -230.579186)
			(xy 355.082318 -230.605835) (xy 355.123989 -230.639066) (xy 355.160241 -230.678137) (xy 355.190265 -230.722174)
			(xy 355.213391 -230.770195) (xy 355.229101 -230.821125) (xy 355.237044 -230.873829) (xy 355.237542 -230.900478)
			(xy 355.237044 -230.927127) (xy 355.46537 -230.927127) (xy 355.46537 -230.873829) (xy 355.473313 -230.821125)
			(xy 355.489023 -230.770195) (xy 355.512149 -230.722174) (xy 355.542173 -230.678137) (xy 355.578425 -230.639066)
			(xy 355.620096 -230.605835) (xy 355.666254 -230.579186) (xy 355.715868 -230.559714) (xy 355.76783 -230.547854)
			(xy 355.82098 -230.543871) (xy 355.87413 -230.547854) (xy 355.926092 -230.559714) (xy 355.975706 -230.579186)
			(xy 356.021864 -230.605835) (xy 356.063535 -230.639066) (xy 356.099787 -230.678137) (xy 356.129811 -230.722174)
			(xy 356.152937 -230.770195) (xy 356.168647 -230.821125) (xy 356.17659 -230.873829) (xy 356.177088 -230.900478)
			(xy 356.17659 -230.927127) (xy 356.405424 -230.927127) (xy 356.405424 -230.873829) (xy 356.413367 -230.821125)
			(xy 356.429077 -230.770195) (xy 356.452203 -230.722174) (xy 356.482227 -230.678137) (xy 356.518479 -230.639066)
			(xy 356.56015 -230.605835) (xy 356.606308 -230.579186) (xy 356.655922 -230.559714) (xy 356.707884 -230.547854)
			(xy 356.761034 -230.543871) (xy 356.814184 -230.547854) (xy 356.866146 -230.559714) (xy 356.91576 -230.579186)
			(xy 356.961918 -230.605835) (xy 357.003589 -230.639066) (xy 357.039841 -230.678137) (xy 357.069865 -230.722174)
			(xy 357.092991 -230.770195) (xy 357.108701 -230.821125) (xy 357.116644 -230.873829) (xy 357.117142 -230.900478)
			(xy 357.116644 -230.927127) (xy 357.34497 -230.927127) (xy 357.34497 -230.873829) (xy 357.352913 -230.821125)
			(xy 357.368623 -230.770195) (xy 357.391749 -230.722174) (xy 357.421773 -230.678137) (xy 357.458025 -230.639066)
			(xy 357.499696 -230.605835) (xy 357.545854 -230.579186) (xy 357.595468 -230.559714) (xy 357.64743 -230.547854)
			(xy 357.70058 -230.543871) (xy 357.75373 -230.547854) (xy 357.805692 -230.559714) (xy 357.855306 -230.579186)
			(xy 357.901464 -230.605835) (xy 357.943135 -230.639066) (xy 357.979387 -230.678137) (xy 358.009411 -230.722174)
			(xy 358.032537 -230.770195) (xy 358.048247 -230.821125) (xy 358.05619 -230.873829) (xy 358.056688 -230.900478)
			(xy 358.05619 -230.927127) (xy 358.285024 -230.927127) (xy 358.285024 -230.873829) (xy 358.292967 -230.821125)
			(xy 358.308677 -230.770195) (xy 358.331803 -230.722174) (xy 358.361827 -230.678137) (xy 358.398079 -230.639066)
			(xy 358.43975 -230.605835) (xy 358.485908 -230.579186) (xy 358.535522 -230.559714) (xy 358.587484 -230.547854)
			(xy 358.640634 -230.543871) (xy 358.693784 -230.547854) (xy 358.745746 -230.559714) (xy 358.79536 -230.579186)
			(xy 358.841518 -230.605835) (xy 358.883189 -230.639066) (xy 358.919441 -230.678137) (xy 358.949465 -230.722174)
			(xy 358.972591 -230.770195) (xy 358.988301 -230.821125) (xy 358.996244 -230.873829) (xy 358.996742 -230.900478)
			(xy 358.996244 -230.927127) (xy 359.224824 -230.927127) (xy 359.224824 -230.873829) (xy 359.232767 -230.821125)
			(xy 359.248477 -230.770195) (xy 359.271603 -230.722174) (xy 359.301627 -230.678137) (xy 359.337879 -230.639066)
			(xy 359.37955 -230.605835) (xy 359.425708 -230.579186) (xy 359.475322 -230.559714) (xy 359.527284 -230.547854)
			(xy 359.580434 -230.543871) (xy 359.633584 -230.547854) (xy 359.685546 -230.559714) (xy 359.73516 -230.579186)
			(xy 359.781318 -230.605835) (xy 359.822989 -230.639066) (xy 359.859241 -230.678137) (xy 359.889265 -230.722174)
			(xy 359.912391 -230.770195) (xy 359.928101 -230.821125) (xy 359.936044 -230.873829) (xy 359.936542 -230.900478)
			(xy 359.936044 -230.927127) (xy 360.164624 -230.927127) (xy 360.164624 -230.873829) (xy 360.172567 -230.821125)
			(xy 360.188277 -230.770195) (xy 360.211403 -230.722174) (xy 360.241427 -230.678137) (xy 360.277679 -230.639066)
			(xy 360.31935 -230.605835) (xy 360.365508 -230.579186) (xy 360.415122 -230.559714) (xy 360.467084 -230.547854)
			(xy 360.520234 -230.543871) (xy 360.573384 -230.547854) (xy 360.625346 -230.559714) (xy 360.67496 -230.579186)
			(xy 360.721118 -230.605835) (xy 360.762789 -230.639066) (xy 360.799041 -230.678137) (xy 360.829065 -230.722174)
			(xy 360.852191 -230.770195) (xy 360.867901 -230.821125) (xy 360.875844 -230.873829) (xy 360.876342 -230.900478)
			(xy 360.875844 -230.927127) (xy 361.104424 -230.927127) (xy 361.104424 -230.873829) (xy 361.112367 -230.821125)
			(xy 361.128077 -230.770195) (xy 361.151203 -230.722174) (xy 361.181227 -230.678137) (xy 361.217479 -230.639066)
			(xy 361.25915 -230.605835) (xy 361.305308 -230.579186) (xy 361.354922 -230.559714) (xy 361.406884 -230.547854)
			(xy 361.460034 -230.543871) (xy 361.513184 -230.547854) (xy 361.565146 -230.559714) (xy 361.61476 -230.579186)
			(xy 361.660918 -230.605835) (xy 361.702589 -230.639066) (xy 361.738841 -230.678137) (xy 361.768865 -230.722174)
			(xy 361.791991 -230.770195) (xy 361.807701 -230.821125) (xy 361.815644 -230.873829) (xy 361.816142 -230.900478)
			(xy 361.815644 -230.927127) (xy 362.044478 -230.927127) (xy 362.044478 -230.873829) (xy 362.052421 -230.821125)
			(xy 362.068131 -230.770195) (xy 362.091257 -230.722174) (xy 362.121281 -230.678137) (xy 362.157533 -230.639066)
			(xy 362.199204 -230.605835) (xy 362.245362 -230.579186) (xy 362.294976 -230.559714) (xy 362.346938 -230.547854)
			(xy 362.400088 -230.543871) (xy 362.453238 -230.547854) (xy 362.5052 -230.559714) (xy 362.554814 -230.579186)
			(xy 362.600972 -230.605835) (xy 362.642643 -230.639066) (xy 362.678895 -230.678137) (xy 362.708919 -230.722174)
			(xy 362.732045 -230.770195) (xy 362.747755 -230.821125) (xy 362.755698 -230.873829) (xy 362.756196 -230.900478)
			(xy 362.755698 -230.927127) (xy 362.984024 -230.927127) (xy 362.984024 -230.873829) (xy 362.991967 -230.821125)
			(xy 363.007677 -230.770195) (xy 363.030803 -230.722174) (xy 363.060827 -230.678137) (xy 363.097079 -230.639066)
			(xy 363.13875 -230.605835) (xy 363.184908 -230.579186) (xy 363.234522 -230.559714) (xy 363.286484 -230.547854)
			(xy 363.339634 -230.543871) (xy 363.392784 -230.547854) (xy 363.444746 -230.559714) (xy 363.49436 -230.579186)
			(xy 363.540518 -230.605835) (xy 363.582189 -230.639066) (xy 363.618441 -230.678137) (xy 363.648465 -230.722174)
			(xy 363.671591 -230.770195) (xy 363.687301 -230.821125) (xy 363.695244 -230.873829) (xy 363.695742 -230.900478)
			(xy 363.695244 -230.927127) (xy 363.923824 -230.927127) (xy 363.923824 -230.873829) (xy 363.931767 -230.821125)
			(xy 363.947477 -230.770195) (xy 363.970603 -230.722174) (xy 364.000627 -230.678137) (xy 364.036879 -230.639066)
			(xy 364.07855 -230.605835) (xy 364.124708 -230.579186) (xy 364.174322 -230.559714) (xy 364.226284 -230.547854)
			(xy 364.279434 -230.543871) (xy 364.332584 -230.547854) (xy 364.384546 -230.559714) (xy 364.43416 -230.579186)
			(xy 364.480318 -230.605835) (xy 364.521989 -230.639066) (xy 364.558241 -230.678137) (xy 364.588265 -230.722174)
			(xy 364.611391 -230.770195) (xy 364.627101 -230.821125) (xy 364.635044 -230.873829) (xy 364.635542 -230.900478)
			(xy 364.635044 -230.927127) (xy 364.863624 -230.927127) (xy 364.863624 -230.873829) (xy 364.871567 -230.821125)
			(xy 364.887277 -230.770195) (xy 364.910403 -230.722174) (xy 364.940427 -230.678137) (xy 364.976679 -230.639066)
			(xy 365.01835 -230.605835) (xy 365.064508 -230.579186) (xy 365.114122 -230.559714) (xy 365.166084 -230.547854)
			(xy 365.219234 -230.543871) (xy 365.272384 -230.547854) (xy 365.324346 -230.559714) (xy 365.37396 -230.579186)
			(xy 365.420118 -230.605835) (xy 365.461789 -230.639066) (xy 365.498041 -230.678137) (xy 365.528065 -230.722174)
			(xy 365.551191 -230.770195) (xy 365.566901 -230.821125) (xy 365.574844 -230.873829) (xy 365.575342 -230.900478)
			(xy 365.574844 -230.927127) (xy 365.803424 -230.927127) (xy 365.803424 -230.873829) (xy 365.811367 -230.821125)
			(xy 365.827077 -230.770195) (xy 365.850203 -230.722174) (xy 365.880227 -230.678137) (xy 365.916479 -230.639066)
			(xy 365.95815 -230.605835) (xy 366.004308 -230.579186) (xy 366.053922 -230.559714) (xy 366.105884 -230.547854)
			(xy 366.159034 -230.543871) (xy 366.212184 -230.547854) (xy 366.264146 -230.559714) (xy 366.31376 -230.579186)
			(xy 366.359918 -230.605835) (xy 366.401589 -230.639066) (xy 366.437841 -230.678137) (xy 366.467865 -230.722174)
			(xy 366.490991 -230.770195) (xy 366.506701 -230.821125) (xy 366.514644 -230.873829) (xy 366.515142 -230.900478)
			(xy 366.514644 -230.927127) (xy 366.743224 -230.927127) (xy 366.743224 -230.873829) (xy 366.751167 -230.821125)
			(xy 366.766877 -230.770195) (xy 366.790003 -230.722174) (xy 366.820027 -230.678137) (xy 366.856279 -230.639066)
			(xy 366.89795 -230.605835) (xy 366.944108 -230.579186) (xy 366.993722 -230.559714) (xy 367.045684 -230.547854)
			(xy 367.098834 -230.543871) (xy 367.151984 -230.547854) (xy 367.203946 -230.559714) (xy 367.25356 -230.579186)
			(xy 367.299718 -230.605835) (xy 367.341389 -230.639066) (xy 367.377641 -230.678137) (xy 367.407665 -230.722174)
			(xy 367.430791 -230.770195) (xy 367.446501 -230.821125) (xy 367.454444 -230.873829) (xy 367.454942 -230.900478)
			(xy 367.454444 -230.927127) (xy 367.683024 -230.927127) (xy 367.683024 -230.873829) (xy 367.690967 -230.821125)
			(xy 367.706677 -230.770195) (xy 367.729803 -230.722174) (xy 367.759827 -230.678137) (xy 367.796079 -230.639066)
			(xy 367.83775 -230.605835) (xy 367.883908 -230.579186) (xy 367.933522 -230.559714) (xy 367.985484 -230.547854)
			(xy 368.038634 -230.543871) (xy 368.091784 -230.547854) (xy 368.143746 -230.559714) (xy 368.19336 -230.579186)
			(xy 368.239518 -230.605835) (xy 368.281189 -230.639066) (xy 368.317441 -230.678137) (xy 368.347465 -230.722174)
			(xy 368.370591 -230.770195) (xy 368.386301 -230.821125) (xy 368.394244 -230.873829) (xy 368.394742 -230.900478)
			(xy 368.394244 -230.927127) (xy 368.622824 -230.927127) (xy 368.622824 -230.873829) (xy 368.630767 -230.821125)
			(xy 368.646477 -230.770195) (xy 368.669603 -230.722174) (xy 368.699627 -230.678137) (xy 368.735879 -230.639066)
			(xy 368.77755 -230.605835) (xy 368.823708 -230.579186) (xy 368.873322 -230.559714) (xy 368.925284 -230.547854)
			(xy 368.978434 -230.543871) (xy 369.031584 -230.547854) (xy 369.083546 -230.559714) (xy 369.13316 -230.579186)
			(xy 369.179318 -230.605835) (xy 369.220989 -230.639066) (xy 369.257241 -230.678137) (xy 369.287265 -230.722174)
			(xy 369.310391 -230.770195) (xy 369.326101 -230.821125) (xy 369.334044 -230.873829) (xy 369.334542 -230.900478)
			(xy 369.334044 -230.927127) (xy 369.56237 -230.927127) (xy 369.56237 -230.873829) (xy 369.570313 -230.821125)
			(xy 369.586023 -230.770195) (xy 369.609149 -230.722174) (xy 369.639173 -230.678137) (xy 369.675425 -230.639066)
			(xy 369.717096 -230.605835) (xy 369.763254 -230.579186) (xy 369.812868 -230.559714) (xy 369.86483 -230.547854)
			(xy 369.91798 -230.543871) (xy 369.97113 -230.547854) (xy 370.023092 -230.559714) (xy 370.072706 -230.579186)
			(xy 370.118864 -230.605835) (xy 370.160535 -230.639066) (xy 370.196787 -230.678137) (xy 370.226811 -230.722174)
			(xy 370.249937 -230.770195) (xy 370.265647 -230.821125) (xy 370.27359 -230.873829) (xy 370.274088 -230.900478)
			(xy 370.27359 -230.927127) (xy 370.502424 -230.927127) (xy 370.502424 -230.873829) (xy 370.510367 -230.821125)
			(xy 370.526077 -230.770195) (xy 370.549203 -230.722174) (xy 370.579227 -230.678137) (xy 370.615479 -230.639066)
			(xy 370.65715 -230.605835) (xy 370.703308 -230.579186) (xy 370.752922 -230.559714) (xy 370.804884 -230.547854)
			(xy 370.858034 -230.543871) (xy 370.911184 -230.547854) (xy 370.963146 -230.559714) (xy 371.01276 -230.579186)
			(xy 371.058918 -230.605835) (xy 371.100589 -230.639066) (xy 371.136841 -230.678137) (xy 371.166865 -230.722174)
			(xy 371.189991 -230.770195) (xy 371.205701 -230.821125) (xy 371.213644 -230.873829) (xy 371.214142 -230.900478)
			(xy 371.213644 -230.927127) (xy 371.442224 -230.927127) (xy 371.442224 -230.873829) (xy 371.450167 -230.821125)
			(xy 371.465877 -230.770195) (xy 371.489003 -230.722174) (xy 371.519027 -230.678137) (xy 371.555279 -230.639066)
			(xy 371.59695 -230.605835) (xy 371.643108 -230.579186) (xy 371.692722 -230.559714) (xy 371.744684 -230.547854)
			(xy 371.797834 -230.543871) (xy 371.850984 -230.547854) (xy 371.902946 -230.559714) (xy 371.95256 -230.579186)
			(xy 371.998718 -230.605835) (xy 372.040389 -230.639066) (xy 372.076641 -230.678137) (xy 372.106665 -230.722174)
			(xy 372.129791 -230.770195) (xy 372.145501 -230.821125) (xy 372.153444 -230.873829) (xy 372.153942 -230.900478)
			(xy 372.153444 -230.927127) (xy 372.382024 -230.927127) (xy 372.382024 -230.873829) (xy 372.389967 -230.821125)
			(xy 372.405677 -230.770195) (xy 372.428803 -230.722174) (xy 372.458827 -230.678137) (xy 372.495079 -230.639066)
			(xy 372.53675 -230.605835) (xy 372.582908 -230.579186) (xy 372.632522 -230.559714) (xy 372.684484 -230.547854)
			(xy 372.737634 -230.543871) (xy 372.790784 -230.547854) (xy 372.842746 -230.559714) (xy 372.89236 -230.579186)
			(xy 372.938518 -230.605835) (xy 372.980189 -230.639066) (xy 373.016441 -230.678137) (xy 373.046465 -230.722174)
			(xy 373.069591 -230.770195) (xy 373.085301 -230.821125) (xy 373.093244 -230.873829) (xy 373.093742 -230.900478)
			(xy 373.093244 -230.927127) (xy 373.321824 -230.927127) (xy 373.321824 -230.873829) (xy 373.329767 -230.821125)
			(xy 373.345477 -230.770195) (xy 373.368603 -230.722174) (xy 373.398627 -230.678137) (xy 373.434879 -230.639066)
			(xy 373.47655 -230.605835) (xy 373.522708 -230.579186) (xy 373.572322 -230.559714) (xy 373.624284 -230.547854)
			(xy 373.677434 -230.543871) (xy 373.730584 -230.547854) (xy 373.782546 -230.559714) (xy 373.83216 -230.579186)
			(xy 373.878318 -230.605835) (xy 373.919989 -230.639066) (xy 373.956241 -230.678137) (xy 373.986265 -230.722174)
			(xy 374.009391 -230.770195) (xy 374.025101 -230.821125) (xy 374.033044 -230.873829) (xy 374.033542 -230.900478)
			(xy 374.033044 -230.927127) (xy 374.261624 -230.927127) (xy 374.261624 -230.873829) (xy 374.269567 -230.821125)
			(xy 374.285277 -230.770195) (xy 374.308403 -230.722174) (xy 374.338427 -230.678137) (xy 374.374679 -230.639066)
			(xy 374.41635 -230.605835) (xy 374.462508 -230.579186) (xy 374.512122 -230.559714) (xy 374.564084 -230.547854)
			(xy 374.617234 -230.543871) (xy 374.670384 -230.547854) (xy 374.722346 -230.559714) (xy 374.77196 -230.579186)
			(xy 374.818118 -230.605835) (xy 374.859789 -230.639066) (xy 374.896041 -230.678137) (xy 374.926065 -230.722174)
			(xy 374.949191 -230.770195) (xy 374.964901 -230.821125) (xy 374.972844 -230.873829) (xy 374.973342 -230.900478)
			(xy 374.972844 -230.927127) (xy 375.201424 -230.927127) (xy 375.201424 -230.873829) (xy 375.209367 -230.821125)
			(xy 375.225077 -230.770195) (xy 375.248203 -230.722174) (xy 375.278227 -230.678137) (xy 375.314479 -230.639066)
			(xy 375.35615 -230.605835) (xy 375.402308 -230.579186) (xy 375.451922 -230.559714) (xy 375.503884 -230.547854)
			(xy 375.557034 -230.543871) (xy 375.610184 -230.547854) (xy 375.662146 -230.559714) (xy 375.71176 -230.579186)
			(xy 375.757918 -230.605835) (xy 375.799589 -230.639066) (xy 375.835841 -230.678137) (xy 375.865865 -230.722174)
			(xy 375.888991 -230.770195) (xy 375.904701 -230.821125) (xy 375.912644 -230.873829) (xy 375.913142 -230.900478)
			(xy 375.912644 -230.927127) (xy 376.141224 -230.927127) (xy 376.141224 -230.873829) (xy 376.149167 -230.821125)
			(xy 376.164877 -230.770195) (xy 376.188003 -230.722174) (xy 376.218027 -230.678137) (xy 376.254279 -230.639066)
			(xy 376.29595 -230.605835) (xy 376.342108 -230.579186) (xy 376.391722 -230.559714) (xy 376.443684 -230.547854)
			(xy 376.496834 -230.543871) (xy 376.549984 -230.547854) (xy 376.601946 -230.559714) (xy 376.65156 -230.579186)
			(xy 376.697718 -230.605835) (xy 376.739389 -230.639066) (xy 376.775641 -230.678137) (xy 376.805665 -230.722174)
			(xy 376.828791 -230.770195) (xy 376.844501 -230.821125) (xy 376.852444 -230.873829) (xy 376.852942 -230.900478)
			(xy 376.852444 -230.927127) (xy 377.081024 -230.927127) (xy 377.081024 -230.873829) (xy 377.088967 -230.821125)
			(xy 377.104677 -230.770195) (xy 377.127803 -230.722174) (xy 377.157827 -230.678137) (xy 377.194079 -230.639066)
			(xy 377.23575 -230.605835) (xy 377.281908 -230.579186) (xy 377.331522 -230.559714) (xy 377.383484 -230.547854)
			(xy 377.436634 -230.543871) (xy 377.489784 -230.547854) (xy 377.541746 -230.559714) (xy 377.59136 -230.579186)
			(xy 377.637518 -230.605835) (xy 377.679189 -230.639066) (xy 377.715441 -230.678137) (xy 377.745465 -230.722174)
			(xy 377.768591 -230.770195) (xy 377.784301 -230.821125) (xy 377.792244 -230.873829) (xy 377.792742 -230.900478)
			(xy 377.792244 -230.927127) (xy 378.020824 -230.927127) (xy 378.020824 -230.873829) (xy 378.028767 -230.821125)
			(xy 378.044477 -230.770195) (xy 378.067603 -230.722174) (xy 378.097627 -230.678137) (xy 378.133879 -230.639066)
			(xy 378.17555 -230.605835) (xy 378.221708 -230.579186) (xy 378.271322 -230.559714) (xy 378.323284 -230.547854)
			(xy 378.376434 -230.543871) (xy 378.429584 -230.547854) (xy 378.481546 -230.559714) (xy 378.53116 -230.579186)
			(xy 378.577318 -230.605835) (xy 378.618989 -230.639066) (xy 378.655241 -230.678137) (xy 378.685265 -230.722174)
			(xy 378.708391 -230.770195) (xy 378.724101 -230.821125) (xy 378.732044 -230.873829) (xy 378.732542 -230.900478)
			(xy 378.732044 -230.927127) (xy 378.960624 -230.927127) (xy 378.960624 -230.873829) (xy 378.968567 -230.821125)
			(xy 378.984277 -230.770195) (xy 379.007403 -230.722174) (xy 379.037427 -230.678137) (xy 379.073679 -230.639066)
			(xy 379.11535 -230.605835) (xy 379.161508 -230.579186) (xy 379.211122 -230.559714) (xy 379.263084 -230.547854)
			(xy 379.316234 -230.543871) (xy 379.369384 -230.547854) (xy 379.421346 -230.559714) (xy 379.47096 -230.579186)
			(xy 379.517118 -230.605835) (xy 379.558789 -230.639066) (xy 379.595041 -230.678137) (xy 379.625065 -230.722174)
			(xy 379.648191 -230.770195) (xy 379.663901 -230.821125) (xy 379.671844 -230.873829) (xy 379.672342 -230.900478)
			(xy 379.671844 -230.927127) (xy 379.663901 -230.979831) (xy 379.648191 -231.030761) (xy 379.625065 -231.078782)
			(xy 379.595041 -231.122819) (xy 379.558789 -231.16189) (xy 379.517118 -231.195121) (xy 379.47096 -231.22177)
			(xy 379.421346 -231.241242) (xy 379.369384 -231.253102) (xy 379.316234 -231.257086) (xy 379.263084 -231.253102)
			(xy 379.211122 -231.241242) (xy 379.161508 -231.22177) (xy 379.11535 -231.195121) (xy 379.073679 -231.16189)
			(xy 379.037427 -231.122819) (xy 379.007403 -231.078782) (xy 378.984277 -231.030761) (xy 378.968567 -230.979831)
			(xy 378.960624 -230.927127) (xy 378.732044 -230.927127) (xy 378.724101 -230.979831) (xy 378.708391 -231.030761)
			(xy 378.685265 -231.078782) (xy 378.655241 -231.122819) (xy 378.618989 -231.16189) (xy 378.577318 -231.195121)
			(xy 378.53116 -231.22177) (xy 378.481546 -231.241242) (xy 378.429584 -231.253102) (xy 378.376434 -231.257086)
			(xy 378.323284 -231.253102) (xy 378.271322 -231.241242) (xy 378.221708 -231.22177) (xy 378.17555 -231.195121)
			(xy 378.133879 -231.16189) (xy 378.097627 -231.122819) (xy 378.067603 -231.078782) (xy 378.044477 -231.030761)
			(xy 378.028767 -230.979831) (xy 378.020824 -230.927127) (xy 377.792244 -230.927127) (xy 377.784301 -230.979831)
			(xy 377.768591 -231.030761) (xy 377.745465 -231.078782) (xy 377.715441 -231.122819) (xy 377.679189 -231.16189)
			(xy 377.637518 -231.195121) (xy 377.59136 -231.22177) (xy 377.541746 -231.241242) (xy 377.489784 -231.253102)
			(xy 377.436634 -231.257086) (xy 377.383484 -231.253102) (xy 377.331522 -231.241242) (xy 377.281908 -231.22177)
			(xy 377.23575 -231.195121) (xy 377.194079 -231.16189) (xy 377.157827 -231.122819) (xy 377.127803 -231.078782)
			(xy 377.104677 -231.030761) (xy 377.088967 -230.979831) (xy 377.081024 -230.927127) (xy 376.852444 -230.927127)
			(xy 376.844501 -230.979831) (xy 376.828791 -231.030761) (xy 376.805665 -231.078782) (xy 376.775641 -231.122819)
			(xy 376.739389 -231.16189) (xy 376.697718 -231.195121) (xy 376.65156 -231.22177) (xy 376.601946 -231.241242)
			(xy 376.549984 -231.253102) (xy 376.496834 -231.257086) (xy 376.443684 -231.253102) (xy 376.391722 -231.241242)
			(xy 376.342108 -231.22177) (xy 376.29595 -231.195121) (xy 376.254279 -231.16189) (xy 376.218027 -231.122819)
			(xy 376.188003 -231.078782) (xy 376.164877 -231.030761) (xy 376.149167 -230.979831) (xy 376.141224 -230.927127)
			(xy 375.912644 -230.927127) (xy 375.904701 -230.979831) (xy 375.888991 -231.030761) (xy 375.865865 -231.078782)
			(xy 375.835841 -231.122819) (xy 375.799589 -231.16189) (xy 375.757918 -231.195121) (xy 375.71176 -231.22177)
			(xy 375.662146 -231.241242) (xy 375.610184 -231.253102) (xy 375.557034 -231.257086) (xy 375.503884 -231.253102)
			(xy 375.451922 -231.241242) (xy 375.402308 -231.22177) (xy 375.35615 -231.195121) (xy 375.314479 -231.16189)
			(xy 375.278227 -231.122819) (xy 375.248203 -231.078782) (xy 375.225077 -231.030761) (xy 375.209367 -230.979831)
			(xy 375.201424 -230.927127) (xy 374.972844 -230.927127) (xy 374.964901 -230.979831) (xy 374.949191 -231.030761)
			(xy 374.926065 -231.078782) (xy 374.896041 -231.122819) (xy 374.859789 -231.16189) (xy 374.818118 -231.195121)
			(xy 374.77196 -231.22177) (xy 374.722346 -231.241242) (xy 374.670384 -231.253102) (xy 374.617234 -231.257086)
			(xy 374.564084 -231.253102) (xy 374.512122 -231.241242) (xy 374.462508 -231.22177) (xy 374.41635 -231.195121)
			(xy 374.374679 -231.16189) (xy 374.338427 -231.122819) (xy 374.308403 -231.078782) (xy 374.285277 -231.030761)
			(xy 374.269567 -230.979831) (xy 374.261624 -230.927127) (xy 374.033044 -230.927127) (xy 374.025101 -230.979831)
			(xy 374.009391 -231.030761) (xy 373.986265 -231.078782) (xy 373.956241 -231.122819) (xy 373.919989 -231.16189)
			(xy 373.878318 -231.195121) (xy 373.83216 -231.22177) (xy 373.782546 -231.241242) (xy 373.730584 -231.253102)
			(xy 373.677434 -231.257086) (xy 373.624284 -231.253102) (xy 373.572322 -231.241242) (xy 373.522708 -231.22177)
			(xy 373.47655 -231.195121) (xy 373.434879 -231.16189) (xy 373.398627 -231.122819) (xy 373.368603 -231.078782)
			(xy 373.345477 -231.030761) (xy 373.329767 -230.979831) (xy 373.321824 -230.927127) (xy 373.093244 -230.927127)
			(xy 373.085301 -230.979831) (xy 373.069591 -231.030761) (xy 373.046465 -231.078782) (xy 373.016441 -231.122819)
			(xy 372.980189 -231.16189) (xy 372.938518 -231.195121) (xy 372.89236 -231.22177) (xy 372.842746 -231.241242)
			(xy 372.790784 -231.253102) (xy 372.737634 -231.257086) (xy 372.684484 -231.253102) (xy 372.632522 -231.241242)
			(xy 372.582908 -231.22177) (xy 372.53675 -231.195121) (xy 372.495079 -231.16189) (xy 372.458827 -231.122819)
			(xy 372.428803 -231.078782) (xy 372.405677 -231.030761) (xy 372.389967 -230.979831) (xy 372.382024 -230.927127)
			(xy 372.153444 -230.927127) (xy 372.145501 -230.979831) (xy 372.129791 -231.030761) (xy 372.106665 -231.078782)
			(xy 372.076641 -231.122819) (xy 372.040389 -231.16189) (xy 371.998718 -231.195121) (xy 371.95256 -231.22177)
			(xy 371.902946 -231.241242) (xy 371.850984 -231.253102) (xy 371.797834 -231.257086) (xy 371.744684 -231.253102)
			(xy 371.692722 -231.241242) (xy 371.643108 -231.22177) (xy 371.59695 -231.195121) (xy 371.555279 -231.16189)
			(xy 371.519027 -231.122819) (xy 371.489003 -231.078782) (xy 371.465877 -231.030761) (xy 371.450167 -230.979831)
			(xy 371.442224 -230.927127) (xy 371.213644 -230.927127) (xy 371.205701 -230.979831) (xy 371.189991 -231.030761)
			(xy 371.166865 -231.078782) (xy 371.136841 -231.122819) (xy 371.100589 -231.16189) (xy 371.058918 -231.195121)
			(xy 371.01276 -231.22177) (xy 370.963146 -231.241242) (xy 370.911184 -231.253102) (xy 370.858034 -231.257086)
			(xy 370.804884 -231.253102) (xy 370.752922 -231.241242) (xy 370.703308 -231.22177) (xy 370.65715 -231.195121)
			(xy 370.615479 -231.16189) (xy 370.579227 -231.122819) (xy 370.549203 -231.078782) (xy 370.526077 -231.030761)
			(xy 370.510367 -230.979831) (xy 370.502424 -230.927127) (xy 370.27359 -230.927127) (xy 370.265647 -230.979831)
			(xy 370.249937 -231.030761) (xy 370.226811 -231.078782) (xy 370.196787 -231.122819) (xy 370.160535 -231.16189)
			(xy 370.118864 -231.195121) (xy 370.072706 -231.22177) (xy 370.023092 -231.241242) (xy 369.97113 -231.253102)
			(xy 369.91798 -231.257086) (xy 369.86483 -231.253102) (xy 369.812868 -231.241242) (xy 369.763254 -231.22177)
			(xy 369.717096 -231.195121) (xy 369.675425 -231.16189) (xy 369.639173 -231.122819) (xy 369.609149 -231.078782)
			(xy 369.586023 -231.030761) (xy 369.570313 -230.979831) (xy 369.56237 -230.927127) (xy 369.334044 -230.927127)
			(xy 369.326101 -230.979831) (xy 369.310391 -231.030761) (xy 369.287265 -231.078782) (xy 369.257241 -231.122819)
			(xy 369.220989 -231.16189) (xy 369.179318 -231.195121) (xy 369.13316 -231.22177) (xy 369.083546 -231.241242)
			(xy 369.031584 -231.253102) (xy 368.978434 -231.257086) (xy 368.925284 -231.253102) (xy 368.873322 -231.241242)
			(xy 368.823708 -231.22177) (xy 368.77755 -231.195121) (xy 368.735879 -231.16189) (xy 368.699627 -231.122819)
			(xy 368.669603 -231.078782) (xy 368.646477 -231.030761) (xy 368.630767 -230.979831) (xy 368.622824 -230.927127)
			(xy 368.394244 -230.927127) (xy 368.386301 -230.979831) (xy 368.370591 -231.030761) (xy 368.347465 -231.078782)
			(xy 368.317441 -231.122819) (xy 368.281189 -231.16189) (xy 368.239518 -231.195121) (xy 368.19336 -231.22177)
			(xy 368.143746 -231.241242) (xy 368.091784 -231.253102) (xy 368.038634 -231.257086) (xy 367.985484 -231.253102)
			(xy 367.933522 -231.241242) (xy 367.883908 -231.22177) (xy 367.83775 -231.195121) (xy 367.796079 -231.16189)
			(xy 367.759827 -231.122819) (xy 367.729803 -231.078782) (xy 367.706677 -231.030761) (xy 367.690967 -230.979831)
			(xy 367.683024 -230.927127) (xy 367.454444 -230.927127) (xy 367.446501 -230.979831) (xy 367.430791 -231.030761)
			(xy 367.407665 -231.078782) (xy 367.377641 -231.122819) (xy 367.341389 -231.16189) (xy 367.299718 -231.195121)
			(xy 367.25356 -231.22177) (xy 367.203946 -231.241242) (xy 367.151984 -231.253102) (xy 367.098834 -231.257086)
			(xy 367.045684 -231.253102) (xy 366.993722 -231.241242) (xy 366.944108 -231.22177) (xy 366.89795 -231.195121)
			(xy 366.856279 -231.16189) (xy 366.820027 -231.122819) (xy 366.790003 -231.078782) (xy 366.766877 -231.030761)
			(xy 366.751167 -230.979831) (xy 366.743224 -230.927127) (xy 366.514644 -230.927127) (xy 366.506701 -230.979831)
			(xy 366.490991 -231.030761) (xy 366.467865 -231.078782) (xy 366.437841 -231.122819) (xy 366.401589 -231.16189)
			(xy 366.359918 -231.195121) (xy 366.31376 -231.22177) (xy 366.264146 -231.241242) (xy 366.212184 -231.253102)
			(xy 366.159034 -231.257086) (xy 366.105884 -231.253102) (xy 366.053922 -231.241242) (xy 366.004308 -231.22177)
			(xy 365.95815 -231.195121) (xy 365.916479 -231.16189) (xy 365.880227 -231.122819) (xy 365.850203 -231.078782)
			(xy 365.827077 -231.030761) (xy 365.811367 -230.979831) (xy 365.803424 -230.927127) (xy 365.574844 -230.927127)
			(xy 365.566901 -230.979831) (xy 365.551191 -231.030761) (xy 365.528065 -231.078782) (xy 365.498041 -231.122819)
			(xy 365.461789 -231.16189) (xy 365.420118 -231.195121) (xy 365.37396 -231.22177) (xy 365.324346 -231.241242)
			(xy 365.272384 -231.253102) (xy 365.219234 -231.257086) (xy 365.166084 -231.253102) (xy 365.114122 -231.241242)
			(xy 365.064508 -231.22177) (xy 365.01835 -231.195121) (xy 364.976679 -231.16189) (xy 364.940427 -231.122819)
			(xy 364.910403 -231.078782) (xy 364.887277 -231.030761) (xy 364.871567 -230.979831) (xy 364.863624 -230.927127)
			(xy 364.635044 -230.927127) (xy 364.627101 -230.979831) (xy 364.611391 -231.030761) (xy 364.588265 -231.078782)
			(xy 364.558241 -231.122819) (xy 364.521989 -231.16189) (xy 364.480318 -231.195121) (xy 364.43416 -231.22177)
			(xy 364.384546 -231.241242) (xy 364.332584 -231.253102) (xy 364.279434 -231.257086) (xy 364.226284 -231.253102)
			(xy 364.174322 -231.241242) (xy 364.124708 -231.22177) (xy 364.07855 -231.195121) (xy 364.036879 -231.16189)
			(xy 364.000627 -231.122819) (xy 363.970603 -231.078782) (xy 363.947477 -231.030761) (xy 363.931767 -230.979831)
			(xy 363.923824 -230.927127) (xy 363.695244 -230.927127) (xy 363.687301 -230.979831) (xy 363.671591 -231.030761)
			(xy 363.648465 -231.078782) (xy 363.618441 -231.122819) (xy 363.582189 -231.16189) (xy 363.540518 -231.195121)
			(xy 363.49436 -231.22177) (xy 363.444746 -231.241242) (xy 363.392784 -231.253102) (xy 363.339634 -231.257086)
			(xy 363.286484 -231.253102) (xy 363.234522 -231.241242) (xy 363.184908 -231.22177) (xy 363.13875 -231.195121)
			(xy 363.097079 -231.16189) (xy 363.060827 -231.122819) (xy 363.030803 -231.078782) (xy 363.007677 -231.030761)
			(xy 362.991967 -230.979831) (xy 362.984024 -230.927127) (xy 362.755698 -230.927127) (xy 362.747755 -230.979831)
			(xy 362.732045 -231.030761) (xy 362.708919 -231.078782) (xy 362.678895 -231.122819) (xy 362.642643 -231.16189)
			(xy 362.600972 -231.195121) (xy 362.554814 -231.22177) (xy 362.5052 -231.241242) (xy 362.453238 -231.253102)
			(xy 362.400088 -231.257086) (xy 362.346938 -231.253102) (xy 362.294976 -231.241242) (xy 362.245362 -231.22177)
			(xy 362.199204 -231.195121) (xy 362.157533 -231.16189) (xy 362.121281 -231.122819) (xy 362.091257 -231.078782)
			(xy 362.068131 -231.030761) (xy 362.052421 -230.979831) (xy 362.044478 -230.927127) (xy 361.815644 -230.927127)
			(xy 361.807701 -230.979831) (xy 361.791991 -231.030761) (xy 361.768865 -231.078782) (xy 361.738841 -231.122819)
			(xy 361.702589 -231.16189) (xy 361.660918 -231.195121) (xy 361.61476 -231.22177) (xy 361.565146 -231.241242)
			(xy 361.513184 -231.253102) (xy 361.460034 -231.257086) (xy 361.406884 -231.253102) (xy 361.354922 -231.241242)
			(xy 361.305308 -231.22177) (xy 361.25915 -231.195121) (xy 361.217479 -231.16189) (xy 361.181227 -231.122819)
			(xy 361.151203 -231.078782) (xy 361.128077 -231.030761) (xy 361.112367 -230.979831) (xy 361.104424 -230.927127)
			(xy 360.875844 -230.927127) (xy 360.867901 -230.979831) (xy 360.852191 -231.030761) (xy 360.829065 -231.078782)
			(xy 360.799041 -231.122819) (xy 360.762789 -231.16189) (xy 360.721118 -231.195121) (xy 360.67496 -231.22177)
			(xy 360.625346 -231.241242) (xy 360.573384 -231.253102) (xy 360.520234 -231.257086) (xy 360.467084 -231.253102)
			(xy 360.415122 -231.241242) (xy 360.365508 -231.22177) (xy 360.31935 -231.195121) (xy 360.277679 -231.16189)
			(xy 360.241427 -231.122819) (xy 360.211403 -231.078782) (xy 360.188277 -231.030761) (xy 360.172567 -230.979831)
			(xy 360.164624 -230.927127) (xy 359.936044 -230.927127) (xy 359.928101 -230.979831) (xy 359.912391 -231.030761)
			(xy 359.889265 -231.078782) (xy 359.859241 -231.122819) (xy 359.822989 -231.16189) (xy 359.781318 -231.195121)
			(xy 359.73516 -231.22177) (xy 359.685546 -231.241242) (xy 359.633584 -231.253102) (xy 359.580434 -231.257086)
			(xy 359.527284 -231.253102) (xy 359.475322 -231.241242) (xy 359.425708 -231.22177) (xy 359.37955 -231.195121)
			(xy 359.337879 -231.16189) (xy 359.301627 -231.122819) (xy 359.271603 -231.078782) (xy 359.248477 -231.030761)
			(xy 359.232767 -230.979831) (xy 359.224824 -230.927127) (xy 358.996244 -230.927127) (xy 358.988301 -230.979831)
			(xy 358.972591 -231.030761) (xy 358.949465 -231.078782) (xy 358.919441 -231.122819) (xy 358.883189 -231.16189)
			(xy 358.841518 -231.195121) (xy 358.79536 -231.22177) (xy 358.745746 -231.241242) (xy 358.693784 -231.253102)
			(xy 358.640634 -231.257086) (xy 358.587484 -231.253102) (xy 358.535522 -231.241242) (xy 358.485908 -231.22177)
			(xy 358.43975 -231.195121) (xy 358.398079 -231.16189) (xy 358.361827 -231.122819) (xy 358.331803 -231.078782)
			(xy 358.308677 -231.030761) (xy 358.292967 -230.979831) (xy 358.285024 -230.927127) (xy 358.05619 -230.927127)
			(xy 358.048247 -230.979831) (xy 358.032537 -231.030761) (xy 358.009411 -231.078782) (xy 357.979387 -231.122819)
			(xy 357.943135 -231.16189) (xy 357.901464 -231.195121) (xy 357.855306 -231.22177) (xy 357.805692 -231.241242)
			(xy 357.75373 -231.253102) (xy 357.70058 -231.257086) (xy 357.64743 -231.253102) (xy 357.595468 -231.241242)
			(xy 357.545854 -231.22177) (xy 357.499696 -231.195121) (xy 357.458025 -231.16189) (xy 357.421773 -231.122819)
			(xy 357.391749 -231.078782) (xy 357.368623 -231.030761) (xy 357.352913 -230.979831) (xy 357.34497 -230.927127)
			(xy 357.116644 -230.927127) (xy 357.108701 -230.979831) (xy 357.092991 -231.030761) (xy 357.069865 -231.078782)
			(xy 357.039841 -231.122819) (xy 357.003589 -231.16189) (xy 356.961918 -231.195121) (xy 356.91576 -231.22177)
			(xy 356.866146 -231.241242) (xy 356.814184 -231.253102) (xy 356.761034 -231.257086) (xy 356.707884 -231.253102)
			(xy 356.655922 -231.241242) (xy 356.606308 -231.22177) (xy 356.56015 -231.195121) (xy 356.518479 -231.16189)
			(xy 356.482227 -231.122819) (xy 356.452203 -231.078782) (xy 356.429077 -231.030761) (xy 356.413367 -230.979831)
			(xy 356.405424 -230.927127) (xy 356.17659 -230.927127) (xy 356.168647 -230.979831) (xy 356.152937 -231.030761)
			(xy 356.129811 -231.078782) (xy 356.099787 -231.122819) (xy 356.063535 -231.16189) (xy 356.021864 -231.195121)
			(xy 355.975706 -231.22177) (xy 355.926092 -231.241242) (xy 355.87413 -231.253102) (xy 355.82098 -231.257086)
			(xy 355.76783 -231.253102) (xy 355.715868 -231.241242) (xy 355.666254 -231.22177) (xy 355.620096 -231.195121)
			(xy 355.578425 -231.16189) (xy 355.542173 -231.122819) (xy 355.512149 -231.078782) (xy 355.489023 -231.030761)
			(xy 355.473313 -230.979831) (xy 355.46537 -230.927127) (xy 355.237044 -230.927127) (xy 355.229101 -230.979831)
			(xy 355.213391 -231.030761) (xy 355.190265 -231.078782) (xy 355.160241 -231.122819) (xy 355.123989 -231.16189)
			(xy 355.082318 -231.195121) (xy 355.03616 -231.22177) (xy 354.986546 -231.241242) (xy 354.934584 -231.253102)
			(xy 354.881434 -231.257086) (xy 354.828284 -231.253102) (xy 354.776322 -231.241242) (xy 354.726708 -231.22177)
			(xy 354.68055 -231.195121) (xy 354.638879 -231.16189) (xy 354.602627 -231.122819) (xy 354.572603 -231.078782)
			(xy 354.549477 -231.030761) (xy 354.533767 -230.979831) (xy 354.525824 -230.927127) (xy 354.297244 -230.927127)
			(xy 354.289301 -230.979831) (xy 354.273591 -231.030761) (xy 354.250465 -231.078782) (xy 354.220441 -231.122819)
			(xy 354.184189 -231.16189) (xy 354.142518 -231.195121) (xy 354.09636 -231.22177) (xy 354.046746 -231.241242)
			(xy 353.994784 -231.253102) (xy 353.941634 -231.257086) (xy 353.888484 -231.253102) (xy 353.836522 -231.241242)
			(xy 353.786908 -231.22177) (xy 353.74075 -231.195121) (xy 353.699079 -231.16189) (xy 353.662827 -231.122819)
			(xy 353.632803 -231.078782) (xy 353.609677 -231.030761) (xy 353.593967 -230.979831) (xy 353.586024 -230.927127)
			(xy 353.357444 -230.927127) (xy 353.349501 -230.979831) (xy 353.333791 -231.030761) (xy 353.310665 -231.078782)
			(xy 353.280641 -231.122819) (xy 353.244389 -231.16189) (xy 353.202718 -231.195121) (xy 353.15656 -231.22177)
			(xy 353.106946 -231.241242) (xy 353.054984 -231.253102) (xy 353.001834 -231.257086) (xy 352.948684 -231.253102)
			(xy 352.896722 -231.241242) (xy 352.847108 -231.22177) (xy 352.80095 -231.195121) (xy 352.759279 -231.16189)
			(xy 352.723027 -231.122819) (xy 352.693003 -231.078782) (xy 352.669877 -231.030761) (xy 352.654167 -230.979831)
			(xy 352.646224 -230.927127) (xy 352.417644 -230.927127) (xy 352.409701 -230.979831) (xy 352.393991 -231.030761)
			(xy 352.370865 -231.078782) (xy 352.340841 -231.122819) (xy 352.304589 -231.16189) (xy 352.262918 -231.195121)
			(xy 352.21676 -231.22177) (xy 352.167146 -231.241242) (xy 352.115184 -231.253102) (xy 352.062034 -231.257086)
			(xy 352.008884 -231.253102) (xy 351.956922 -231.241242) (xy 351.907308 -231.22177) (xy 351.86115 -231.195121)
			(xy 351.819479 -231.16189) (xy 351.783227 -231.122819) (xy 351.753203 -231.078782) (xy 351.730077 -231.030761)
			(xy 351.714367 -230.979831) (xy 351.706424 -230.927127) (xy 351.477844 -230.927127) (xy 351.469901 -230.979831)
			(xy 351.454191 -231.030761) (xy 351.431065 -231.078782) (xy 351.401041 -231.122819) (xy 351.364789 -231.16189)
			(xy 351.323118 -231.195121) (xy 351.27696 -231.22177) (xy 351.227346 -231.241242) (xy 351.175384 -231.253102)
			(xy 351.122234 -231.257086) (xy 351.069084 -231.253102) (xy 351.017122 -231.241242) (xy 350.967508 -231.22177)
			(xy 350.92135 -231.195121) (xy 350.879679 -231.16189) (xy 350.843427 -231.122819) (xy 350.813403 -231.078782)
			(xy 350.790277 -231.030761) (xy 350.774567 -230.979831) (xy 350.766624 -230.927127) (xy 350.538044 -230.927127)
			(xy 350.530101 -230.979831) (xy 350.514391 -231.030761) (xy 350.491265 -231.078782) (xy 350.461241 -231.122819)
			(xy 350.424989 -231.16189) (xy 350.383318 -231.195121) (xy 350.33716 -231.22177) (xy 350.287546 -231.241242)
			(xy 350.235584 -231.253102) (xy 350.182434 -231.257086) (xy 350.129284 -231.253102) (xy 350.077322 -231.241242)
			(xy 350.027708 -231.22177) (xy 349.98155 -231.195121) (xy 349.939879 -231.16189) (xy 349.903627 -231.122819)
			(xy 349.873603 -231.078782) (xy 349.850477 -231.030761) (xy 349.834767 -230.979831) (xy 349.826824 -230.927127)
			(xy 349.598244 -230.927127) (xy 349.590301 -230.979831) (xy 349.574591 -231.030761) (xy 349.551465 -231.078782)
			(xy 349.521441 -231.122819) (xy 349.485189 -231.16189) (xy 349.443518 -231.195121) (xy 349.39736 -231.22177)
			(xy 349.347746 -231.241242) (xy 349.295784 -231.253102) (xy 349.242634 -231.257086) (xy 349.189484 -231.253102)
			(xy 349.137522 -231.241242) (xy 349.087908 -231.22177) (xy 349.04175 -231.195121) (xy 349.000079 -231.16189)
			(xy 348.963827 -231.122819) (xy 348.933803 -231.078782) (xy 348.910677 -231.030761) (xy 348.894967 -230.979831)
			(xy 348.887024 -230.927127) (xy 348.658444 -230.927127) (xy 348.650501 -230.979831) (xy 348.634791 -231.030761)
			(xy 348.611665 -231.078782) (xy 348.581641 -231.122819) (xy 348.545389 -231.16189) (xy 348.503718 -231.195121)
			(xy 348.45756 -231.22177) (xy 348.407946 -231.241242) (xy 348.355984 -231.253102) (xy 348.302834 -231.257086)
			(xy 348.249684 -231.253102) (xy 348.197722 -231.241242) (xy 348.148108 -231.22177) (xy 348.10195 -231.195121)
			(xy 348.060279 -231.16189) (xy 348.024027 -231.122819) (xy 347.994003 -231.078782) (xy 347.970877 -231.030761)
			(xy 347.955167 -230.979831) (xy 347.947224 -230.927127) (xy 347.718644 -230.927127) (xy 347.710701 -230.979831)
			(xy 347.694991 -231.030761) (xy 347.671865 -231.078782) (xy 347.641841 -231.122819) (xy 347.605589 -231.16189)
			(xy 347.563918 -231.195121) (xy 347.51776 -231.22177) (xy 347.468146 -231.241242) (xy 347.416184 -231.253102)
			(xy 347.363034 -231.257086) (xy 347.309884 -231.253102) (xy 347.257922 -231.241242) (xy 347.208308 -231.22177)
			(xy 347.16215 -231.195121) (xy 347.120479 -231.16189) (xy 347.084227 -231.122819) (xy 347.054203 -231.078782)
			(xy 347.031077 -231.030761) (xy 347.015367 -230.979831) (xy 347.007424 -230.927127) (xy 346.778844 -230.927127)
			(xy 346.770901 -230.979831) (xy 346.755191 -231.030761) (xy 346.732065 -231.078782) (xy 346.702041 -231.122819)
			(xy 346.665789 -231.16189) (xy 346.624118 -231.195121) (xy 346.57796 -231.22177) (xy 346.528346 -231.241242)
			(xy 346.476384 -231.253102) (xy 346.423234 -231.257086) (xy 346.370084 -231.253102) (xy 346.318122 -231.241242)
			(xy 346.268508 -231.22177) (xy 346.22235 -231.195121) (xy 346.180679 -231.16189) (xy 346.144427 -231.122819)
			(xy 346.114403 -231.078782) (xy 346.091277 -231.030761) (xy 346.075567 -230.979831) (xy 346.067624 -230.927127)
			(xy 345.83879 -230.927127) (xy 345.830847 -230.979831) (xy 345.815137 -231.030761) (xy 345.792011 -231.078782)
			(xy 345.761987 -231.122819) (xy 345.725735 -231.16189) (xy 345.684064 -231.195121) (xy 345.637906 -231.22177)
			(xy 345.588292 -231.241242) (xy 345.53633 -231.253102) (xy 345.48318 -231.257086) (xy 345.43003 -231.253102)
			(xy 345.378068 -231.241242) (xy 345.328454 -231.22177) (xy 345.282296 -231.195121) (xy 345.240625 -231.16189)
			(xy 345.204373 -231.122819) (xy 345.174349 -231.078782) (xy 345.151223 -231.030761) (xy 345.135513 -230.979831)
			(xy 345.12757 -230.927127) (xy 344.899244 -230.927127) (xy 344.891301 -230.979831) (xy 344.875591 -231.030761)
			(xy 344.852465 -231.078782) (xy 344.822441 -231.122819) (xy 344.786189 -231.16189) (xy 344.744518 -231.195121)
			(xy 344.69836 -231.22177) (xy 344.648746 -231.241242) (xy 344.596784 -231.253102) (xy 344.543634 -231.257086)
			(xy 344.490484 -231.253102) (xy 344.438522 -231.241242) (xy 344.388908 -231.22177) (xy 344.34275 -231.195121)
			(xy 344.301079 -231.16189) (xy 344.264827 -231.122819) (xy 344.234803 -231.078782) (xy 344.211677 -231.030761)
			(xy 344.195967 -230.979831) (xy 344.188024 -230.927127) (xy 343.959444 -230.927127) (xy 343.951501 -230.979831)
			(xy 343.935791 -231.030761) (xy 343.912665 -231.078782) (xy 343.882641 -231.122819) (xy 343.846389 -231.16189)
			(xy 343.804718 -231.195121) (xy 343.75856 -231.22177) (xy 343.708946 -231.241242) (xy 343.656984 -231.253102)
			(xy 343.603834 -231.257086) (xy 343.550684 -231.253102) (xy 343.498722 -231.241242) (xy 343.449108 -231.22177)
			(xy 343.40295 -231.195121) (xy 343.361279 -231.16189) (xy 343.325027 -231.122819) (xy 343.295003 -231.078782)
			(xy 343.271877 -231.030761) (xy 343.256167 -230.979831) (xy 343.248224 -230.927127) (xy 343.019644 -230.927127)
			(xy 343.011701 -230.979831) (xy 342.995991 -231.030761) (xy 342.972865 -231.078782) (xy 342.942841 -231.122819)
			(xy 342.906589 -231.16189) (xy 342.864918 -231.195121) (xy 342.81876 -231.22177) (xy 342.769146 -231.241242)
			(xy 342.717184 -231.253102) (xy 342.664034 -231.257086) (xy 342.610884 -231.253102) (xy 342.558922 -231.241242)
			(xy 342.509308 -231.22177) (xy 342.46315 -231.195121) (xy 342.421479 -231.16189) (xy 342.385227 -231.122819)
			(xy 342.355203 -231.078782) (xy 342.332077 -231.030761) (xy 342.316367 -230.979831) (xy 342.308424 -230.927127)
			(xy 342.079844 -230.927127) (xy 342.071901 -230.979831) (xy 342.056191 -231.030761) (xy 342.033065 -231.078782)
			(xy 342.003041 -231.122819) (xy 341.966789 -231.16189) (xy 341.925118 -231.195121) (xy 341.87896 -231.22177)
			(xy 341.829346 -231.241242) (xy 341.777384 -231.253102) (xy 341.724234 -231.257086) (xy 341.671084 -231.253102)
			(xy 341.619122 -231.241242) (xy 341.569508 -231.22177) (xy 341.52335 -231.195121) (xy 341.481679 -231.16189)
			(xy 341.445427 -231.122819) (xy 341.415403 -231.078782) (xy 341.392277 -231.030761) (xy 341.376567 -230.979831)
			(xy 341.368624 -230.927127) (xy 341.140044 -230.927127) (xy 341.132101 -230.979831) (xy 341.116391 -231.030761)
			(xy 341.093265 -231.078782) (xy 341.063241 -231.122819) (xy 341.026989 -231.16189) (xy 340.985318 -231.195121)
			(xy 340.93916 -231.22177) (xy 340.889546 -231.241242) (xy 340.837584 -231.253102) (xy 340.784434 -231.257086)
			(xy 340.731284 -231.253102) (xy 340.679322 -231.241242) (xy 340.629708 -231.22177) (xy 340.58355 -231.195121)
			(xy 340.541879 -231.16189) (xy 340.505627 -231.122819) (xy 340.475603 -231.078782) (xy 340.452477 -231.030761)
			(xy 340.436767 -230.979831) (xy 340.428824 -230.927127) (xy 340.200244 -230.927127) (xy 340.192301 -230.979831)
			(xy 340.176591 -231.030761) (xy 340.153465 -231.078782) (xy 340.123441 -231.122819) (xy 340.087189 -231.16189)
			(xy 340.045518 -231.195121) (xy 339.99936 -231.22177) (xy 339.949746 -231.241242) (xy 339.897784 -231.253102)
			(xy 339.844634 -231.257086) (xy 339.791484 -231.253102) (xy 339.739522 -231.241242) (xy 339.689908 -231.22177)
			(xy 339.64375 -231.195121) (xy 339.602079 -231.16189) (xy 339.565827 -231.122819) (xy 339.535803 -231.078782)
			(xy 339.512677 -231.030761) (xy 339.496967 -230.979831) (xy 339.489024 -230.927127) (xy 339.37956 -230.927127)
			(xy 339.37956 -231.355646) (xy 339.423502 -231.361742) (xy 339.45005 -231.365924) (xy 339.501565 -231.381232)
			(xy 339.550196 -231.404107) (xy 339.594838 -231.434028) (xy 339.634477 -231.470318) (xy 339.668214 -231.512151)
			(xy 339.695282 -231.558578) (xy 339.715068 -231.608545) (xy 339.727121 -231.660918) (xy 339.731169 -231.714507)
			(xy 339.729152 -231.741197) (xy 339.95867 -231.741197) (xy 339.95867 -231.687899) (xy 339.966613 -231.635195)
			(xy 339.982323 -231.584265) (xy 340.005449 -231.536244) (xy 340.035473 -231.492207) (xy 340.071725 -231.453136)
			(xy 340.113396 -231.419905) (xy 340.159554 -231.393256) (xy 340.209168 -231.373784) (xy 340.26113 -231.361924)
			(xy 340.31428 -231.357941) (xy 340.36743 -231.361924) (xy 340.419392 -231.373784) (xy 340.469006 -231.393256)
			(xy 340.515164 -231.419905) (xy 340.556835 -231.453136) (xy 340.593087 -231.492207) (xy 340.623111 -231.536244)
			(xy 340.646237 -231.584265) (xy 340.661947 -231.635195) (xy 340.66989 -231.687899) (xy 340.670388 -231.714548)
			(xy 340.66989 -231.741197) (xy 340.89847 -231.741197) (xy 340.89847 -231.687899) (xy 340.906413 -231.635195)
			(xy 340.922123 -231.584265) (xy 340.945249 -231.536244) (xy 340.975273 -231.492207) (xy 341.011525 -231.453136)
			(xy 341.053196 -231.419905) (xy 341.099354 -231.393256) (xy 341.148968 -231.373784) (xy 341.20093 -231.361924)
			(xy 341.25408 -231.357941) (xy 341.30723 -231.361924) (xy 341.359192 -231.373784) (xy 341.408806 -231.393256)
			(xy 341.454964 -231.419905) (xy 341.496635 -231.453136) (xy 341.532887 -231.492207) (xy 341.562911 -231.536244)
			(xy 341.586037 -231.584265) (xy 341.601747 -231.635195) (xy 341.60969 -231.687899) (xy 341.610188 -231.714548)
			(xy 341.60969 -231.741197) (xy 341.838524 -231.741197) (xy 341.838524 -231.687899) (xy 341.846467 -231.635195)
			(xy 341.862177 -231.584265) (xy 341.885303 -231.536244) (xy 341.915327 -231.492207) (xy 341.951579 -231.453136)
			(xy 341.99325 -231.419905) (xy 342.039408 -231.393256) (xy 342.089022 -231.373784) (xy 342.140984 -231.361924)
			(xy 342.194134 -231.357941) (xy 342.247284 -231.361924) (xy 342.299246 -231.373784) (xy 342.34886 -231.393256)
			(xy 342.395018 -231.419905) (xy 342.436689 -231.453136) (xy 342.472941 -231.492207) (xy 342.502965 -231.536244)
			(xy 342.526091 -231.584265) (xy 342.541801 -231.635195) (xy 342.549744 -231.687899) (xy 342.550242 -231.714548)
			(xy 342.549744 -231.741197) (xy 342.77807 -231.741197) (xy 342.77807 -231.687899) (xy 342.786013 -231.635195)
			(xy 342.801723 -231.584265) (xy 342.824849 -231.536244) (xy 342.854873 -231.492207) (xy 342.891125 -231.453136)
			(xy 342.932796 -231.419905) (xy 342.978954 -231.393256) (xy 343.028568 -231.373784) (xy 343.08053 -231.361924)
			(xy 343.13368 -231.357941) (xy 343.18683 -231.361924) (xy 343.238792 -231.373784) (xy 343.288406 -231.393256)
			(xy 343.334564 -231.419905) (xy 343.376235 -231.453136) (xy 343.412487 -231.492207) (xy 343.442511 -231.536244)
			(xy 343.465637 -231.584265) (xy 343.481347 -231.635195) (xy 343.48929 -231.687899) (xy 343.489788 -231.714548)
			(xy 343.48929 -231.741197) (xy 343.71787 -231.741197) (xy 343.71787 -231.687899) (xy 343.725813 -231.635195)
			(xy 343.741523 -231.584265) (xy 343.764649 -231.536244) (xy 343.794673 -231.492207) (xy 343.830925 -231.453136)
			(xy 343.872596 -231.419905) (xy 343.918754 -231.393256) (xy 343.968368 -231.373784) (xy 344.02033 -231.361924)
			(xy 344.07348 -231.357941) (xy 344.12663 -231.361924) (xy 344.178592 -231.373784) (xy 344.228206 -231.393256)
			(xy 344.274364 -231.419905) (xy 344.316035 -231.453136) (xy 344.352287 -231.492207) (xy 344.382311 -231.536244)
			(xy 344.405437 -231.584265) (xy 344.421147 -231.635195) (xy 344.42909 -231.687899) (xy 344.429588 -231.714548)
			(xy 344.42909 -231.741197) (xy 344.65767 -231.741197) (xy 344.65767 -231.687899) (xy 344.665613 -231.635195)
			(xy 344.681323 -231.584265) (xy 344.704449 -231.536244) (xy 344.734473 -231.492207) (xy 344.770725 -231.453136)
			(xy 344.812396 -231.419905) (xy 344.858554 -231.393256) (xy 344.908168 -231.373784) (xy 344.96013 -231.361924)
			(xy 345.01328 -231.357941) (xy 345.06643 -231.361924) (xy 345.118392 -231.373784) (xy 345.168006 -231.393256)
			(xy 345.214164 -231.419905) (xy 345.255835 -231.453136) (xy 345.292087 -231.492207) (xy 345.322111 -231.536244)
			(xy 345.345237 -231.584265) (xy 345.360947 -231.635195) (xy 345.36889 -231.687899) (xy 345.369388 -231.714548)
			(xy 345.36889 -231.741197) (xy 345.59747 -231.741197) (xy 345.59747 -231.687899) (xy 345.605413 -231.635195)
			(xy 345.621123 -231.584265) (xy 345.644249 -231.536244) (xy 345.674273 -231.492207) (xy 345.710525 -231.453136)
			(xy 345.752196 -231.419905) (xy 345.798354 -231.393256) (xy 345.847968 -231.373784) (xy 345.89993 -231.361924)
			(xy 345.95308 -231.357941) (xy 346.00623 -231.361924) (xy 346.058192 -231.373784) (xy 346.107806 -231.393256)
			(xy 346.153964 -231.419905) (xy 346.195635 -231.453136) (xy 346.231887 -231.492207) (xy 346.261911 -231.536244)
			(xy 346.285037 -231.584265) (xy 346.300747 -231.635195) (xy 346.30869 -231.687899) (xy 346.309188 -231.714548)
			(xy 346.30869 -231.741197) (xy 346.53727 -231.741197) (xy 346.53727 -231.687899) (xy 346.545213 -231.635195)
			(xy 346.560923 -231.584265) (xy 346.584049 -231.536244) (xy 346.614073 -231.492207) (xy 346.650325 -231.453136)
			(xy 346.691996 -231.419905) (xy 346.738154 -231.393256) (xy 346.787768 -231.373784) (xy 346.83973 -231.361924)
			(xy 346.89288 -231.357941) (xy 346.94603 -231.361924) (xy 346.997992 -231.373784) (xy 347.047606 -231.393256)
			(xy 347.093764 -231.419905) (xy 347.135435 -231.453136) (xy 347.171687 -231.492207) (xy 347.201711 -231.536244)
			(xy 347.224837 -231.584265) (xy 347.240547 -231.635195) (xy 347.24849 -231.687899) (xy 347.248988 -231.714548)
			(xy 347.24849 -231.741197) (xy 347.47707 -231.741197) (xy 347.47707 -231.687899) (xy 347.485013 -231.635195)
			(xy 347.500723 -231.584265) (xy 347.523849 -231.536244) (xy 347.553873 -231.492207) (xy 347.590125 -231.453136)
			(xy 347.631796 -231.419905) (xy 347.677954 -231.393256) (xy 347.727568 -231.373784) (xy 347.77953 -231.361924)
			(xy 347.83268 -231.357941) (xy 347.88583 -231.361924) (xy 347.937792 -231.373784) (xy 347.987406 -231.393256)
			(xy 348.033564 -231.419905) (xy 348.075235 -231.453136) (xy 348.111487 -231.492207) (xy 348.141511 -231.536244)
			(xy 348.164637 -231.584265) (xy 348.180347 -231.635195) (xy 348.18829 -231.687899) (xy 348.188788 -231.714548)
			(xy 348.18829 -231.741197) (xy 348.417124 -231.741197) (xy 348.417124 -231.687899) (xy 348.425067 -231.635195)
			(xy 348.440777 -231.584265) (xy 348.463903 -231.536244) (xy 348.493927 -231.492207) (xy 348.530179 -231.453136)
			(xy 348.57185 -231.419905) (xy 348.618008 -231.393256) (xy 348.667622 -231.373784) (xy 348.719584 -231.361924)
			(xy 348.772734 -231.357941) (xy 348.825884 -231.361924) (xy 348.877846 -231.373784) (xy 348.92746 -231.393256)
			(xy 348.973618 -231.419905) (xy 349.015289 -231.453136) (xy 349.051541 -231.492207) (xy 349.081565 -231.536244)
			(xy 349.104691 -231.584265) (xy 349.120401 -231.635195) (xy 349.128344 -231.687899) (xy 349.128842 -231.714548)
			(xy 349.128344 -231.741197) (xy 349.35667 -231.741197) (xy 349.35667 -231.687899) (xy 349.364613 -231.635195)
			(xy 349.380323 -231.584265) (xy 349.403449 -231.536244) (xy 349.433473 -231.492207) (xy 349.469725 -231.453136)
			(xy 349.511396 -231.419905) (xy 349.557554 -231.393256) (xy 349.607168 -231.373784) (xy 349.65913 -231.361924)
			(xy 349.71228 -231.357941) (xy 349.76543 -231.361924) (xy 349.817392 -231.373784) (xy 349.867006 -231.393256)
			(xy 349.913164 -231.419905) (xy 349.954835 -231.453136) (xy 349.991087 -231.492207) (xy 350.021111 -231.536244)
			(xy 350.044237 -231.584265) (xy 350.059947 -231.635195) (xy 350.06789 -231.687899) (xy 350.068388 -231.714548)
			(xy 350.06789 -231.741197) (xy 350.29647 -231.741197) (xy 350.29647 -231.687899) (xy 350.304413 -231.635195)
			(xy 350.320123 -231.584265) (xy 350.343249 -231.536244) (xy 350.373273 -231.492207) (xy 350.409525 -231.453136)
			(xy 350.451196 -231.419905) (xy 350.497354 -231.393256) (xy 350.546968 -231.373784) (xy 350.59893 -231.361924)
			(xy 350.65208 -231.357941) (xy 350.70523 -231.361924) (xy 350.757192 -231.373784) (xy 350.806806 -231.393256)
			(xy 350.852964 -231.419905) (xy 350.894635 -231.453136) (xy 350.930887 -231.492207) (xy 350.960911 -231.536244)
			(xy 350.984037 -231.584265) (xy 350.999747 -231.635195) (xy 351.00769 -231.687899) (xy 351.008188 -231.714548)
			(xy 351.00769 -231.741197) (xy 351.23627 -231.741197) (xy 351.23627 -231.687899) (xy 351.244213 -231.635195)
			(xy 351.259923 -231.584265) (xy 351.283049 -231.536244) (xy 351.313073 -231.492207) (xy 351.349325 -231.453136)
			(xy 351.390996 -231.419905) (xy 351.437154 -231.393256) (xy 351.486768 -231.373784) (xy 351.53873 -231.361924)
			(xy 351.59188 -231.357941) (xy 351.64503 -231.361924) (xy 351.696992 -231.373784) (xy 351.746606 -231.393256)
			(xy 351.792764 -231.419905) (xy 351.834435 -231.453136) (xy 351.870687 -231.492207) (xy 351.900711 -231.536244)
			(xy 351.923837 -231.584265) (xy 351.939547 -231.635195) (xy 351.94749 -231.687899) (xy 351.947988 -231.714548)
			(xy 351.94749 -231.741197) (xy 352.17607 -231.741197) (xy 352.17607 -231.687899) (xy 352.184013 -231.635195)
			(xy 352.199723 -231.584265) (xy 352.222849 -231.536244) (xy 352.252873 -231.492207) (xy 352.289125 -231.453136)
			(xy 352.330796 -231.419905) (xy 352.376954 -231.393256) (xy 352.426568 -231.373784) (xy 352.47853 -231.361924)
			(xy 352.53168 -231.357941) (xy 352.58483 -231.361924) (xy 352.636792 -231.373784) (xy 352.686406 -231.393256)
			(xy 352.732564 -231.419905) (xy 352.774235 -231.453136) (xy 352.810487 -231.492207) (xy 352.840511 -231.536244)
			(xy 352.863637 -231.584265) (xy 352.879347 -231.635195) (xy 352.88729 -231.687899) (xy 352.887788 -231.714548)
			(xy 352.88729 -231.741197) (xy 353.11587 -231.741197) (xy 353.11587 -231.687899) (xy 353.123813 -231.635195)
			(xy 353.139523 -231.584265) (xy 353.162649 -231.536244) (xy 353.192673 -231.492207) (xy 353.228925 -231.453136)
			(xy 353.270596 -231.419905) (xy 353.316754 -231.393256) (xy 353.366368 -231.373784) (xy 353.41833 -231.361924)
			(xy 353.47148 -231.357941) (xy 353.52463 -231.361924) (xy 353.576592 -231.373784) (xy 353.626206 -231.393256)
			(xy 353.672364 -231.419905) (xy 353.714035 -231.453136) (xy 353.750287 -231.492207) (xy 353.780311 -231.536244)
			(xy 353.803437 -231.584265) (xy 353.819147 -231.635195) (xy 353.82709 -231.687899) (xy 353.827588 -231.714548)
			(xy 353.82709 -231.741197) (xy 354.05567 -231.741197) (xy 354.05567 -231.687899) (xy 354.063613 -231.635195)
			(xy 354.079323 -231.584265) (xy 354.102449 -231.536244) (xy 354.132473 -231.492207) (xy 354.168725 -231.453136)
			(xy 354.210396 -231.419905) (xy 354.256554 -231.393256) (xy 354.306168 -231.373784) (xy 354.35813 -231.361924)
			(xy 354.41128 -231.357941) (xy 354.46443 -231.361924) (xy 354.516392 -231.373784) (xy 354.566006 -231.393256)
			(xy 354.612164 -231.419905) (xy 354.653835 -231.453136) (xy 354.690087 -231.492207) (xy 354.720111 -231.536244)
			(xy 354.743237 -231.584265) (xy 354.758947 -231.635195) (xy 354.76689 -231.687899) (xy 354.767388 -231.714548)
			(xy 354.76689 -231.741197) (xy 354.99547 -231.741197) (xy 354.99547 -231.687899) (xy 355.003413 -231.635195)
			(xy 355.019123 -231.584265) (xy 355.042249 -231.536244) (xy 355.072273 -231.492207) (xy 355.108525 -231.453136)
			(xy 355.150196 -231.419905) (xy 355.196354 -231.393256) (xy 355.245968 -231.373784) (xy 355.29793 -231.361924)
			(xy 355.35108 -231.357941) (xy 355.40423 -231.361924) (xy 355.456192 -231.373784) (xy 355.505806 -231.393256)
			(xy 355.551964 -231.419905) (xy 355.593635 -231.453136) (xy 355.629887 -231.492207) (xy 355.659911 -231.536244)
			(xy 355.683037 -231.584265) (xy 355.698747 -231.635195) (xy 355.70669 -231.687899) (xy 355.707188 -231.714548)
			(xy 355.70669 -231.741197) (xy 355.93527 -231.741197) (xy 355.93527 -231.687899) (xy 355.943213 -231.635195)
			(xy 355.958923 -231.584265) (xy 355.982049 -231.536244) (xy 356.012073 -231.492207) (xy 356.048325 -231.453136)
			(xy 356.089996 -231.419905) (xy 356.136154 -231.393256) (xy 356.185768 -231.373784) (xy 356.23773 -231.361924)
			(xy 356.29088 -231.357941) (xy 356.34403 -231.361924) (xy 356.395992 -231.373784) (xy 356.445606 -231.393256)
			(xy 356.491764 -231.419905) (xy 356.533435 -231.453136) (xy 356.569687 -231.492207) (xy 356.599711 -231.536244)
			(xy 356.622837 -231.584265) (xy 356.638547 -231.635195) (xy 356.64649 -231.687899) (xy 356.646988 -231.714548)
			(xy 356.64649 -231.741197) (xy 356.87507 -231.741197) (xy 356.87507 -231.687899) (xy 356.883013 -231.635195)
			(xy 356.898723 -231.584265) (xy 356.921849 -231.536244) (xy 356.951873 -231.492207) (xy 356.988125 -231.453136)
			(xy 357.029796 -231.419905) (xy 357.075954 -231.393256) (xy 357.125568 -231.373784) (xy 357.17753 -231.361924)
			(xy 357.23068 -231.357941) (xy 357.28383 -231.361924) (xy 357.335792 -231.373784) (xy 357.385406 -231.393256)
			(xy 357.431564 -231.419905) (xy 357.473235 -231.453136) (xy 357.509487 -231.492207) (xy 357.539511 -231.536244)
			(xy 357.562637 -231.584265) (xy 357.578347 -231.635195) (xy 357.58629 -231.687899) (xy 357.586788 -231.714548)
			(xy 357.58629 -231.741197) (xy 357.815124 -231.741197) (xy 357.815124 -231.687899) (xy 357.823067 -231.635195)
			(xy 357.838777 -231.584265) (xy 357.861903 -231.536244) (xy 357.891927 -231.492207) (xy 357.928179 -231.453136)
			(xy 357.96985 -231.419905) (xy 358.016008 -231.393256) (xy 358.065622 -231.373784) (xy 358.117584 -231.361924)
			(xy 358.170734 -231.357941) (xy 358.223884 -231.361924) (xy 358.275846 -231.373784) (xy 358.32546 -231.393256)
			(xy 358.371618 -231.419905) (xy 358.413289 -231.453136) (xy 358.449541 -231.492207) (xy 358.479565 -231.536244)
			(xy 358.502691 -231.584265) (xy 358.518401 -231.635195) (xy 358.526344 -231.687899) (xy 358.526842 -231.714548)
			(xy 358.526344 -231.741197) (xy 358.75467 -231.741197) (xy 358.75467 -231.687899) (xy 358.762613 -231.635195)
			(xy 358.778323 -231.584265) (xy 358.801449 -231.536244) (xy 358.831473 -231.492207) (xy 358.867725 -231.453136)
			(xy 358.909396 -231.419905) (xy 358.955554 -231.393256) (xy 359.005168 -231.373784) (xy 359.05713 -231.361924)
			(xy 359.11028 -231.357941) (xy 359.16343 -231.361924) (xy 359.215392 -231.373784) (xy 359.265006 -231.393256)
			(xy 359.311164 -231.419905) (xy 359.352835 -231.453136) (xy 359.389087 -231.492207) (xy 359.419111 -231.536244)
			(xy 359.442237 -231.584265) (xy 359.457947 -231.635195) (xy 359.46589 -231.687899) (xy 359.466388 -231.714548)
			(xy 359.46589 -231.741197) (xy 359.694978 -231.741197) (xy 359.694978 -231.687899) (xy 359.702921 -231.635195)
			(xy 359.718631 -231.584265) (xy 359.741757 -231.536244) (xy 359.771781 -231.492207) (xy 359.808033 -231.453136)
			(xy 359.849704 -231.419905) (xy 359.895862 -231.393256) (xy 359.945476 -231.373784) (xy 359.997438 -231.361924)
			(xy 360.050588 -231.357941) (xy 360.103738 -231.361924) (xy 360.1557 -231.373784) (xy 360.205314 -231.393256)
			(xy 360.251472 -231.419905) (xy 360.293143 -231.453136) (xy 360.329395 -231.492207) (xy 360.359419 -231.536244)
			(xy 360.382545 -231.584265) (xy 360.398255 -231.635195) (xy 360.406198 -231.687899) (xy 360.406696 -231.714548)
			(xy 360.406198 -231.741197) (xy 360.634778 -231.741197) (xy 360.634778 -231.687899) (xy 360.642721 -231.635195)
			(xy 360.658431 -231.584265) (xy 360.681557 -231.536244) (xy 360.711581 -231.492207) (xy 360.747833 -231.453136)
			(xy 360.789504 -231.419905) (xy 360.835662 -231.393256) (xy 360.885276 -231.373784) (xy 360.937238 -231.361924)
			(xy 360.990388 -231.357941) (xy 361.043538 -231.361924) (xy 361.0955 -231.373784) (xy 361.145114 -231.393256)
			(xy 361.191272 -231.419905) (xy 361.232943 -231.453136) (xy 361.269195 -231.492207) (xy 361.299219 -231.536244)
			(xy 361.322345 -231.584265) (xy 361.338055 -231.635195) (xy 361.345998 -231.687899) (xy 361.346496 -231.714548)
			(xy 361.345998 -231.741197) (xy 361.574578 -231.741197) (xy 361.574578 -231.687899) (xy 361.582521 -231.635195)
			(xy 361.598231 -231.584265) (xy 361.621357 -231.536244) (xy 361.651381 -231.492207) (xy 361.687633 -231.453136)
			(xy 361.729304 -231.419905) (xy 361.775462 -231.393256) (xy 361.825076 -231.373784) (xy 361.877038 -231.361924)
			(xy 361.930188 -231.357941) (xy 361.983338 -231.361924) (xy 362.0353 -231.373784) (xy 362.084914 -231.393256)
			(xy 362.131072 -231.419905) (xy 362.172743 -231.453136) (xy 362.208995 -231.492207) (xy 362.239019 -231.536244)
			(xy 362.262145 -231.584265) (xy 362.277855 -231.635195) (xy 362.285798 -231.687899) (xy 362.286296 -231.714548)
			(xy 362.285798 -231.741197) (xy 362.51387 -231.741197) (xy 362.51387 -231.687899) (xy 362.521813 -231.635195)
			(xy 362.537523 -231.584265) (xy 362.560649 -231.536244) (xy 362.590673 -231.492207) (xy 362.626925 -231.453136)
			(xy 362.668596 -231.419905) (xy 362.714754 -231.393256) (xy 362.764368 -231.373784) (xy 362.81633 -231.361924)
			(xy 362.86948 -231.357941) (xy 362.92263 -231.361924) (xy 362.974592 -231.373784) (xy 363.024206 -231.393256)
			(xy 363.070364 -231.419905) (xy 363.112035 -231.453136) (xy 363.148287 -231.492207) (xy 363.178311 -231.536244)
			(xy 363.201437 -231.584265) (xy 363.217147 -231.635195) (xy 363.22509 -231.687899) (xy 363.225588 -231.714548)
			(xy 363.22509 -231.741197) (xy 363.45367 -231.741197) (xy 363.45367 -231.687899) (xy 363.461613 -231.635195)
			(xy 363.477323 -231.584265) (xy 363.500449 -231.536244) (xy 363.530473 -231.492207) (xy 363.566725 -231.453136)
			(xy 363.608396 -231.419905) (xy 363.654554 -231.393256) (xy 363.704168 -231.373784) (xy 363.75613 -231.361924)
			(xy 363.80928 -231.357941) (xy 363.86243 -231.361924) (xy 363.914392 -231.373784) (xy 363.964006 -231.393256)
			(xy 364.010164 -231.419905) (xy 364.051835 -231.453136) (xy 364.088087 -231.492207) (xy 364.118111 -231.536244)
			(xy 364.141237 -231.584265) (xy 364.156947 -231.635195) (xy 364.16489 -231.687899) (xy 364.165388 -231.714548)
			(xy 364.16489 -231.741197) (xy 364.39347 -231.741197) (xy 364.39347 -231.687899) (xy 364.401413 -231.635195)
			(xy 364.417123 -231.584265) (xy 364.440249 -231.536244) (xy 364.470273 -231.492207) (xy 364.506525 -231.453136)
			(xy 364.548196 -231.419905) (xy 364.594354 -231.393256) (xy 364.643968 -231.373784) (xy 364.69593 -231.361924)
			(xy 364.74908 -231.357941) (xy 364.80223 -231.361924) (xy 364.854192 -231.373784) (xy 364.903806 -231.393256)
			(xy 364.949964 -231.419905) (xy 364.991635 -231.453136) (xy 365.027887 -231.492207) (xy 365.057911 -231.536244)
			(xy 365.081037 -231.584265) (xy 365.096747 -231.635195) (xy 365.10469 -231.687899) (xy 365.105188 -231.714548)
			(xy 365.10469 -231.741197) (xy 365.33327 -231.741197) (xy 365.33327 -231.687899) (xy 365.341213 -231.635195)
			(xy 365.356923 -231.584265) (xy 365.380049 -231.536244) (xy 365.410073 -231.492207) (xy 365.446325 -231.453136)
			(xy 365.487996 -231.419905) (xy 365.534154 -231.393256) (xy 365.583768 -231.373784) (xy 365.63573 -231.361924)
			(xy 365.68888 -231.357941) (xy 365.74203 -231.361924) (xy 365.793992 -231.373784) (xy 365.843606 -231.393256)
			(xy 365.889764 -231.419905) (xy 365.931435 -231.453136) (xy 365.967687 -231.492207) (xy 365.997711 -231.536244)
			(xy 366.020837 -231.584265) (xy 366.036547 -231.635195) (xy 366.04449 -231.687899) (xy 366.044988 -231.714548)
			(xy 366.04449 -231.741197) (xy 366.27307 -231.741197) (xy 366.27307 -231.687899) (xy 366.281013 -231.635195)
			(xy 366.296723 -231.584265) (xy 366.319849 -231.536244) (xy 366.349873 -231.492207) (xy 366.386125 -231.453136)
			(xy 366.427796 -231.419905) (xy 366.473954 -231.393256) (xy 366.523568 -231.373784) (xy 366.57553 -231.361924)
			(xy 366.62868 -231.357941) (xy 366.68183 -231.361924) (xy 366.733792 -231.373784) (xy 366.783406 -231.393256)
			(xy 366.829564 -231.419905) (xy 366.871235 -231.453136) (xy 366.907487 -231.492207) (xy 366.937511 -231.536244)
			(xy 366.960637 -231.584265) (xy 366.976347 -231.635195) (xy 366.98429 -231.687899) (xy 366.984788 -231.714548)
			(xy 366.98429 -231.741197) (xy 367.213378 -231.741197) (xy 367.213378 -231.687899) (xy 367.221321 -231.635195)
			(xy 367.237031 -231.584265) (xy 367.260157 -231.536244) (xy 367.290181 -231.492207) (xy 367.326433 -231.453136)
			(xy 367.368104 -231.419905) (xy 367.414262 -231.393256) (xy 367.463876 -231.373784) (xy 367.515838 -231.361924)
			(xy 367.568988 -231.357941) (xy 367.622138 -231.361924) (xy 367.6741 -231.373784) (xy 367.723714 -231.393256)
			(xy 367.769872 -231.419905) (xy 367.811543 -231.453136) (xy 367.847795 -231.492207) (xy 367.877819 -231.536244)
			(xy 367.900945 -231.584265) (xy 367.916655 -231.635195) (xy 367.924598 -231.687899) (xy 367.925096 -231.714548)
			(xy 367.924598 -231.741197) (xy 368.15267 -231.741197) (xy 368.15267 -231.687899) (xy 368.160613 -231.635195)
			(xy 368.176323 -231.584265) (xy 368.199449 -231.536244) (xy 368.229473 -231.492207) (xy 368.265725 -231.453136)
			(xy 368.307396 -231.419905) (xy 368.353554 -231.393256) (xy 368.403168 -231.373784) (xy 368.45513 -231.361924)
			(xy 368.50828 -231.357941) (xy 368.56143 -231.361924) (xy 368.613392 -231.373784) (xy 368.663006 -231.393256)
			(xy 368.709164 -231.419905) (xy 368.750835 -231.453136) (xy 368.787087 -231.492207) (xy 368.817111 -231.536244)
			(xy 368.840237 -231.584265) (xy 368.855947 -231.635195) (xy 368.86389 -231.687899) (xy 368.864388 -231.714548)
			(xy 368.86389 -231.741197) (xy 369.092978 -231.741197) (xy 369.092978 -231.687899) (xy 369.100921 -231.635195)
			(xy 369.116631 -231.584265) (xy 369.139757 -231.536244) (xy 369.169781 -231.492207) (xy 369.206033 -231.453136)
			(xy 369.247704 -231.419905) (xy 369.293862 -231.393256) (xy 369.343476 -231.373784) (xy 369.395438 -231.361924)
			(xy 369.448588 -231.357941) (xy 369.501738 -231.361924) (xy 369.5537 -231.373784) (xy 369.603314 -231.393256)
			(xy 369.649472 -231.419905) (xy 369.691143 -231.453136) (xy 369.727395 -231.492207) (xy 369.757419 -231.536244)
			(xy 369.780545 -231.584265) (xy 369.796255 -231.635195) (xy 369.804198 -231.687899) (xy 369.804696 -231.714548)
			(xy 369.804198 -231.741197) (xy 370.032524 -231.741197) (xy 370.032524 -231.687899) (xy 370.040467 -231.635195)
			(xy 370.056177 -231.584265) (xy 370.079303 -231.536244) (xy 370.109327 -231.492207) (xy 370.145579 -231.453136)
			(xy 370.18725 -231.419905) (xy 370.233408 -231.393256) (xy 370.283022 -231.373784) (xy 370.334984 -231.361924)
			(xy 370.388134 -231.357941) (xy 370.441284 -231.361924) (xy 370.493246 -231.373784) (xy 370.54286 -231.393256)
			(xy 370.589018 -231.419905) (xy 370.630689 -231.453136) (xy 370.666941 -231.492207) (xy 370.696965 -231.536244)
			(xy 370.720091 -231.584265) (xy 370.735801 -231.635195) (xy 370.743744 -231.687899) (xy 370.744242 -231.714548)
			(xy 370.743744 -231.741197) (xy 370.97207 -231.741197) (xy 370.97207 -231.687899) (xy 370.980013 -231.635195)
			(xy 370.995723 -231.584265) (xy 371.018849 -231.536244) (xy 371.048873 -231.492207) (xy 371.085125 -231.453136)
			(xy 371.126796 -231.419905) (xy 371.172954 -231.393256) (xy 371.222568 -231.373784) (xy 371.27453 -231.361924)
			(xy 371.32768 -231.357941) (xy 371.38083 -231.361924) (xy 371.432792 -231.373784) (xy 371.482406 -231.393256)
			(xy 371.528564 -231.419905) (xy 371.570235 -231.453136) (xy 371.606487 -231.492207) (xy 371.636511 -231.536244)
			(xy 371.659637 -231.584265) (xy 371.675347 -231.635195) (xy 371.68329 -231.687899) (xy 371.683788 -231.714548)
			(xy 371.68329 -231.741197) (xy 371.91187 -231.741197) (xy 371.91187 -231.687899) (xy 371.919813 -231.635195)
			(xy 371.935523 -231.584265) (xy 371.958649 -231.536244) (xy 371.988673 -231.492207) (xy 372.024925 -231.453136)
			(xy 372.066596 -231.419905) (xy 372.112754 -231.393256) (xy 372.162368 -231.373784) (xy 372.21433 -231.361924)
			(xy 372.26748 -231.357941) (xy 372.32063 -231.361924) (xy 372.372592 -231.373784) (xy 372.422206 -231.393256)
			(xy 372.468364 -231.419905) (xy 372.510035 -231.453136) (xy 372.546287 -231.492207) (xy 372.576311 -231.536244)
			(xy 372.599437 -231.584265) (xy 372.615147 -231.635195) (xy 372.62309 -231.687899) (xy 372.623588 -231.714548)
			(xy 372.62309 -231.741197) (xy 372.85167 -231.741197) (xy 372.85167 -231.687899) (xy 372.859613 -231.635195)
			(xy 372.875323 -231.584265) (xy 372.898449 -231.536244) (xy 372.928473 -231.492207) (xy 372.964725 -231.453136)
			(xy 373.006396 -231.419905) (xy 373.052554 -231.393256) (xy 373.102168 -231.373784) (xy 373.15413 -231.361924)
			(xy 373.20728 -231.357941) (xy 373.26043 -231.361924) (xy 373.312392 -231.373784) (xy 373.362006 -231.393256)
			(xy 373.408164 -231.419905) (xy 373.449835 -231.453136) (xy 373.486087 -231.492207) (xy 373.516111 -231.536244)
			(xy 373.539237 -231.584265) (xy 373.554947 -231.635195) (xy 373.56289 -231.687899) (xy 373.563388 -231.714548)
			(xy 373.56289 -231.741197) (xy 373.79147 -231.741197) (xy 373.79147 -231.687899) (xy 373.799413 -231.635195)
			(xy 373.815123 -231.584265) (xy 373.838249 -231.536244) (xy 373.868273 -231.492207) (xy 373.904525 -231.453136)
			(xy 373.946196 -231.419905) (xy 373.992354 -231.393256) (xy 374.041968 -231.373784) (xy 374.09393 -231.361924)
			(xy 374.14708 -231.357941) (xy 374.20023 -231.361924) (xy 374.252192 -231.373784) (xy 374.301806 -231.393256)
			(xy 374.347964 -231.419905) (xy 374.389635 -231.453136) (xy 374.425887 -231.492207) (xy 374.455911 -231.536244)
			(xy 374.479037 -231.584265) (xy 374.494747 -231.635195) (xy 374.50269 -231.687899) (xy 374.503188 -231.714548)
			(xy 374.50269 -231.741197) (xy 374.73127 -231.741197) (xy 374.73127 -231.687899) (xy 374.739213 -231.635195)
			(xy 374.754923 -231.584265) (xy 374.778049 -231.536244) (xy 374.808073 -231.492207) (xy 374.844325 -231.453136)
			(xy 374.885996 -231.419905) (xy 374.932154 -231.393256) (xy 374.981768 -231.373784) (xy 375.03373 -231.361924)
			(xy 375.08688 -231.357941) (xy 375.14003 -231.361924) (xy 375.191992 -231.373784) (xy 375.241606 -231.393256)
			(xy 375.287764 -231.419905) (xy 375.329435 -231.453136) (xy 375.365687 -231.492207) (xy 375.395711 -231.536244)
			(xy 375.418837 -231.584265) (xy 375.434547 -231.635195) (xy 375.44249 -231.687899) (xy 375.442988 -231.714548)
			(xy 375.44249 -231.741197) (xy 375.67107 -231.741197) (xy 375.67107 -231.687899) (xy 375.679013 -231.635195)
			(xy 375.694723 -231.584265) (xy 375.717849 -231.536244) (xy 375.747873 -231.492207) (xy 375.784125 -231.453136)
			(xy 375.825796 -231.419905) (xy 375.871954 -231.393256) (xy 375.921568 -231.373784) (xy 375.97353 -231.361924)
			(xy 376.02668 -231.357941) (xy 376.07983 -231.361924) (xy 376.131792 -231.373784) (xy 376.181406 -231.393256)
			(xy 376.227564 -231.419905) (xy 376.269235 -231.453136) (xy 376.305487 -231.492207) (xy 376.335511 -231.536244)
			(xy 376.358637 -231.584265) (xy 376.374347 -231.635195) (xy 376.38229 -231.687899) (xy 376.382788 -231.714548)
			(xy 376.38229 -231.741197) (xy 376.611124 -231.741197) (xy 376.611124 -231.687899) (xy 376.619067 -231.635195)
			(xy 376.634777 -231.584265) (xy 376.657903 -231.536244) (xy 376.687927 -231.492207) (xy 376.724179 -231.453136)
			(xy 376.76585 -231.419905) (xy 376.812008 -231.393256) (xy 376.861622 -231.373784) (xy 376.913584 -231.361924)
			(xy 376.966734 -231.357941) (xy 377.019884 -231.361924) (xy 377.071846 -231.373784) (xy 377.12146 -231.393256)
			(xy 377.167618 -231.419905) (xy 377.209289 -231.453136) (xy 377.245541 -231.492207) (xy 377.275565 -231.536244)
			(xy 377.298691 -231.584265) (xy 377.314401 -231.635195) (xy 377.322344 -231.687899) (xy 377.322842 -231.714548)
			(xy 377.322344 -231.741197) (xy 377.55067 -231.741197) (xy 377.55067 -231.687899) (xy 377.558613 -231.635195)
			(xy 377.574323 -231.584265) (xy 377.597449 -231.536244) (xy 377.627473 -231.492207) (xy 377.663725 -231.453136)
			(xy 377.705396 -231.419905) (xy 377.751554 -231.393256) (xy 377.801168 -231.373784) (xy 377.85313 -231.361924)
			(xy 377.90628 -231.357941) (xy 377.95943 -231.361924) (xy 378.011392 -231.373784) (xy 378.061006 -231.393256)
			(xy 378.107164 -231.419905) (xy 378.148835 -231.453136) (xy 378.185087 -231.492207) (xy 378.215111 -231.536244)
			(xy 378.238237 -231.584265) (xy 378.253947 -231.635195) (xy 378.26189 -231.687899) (xy 378.262388 -231.714548)
			(xy 378.26189 -231.741197) (xy 378.49047 -231.741197) (xy 378.49047 -231.687899) (xy 378.498413 -231.635195)
			(xy 378.514123 -231.584265) (xy 378.537249 -231.536244) (xy 378.567273 -231.492207) (xy 378.603525 -231.453136)
			(xy 378.645196 -231.419905) (xy 378.691354 -231.393256) (xy 378.740968 -231.373784) (xy 378.79293 -231.361924)
			(xy 378.84608 -231.357941) (xy 378.89923 -231.361924) (xy 378.951192 -231.373784) (xy 379.000806 -231.393256)
			(xy 379.046964 -231.419905) (xy 379.088635 -231.453136) (xy 379.124887 -231.492207) (xy 379.154911 -231.536244)
			(xy 379.178037 -231.584265) (xy 379.193747 -231.635195) (xy 379.20169 -231.687899) (xy 379.202188 -231.714548)
			(xy 379.20169 -231.741197) (xy 379.43027 -231.741197) (xy 379.43027 -231.687899) (xy 379.438213 -231.635195)
			(xy 379.453923 -231.584265) (xy 379.477049 -231.536244) (xy 379.507073 -231.492207) (xy 379.543325 -231.453136)
			(xy 379.584996 -231.419905) (xy 379.631154 -231.393256) (xy 379.680768 -231.373784) (xy 379.73273 -231.361924)
			(xy 379.78588 -231.357941) (xy 379.83903 -231.361924) (xy 379.890992 -231.373784) (xy 379.940606 -231.393256)
			(xy 379.986764 -231.419905) (xy 380.028435 -231.453136) (xy 380.064687 -231.492207) (xy 380.094711 -231.536244)
			(xy 380.117837 -231.584265) (xy 380.133547 -231.635195) (xy 380.14149 -231.687899) (xy 380.141988 -231.714548)
			(xy 380.14149 -231.741197) (xy 380.133547 -231.793901) (xy 380.117837 -231.844831) (xy 380.094711 -231.892852)
			(xy 380.064687 -231.936889) (xy 380.028435 -231.97596) (xy 379.986764 -232.009191) (xy 379.940606 -232.03584)
			(xy 379.890992 -232.055312) (xy 379.83903 -232.067172) (xy 379.78588 -232.071156) (xy 379.73273 -232.067172)
			(xy 379.680768 -232.055312) (xy 379.631154 -232.03584) (xy 379.584996 -232.009191) (xy 379.543325 -231.97596)
			(xy 379.507073 -231.936889) (xy 379.477049 -231.892852) (xy 379.453923 -231.844831) (xy 379.438213 -231.793901)
			(xy 379.43027 -231.741197) (xy 379.20169 -231.741197) (xy 379.193747 -231.793901) (xy 379.178037 -231.844831)
			(xy 379.154911 -231.892852) (xy 379.124887 -231.936889) (xy 379.088635 -231.97596) (xy 379.046964 -232.009191)
			(xy 379.000806 -232.03584) (xy 378.951192 -232.055312) (xy 378.89923 -232.067172) (xy 378.84608 -232.071156)
			(xy 378.79293 -232.067172) (xy 378.740968 -232.055312) (xy 378.691354 -232.03584) (xy 378.645196 -232.009191)
			(xy 378.603525 -231.97596) (xy 378.567273 -231.936889) (xy 378.537249 -231.892852) (xy 378.514123 -231.844831)
			(xy 378.498413 -231.793901) (xy 378.49047 -231.741197) (xy 378.26189 -231.741197) (xy 378.253947 -231.793901)
			(xy 378.238237 -231.844831) (xy 378.215111 -231.892852) (xy 378.185087 -231.936889) (xy 378.148835 -231.97596)
			(xy 378.107164 -232.009191) (xy 378.061006 -232.03584) (xy 378.011392 -232.055312) (xy 377.95943 -232.067172)
			(xy 377.90628 -232.071156) (xy 377.85313 -232.067172) (xy 377.801168 -232.055312) (xy 377.751554 -232.03584)
			(xy 377.705396 -232.009191) (xy 377.663725 -231.97596) (xy 377.627473 -231.936889) (xy 377.597449 -231.892852)
			(xy 377.574323 -231.844831) (xy 377.558613 -231.793901) (xy 377.55067 -231.741197) (xy 377.322344 -231.741197)
			(xy 377.314401 -231.793901) (xy 377.298691 -231.844831) (xy 377.275565 -231.892852) (xy 377.245541 -231.936889)
			(xy 377.209289 -231.97596) (xy 377.167618 -232.009191) (xy 377.12146 -232.03584) (xy 377.071846 -232.055312)
			(xy 377.019884 -232.067172) (xy 376.966734 -232.071156) (xy 376.913584 -232.067172) (xy 376.861622 -232.055312)
			(xy 376.812008 -232.03584) (xy 376.76585 -232.009191) (xy 376.724179 -231.97596) (xy 376.687927 -231.936889)
			(xy 376.657903 -231.892852) (xy 376.634777 -231.844831) (xy 376.619067 -231.793901) (xy 376.611124 -231.741197)
			(xy 376.38229 -231.741197) (xy 376.374347 -231.793901) (xy 376.358637 -231.844831) (xy 376.335511 -231.892852)
			(xy 376.305487 -231.936889) (xy 376.269235 -231.97596) (xy 376.227564 -232.009191) (xy 376.181406 -232.03584)
			(xy 376.131792 -232.055312) (xy 376.07983 -232.067172) (xy 376.02668 -232.071156) (xy 375.97353 -232.067172)
			(xy 375.921568 -232.055312) (xy 375.871954 -232.03584) (xy 375.825796 -232.009191) (xy 375.784125 -231.97596)
			(xy 375.747873 -231.936889) (xy 375.717849 -231.892852) (xy 375.694723 -231.844831) (xy 375.679013 -231.793901)
			(xy 375.67107 -231.741197) (xy 375.44249 -231.741197) (xy 375.434547 -231.793901) (xy 375.418837 -231.844831)
			(xy 375.395711 -231.892852) (xy 375.365687 -231.936889) (xy 375.329435 -231.97596) (xy 375.287764 -232.009191)
			(xy 375.241606 -232.03584) (xy 375.191992 -232.055312) (xy 375.14003 -232.067172) (xy 375.08688 -232.071156)
			(xy 375.03373 -232.067172) (xy 374.981768 -232.055312) (xy 374.932154 -232.03584) (xy 374.885996 -232.009191)
			(xy 374.844325 -231.97596) (xy 374.808073 -231.936889) (xy 374.778049 -231.892852) (xy 374.754923 -231.844831)
			(xy 374.739213 -231.793901) (xy 374.73127 -231.741197) (xy 374.50269 -231.741197) (xy 374.494747 -231.793901)
			(xy 374.479037 -231.844831) (xy 374.455911 -231.892852) (xy 374.425887 -231.936889) (xy 374.389635 -231.97596)
			(xy 374.347964 -232.009191) (xy 374.301806 -232.03584) (xy 374.252192 -232.055312) (xy 374.20023 -232.067172)
			(xy 374.14708 -232.071156) (xy 374.09393 -232.067172) (xy 374.041968 -232.055312) (xy 373.992354 -232.03584)
			(xy 373.946196 -232.009191) (xy 373.904525 -231.97596) (xy 373.868273 -231.936889) (xy 373.838249 -231.892852)
			(xy 373.815123 -231.844831) (xy 373.799413 -231.793901) (xy 373.79147 -231.741197) (xy 373.56289 -231.741197)
			(xy 373.554947 -231.793901) (xy 373.539237 -231.844831) (xy 373.516111 -231.892852) (xy 373.486087 -231.936889)
			(xy 373.449835 -231.97596) (xy 373.408164 -232.009191) (xy 373.362006 -232.03584) (xy 373.312392 -232.055312)
			(xy 373.26043 -232.067172) (xy 373.20728 -232.071156) (xy 373.15413 -232.067172) (xy 373.102168 -232.055312)
			(xy 373.052554 -232.03584) (xy 373.006396 -232.009191) (xy 372.964725 -231.97596) (xy 372.928473 -231.936889)
			(xy 372.898449 -231.892852) (xy 372.875323 -231.844831) (xy 372.859613 -231.793901) (xy 372.85167 -231.741197)
			(xy 372.62309 -231.741197) (xy 372.615147 -231.793901) (xy 372.599437 -231.844831) (xy 372.576311 -231.892852)
			(xy 372.546287 -231.936889) (xy 372.510035 -231.97596) (xy 372.468364 -232.009191) (xy 372.422206 -232.03584)
			(xy 372.372592 -232.055312) (xy 372.32063 -232.067172) (xy 372.26748 -232.071156) (xy 372.21433 -232.067172)
			(xy 372.162368 -232.055312) (xy 372.112754 -232.03584) (xy 372.066596 -232.009191) (xy 372.024925 -231.97596)
			(xy 371.988673 -231.936889) (xy 371.958649 -231.892852) (xy 371.935523 -231.844831) (xy 371.919813 -231.793901)
			(xy 371.91187 -231.741197) (xy 371.68329 -231.741197) (xy 371.675347 -231.793901) (xy 371.659637 -231.844831)
			(xy 371.636511 -231.892852) (xy 371.606487 -231.936889) (xy 371.570235 -231.97596) (xy 371.528564 -232.009191)
			(xy 371.482406 -232.03584) (xy 371.432792 -232.055312) (xy 371.38083 -232.067172) (xy 371.32768 -232.071156)
			(xy 371.27453 -232.067172) (xy 371.222568 -232.055312) (xy 371.172954 -232.03584) (xy 371.126796 -232.009191)
			(xy 371.085125 -231.97596) (xy 371.048873 -231.936889) (xy 371.018849 -231.892852) (xy 370.995723 -231.844831)
			(xy 370.980013 -231.793901) (xy 370.97207 -231.741197) (xy 370.743744 -231.741197) (xy 370.735801 -231.793901)
			(xy 370.720091 -231.844831) (xy 370.696965 -231.892852) (xy 370.666941 -231.936889) (xy 370.630689 -231.97596)
			(xy 370.589018 -232.009191) (xy 370.54286 -232.03584) (xy 370.493246 -232.055312) (xy 370.441284 -232.067172)
			(xy 370.388134 -232.071156) (xy 370.334984 -232.067172) (xy 370.283022 -232.055312) (xy 370.233408 -232.03584)
			(xy 370.18725 -232.009191) (xy 370.145579 -231.97596) (xy 370.109327 -231.936889) (xy 370.079303 -231.892852)
			(xy 370.056177 -231.844831) (xy 370.040467 -231.793901) (xy 370.032524 -231.741197) (xy 369.804198 -231.741197)
			(xy 369.796255 -231.793901) (xy 369.780545 -231.844831) (xy 369.757419 -231.892852) (xy 369.727395 -231.936889)
			(xy 369.691143 -231.97596) (xy 369.649472 -232.009191) (xy 369.603314 -232.03584) (xy 369.5537 -232.055312)
			(xy 369.501738 -232.067172) (xy 369.448588 -232.071156) (xy 369.395438 -232.067172) (xy 369.343476 -232.055312)
			(xy 369.293862 -232.03584) (xy 369.247704 -232.009191) (xy 369.206033 -231.97596) (xy 369.169781 -231.936889)
			(xy 369.139757 -231.892852) (xy 369.116631 -231.844831) (xy 369.100921 -231.793901) (xy 369.092978 -231.741197)
			(xy 368.86389 -231.741197) (xy 368.855947 -231.793901) (xy 368.840237 -231.844831) (xy 368.817111 -231.892852)
			(xy 368.787087 -231.936889) (xy 368.750835 -231.97596) (xy 368.709164 -232.009191) (xy 368.663006 -232.03584)
			(xy 368.613392 -232.055312) (xy 368.56143 -232.067172) (xy 368.50828 -232.071156) (xy 368.45513 -232.067172)
			(xy 368.403168 -232.055312) (xy 368.353554 -232.03584) (xy 368.307396 -232.009191) (xy 368.265725 -231.97596)
			(xy 368.229473 -231.936889) (xy 368.199449 -231.892852) (xy 368.176323 -231.844831) (xy 368.160613 -231.793901)
			(xy 368.15267 -231.741197) (xy 367.924598 -231.741197) (xy 367.916655 -231.793901) (xy 367.900945 -231.844831)
			(xy 367.877819 -231.892852) (xy 367.847795 -231.936889) (xy 367.811543 -231.97596) (xy 367.769872 -232.009191)
			(xy 367.723714 -232.03584) (xy 367.6741 -232.055312) (xy 367.622138 -232.067172) (xy 367.568988 -232.071156)
			(xy 367.515838 -232.067172) (xy 367.463876 -232.055312) (xy 367.414262 -232.03584) (xy 367.368104 -232.009191)
			(xy 367.326433 -231.97596) (xy 367.290181 -231.936889) (xy 367.260157 -231.892852) (xy 367.237031 -231.844831)
			(xy 367.221321 -231.793901) (xy 367.213378 -231.741197) (xy 366.98429 -231.741197) (xy 366.976347 -231.793901)
			(xy 366.960637 -231.844831) (xy 366.937511 -231.892852) (xy 366.907487 -231.936889) (xy 366.871235 -231.97596)
			(xy 366.829564 -232.009191) (xy 366.783406 -232.03584) (xy 366.733792 -232.055312) (xy 366.68183 -232.067172)
			(xy 366.62868 -232.071156) (xy 366.57553 -232.067172) (xy 366.523568 -232.055312) (xy 366.473954 -232.03584)
			(xy 366.427796 -232.009191) (xy 366.386125 -231.97596) (xy 366.349873 -231.936889) (xy 366.319849 -231.892852)
			(xy 366.296723 -231.844831) (xy 366.281013 -231.793901) (xy 366.27307 -231.741197) (xy 366.04449 -231.741197)
			(xy 366.036547 -231.793901) (xy 366.020837 -231.844831) (xy 365.997711 -231.892852) (xy 365.967687 -231.936889)
			(xy 365.931435 -231.97596) (xy 365.889764 -232.009191) (xy 365.843606 -232.03584) (xy 365.793992 -232.055312)
			(xy 365.74203 -232.067172) (xy 365.68888 -232.071156) (xy 365.63573 -232.067172) (xy 365.583768 -232.055312)
			(xy 365.534154 -232.03584) (xy 365.487996 -232.009191) (xy 365.446325 -231.97596) (xy 365.410073 -231.936889)
			(xy 365.380049 -231.892852) (xy 365.356923 -231.844831) (xy 365.341213 -231.793901) (xy 365.33327 -231.741197)
			(xy 365.10469 -231.741197) (xy 365.096747 -231.793901) (xy 365.081037 -231.844831) (xy 365.057911 -231.892852)
			(xy 365.027887 -231.936889) (xy 364.991635 -231.97596) (xy 364.949964 -232.009191) (xy 364.903806 -232.03584)
			(xy 364.854192 -232.055312) (xy 364.80223 -232.067172) (xy 364.74908 -232.071156) (xy 364.69593 -232.067172)
			(xy 364.643968 -232.055312) (xy 364.594354 -232.03584) (xy 364.548196 -232.009191) (xy 364.506525 -231.97596)
			(xy 364.470273 -231.936889) (xy 364.440249 -231.892852) (xy 364.417123 -231.844831) (xy 364.401413 -231.793901)
			(xy 364.39347 -231.741197) (xy 364.16489 -231.741197) (xy 364.156947 -231.793901) (xy 364.141237 -231.844831)
			(xy 364.118111 -231.892852) (xy 364.088087 -231.936889) (xy 364.051835 -231.97596) (xy 364.010164 -232.009191)
			(xy 363.964006 -232.03584) (xy 363.914392 -232.055312) (xy 363.86243 -232.067172) (xy 363.80928 -232.071156)
			(xy 363.75613 -232.067172) (xy 363.704168 -232.055312) (xy 363.654554 -232.03584) (xy 363.608396 -232.009191)
			(xy 363.566725 -231.97596) (xy 363.530473 -231.936889) (xy 363.500449 -231.892852) (xy 363.477323 -231.844831)
			(xy 363.461613 -231.793901) (xy 363.45367 -231.741197) (xy 363.22509 -231.741197) (xy 363.217147 -231.793901)
			(xy 363.201437 -231.844831) (xy 363.178311 -231.892852) (xy 363.148287 -231.936889) (xy 363.112035 -231.97596)
			(xy 363.070364 -232.009191) (xy 363.024206 -232.03584) (xy 362.974592 -232.055312) (xy 362.92263 -232.067172)
			(xy 362.86948 -232.071156) (xy 362.81633 -232.067172) (xy 362.764368 -232.055312) (xy 362.714754 -232.03584)
			(xy 362.668596 -232.009191) (xy 362.626925 -231.97596) (xy 362.590673 -231.936889) (xy 362.560649 -231.892852)
			(xy 362.537523 -231.844831) (xy 362.521813 -231.793901) (xy 362.51387 -231.741197) (xy 362.285798 -231.741197)
			(xy 362.277855 -231.793901) (xy 362.262145 -231.844831) (xy 362.239019 -231.892852) (xy 362.208995 -231.936889)
			(xy 362.172743 -231.97596) (xy 362.131072 -232.009191) (xy 362.084914 -232.03584) (xy 362.0353 -232.055312)
			(xy 361.983338 -232.067172) (xy 361.930188 -232.071156) (xy 361.877038 -232.067172) (xy 361.825076 -232.055312)
			(xy 361.775462 -232.03584) (xy 361.729304 -232.009191) (xy 361.687633 -231.97596) (xy 361.651381 -231.936889)
			(xy 361.621357 -231.892852) (xy 361.598231 -231.844831) (xy 361.582521 -231.793901) (xy 361.574578 -231.741197)
			(xy 361.345998 -231.741197) (xy 361.338055 -231.793901) (xy 361.322345 -231.844831) (xy 361.299219 -231.892852)
			(xy 361.269195 -231.936889) (xy 361.232943 -231.97596) (xy 361.191272 -232.009191) (xy 361.145114 -232.03584)
			(xy 361.0955 -232.055312) (xy 361.043538 -232.067172) (xy 360.990388 -232.071156) (xy 360.937238 -232.067172)
			(xy 360.885276 -232.055312) (xy 360.835662 -232.03584) (xy 360.789504 -232.009191) (xy 360.747833 -231.97596)
			(xy 360.711581 -231.936889) (xy 360.681557 -231.892852) (xy 360.658431 -231.844831) (xy 360.642721 -231.793901)
			(xy 360.634778 -231.741197) (xy 360.406198 -231.741197) (xy 360.398255 -231.793901) (xy 360.382545 -231.844831)
			(xy 360.359419 -231.892852) (xy 360.329395 -231.936889) (xy 360.293143 -231.97596) (xy 360.251472 -232.009191)
			(xy 360.205314 -232.03584) (xy 360.1557 -232.055312) (xy 360.103738 -232.067172) (xy 360.050588 -232.071156)
			(xy 359.997438 -232.067172) (xy 359.945476 -232.055312) (xy 359.895862 -232.03584) (xy 359.849704 -232.009191)
			(xy 359.808033 -231.97596) (xy 359.771781 -231.936889) (xy 359.741757 -231.892852) (xy 359.718631 -231.844831)
			(xy 359.702921 -231.793901) (xy 359.694978 -231.741197) (xy 359.46589 -231.741197) (xy 359.457947 -231.793901)
			(xy 359.442237 -231.844831) (xy 359.419111 -231.892852) (xy 359.389087 -231.936889) (xy 359.352835 -231.97596)
			(xy 359.311164 -232.009191) (xy 359.265006 -232.03584) (xy 359.215392 -232.055312) (xy 359.16343 -232.067172)
			(xy 359.11028 -232.071156) (xy 359.05713 -232.067172) (xy 359.005168 -232.055312) (xy 358.955554 -232.03584)
			(xy 358.909396 -232.009191) (xy 358.867725 -231.97596) (xy 358.831473 -231.936889) (xy 358.801449 -231.892852)
			(xy 358.778323 -231.844831) (xy 358.762613 -231.793901) (xy 358.75467 -231.741197) (xy 358.526344 -231.741197)
			(xy 358.518401 -231.793901) (xy 358.502691 -231.844831) (xy 358.479565 -231.892852) (xy 358.449541 -231.936889)
			(xy 358.413289 -231.97596) (xy 358.371618 -232.009191) (xy 358.32546 -232.03584) (xy 358.275846 -232.055312)
			(xy 358.223884 -232.067172) (xy 358.170734 -232.071156) (xy 358.117584 -232.067172) (xy 358.065622 -232.055312)
			(xy 358.016008 -232.03584) (xy 357.96985 -232.009191) (xy 357.928179 -231.97596) (xy 357.891927 -231.936889)
			(xy 357.861903 -231.892852) (xy 357.838777 -231.844831) (xy 357.823067 -231.793901) (xy 357.815124 -231.741197)
			(xy 357.58629 -231.741197) (xy 357.578347 -231.793901) (xy 357.562637 -231.844831) (xy 357.539511 -231.892852)
			(xy 357.509487 -231.936889) (xy 357.473235 -231.97596) (xy 357.431564 -232.009191) (xy 357.385406 -232.03584)
			(xy 357.335792 -232.055312) (xy 357.28383 -232.067172) (xy 357.23068 -232.071156) (xy 357.17753 -232.067172)
			(xy 357.125568 -232.055312) (xy 357.075954 -232.03584) (xy 357.029796 -232.009191) (xy 356.988125 -231.97596)
			(xy 356.951873 -231.936889) (xy 356.921849 -231.892852) (xy 356.898723 -231.844831) (xy 356.883013 -231.793901)
			(xy 356.87507 -231.741197) (xy 356.64649 -231.741197) (xy 356.638547 -231.793901) (xy 356.622837 -231.844831)
			(xy 356.599711 -231.892852) (xy 356.569687 -231.936889) (xy 356.533435 -231.97596) (xy 356.491764 -232.009191)
			(xy 356.445606 -232.03584) (xy 356.395992 -232.055312) (xy 356.34403 -232.067172) (xy 356.29088 -232.071156)
			(xy 356.23773 -232.067172) (xy 356.185768 -232.055312) (xy 356.136154 -232.03584) (xy 356.089996 -232.009191)
			(xy 356.048325 -231.97596) (xy 356.012073 -231.936889) (xy 355.982049 -231.892852) (xy 355.958923 -231.844831)
			(xy 355.943213 -231.793901) (xy 355.93527 -231.741197) (xy 355.70669 -231.741197) (xy 355.698747 -231.793901)
			(xy 355.683037 -231.844831) (xy 355.659911 -231.892852) (xy 355.629887 -231.936889) (xy 355.593635 -231.97596)
			(xy 355.551964 -232.009191) (xy 355.505806 -232.03584) (xy 355.456192 -232.055312) (xy 355.40423 -232.067172)
			(xy 355.35108 -232.071156) (xy 355.29793 -232.067172) (xy 355.245968 -232.055312) (xy 355.196354 -232.03584)
			(xy 355.150196 -232.009191) (xy 355.108525 -231.97596) (xy 355.072273 -231.936889) (xy 355.042249 -231.892852)
			(xy 355.019123 -231.844831) (xy 355.003413 -231.793901) (xy 354.99547 -231.741197) (xy 354.76689 -231.741197)
			(xy 354.758947 -231.793901) (xy 354.743237 -231.844831) (xy 354.720111 -231.892852) (xy 354.690087 -231.936889)
			(xy 354.653835 -231.97596) (xy 354.612164 -232.009191) (xy 354.566006 -232.03584) (xy 354.516392 -232.055312)
			(xy 354.46443 -232.067172) (xy 354.41128 -232.071156) (xy 354.35813 -232.067172) (xy 354.306168 -232.055312)
			(xy 354.256554 -232.03584) (xy 354.210396 -232.009191) (xy 354.168725 -231.97596) (xy 354.132473 -231.936889)
			(xy 354.102449 -231.892852) (xy 354.079323 -231.844831) (xy 354.063613 -231.793901) (xy 354.05567 -231.741197)
			(xy 353.82709 -231.741197) (xy 353.819147 -231.793901) (xy 353.803437 -231.844831) (xy 353.780311 -231.892852)
			(xy 353.750287 -231.936889) (xy 353.714035 -231.97596) (xy 353.672364 -232.009191) (xy 353.626206 -232.03584)
			(xy 353.576592 -232.055312) (xy 353.52463 -232.067172) (xy 353.47148 -232.071156) (xy 353.41833 -232.067172)
			(xy 353.366368 -232.055312) (xy 353.316754 -232.03584) (xy 353.270596 -232.009191) (xy 353.228925 -231.97596)
			(xy 353.192673 -231.936889) (xy 353.162649 -231.892852) (xy 353.139523 -231.844831) (xy 353.123813 -231.793901)
			(xy 353.11587 -231.741197) (xy 352.88729 -231.741197) (xy 352.879347 -231.793901) (xy 352.863637 -231.844831)
			(xy 352.840511 -231.892852) (xy 352.810487 -231.936889) (xy 352.774235 -231.97596) (xy 352.732564 -232.009191)
			(xy 352.686406 -232.03584) (xy 352.636792 -232.055312) (xy 352.58483 -232.067172) (xy 352.53168 -232.071156)
			(xy 352.47853 -232.067172) (xy 352.426568 -232.055312) (xy 352.376954 -232.03584) (xy 352.330796 -232.009191)
			(xy 352.289125 -231.97596) (xy 352.252873 -231.936889) (xy 352.222849 -231.892852) (xy 352.199723 -231.844831)
			(xy 352.184013 -231.793901) (xy 352.17607 -231.741197) (xy 351.94749 -231.741197) (xy 351.939547 -231.793901)
			(xy 351.923837 -231.844831) (xy 351.900711 -231.892852) (xy 351.870687 -231.936889) (xy 351.834435 -231.97596)
			(xy 351.792764 -232.009191) (xy 351.746606 -232.03584) (xy 351.696992 -232.055312) (xy 351.64503 -232.067172)
			(xy 351.59188 -232.071156) (xy 351.53873 -232.067172) (xy 351.486768 -232.055312) (xy 351.437154 -232.03584)
			(xy 351.390996 -232.009191) (xy 351.349325 -231.97596) (xy 351.313073 -231.936889) (xy 351.283049 -231.892852)
			(xy 351.259923 -231.844831) (xy 351.244213 -231.793901) (xy 351.23627 -231.741197) (xy 351.00769 -231.741197)
			(xy 350.999747 -231.793901) (xy 350.984037 -231.844831) (xy 350.960911 -231.892852) (xy 350.930887 -231.936889)
			(xy 350.894635 -231.97596) (xy 350.852964 -232.009191) (xy 350.806806 -232.03584) (xy 350.757192 -232.055312)
			(xy 350.70523 -232.067172) (xy 350.65208 -232.071156) (xy 350.59893 -232.067172) (xy 350.546968 -232.055312)
			(xy 350.497354 -232.03584) (xy 350.451196 -232.009191) (xy 350.409525 -231.97596) (xy 350.373273 -231.936889)
			(xy 350.343249 -231.892852) (xy 350.320123 -231.844831) (xy 350.304413 -231.793901) (xy 350.29647 -231.741197)
			(xy 350.06789 -231.741197) (xy 350.059947 -231.793901) (xy 350.044237 -231.844831) (xy 350.021111 -231.892852)
			(xy 349.991087 -231.936889) (xy 349.954835 -231.97596) (xy 349.913164 -232.009191) (xy 349.867006 -232.03584)
			(xy 349.817392 -232.055312) (xy 349.76543 -232.067172) (xy 349.71228 -232.071156) (xy 349.65913 -232.067172)
			(xy 349.607168 -232.055312) (xy 349.557554 -232.03584) (xy 349.511396 -232.009191) (xy 349.469725 -231.97596)
			(xy 349.433473 -231.936889) (xy 349.403449 -231.892852) (xy 349.380323 -231.844831) (xy 349.364613 -231.793901)
			(xy 349.35667 -231.741197) (xy 349.128344 -231.741197) (xy 349.120401 -231.793901) (xy 349.104691 -231.844831)
			(xy 349.081565 -231.892852) (xy 349.051541 -231.936889) (xy 349.015289 -231.97596) (xy 348.973618 -232.009191)
			(xy 348.92746 -232.03584) (xy 348.877846 -232.055312) (xy 348.825884 -232.067172) (xy 348.772734 -232.071156)
			(xy 348.719584 -232.067172) (xy 348.667622 -232.055312) (xy 348.618008 -232.03584) (xy 348.57185 -232.009191)
			(xy 348.530179 -231.97596) (xy 348.493927 -231.936889) (xy 348.463903 -231.892852) (xy 348.440777 -231.844831)
			(xy 348.425067 -231.793901) (xy 348.417124 -231.741197) (xy 348.18829 -231.741197) (xy 348.180347 -231.793901)
			(xy 348.164637 -231.844831) (xy 348.141511 -231.892852) (xy 348.111487 -231.936889) (xy 348.075235 -231.97596)
			(xy 348.033564 -232.009191) (xy 347.987406 -232.03584) (xy 347.937792 -232.055312) (xy 347.88583 -232.067172)
			(xy 347.83268 -232.071156) (xy 347.77953 -232.067172) (xy 347.727568 -232.055312) (xy 347.677954 -232.03584)
			(xy 347.631796 -232.009191) (xy 347.590125 -231.97596) (xy 347.553873 -231.936889) (xy 347.523849 -231.892852)
			(xy 347.500723 -231.844831) (xy 347.485013 -231.793901) (xy 347.47707 -231.741197) (xy 347.24849 -231.741197)
			(xy 347.240547 -231.793901) (xy 347.224837 -231.844831) (xy 347.201711 -231.892852) (xy 347.171687 -231.936889)
			(xy 347.135435 -231.97596) (xy 347.093764 -232.009191) (xy 347.047606 -232.03584) (xy 346.997992 -232.055312)
			(xy 346.94603 -232.067172) (xy 346.89288 -232.071156) (xy 346.83973 -232.067172) (xy 346.787768 -232.055312)
			(xy 346.738154 -232.03584) (xy 346.691996 -232.009191) (xy 346.650325 -231.97596) (xy 346.614073 -231.936889)
			(xy 346.584049 -231.892852) (xy 346.560923 -231.844831) (xy 346.545213 -231.793901) (xy 346.53727 -231.741197)
			(xy 346.30869 -231.741197) (xy 346.300747 -231.793901) (xy 346.285037 -231.844831) (xy 346.261911 -231.892852)
			(xy 346.231887 -231.936889) (xy 346.195635 -231.97596) (xy 346.153964 -232.009191) (xy 346.107806 -232.03584)
			(xy 346.058192 -232.055312) (xy 346.00623 -232.067172) (xy 345.95308 -232.071156) (xy 345.89993 -232.067172)
			(xy 345.847968 -232.055312) (xy 345.798354 -232.03584) (xy 345.752196 -232.009191) (xy 345.710525 -231.97596)
			(xy 345.674273 -231.936889) (xy 345.644249 -231.892852) (xy 345.621123 -231.844831) (xy 345.605413 -231.793901)
			(xy 345.59747 -231.741197) (xy 345.36889 -231.741197) (xy 345.360947 -231.793901) (xy 345.345237 -231.844831)
			(xy 345.322111 -231.892852) (xy 345.292087 -231.936889) (xy 345.255835 -231.97596) (xy 345.214164 -232.009191)
			(xy 345.168006 -232.03584) (xy 345.118392 -232.055312) (xy 345.06643 -232.067172) (xy 345.01328 -232.071156)
			(xy 344.96013 -232.067172) (xy 344.908168 -232.055312) (xy 344.858554 -232.03584) (xy 344.812396 -232.009191)
			(xy 344.770725 -231.97596) (xy 344.734473 -231.936889) (xy 344.704449 -231.892852) (xy 344.681323 -231.844831)
			(xy 344.665613 -231.793901) (xy 344.65767 -231.741197) (xy 344.42909 -231.741197) (xy 344.421147 -231.793901)
			(xy 344.405437 -231.844831) (xy 344.382311 -231.892852) (xy 344.352287 -231.936889) (xy 344.316035 -231.97596)
			(xy 344.274364 -232.009191) (xy 344.228206 -232.03584) (xy 344.178592 -232.055312) (xy 344.12663 -232.067172)
			(xy 344.07348 -232.071156) (xy 344.02033 -232.067172) (xy 343.968368 -232.055312) (xy 343.918754 -232.03584)
			(xy 343.872596 -232.009191) (xy 343.830925 -231.97596) (xy 343.794673 -231.936889) (xy 343.764649 -231.892852)
			(xy 343.741523 -231.844831) (xy 343.725813 -231.793901) (xy 343.71787 -231.741197) (xy 343.48929 -231.741197)
			(xy 343.481347 -231.793901) (xy 343.465637 -231.844831) (xy 343.442511 -231.892852) (xy 343.412487 -231.936889)
			(xy 343.376235 -231.97596) (xy 343.334564 -232.009191) (xy 343.288406 -232.03584) (xy 343.238792 -232.055312)
			(xy 343.18683 -232.067172) (xy 343.13368 -232.071156) (xy 343.08053 -232.067172) (xy 343.028568 -232.055312)
			(xy 342.978954 -232.03584) (xy 342.932796 -232.009191) (xy 342.891125 -231.97596) (xy 342.854873 -231.936889)
			(xy 342.824849 -231.892852) (xy 342.801723 -231.844831) (xy 342.786013 -231.793901) (xy 342.77807 -231.741197)
			(xy 342.549744 -231.741197) (xy 342.541801 -231.793901) (xy 342.526091 -231.844831) (xy 342.502965 -231.892852)
			(xy 342.472941 -231.936889) (xy 342.436689 -231.97596) (xy 342.395018 -232.009191) (xy 342.34886 -232.03584)
			(xy 342.299246 -232.055312) (xy 342.247284 -232.067172) (xy 342.194134 -232.071156) (xy 342.140984 -232.067172)
			(xy 342.089022 -232.055312) (xy 342.039408 -232.03584) (xy 341.99325 -232.009191) (xy 341.951579 -231.97596)
			(xy 341.915327 -231.936889) (xy 341.885303 -231.892852) (xy 341.862177 -231.844831) (xy 341.846467 -231.793901)
			(xy 341.838524 -231.741197) (xy 341.60969 -231.741197) (xy 341.601747 -231.793901) (xy 341.586037 -231.844831)
			(xy 341.562911 -231.892852) (xy 341.532887 -231.936889) (xy 341.496635 -231.97596) (xy 341.454964 -232.009191)
			(xy 341.408806 -232.03584) (xy 341.359192 -232.055312) (xy 341.30723 -232.067172) (xy 341.25408 -232.071156)
			(xy 341.20093 -232.067172) (xy 341.148968 -232.055312) (xy 341.099354 -232.03584) (xy 341.053196 -232.009191)
			(xy 341.011525 -231.97596) (xy 340.975273 -231.936889) (xy 340.945249 -231.892852) (xy 340.922123 -231.844831)
			(xy 340.906413 -231.793901) (xy 340.89847 -231.741197) (xy 340.66989 -231.741197) (xy 340.661947 -231.793901)
			(xy 340.646237 -231.844831) (xy 340.623111 -231.892852) (xy 340.593087 -231.936889) (xy 340.556835 -231.97596)
			(xy 340.515164 -232.009191) (xy 340.469006 -232.03584) (xy 340.419392 -232.055312) (xy 340.36743 -232.067172)
			(xy 340.31428 -232.071156) (xy 340.26113 -232.067172) (xy 340.209168 -232.055312) (xy 340.159554 -232.03584)
			(xy 340.113396 -232.009191) (xy 340.071725 -231.97596) (xy 340.035473 -231.936889) (xy 340.005449 -231.892852)
			(xy 339.982323 -231.844831) (xy 339.966613 -231.793901) (xy 339.95867 -231.741197) (xy 339.729152 -231.741197)
			(xy 339.727119 -231.768096) (xy 339.715064 -231.820468) (xy 339.695276 -231.870434) (xy 339.668206 -231.91686)
			(xy 339.634468 -231.958692) (xy 339.594827 -231.99498) (xy 339.550184 -232.0249) (xy 339.501553 -232.047772)
			(xy 339.450037 -232.063079) (xy 339.423502 -232.067354) (xy 339.37956 -232.07345) (xy 339.37956 -232.555013)
			(xy 339.48877 -232.555013) (xy 339.48877 -232.501715) (xy 339.496713 -232.449011) (xy 339.512423 -232.398081)
			(xy 339.535549 -232.35006) (xy 339.565573 -232.306023) (xy 339.601825 -232.266952) (xy 339.643496 -232.233721)
			(xy 339.689654 -232.207072) (xy 339.739268 -232.1876) (xy 339.79123 -232.17574) (xy 339.84438 -232.171757)
			(xy 339.89753 -232.17574) (xy 339.949492 -232.1876) (xy 339.999106 -232.207072) (xy 340.045264 -232.233721)
			(xy 340.086935 -232.266952) (xy 340.123187 -232.306023) (xy 340.153211 -232.35006) (xy 340.176337 -232.398081)
			(xy 340.192047 -232.449011) (xy 340.19999 -232.501715) (xy 340.200488 -232.528364) (xy 340.19999 -232.555013)
			(xy 340.428824 -232.555013) (xy 340.428824 -232.501715) (xy 340.436767 -232.449011) (xy 340.452477 -232.398081)
			(xy 340.475603 -232.35006) (xy 340.505627 -232.306023) (xy 340.541879 -232.266952) (xy 340.58355 -232.233721)
			(xy 340.629708 -232.207072) (xy 340.679322 -232.1876) (xy 340.731284 -232.17574) (xy 340.784434 -232.171757)
			(xy 340.837584 -232.17574) (xy 340.889546 -232.1876) (xy 340.93916 -232.207072) (xy 340.985318 -232.233721)
			(xy 341.026989 -232.266952) (xy 341.063241 -232.306023) (xy 341.093265 -232.35006) (xy 341.116391 -232.398081)
			(xy 341.132101 -232.449011) (xy 341.140044 -232.501715) (xy 341.140542 -232.528364) (xy 341.140044 -232.555013)
			(xy 341.368624 -232.555013) (xy 341.368624 -232.501715) (xy 341.376567 -232.449011) (xy 341.392277 -232.398081)
			(xy 341.415403 -232.35006) (xy 341.445427 -232.306023) (xy 341.481679 -232.266952) (xy 341.52335 -232.233721)
			(xy 341.569508 -232.207072) (xy 341.619122 -232.1876) (xy 341.671084 -232.17574) (xy 341.724234 -232.171757)
			(xy 341.777384 -232.17574) (xy 341.829346 -232.1876) (xy 341.87896 -232.207072) (xy 341.925118 -232.233721)
			(xy 341.966789 -232.266952) (xy 342.003041 -232.306023) (xy 342.033065 -232.35006) (xy 342.056191 -232.398081)
			(xy 342.071901 -232.449011) (xy 342.079844 -232.501715) (xy 342.080342 -232.528364) (xy 342.079844 -232.555013)
			(xy 342.308424 -232.555013) (xy 342.308424 -232.501715) (xy 342.316367 -232.449011) (xy 342.332077 -232.398081)
			(xy 342.355203 -232.35006) (xy 342.385227 -232.306023) (xy 342.421479 -232.266952) (xy 342.46315 -232.233721)
			(xy 342.509308 -232.207072) (xy 342.558922 -232.1876) (xy 342.610884 -232.17574) (xy 342.664034 -232.171757)
			(xy 342.717184 -232.17574) (xy 342.769146 -232.1876) (xy 342.81876 -232.207072) (xy 342.864918 -232.233721)
			(xy 342.906589 -232.266952) (xy 342.942841 -232.306023) (xy 342.972865 -232.35006) (xy 342.995991 -232.398081)
			(xy 343.011701 -232.449011) (xy 343.019644 -232.501715) (xy 343.020142 -232.528364) (xy 343.019644 -232.555013)
			(xy 343.248224 -232.555013) (xy 343.248224 -232.501715) (xy 343.256167 -232.449011) (xy 343.271877 -232.398081)
			(xy 343.295003 -232.35006) (xy 343.325027 -232.306023) (xy 343.361279 -232.266952) (xy 343.40295 -232.233721)
			(xy 343.449108 -232.207072) (xy 343.498722 -232.1876) (xy 343.550684 -232.17574) (xy 343.603834 -232.171757)
			(xy 343.656984 -232.17574) (xy 343.708946 -232.1876) (xy 343.75856 -232.207072) (xy 343.804718 -232.233721)
			(xy 343.846389 -232.266952) (xy 343.882641 -232.306023) (xy 343.912665 -232.35006) (xy 343.935791 -232.398081)
			(xy 343.951501 -232.449011) (xy 343.959444 -232.501715) (xy 343.959942 -232.528364) (xy 343.959444 -232.555013)
			(xy 344.188024 -232.555013) (xy 344.188024 -232.501715) (xy 344.195967 -232.449011) (xy 344.211677 -232.398081)
			(xy 344.234803 -232.35006) (xy 344.264827 -232.306023) (xy 344.301079 -232.266952) (xy 344.34275 -232.233721)
			(xy 344.388908 -232.207072) (xy 344.438522 -232.1876) (xy 344.490484 -232.17574) (xy 344.543634 -232.171757)
			(xy 344.596784 -232.17574) (xy 344.648746 -232.1876) (xy 344.69836 -232.207072) (xy 344.744518 -232.233721)
			(xy 344.786189 -232.266952) (xy 344.822441 -232.306023) (xy 344.852465 -232.35006) (xy 344.875591 -232.398081)
			(xy 344.891301 -232.449011) (xy 344.899244 -232.501715) (xy 344.899742 -232.528364) (xy 344.899244 -232.555013)
			(xy 345.127824 -232.555013) (xy 345.127824 -232.501715) (xy 345.135767 -232.449011) (xy 345.151477 -232.398081)
			(xy 345.174603 -232.35006) (xy 345.204627 -232.306023) (xy 345.240879 -232.266952) (xy 345.28255 -232.233721)
			(xy 345.328708 -232.207072) (xy 345.378322 -232.1876) (xy 345.430284 -232.17574) (xy 345.483434 -232.171757)
			(xy 345.536584 -232.17574) (xy 345.588546 -232.1876) (xy 345.63816 -232.207072) (xy 345.684318 -232.233721)
			(xy 345.725989 -232.266952) (xy 345.762241 -232.306023) (xy 345.792265 -232.35006) (xy 345.815391 -232.398081)
			(xy 345.831101 -232.449011) (xy 345.839044 -232.501715) (xy 345.839542 -232.528364) (xy 345.839044 -232.555013)
			(xy 346.06737 -232.555013) (xy 346.06737 -232.501715) (xy 346.075313 -232.449011) (xy 346.091023 -232.398081)
			(xy 346.114149 -232.35006) (xy 346.144173 -232.306023) (xy 346.180425 -232.266952) (xy 346.222096 -232.233721)
			(xy 346.268254 -232.207072) (xy 346.317868 -232.1876) (xy 346.36983 -232.17574) (xy 346.42298 -232.171757)
			(xy 346.47613 -232.17574) (xy 346.528092 -232.1876) (xy 346.577706 -232.207072) (xy 346.623864 -232.233721)
			(xy 346.665535 -232.266952) (xy 346.701787 -232.306023) (xy 346.731811 -232.35006) (xy 346.754937 -232.398081)
			(xy 346.770647 -232.449011) (xy 346.77859 -232.501715) (xy 346.779088 -232.528364) (xy 346.77859 -232.555013)
			(xy 347.007424 -232.555013) (xy 347.007424 -232.501715) (xy 347.015367 -232.449011) (xy 347.031077 -232.398081)
			(xy 347.054203 -232.35006) (xy 347.084227 -232.306023) (xy 347.120479 -232.266952) (xy 347.16215 -232.233721)
			(xy 347.208308 -232.207072) (xy 347.257922 -232.1876) (xy 347.309884 -232.17574) (xy 347.363034 -232.171757)
			(xy 347.416184 -232.17574) (xy 347.468146 -232.1876) (xy 347.51776 -232.207072) (xy 347.563918 -232.233721)
			(xy 347.605589 -232.266952) (xy 347.641841 -232.306023) (xy 347.671865 -232.35006) (xy 347.694991 -232.398081)
			(xy 347.710701 -232.449011) (xy 347.718644 -232.501715) (xy 347.719142 -232.528364) (xy 347.718644 -232.555013)
			(xy 347.947224 -232.555013) (xy 347.947224 -232.501715) (xy 347.955167 -232.449011) (xy 347.970877 -232.398081)
			(xy 347.994003 -232.35006) (xy 348.024027 -232.306023) (xy 348.060279 -232.266952) (xy 348.10195 -232.233721)
			(xy 348.148108 -232.207072) (xy 348.197722 -232.1876) (xy 348.249684 -232.17574) (xy 348.302834 -232.171757)
			(xy 348.355984 -232.17574) (xy 348.407946 -232.1876) (xy 348.45756 -232.207072) (xy 348.503718 -232.233721)
			(xy 348.545389 -232.266952) (xy 348.581641 -232.306023) (xy 348.611665 -232.35006) (xy 348.634791 -232.398081)
			(xy 348.650501 -232.449011) (xy 348.658444 -232.501715) (xy 348.658942 -232.528364) (xy 348.658444 -232.555013)
			(xy 349.826824 -232.555013) (xy 349.826824 -232.501715) (xy 349.834767 -232.449011) (xy 349.850477 -232.398081)
			(xy 349.873603 -232.35006) (xy 349.903627 -232.306023) (xy 349.939879 -232.266952) (xy 349.98155 -232.233721)
			(xy 350.027708 -232.207072) (xy 350.077322 -232.1876) (xy 350.129284 -232.17574) (xy 350.182434 -232.171757)
			(xy 350.235584 -232.17574) (xy 350.287546 -232.1876) (xy 350.33716 -232.207072) (xy 350.383318 -232.233721)
			(xy 350.424989 -232.266952) (xy 350.461241 -232.306023) (xy 350.491265 -232.35006) (xy 350.514391 -232.398081)
			(xy 350.530101 -232.449011) (xy 350.538044 -232.501715) (xy 350.538542 -232.528364) (xy 350.538044 -232.555013)
			(xy 350.766624 -232.555013) (xy 350.766624 -232.501715) (xy 350.774567 -232.449011) (xy 350.790277 -232.398081)
			(xy 350.813403 -232.35006) (xy 350.843427 -232.306023) (xy 350.879679 -232.266952) (xy 350.92135 -232.233721)
			(xy 350.967508 -232.207072) (xy 351.017122 -232.1876) (xy 351.069084 -232.17574) (xy 351.122234 -232.171757)
			(xy 351.175384 -232.17574) (xy 351.227346 -232.1876) (xy 351.27696 -232.207072) (xy 351.323118 -232.233721)
			(xy 351.364789 -232.266952) (xy 351.401041 -232.306023) (xy 351.431065 -232.35006) (xy 351.454191 -232.398081)
			(xy 351.469901 -232.449011) (xy 351.477844 -232.501715) (xy 351.478342 -232.528364) (xy 351.477844 -232.555013)
			(xy 351.706424 -232.555013) (xy 351.706424 -232.501715) (xy 351.714367 -232.449011) (xy 351.730077 -232.398081)
			(xy 351.753203 -232.35006) (xy 351.783227 -232.306023) (xy 351.819479 -232.266952) (xy 351.86115 -232.233721)
			(xy 351.907308 -232.207072) (xy 351.956922 -232.1876) (xy 352.008884 -232.17574) (xy 352.062034 -232.171757)
			(xy 352.115184 -232.17574) (xy 352.167146 -232.1876) (xy 352.21676 -232.207072) (xy 352.262918 -232.233721)
			(xy 352.304589 -232.266952) (xy 352.340841 -232.306023) (xy 352.370865 -232.35006) (xy 352.393991 -232.398081)
			(xy 352.409701 -232.449011) (xy 352.417644 -232.501715) (xy 352.418142 -232.528364) (xy 352.417644 -232.555013)
			(xy 352.646224 -232.555013) (xy 352.646224 -232.501715) (xy 352.654167 -232.449011) (xy 352.669877 -232.398081)
			(xy 352.693003 -232.35006) (xy 352.723027 -232.306023) (xy 352.759279 -232.266952) (xy 352.80095 -232.233721)
			(xy 352.847108 -232.207072) (xy 352.896722 -232.1876) (xy 352.948684 -232.17574) (xy 353.001834 -232.171757)
			(xy 353.054984 -232.17574) (xy 353.106946 -232.1876) (xy 353.15656 -232.207072) (xy 353.202718 -232.233721)
			(xy 353.244389 -232.266952) (xy 353.280641 -232.306023) (xy 353.310665 -232.35006) (xy 353.333791 -232.398081)
			(xy 353.349501 -232.449011) (xy 353.357444 -232.501715) (xy 353.357942 -232.528364) (xy 353.357444 -232.555013)
			(xy 353.586024 -232.555013) (xy 353.586024 -232.501715) (xy 353.593967 -232.449011) (xy 353.609677 -232.398081)
			(xy 353.632803 -232.35006) (xy 353.662827 -232.306023) (xy 353.699079 -232.266952) (xy 353.74075 -232.233721)
			(xy 353.786908 -232.207072) (xy 353.836522 -232.1876) (xy 353.888484 -232.17574) (xy 353.941634 -232.171757)
			(xy 353.994784 -232.17574) (xy 354.046746 -232.1876) (xy 354.09636 -232.207072) (xy 354.142518 -232.233721)
			(xy 354.184189 -232.266952) (xy 354.220441 -232.306023) (xy 354.250465 -232.35006) (xy 354.273591 -232.398081)
			(xy 354.289301 -232.449011) (xy 354.297244 -232.501715) (xy 354.297742 -232.528364) (xy 354.297244 -232.555013)
			(xy 354.525824 -232.555013) (xy 354.525824 -232.501715) (xy 354.533767 -232.449011) (xy 354.549477 -232.398081)
			(xy 354.572603 -232.35006) (xy 354.602627 -232.306023) (xy 354.638879 -232.266952) (xy 354.68055 -232.233721)
			(xy 354.726708 -232.207072) (xy 354.776322 -232.1876) (xy 354.828284 -232.17574) (xy 354.881434 -232.171757)
			(xy 354.934584 -232.17574) (xy 354.986546 -232.1876) (xy 355.03616 -232.207072) (xy 355.082318 -232.233721)
			(xy 355.123989 -232.266952) (xy 355.160241 -232.306023) (xy 355.190265 -232.35006) (xy 355.213391 -232.398081)
			(xy 355.229101 -232.449011) (xy 355.237044 -232.501715) (xy 355.237542 -232.528364) (xy 355.237044 -232.555013)
			(xy 355.465624 -232.555013) (xy 355.465624 -232.501715) (xy 355.473567 -232.449011) (xy 355.489277 -232.398081)
			(xy 355.512403 -232.35006) (xy 355.542427 -232.306023) (xy 355.578679 -232.266952) (xy 355.62035 -232.233721)
			(xy 355.666508 -232.207072) (xy 355.716122 -232.1876) (xy 355.768084 -232.17574) (xy 355.821234 -232.171757)
			(xy 355.874384 -232.17574) (xy 355.926346 -232.1876) (xy 355.97596 -232.207072) (xy 356.022118 -232.233721)
			(xy 356.063789 -232.266952) (xy 356.100041 -232.306023) (xy 356.130065 -232.35006) (xy 356.153191 -232.398081)
			(xy 356.168901 -232.449011) (xy 356.176844 -232.501715) (xy 356.177342 -232.528364) (xy 356.176844 -232.555013)
			(xy 356.405424 -232.555013) (xy 356.405424 -232.501715) (xy 356.413367 -232.449011) (xy 356.429077 -232.398081)
			(xy 356.452203 -232.35006) (xy 356.482227 -232.306023) (xy 356.518479 -232.266952) (xy 356.56015 -232.233721)
			(xy 356.606308 -232.207072) (xy 356.655922 -232.1876) (xy 356.707884 -232.17574) (xy 356.761034 -232.171757)
			(xy 356.814184 -232.17574) (xy 356.866146 -232.1876) (xy 356.91576 -232.207072) (xy 356.961918 -232.233721)
			(xy 357.003589 -232.266952) (xy 357.039841 -232.306023) (xy 357.069865 -232.35006) (xy 357.092991 -232.398081)
			(xy 357.108701 -232.449011) (xy 357.116644 -232.501715) (xy 357.117142 -232.528364) (xy 357.116644 -232.555013)
			(xy 357.345224 -232.555013) (xy 357.345224 -232.501715) (xy 357.353167 -232.449011) (xy 357.368877 -232.398081)
			(xy 357.392003 -232.35006) (xy 357.422027 -232.306023) (xy 357.458279 -232.266952) (xy 357.49995 -232.233721)
			(xy 357.546108 -232.207072) (xy 357.595722 -232.1876) (xy 357.647684 -232.17574) (xy 357.700834 -232.171757)
			(xy 357.753984 -232.17574) (xy 357.805946 -232.1876) (xy 357.85556 -232.207072) (xy 357.901718 -232.233721)
			(xy 357.943389 -232.266952) (xy 357.979641 -232.306023) (xy 358.009665 -232.35006) (xy 358.032791 -232.398081)
			(xy 358.048501 -232.449011) (xy 358.056444 -232.501715) (xy 358.056942 -232.528364) (xy 358.056444 -232.555013)
			(xy 358.285024 -232.555013) (xy 358.285024 -232.501715) (xy 358.292967 -232.449011) (xy 358.308677 -232.398081)
			(xy 358.331803 -232.35006) (xy 358.361827 -232.306023) (xy 358.398079 -232.266952) (xy 358.43975 -232.233721)
			(xy 358.485908 -232.207072) (xy 358.535522 -232.1876) (xy 358.587484 -232.17574) (xy 358.640634 -232.171757)
			(xy 358.693784 -232.17574) (xy 358.745746 -232.1876) (xy 358.79536 -232.207072) (xy 358.841518 -232.233721)
			(xy 358.883189 -232.266952) (xy 358.919441 -232.306023) (xy 358.949465 -232.35006) (xy 358.972591 -232.398081)
			(xy 358.988301 -232.449011) (xy 358.996244 -232.501715) (xy 358.996742 -232.528364) (xy 358.996244 -232.555013)
			(xy 359.224824 -232.555013) (xy 359.224824 -232.501715) (xy 359.232767 -232.449011) (xy 359.248477 -232.398081)
			(xy 359.271603 -232.35006) (xy 359.301627 -232.306023) (xy 359.337879 -232.266952) (xy 359.37955 -232.233721)
			(xy 359.425708 -232.207072) (xy 359.475322 -232.1876) (xy 359.527284 -232.17574) (xy 359.580434 -232.171757)
			(xy 359.633584 -232.17574) (xy 359.685546 -232.1876) (xy 359.73516 -232.207072) (xy 359.781318 -232.233721)
			(xy 359.822989 -232.266952) (xy 359.859241 -232.306023) (xy 359.889265 -232.35006) (xy 359.912391 -232.398081)
			(xy 359.928101 -232.449011) (xy 359.936044 -232.501715) (xy 359.936542 -232.528364) (xy 359.936044 -232.555013)
			(xy 360.164624 -232.555013) (xy 360.164624 -232.501715) (xy 360.172567 -232.449011) (xy 360.188277 -232.398081)
			(xy 360.211403 -232.35006) (xy 360.241427 -232.306023) (xy 360.277679 -232.266952) (xy 360.31935 -232.233721)
			(xy 360.365508 -232.207072) (xy 360.415122 -232.1876) (xy 360.467084 -232.17574) (xy 360.520234 -232.171757)
			(xy 360.573384 -232.17574) (xy 360.625346 -232.1876) (xy 360.67496 -232.207072) (xy 360.721118 -232.233721)
			(xy 360.762789 -232.266952) (xy 360.799041 -232.306023) (xy 360.829065 -232.35006) (xy 360.852191 -232.398081)
			(xy 360.867901 -232.449011) (xy 360.875844 -232.501715) (xy 360.876342 -232.528364) (xy 360.875844 -232.555013)
			(xy 361.104424 -232.555013) (xy 361.104424 -232.501715) (xy 361.112367 -232.449011) (xy 361.128077 -232.398081)
			(xy 361.151203 -232.35006) (xy 361.181227 -232.306023) (xy 361.217479 -232.266952) (xy 361.25915 -232.233721)
			(xy 361.305308 -232.207072) (xy 361.354922 -232.1876) (xy 361.406884 -232.17574) (xy 361.460034 -232.171757)
			(xy 361.513184 -232.17574) (xy 361.565146 -232.1876) (xy 361.61476 -232.207072) (xy 361.660918 -232.233721)
			(xy 361.702589 -232.266952) (xy 361.738841 -232.306023) (xy 361.768865 -232.35006) (xy 361.791991 -232.398081)
			(xy 361.807701 -232.449011) (xy 361.815644 -232.501715) (xy 361.816142 -232.528364) (xy 361.815644 -232.555013)
			(xy 362.044224 -232.555013) (xy 362.044224 -232.501715) (xy 362.052167 -232.449011) (xy 362.067877 -232.398081)
			(xy 362.091003 -232.35006) (xy 362.121027 -232.306023) (xy 362.157279 -232.266952) (xy 362.19895 -232.233721)
			(xy 362.245108 -232.207072) (xy 362.294722 -232.1876) (xy 362.346684 -232.17574) (xy 362.399834 -232.171757)
			(xy 362.452984 -232.17574) (xy 362.504946 -232.1876) (xy 362.55456 -232.207072) (xy 362.600718 -232.233721)
			(xy 362.642389 -232.266952) (xy 362.678641 -232.306023) (xy 362.708665 -232.35006) (xy 362.731791 -232.398081)
			(xy 362.747501 -232.449011) (xy 362.755444 -232.501715) (xy 362.755942 -232.528364) (xy 362.755444 -232.555013)
			(xy 362.984024 -232.555013) (xy 362.984024 -232.501715) (xy 362.991967 -232.449011) (xy 363.007677 -232.398081)
			(xy 363.030803 -232.35006) (xy 363.060827 -232.306023) (xy 363.097079 -232.266952) (xy 363.13875 -232.233721)
			(xy 363.184908 -232.207072) (xy 363.234522 -232.1876) (xy 363.286484 -232.17574) (xy 363.339634 -232.171757)
			(xy 363.392784 -232.17574) (xy 363.444746 -232.1876) (xy 363.49436 -232.207072) (xy 363.540518 -232.233721)
			(xy 363.582189 -232.266952) (xy 363.618441 -232.306023) (xy 363.648465 -232.35006) (xy 363.671591 -232.398081)
			(xy 363.687301 -232.449011) (xy 363.695244 -232.501715) (xy 363.695742 -232.528364) (xy 363.695244 -232.555013)
			(xy 363.923824 -232.555013) (xy 363.923824 -232.501715) (xy 363.931767 -232.449011) (xy 363.947477 -232.398081)
			(xy 363.970603 -232.35006) (xy 364.000627 -232.306023) (xy 364.036879 -232.266952) (xy 364.07855 -232.233721)
			(xy 364.124708 -232.207072) (xy 364.174322 -232.1876) (xy 364.226284 -232.17574) (xy 364.279434 -232.171757)
			(xy 364.332584 -232.17574) (xy 364.384546 -232.1876) (xy 364.43416 -232.207072) (xy 364.480318 -232.233721)
			(xy 364.521989 -232.266952) (xy 364.558241 -232.306023) (xy 364.588265 -232.35006) (xy 364.611391 -232.398081)
			(xy 364.627101 -232.449011) (xy 364.635044 -232.501715) (xy 364.635542 -232.528364) (xy 364.635044 -232.555013)
			(xy 364.863624 -232.555013) (xy 364.863624 -232.501715) (xy 364.871567 -232.449011) (xy 364.887277 -232.398081)
			(xy 364.910403 -232.35006) (xy 364.940427 -232.306023) (xy 364.976679 -232.266952) (xy 365.01835 -232.233721)
			(xy 365.064508 -232.207072) (xy 365.114122 -232.1876) (xy 365.166084 -232.17574) (xy 365.219234 -232.171757)
			(xy 365.272384 -232.17574) (xy 365.324346 -232.1876) (xy 365.37396 -232.207072) (xy 365.420118 -232.233721)
			(xy 365.461789 -232.266952) (xy 365.498041 -232.306023) (xy 365.528065 -232.35006) (xy 365.551191 -232.398081)
			(xy 365.566901 -232.449011) (xy 365.574844 -232.501715) (xy 365.575342 -232.528364) (xy 365.574844 -232.555013)
			(xy 365.803424 -232.555013) (xy 365.803424 -232.501715) (xy 365.811367 -232.449011) (xy 365.827077 -232.398081)
			(xy 365.850203 -232.35006) (xy 365.880227 -232.306023) (xy 365.916479 -232.266952) (xy 365.95815 -232.233721)
			(xy 366.004308 -232.207072) (xy 366.053922 -232.1876) (xy 366.105884 -232.17574) (xy 366.159034 -232.171757)
			(xy 366.212184 -232.17574) (xy 366.264146 -232.1876) (xy 366.31376 -232.207072) (xy 366.359918 -232.233721)
			(xy 366.401589 -232.266952) (xy 366.437841 -232.306023) (xy 366.467865 -232.35006) (xy 366.490991 -232.398081)
			(xy 366.506701 -232.449011) (xy 366.514644 -232.501715) (xy 366.515142 -232.528364) (xy 366.514644 -232.555013)
			(xy 366.743224 -232.555013) (xy 366.743224 -232.501715) (xy 366.751167 -232.449011) (xy 366.766877 -232.398081)
			(xy 366.790003 -232.35006) (xy 366.820027 -232.306023) (xy 366.856279 -232.266952) (xy 366.89795 -232.233721)
			(xy 366.944108 -232.207072) (xy 366.993722 -232.1876) (xy 367.045684 -232.17574) (xy 367.098834 -232.171757)
			(xy 367.151984 -232.17574) (xy 367.203946 -232.1876) (xy 367.25356 -232.207072) (xy 367.299718 -232.233721)
			(xy 367.341389 -232.266952) (xy 367.377641 -232.306023) (xy 367.407665 -232.35006) (xy 367.430791 -232.398081)
			(xy 367.446501 -232.449011) (xy 367.454444 -232.501715) (xy 367.454942 -232.528364) (xy 367.454444 -232.555013)
			(xy 367.68277 -232.555013) (xy 367.68277 -232.501715) (xy 367.690713 -232.449011) (xy 367.706423 -232.398081)
			(xy 367.729549 -232.35006) (xy 367.759573 -232.306023) (xy 367.795825 -232.266952) (xy 367.837496 -232.233721)
			(xy 367.883654 -232.207072) (xy 367.933268 -232.1876) (xy 367.98523 -232.17574) (xy 368.03838 -232.171757)
			(xy 368.09153 -232.17574) (xy 368.143492 -232.1876) (xy 368.193106 -232.207072) (xy 368.239264 -232.233721)
			(xy 368.280935 -232.266952) (xy 368.317187 -232.306023) (xy 368.347211 -232.35006) (xy 368.370337 -232.398081)
			(xy 368.386047 -232.449011) (xy 368.39399 -232.501715) (xy 368.394488 -232.528364) (xy 368.39399 -232.555013)
			(xy 368.622824 -232.555013) (xy 368.622824 -232.501715) (xy 368.630767 -232.449011) (xy 368.646477 -232.398081)
			(xy 368.669603 -232.35006) (xy 368.699627 -232.306023) (xy 368.735879 -232.266952) (xy 368.77755 -232.233721)
			(xy 368.823708 -232.207072) (xy 368.873322 -232.1876) (xy 368.925284 -232.17574) (xy 368.978434 -232.171757)
			(xy 369.031584 -232.17574) (xy 369.083546 -232.1876) (xy 369.13316 -232.207072) (xy 369.179318 -232.233721)
			(xy 369.220989 -232.266952) (xy 369.257241 -232.306023) (xy 369.287265 -232.35006) (xy 369.310391 -232.398081)
			(xy 369.326101 -232.449011) (xy 369.334044 -232.501715) (xy 369.334542 -232.528364) (xy 369.334044 -232.555013)
			(xy 369.562624 -232.555013) (xy 369.562624 -232.501715) (xy 369.570567 -232.449011) (xy 369.586277 -232.398081)
			(xy 369.609403 -232.35006) (xy 369.639427 -232.306023) (xy 369.675679 -232.266952) (xy 369.71735 -232.233721)
			(xy 369.763508 -232.207072) (xy 369.813122 -232.1876) (xy 369.865084 -232.17574) (xy 369.918234 -232.171757)
			(xy 369.971384 -232.17574) (xy 370.023346 -232.1876) (xy 370.07296 -232.207072) (xy 370.119118 -232.233721)
			(xy 370.160789 -232.266952) (xy 370.197041 -232.306023) (xy 370.227065 -232.35006) (xy 370.250191 -232.398081)
			(xy 370.265901 -232.449011) (xy 370.273844 -232.501715) (xy 370.274342 -232.528364) (xy 370.273844 -232.555013)
			(xy 370.502424 -232.555013) (xy 370.502424 -232.501715) (xy 370.510367 -232.449011) (xy 370.526077 -232.398081)
			(xy 370.549203 -232.35006) (xy 370.579227 -232.306023) (xy 370.615479 -232.266952) (xy 370.65715 -232.233721)
			(xy 370.703308 -232.207072) (xy 370.752922 -232.1876) (xy 370.804884 -232.17574) (xy 370.858034 -232.171757)
			(xy 370.911184 -232.17574) (xy 370.963146 -232.1876) (xy 371.01276 -232.207072) (xy 371.058918 -232.233721)
			(xy 371.100589 -232.266952) (xy 371.136841 -232.306023) (xy 371.166865 -232.35006) (xy 371.189991 -232.398081)
			(xy 371.205701 -232.449011) (xy 371.213644 -232.501715) (xy 371.214142 -232.528364) (xy 371.213644 -232.555013)
			(xy 371.442224 -232.555013) (xy 371.442224 -232.501715) (xy 371.450167 -232.449011) (xy 371.465877 -232.398081)
			(xy 371.489003 -232.35006) (xy 371.519027 -232.306023) (xy 371.555279 -232.266952) (xy 371.59695 -232.233721)
			(xy 371.643108 -232.207072) (xy 371.692722 -232.1876) (xy 371.744684 -232.17574) (xy 371.797834 -232.171757)
			(xy 371.850984 -232.17574) (xy 371.902946 -232.1876) (xy 371.95256 -232.207072) (xy 371.998718 -232.233721)
			(xy 372.040389 -232.266952) (xy 372.076641 -232.306023) (xy 372.106665 -232.35006) (xy 372.129791 -232.398081)
			(xy 372.145501 -232.449011) (xy 372.153444 -232.501715) (xy 372.153942 -232.528364) (xy 372.153444 -232.555013)
			(xy 372.382024 -232.555013) (xy 372.382024 -232.501715) (xy 372.389967 -232.449011) (xy 372.405677 -232.398081)
			(xy 372.428803 -232.35006) (xy 372.458827 -232.306023) (xy 372.495079 -232.266952) (xy 372.53675 -232.233721)
			(xy 372.582908 -232.207072) (xy 372.632522 -232.1876) (xy 372.684484 -232.17574) (xy 372.737634 -232.171757)
			(xy 372.790784 -232.17574) (xy 372.842746 -232.1876) (xy 372.89236 -232.207072) (xy 372.938518 -232.233721)
			(xy 372.980189 -232.266952) (xy 373.016441 -232.306023) (xy 373.046465 -232.35006) (xy 373.069591 -232.398081)
			(xy 373.085301 -232.449011) (xy 373.093244 -232.501715) (xy 373.093742 -232.528364) (xy 373.093244 -232.555013)
			(xy 373.321824 -232.555013) (xy 373.321824 -232.501715) (xy 373.329767 -232.449011) (xy 373.345477 -232.398081)
			(xy 373.368603 -232.35006) (xy 373.398627 -232.306023) (xy 373.434879 -232.266952) (xy 373.47655 -232.233721)
			(xy 373.522708 -232.207072) (xy 373.572322 -232.1876) (xy 373.624284 -232.17574) (xy 373.677434 -232.171757)
			(xy 373.730584 -232.17574) (xy 373.782546 -232.1876) (xy 373.83216 -232.207072) (xy 373.878318 -232.233721)
			(xy 373.919989 -232.266952) (xy 373.956241 -232.306023) (xy 373.986265 -232.35006) (xy 374.009391 -232.398081)
			(xy 374.025101 -232.449011) (xy 374.033044 -232.501715) (xy 374.033542 -232.528364) (xy 374.033044 -232.555013)
			(xy 374.26137 -232.555013) (xy 374.26137 -232.501715) (xy 374.269313 -232.449011) (xy 374.285023 -232.398081)
			(xy 374.308149 -232.35006) (xy 374.338173 -232.306023) (xy 374.374425 -232.266952) (xy 374.416096 -232.233721)
			(xy 374.462254 -232.207072) (xy 374.511868 -232.1876) (xy 374.56383 -232.17574) (xy 374.61698 -232.171757)
			(xy 374.67013 -232.17574) (xy 374.722092 -232.1876) (xy 374.771706 -232.207072) (xy 374.817864 -232.233721)
			(xy 374.859535 -232.266952) (xy 374.895787 -232.306023) (xy 374.925811 -232.35006) (xy 374.948937 -232.398081)
			(xy 374.964647 -232.449011) (xy 374.97259 -232.501715) (xy 374.973088 -232.528364) (xy 374.97259 -232.555013)
			(xy 375.201424 -232.555013) (xy 375.201424 -232.501715) (xy 375.209367 -232.449011) (xy 375.225077 -232.398081)
			(xy 375.248203 -232.35006) (xy 375.278227 -232.306023) (xy 375.314479 -232.266952) (xy 375.35615 -232.233721)
			(xy 375.402308 -232.207072) (xy 375.451922 -232.1876) (xy 375.503884 -232.17574) (xy 375.557034 -232.171757)
			(xy 375.610184 -232.17574) (xy 375.662146 -232.1876) (xy 375.71176 -232.207072) (xy 375.757918 -232.233721)
			(xy 375.799589 -232.266952) (xy 375.835841 -232.306023) (xy 375.865865 -232.35006) (xy 375.888991 -232.398081)
			(xy 375.904701 -232.449011) (xy 375.912644 -232.501715) (xy 375.913142 -232.528364) (xy 375.912644 -232.555013)
			(xy 376.141224 -232.555013) (xy 376.141224 -232.501715) (xy 376.149167 -232.449011) (xy 376.164877 -232.398081)
			(xy 376.188003 -232.35006) (xy 376.218027 -232.306023) (xy 376.254279 -232.266952) (xy 376.29595 -232.233721)
			(xy 376.342108 -232.207072) (xy 376.391722 -232.1876) (xy 376.443684 -232.17574) (xy 376.496834 -232.171757)
			(xy 376.549984 -232.17574) (xy 376.601946 -232.1876) (xy 376.65156 -232.207072) (xy 376.697718 -232.233721)
			(xy 376.739389 -232.266952) (xy 376.775641 -232.306023) (xy 376.805665 -232.35006) (xy 376.828791 -232.398081)
			(xy 376.844501 -232.449011) (xy 376.852444 -232.501715) (xy 376.852942 -232.528364) (xy 376.852444 -232.555013)
			(xy 377.081024 -232.555013) (xy 377.081024 -232.501715) (xy 377.088967 -232.449011) (xy 377.104677 -232.398081)
			(xy 377.127803 -232.35006) (xy 377.157827 -232.306023) (xy 377.194079 -232.266952) (xy 377.23575 -232.233721)
			(xy 377.281908 -232.207072) (xy 377.331522 -232.1876) (xy 377.383484 -232.17574) (xy 377.436634 -232.171757)
			(xy 377.489784 -232.17574) (xy 377.541746 -232.1876) (xy 377.59136 -232.207072) (xy 377.637518 -232.233721)
			(xy 377.679189 -232.266952) (xy 377.715441 -232.306023) (xy 377.745465 -232.35006) (xy 377.768591 -232.398081)
			(xy 377.784301 -232.449011) (xy 377.792244 -232.501715) (xy 377.792742 -232.528364) (xy 377.792244 -232.555013)
			(xy 378.020824 -232.555013) (xy 378.020824 -232.501715) (xy 378.028767 -232.449011) (xy 378.044477 -232.398081)
			(xy 378.067603 -232.35006) (xy 378.097627 -232.306023) (xy 378.133879 -232.266952) (xy 378.17555 -232.233721)
			(xy 378.221708 -232.207072) (xy 378.271322 -232.1876) (xy 378.323284 -232.17574) (xy 378.376434 -232.171757)
			(xy 378.429584 -232.17574) (xy 378.481546 -232.1876) (xy 378.53116 -232.207072) (xy 378.577318 -232.233721)
			(xy 378.618989 -232.266952) (xy 378.655241 -232.306023) (xy 378.685265 -232.35006) (xy 378.708391 -232.398081)
			(xy 378.724101 -232.449011) (xy 378.732044 -232.501715) (xy 378.732542 -232.528364) (xy 378.732044 -232.555013)
			(xy 378.960624 -232.555013) (xy 378.960624 -232.501715) (xy 378.968567 -232.449011) (xy 378.984277 -232.398081)
			(xy 379.007403 -232.35006) (xy 379.037427 -232.306023) (xy 379.073679 -232.266952) (xy 379.11535 -232.233721)
			(xy 379.161508 -232.207072) (xy 379.211122 -232.1876) (xy 379.263084 -232.17574) (xy 379.316234 -232.171757)
			(xy 379.369384 -232.17574) (xy 379.421346 -232.1876) (xy 379.47096 -232.207072) (xy 379.517118 -232.233721)
			(xy 379.558789 -232.266952) (xy 379.595041 -232.306023) (xy 379.625065 -232.35006) (xy 379.648191 -232.398081)
			(xy 379.663901 -232.449011) (xy 379.671844 -232.501715) (xy 379.672342 -232.528364) (xy 379.671844 -232.555013)
			(xy 379.900424 -232.555013) (xy 379.900424 -232.501715) (xy 379.908367 -232.449011) (xy 379.924077 -232.398081)
			(xy 379.947203 -232.35006) (xy 379.977227 -232.306023) (xy 380.013479 -232.266952) (xy 380.05515 -232.233721)
			(xy 380.101308 -232.207072) (xy 380.150922 -232.1876) (xy 380.202884 -232.17574) (xy 380.256034 -232.171757)
			(xy 380.309184 -232.17574) (xy 380.361146 -232.1876) (xy 380.41076 -232.207072) (xy 380.456918 -232.233721)
			(xy 380.498589 -232.266952) (xy 380.534841 -232.306023) (xy 380.564865 -232.35006) (xy 380.587991 -232.398081)
			(xy 380.603701 -232.449011) (xy 380.611644 -232.501715) (xy 380.612142 -232.528364) (xy 380.611644 -232.555013)
			(xy 380.83997 -232.555013) (xy 380.83997 -232.501715) (xy 380.847913 -232.449011) (xy 380.863623 -232.398081)
			(xy 380.886749 -232.35006) (xy 380.916773 -232.306023) (xy 380.953025 -232.266952) (xy 380.994696 -232.233721)
			(xy 381.040854 -232.207072) (xy 381.090468 -232.1876) (xy 381.14243 -232.17574) (xy 381.19558 -232.171757)
			(xy 381.24873 -232.17574) (xy 381.300692 -232.1876) (xy 381.350306 -232.207072) (xy 381.396464 -232.233721)
			(xy 381.438135 -232.266952) (xy 381.474387 -232.306023) (xy 381.504411 -232.35006) (xy 381.527537 -232.398081)
			(xy 381.543247 -232.449011) (xy 381.55119 -232.501715) (xy 381.551688 -232.528364) (xy 381.55119 -232.555013)
			(xy 381.543247 -232.607717) (xy 381.527537 -232.658647) (xy 381.504411 -232.706668) (xy 381.474387 -232.750705)
			(xy 381.438135 -232.789776) (xy 381.396464 -232.823007) (xy 381.350306 -232.849656) (xy 381.300692 -232.869128)
			(xy 381.24873 -232.880988) (xy 381.19558 -232.884972) (xy 381.14243 -232.880988) (xy 381.090468 -232.869128)
			(xy 381.040854 -232.849656) (xy 380.994696 -232.823007) (xy 380.953025 -232.789776) (xy 380.916773 -232.750705)
			(xy 380.886749 -232.706668) (xy 380.863623 -232.658647) (xy 380.847913 -232.607717) (xy 380.83997 -232.555013)
			(xy 380.611644 -232.555013) (xy 380.603701 -232.607717) (xy 380.587991 -232.658647) (xy 380.564865 -232.706668)
			(xy 380.534841 -232.750705) (xy 380.498589 -232.789776) (xy 380.456918 -232.823007) (xy 380.41076 -232.849656)
			(xy 380.361146 -232.869128) (xy 380.309184 -232.880988) (xy 380.256034 -232.884972) (xy 380.202884 -232.880988)
			(xy 380.150922 -232.869128) (xy 380.101308 -232.849656) (xy 380.05515 -232.823007) (xy 380.013479 -232.789776)
			(xy 379.977227 -232.750705) (xy 379.947203 -232.706668) (xy 379.924077 -232.658647) (xy 379.908367 -232.607717)
			(xy 379.900424 -232.555013) (xy 379.671844 -232.555013) (xy 379.663901 -232.607717) (xy 379.648191 -232.658647)
			(xy 379.625065 -232.706668) (xy 379.595041 -232.750705) (xy 379.558789 -232.789776) (xy 379.517118 -232.823007)
			(xy 379.47096 -232.849656) (xy 379.421346 -232.869128) (xy 379.369384 -232.880988) (xy 379.316234 -232.884972)
			(xy 379.263084 -232.880988) (xy 379.211122 -232.869128) (xy 379.161508 -232.849656) (xy 379.11535 -232.823007)
			(xy 379.073679 -232.789776) (xy 379.037427 -232.750705) (xy 379.007403 -232.706668) (xy 378.984277 -232.658647)
			(xy 378.968567 -232.607717) (xy 378.960624 -232.555013) (xy 378.732044 -232.555013) (xy 378.724101 -232.607717)
			(xy 378.708391 -232.658647) (xy 378.685265 -232.706668) (xy 378.655241 -232.750705) (xy 378.618989 -232.789776)
			(xy 378.577318 -232.823007) (xy 378.53116 -232.849656) (xy 378.481546 -232.869128) (xy 378.429584 -232.880988)
			(xy 378.376434 -232.884972) (xy 378.323284 -232.880988) (xy 378.271322 -232.869128) (xy 378.221708 -232.849656)
			(xy 378.17555 -232.823007) (xy 378.133879 -232.789776) (xy 378.097627 -232.750705) (xy 378.067603 -232.706668)
			(xy 378.044477 -232.658647) (xy 378.028767 -232.607717) (xy 378.020824 -232.555013) (xy 377.792244 -232.555013)
			(xy 377.784301 -232.607717) (xy 377.768591 -232.658647) (xy 377.745465 -232.706668) (xy 377.715441 -232.750705)
			(xy 377.679189 -232.789776) (xy 377.637518 -232.823007) (xy 377.59136 -232.849656) (xy 377.541746 -232.869128)
			(xy 377.489784 -232.880988) (xy 377.436634 -232.884972) (xy 377.383484 -232.880988) (xy 377.331522 -232.869128)
			(xy 377.281908 -232.849656) (xy 377.23575 -232.823007) (xy 377.194079 -232.789776) (xy 377.157827 -232.750705)
			(xy 377.127803 -232.706668) (xy 377.104677 -232.658647) (xy 377.088967 -232.607717) (xy 377.081024 -232.555013)
			(xy 376.852444 -232.555013) (xy 376.844501 -232.607717) (xy 376.828791 -232.658647) (xy 376.805665 -232.706668)
			(xy 376.775641 -232.750705) (xy 376.739389 -232.789776) (xy 376.697718 -232.823007) (xy 376.65156 -232.849656)
			(xy 376.601946 -232.869128) (xy 376.549984 -232.880988) (xy 376.496834 -232.884972) (xy 376.443684 -232.880988)
			(xy 376.391722 -232.869128) (xy 376.342108 -232.849656) (xy 376.29595 -232.823007) (xy 376.254279 -232.789776)
			(xy 376.218027 -232.750705) (xy 376.188003 -232.706668) (xy 376.164877 -232.658647) (xy 376.149167 -232.607717)
			(xy 376.141224 -232.555013) (xy 375.912644 -232.555013) (xy 375.904701 -232.607717) (xy 375.888991 -232.658647)
			(xy 375.865865 -232.706668) (xy 375.835841 -232.750705) (xy 375.799589 -232.789776) (xy 375.757918 -232.823007)
			(xy 375.71176 -232.849656) (xy 375.662146 -232.869128) (xy 375.610184 -232.880988) (xy 375.557034 -232.884972)
			(xy 375.503884 -232.880988) (xy 375.451922 -232.869128) (xy 375.402308 -232.849656) (xy 375.35615 -232.823007)
			(xy 375.314479 -232.789776) (xy 375.278227 -232.750705) (xy 375.248203 -232.706668) (xy 375.225077 -232.658647)
			(xy 375.209367 -232.607717) (xy 375.201424 -232.555013) (xy 374.97259 -232.555013) (xy 374.964647 -232.607717)
			(xy 374.948937 -232.658647) (xy 374.925811 -232.706668) (xy 374.895787 -232.750705) (xy 374.859535 -232.789776)
			(xy 374.817864 -232.823007) (xy 374.771706 -232.849656) (xy 374.722092 -232.869128) (xy 374.67013 -232.880988)
			(xy 374.61698 -232.884972) (xy 374.56383 -232.880988) (xy 374.511868 -232.869128) (xy 374.462254 -232.849656)
			(xy 374.416096 -232.823007) (xy 374.374425 -232.789776) (xy 374.338173 -232.750705) (xy 374.308149 -232.706668)
			(xy 374.285023 -232.658647) (xy 374.269313 -232.607717) (xy 374.26137 -232.555013) (xy 374.033044 -232.555013)
			(xy 374.025101 -232.607717) (xy 374.009391 -232.658647) (xy 373.986265 -232.706668) (xy 373.956241 -232.750705)
			(xy 373.919989 -232.789776) (xy 373.878318 -232.823007) (xy 373.83216 -232.849656) (xy 373.782546 -232.869128)
			(xy 373.730584 -232.880988) (xy 373.677434 -232.884972) (xy 373.624284 -232.880988) (xy 373.572322 -232.869128)
			(xy 373.522708 -232.849656) (xy 373.47655 -232.823007) (xy 373.434879 -232.789776) (xy 373.398627 -232.750705)
			(xy 373.368603 -232.706668) (xy 373.345477 -232.658647) (xy 373.329767 -232.607717) (xy 373.321824 -232.555013)
			(xy 373.093244 -232.555013) (xy 373.085301 -232.607717) (xy 373.069591 -232.658647) (xy 373.046465 -232.706668)
			(xy 373.016441 -232.750705) (xy 372.980189 -232.789776) (xy 372.938518 -232.823007) (xy 372.89236 -232.849656)
			(xy 372.842746 -232.869128) (xy 372.790784 -232.880988) (xy 372.737634 -232.884972) (xy 372.684484 -232.880988)
			(xy 372.632522 -232.869128) (xy 372.582908 -232.849656) (xy 372.53675 -232.823007) (xy 372.495079 -232.789776)
			(xy 372.458827 -232.750705) (xy 372.428803 -232.706668) (xy 372.405677 -232.658647) (xy 372.389967 -232.607717)
			(xy 372.382024 -232.555013) (xy 372.153444 -232.555013) (xy 372.145501 -232.607717) (xy 372.129791 -232.658647)
			(xy 372.106665 -232.706668) (xy 372.076641 -232.750705) (xy 372.040389 -232.789776) (xy 371.998718 -232.823007)
			(xy 371.95256 -232.849656) (xy 371.902946 -232.869128) (xy 371.850984 -232.880988) (xy 371.797834 -232.884972)
			(xy 371.744684 -232.880988) (xy 371.692722 -232.869128) (xy 371.643108 -232.849656) (xy 371.59695 -232.823007)
			(xy 371.555279 -232.789776) (xy 371.519027 -232.750705) (xy 371.489003 -232.706668) (xy 371.465877 -232.658647)
			(xy 371.450167 -232.607717) (xy 371.442224 -232.555013) (xy 371.213644 -232.555013) (xy 371.205701 -232.607717)
			(xy 371.189991 -232.658647) (xy 371.166865 -232.706668) (xy 371.136841 -232.750705) (xy 371.100589 -232.789776)
			(xy 371.058918 -232.823007) (xy 371.01276 -232.849656) (xy 370.963146 -232.869128) (xy 370.911184 -232.880988)
			(xy 370.858034 -232.884972) (xy 370.804884 -232.880988) (xy 370.752922 -232.869128) (xy 370.703308 -232.849656)
			(xy 370.65715 -232.823007) (xy 370.615479 -232.789776) (xy 370.579227 -232.750705) (xy 370.549203 -232.706668)
			(xy 370.526077 -232.658647) (xy 370.510367 -232.607717) (xy 370.502424 -232.555013) (xy 370.273844 -232.555013)
			(xy 370.265901 -232.607717) (xy 370.250191 -232.658647) (xy 370.227065 -232.706668) (xy 370.197041 -232.750705)
			(xy 370.160789 -232.789776) (xy 370.119118 -232.823007) (xy 370.07296 -232.849656) (xy 370.023346 -232.869128)
			(xy 369.971384 -232.880988) (xy 369.918234 -232.884972) (xy 369.865084 -232.880988) (xy 369.813122 -232.869128)
			(xy 369.763508 -232.849656) (xy 369.71735 -232.823007) (xy 369.675679 -232.789776) (xy 369.639427 -232.750705)
			(xy 369.609403 -232.706668) (xy 369.586277 -232.658647) (xy 369.570567 -232.607717) (xy 369.562624 -232.555013)
			(xy 369.334044 -232.555013) (xy 369.326101 -232.607717) (xy 369.310391 -232.658647) (xy 369.287265 -232.706668)
			(xy 369.257241 -232.750705) (xy 369.220989 -232.789776) (xy 369.179318 -232.823007) (xy 369.13316 -232.849656)
			(xy 369.083546 -232.869128) (xy 369.031584 -232.880988) (xy 368.978434 -232.884972) (xy 368.925284 -232.880988)
			(xy 368.873322 -232.869128) (xy 368.823708 -232.849656) (xy 368.77755 -232.823007) (xy 368.735879 -232.789776)
			(xy 368.699627 -232.750705) (xy 368.669603 -232.706668) (xy 368.646477 -232.658647) (xy 368.630767 -232.607717)
			(xy 368.622824 -232.555013) (xy 368.39399 -232.555013) (xy 368.386047 -232.607717) (xy 368.370337 -232.658647)
			(xy 368.347211 -232.706668) (xy 368.317187 -232.750705) (xy 368.280935 -232.789776) (xy 368.239264 -232.823007)
			(xy 368.193106 -232.849656) (xy 368.143492 -232.869128) (xy 368.09153 -232.880988) (xy 368.03838 -232.884972)
			(xy 367.98523 -232.880988) (xy 367.933268 -232.869128) (xy 367.883654 -232.849656) (xy 367.837496 -232.823007)
			(xy 367.795825 -232.789776) (xy 367.759573 -232.750705) (xy 367.729549 -232.706668) (xy 367.706423 -232.658647)
			(xy 367.690713 -232.607717) (xy 367.68277 -232.555013) (xy 367.454444 -232.555013) (xy 367.446501 -232.607717)
			(xy 367.430791 -232.658647) (xy 367.407665 -232.706668) (xy 367.377641 -232.750705) (xy 367.341389 -232.789776)
			(xy 367.299718 -232.823007) (xy 367.25356 -232.849656) (xy 367.203946 -232.869128) (xy 367.151984 -232.880988)
			(xy 367.098834 -232.884972) (xy 367.045684 -232.880988) (xy 366.993722 -232.869128) (xy 366.944108 -232.849656)
			(xy 366.89795 -232.823007) (xy 366.856279 -232.789776) (xy 366.820027 -232.750705) (xy 366.790003 -232.706668)
			(xy 366.766877 -232.658647) (xy 366.751167 -232.607717) (xy 366.743224 -232.555013) (xy 366.514644 -232.555013)
			(xy 366.506701 -232.607717) (xy 366.490991 -232.658647) (xy 366.467865 -232.706668) (xy 366.437841 -232.750705)
			(xy 366.401589 -232.789776) (xy 366.359918 -232.823007) (xy 366.31376 -232.849656) (xy 366.264146 -232.869128)
			(xy 366.212184 -232.880988) (xy 366.159034 -232.884972) (xy 366.105884 -232.880988) (xy 366.053922 -232.869128)
			(xy 366.004308 -232.849656) (xy 365.95815 -232.823007) (xy 365.916479 -232.789776) (xy 365.880227 -232.750705)
			(xy 365.850203 -232.706668) (xy 365.827077 -232.658647) (xy 365.811367 -232.607717) (xy 365.803424 -232.555013)
			(xy 365.574844 -232.555013) (xy 365.566901 -232.607717) (xy 365.551191 -232.658647) (xy 365.528065 -232.706668)
			(xy 365.498041 -232.750705) (xy 365.461789 -232.789776) (xy 365.420118 -232.823007) (xy 365.37396 -232.849656)
			(xy 365.324346 -232.869128) (xy 365.272384 -232.880988) (xy 365.219234 -232.884972) (xy 365.166084 -232.880988)
			(xy 365.114122 -232.869128) (xy 365.064508 -232.849656) (xy 365.01835 -232.823007) (xy 364.976679 -232.789776)
			(xy 364.940427 -232.750705) (xy 364.910403 -232.706668) (xy 364.887277 -232.658647) (xy 364.871567 -232.607717)
			(xy 364.863624 -232.555013) (xy 364.635044 -232.555013) (xy 364.627101 -232.607717) (xy 364.611391 -232.658647)
			(xy 364.588265 -232.706668) (xy 364.558241 -232.750705) (xy 364.521989 -232.789776) (xy 364.480318 -232.823007)
			(xy 364.43416 -232.849656) (xy 364.384546 -232.869128) (xy 364.332584 -232.880988) (xy 364.279434 -232.884972)
			(xy 364.226284 -232.880988) (xy 364.174322 -232.869128) (xy 364.124708 -232.849656) (xy 364.07855 -232.823007)
			(xy 364.036879 -232.789776) (xy 364.000627 -232.750705) (xy 363.970603 -232.706668) (xy 363.947477 -232.658647)
			(xy 363.931767 -232.607717) (xy 363.923824 -232.555013) (xy 363.695244 -232.555013) (xy 363.687301 -232.607717)
			(xy 363.671591 -232.658647) (xy 363.648465 -232.706668) (xy 363.618441 -232.750705) (xy 363.582189 -232.789776)
			(xy 363.540518 -232.823007) (xy 363.49436 -232.849656) (xy 363.444746 -232.869128) (xy 363.392784 -232.880988)
			(xy 363.339634 -232.884972) (xy 363.286484 -232.880988) (xy 363.234522 -232.869128) (xy 363.184908 -232.849656)
			(xy 363.13875 -232.823007) (xy 363.097079 -232.789776) (xy 363.060827 -232.750705) (xy 363.030803 -232.706668)
			(xy 363.007677 -232.658647) (xy 362.991967 -232.607717) (xy 362.984024 -232.555013) (xy 362.755444 -232.555013)
			(xy 362.747501 -232.607717) (xy 362.731791 -232.658647) (xy 362.708665 -232.706668) (xy 362.678641 -232.750705)
			(xy 362.642389 -232.789776) (xy 362.600718 -232.823007) (xy 362.55456 -232.849656) (xy 362.504946 -232.869128)
			(xy 362.452984 -232.880988) (xy 362.399834 -232.884972) (xy 362.346684 -232.880988) (xy 362.294722 -232.869128)
			(xy 362.245108 -232.849656) (xy 362.19895 -232.823007) (xy 362.157279 -232.789776) (xy 362.121027 -232.750705)
			(xy 362.091003 -232.706668) (xy 362.067877 -232.658647) (xy 362.052167 -232.607717) (xy 362.044224 -232.555013)
			(xy 361.815644 -232.555013) (xy 361.807701 -232.607717) (xy 361.791991 -232.658647) (xy 361.768865 -232.706668)
			(xy 361.738841 -232.750705) (xy 361.702589 -232.789776) (xy 361.660918 -232.823007) (xy 361.61476 -232.849656)
			(xy 361.565146 -232.869128) (xy 361.513184 -232.880988) (xy 361.460034 -232.884972) (xy 361.406884 -232.880988)
			(xy 361.354922 -232.869128) (xy 361.305308 -232.849656) (xy 361.25915 -232.823007) (xy 361.217479 -232.789776)
			(xy 361.181227 -232.750705) (xy 361.151203 -232.706668) (xy 361.128077 -232.658647) (xy 361.112367 -232.607717)
			(xy 361.104424 -232.555013) (xy 360.875844 -232.555013) (xy 360.867901 -232.607717) (xy 360.852191 -232.658647)
			(xy 360.829065 -232.706668) (xy 360.799041 -232.750705) (xy 360.762789 -232.789776) (xy 360.721118 -232.823007)
			(xy 360.67496 -232.849656) (xy 360.625346 -232.869128) (xy 360.573384 -232.880988) (xy 360.520234 -232.884972)
			(xy 360.467084 -232.880988) (xy 360.415122 -232.869128) (xy 360.365508 -232.849656) (xy 360.31935 -232.823007)
			(xy 360.277679 -232.789776) (xy 360.241427 -232.750705) (xy 360.211403 -232.706668) (xy 360.188277 -232.658647)
			(xy 360.172567 -232.607717) (xy 360.164624 -232.555013) (xy 359.936044 -232.555013) (xy 359.928101 -232.607717)
			(xy 359.912391 -232.658647) (xy 359.889265 -232.706668) (xy 359.859241 -232.750705) (xy 359.822989 -232.789776)
			(xy 359.781318 -232.823007) (xy 359.73516 -232.849656) (xy 359.685546 -232.869128) (xy 359.633584 -232.880988)
			(xy 359.580434 -232.884972) (xy 359.527284 -232.880988) (xy 359.475322 -232.869128) (xy 359.425708 -232.849656)
			(xy 359.37955 -232.823007) (xy 359.337879 -232.789776) (xy 359.301627 -232.750705) (xy 359.271603 -232.706668)
			(xy 359.248477 -232.658647) (xy 359.232767 -232.607717) (xy 359.224824 -232.555013) (xy 358.996244 -232.555013)
			(xy 358.988301 -232.607717) (xy 358.972591 -232.658647) (xy 358.949465 -232.706668) (xy 358.919441 -232.750705)
			(xy 358.883189 -232.789776) (xy 358.841518 -232.823007) (xy 358.79536 -232.849656) (xy 358.745746 -232.869128)
			(xy 358.693784 -232.880988) (xy 358.640634 -232.884972) (xy 358.587484 -232.880988) (xy 358.535522 -232.869128)
			(xy 358.485908 -232.849656) (xy 358.43975 -232.823007) (xy 358.398079 -232.789776) (xy 358.361827 -232.750705)
			(xy 358.331803 -232.706668) (xy 358.308677 -232.658647) (xy 358.292967 -232.607717) (xy 358.285024 -232.555013)
			(xy 358.056444 -232.555013) (xy 358.048501 -232.607717) (xy 358.032791 -232.658647) (xy 358.009665 -232.706668)
			(xy 357.979641 -232.750705) (xy 357.943389 -232.789776) (xy 357.901718 -232.823007) (xy 357.85556 -232.849656)
			(xy 357.805946 -232.869128) (xy 357.753984 -232.880988) (xy 357.700834 -232.884972) (xy 357.647684 -232.880988)
			(xy 357.595722 -232.869128) (xy 357.546108 -232.849656) (xy 357.49995 -232.823007) (xy 357.458279 -232.789776)
			(xy 357.422027 -232.750705) (xy 357.392003 -232.706668) (xy 357.368877 -232.658647) (xy 357.353167 -232.607717)
			(xy 357.345224 -232.555013) (xy 357.116644 -232.555013) (xy 357.108701 -232.607717) (xy 357.092991 -232.658647)
			(xy 357.069865 -232.706668) (xy 357.039841 -232.750705) (xy 357.003589 -232.789776) (xy 356.961918 -232.823007)
			(xy 356.91576 -232.849656) (xy 356.866146 -232.869128) (xy 356.814184 -232.880988) (xy 356.761034 -232.884972)
			(xy 356.707884 -232.880988) (xy 356.655922 -232.869128) (xy 356.606308 -232.849656) (xy 356.56015 -232.823007)
			(xy 356.518479 -232.789776) (xy 356.482227 -232.750705) (xy 356.452203 -232.706668) (xy 356.429077 -232.658647)
			(xy 356.413367 -232.607717) (xy 356.405424 -232.555013) (xy 356.176844 -232.555013) (xy 356.168901 -232.607717)
			(xy 356.153191 -232.658647) (xy 356.130065 -232.706668) (xy 356.100041 -232.750705) (xy 356.063789 -232.789776)
			(xy 356.022118 -232.823007) (xy 355.97596 -232.849656) (xy 355.926346 -232.869128) (xy 355.874384 -232.880988)
			(xy 355.821234 -232.884972) (xy 355.768084 -232.880988) (xy 355.716122 -232.869128) (xy 355.666508 -232.849656)
			(xy 355.62035 -232.823007) (xy 355.578679 -232.789776) (xy 355.542427 -232.750705) (xy 355.512403 -232.706668)
			(xy 355.489277 -232.658647) (xy 355.473567 -232.607717) (xy 355.465624 -232.555013) (xy 355.237044 -232.555013)
			(xy 355.229101 -232.607717) (xy 355.213391 -232.658647) (xy 355.190265 -232.706668) (xy 355.160241 -232.750705)
			(xy 355.123989 -232.789776) (xy 355.082318 -232.823007) (xy 355.03616 -232.849656) (xy 354.986546 -232.869128)
			(xy 354.934584 -232.880988) (xy 354.881434 -232.884972) (xy 354.828284 -232.880988) (xy 354.776322 -232.869128)
			(xy 354.726708 -232.849656) (xy 354.68055 -232.823007) (xy 354.638879 -232.789776) (xy 354.602627 -232.750705)
			(xy 354.572603 -232.706668) (xy 354.549477 -232.658647) (xy 354.533767 -232.607717) (xy 354.525824 -232.555013)
			(xy 354.297244 -232.555013) (xy 354.289301 -232.607717) (xy 354.273591 -232.658647) (xy 354.250465 -232.706668)
			(xy 354.220441 -232.750705) (xy 354.184189 -232.789776) (xy 354.142518 -232.823007) (xy 354.09636 -232.849656)
			(xy 354.046746 -232.869128) (xy 353.994784 -232.880988) (xy 353.941634 -232.884972) (xy 353.888484 -232.880988)
			(xy 353.836522 -232.869128) (xy 353.786908 -232.849656) (xy 353.74075 -232.823007) (xy 353.699079 -232.789776)
			(xy 353.662827 -232.750705) (xy 353.632803 -232.706668) (xy 353.609677 -232.658647) (xy 353.593967 -232.607717)
			(xy 353.586024 -232.555013) (xy 353.357444 -232.555013) (xy 353.349501 -232.607717) (xy 353.333791 -232.658647)
			(xy 353.310665 -232.706668) (xy 353.280641 -232.750705) (xy 353.244389 -232.789776) (xy 353.202718 -232.823007)
			(xy 353.15656 -232.849656) (xy 353.106946 -232.869128) (xy 353.054984 -232.880988) (xy 353.001834 -232.884972)
			(xy 352.948684 -232.880988) (xy 352.896722 -232.869128) (xy 352.847108 -232.849656) (xy 352.80095 -232.823007)
			(xy 352.759279 -232.789776) (xy 352.723027 -232.750705) (xy 352.693003 -232.706668) (xy 352.669877 -232.658647)
			(xy 352.654167 -232.607717) (xy 352.646224 -232.555013) (xy 352.417644 -232.555013) (xy 352.409701 -232.607717)
			(xy 352.393991 -232.658647) (xy 352.370865 -232.706668) (xy 352.340841 -232.750705) (xy 352.304589 -232.789776)
			(xy 352.262918 -232.823007) (xy 352.21676 -232.849656) (xy 352.167146 -232.869128) (xy 352.115184 -232.880988)
			(xy 352.062034 -232.884972) (xy 352.008884 -232.880988) (xy 351.956922 -232.869128) (xy 351.907308 -232.849656)
			(xy 351.86115 -232.823007) (xy 351.819479 -232.789776) (xy 351.783227 -232.750705) (xy 351.753203 -232.706668)
			(xy 351.730077 -232.658647) (xy 351.714367 -232.607717) (xy 351.706424 -232.555013) (xy 351.477844 -232.555013)
			(xy 351.469901 -232.607717) (xy 351.454191 -232.658647) (xy 351.431065 -232.706668) (xy 351.401041 -232.750705)
			(xy 351.364789 -232.789776) (xy 351.323118 -232.823007) (xy 351.27696 -232.849656) (xy 351.227346 -232.869128)
			(xy 351.175384 -232.880988) (xy 351.122234 -232.884972) (xy 351.069084 -232.880988) (xy 351.017122 -232.869128)
			(xy 350.967508 -232.849656) (xy 350.92135 -232.823007) (xy 350.879679 -232.789776) (xy 350.843427 -232.750705)
			(xy 350.813403 -232.706668) (xy 350.790277 -232.658647) (xy 350.774567 -232.607717) (xy 350.766624 -232.555013)
			(xy 350.538044 -232.555013) (xy 350.530101 -232.607717) (xy 350.514391 -232.658647) (xy 350.491265 -232.706668)
			(xy 350.461241 -232.750705) (xy 350.424989 -232.789776) (xy 350.383318 -232.823007) (xy 350.33716 -232.849656)
			(xy 350.287546 -232.869128) (xy 350.235584 -232.880988) (xy 350.182434 -232.884972) (xy 350.129284 -232.880988)
			(xy 350.077322 -232.869128) (xy 350.027708 -232.849656) (xy 349.98155 -232.823007) (xy 349.939879 -232.789776)
			(xy 349.903627 -232.750705) (xy 349.873603 -232.706668) (xy 349.850477 -232.658647) (xy 349.834767 -232.607717)
			(xy 349.826824 -232.555013) (xy 348.658444 -232.555013) (xy 348.650501 -232.607717) (xy 348.634791 -232.658647)
			(xy 348.611665 -232.706668) (xy 348.581641 -232.750705) (xy 348.545389 -232.789776) (xy 348.503718 -232.823007)
			(xy 348.45756 -232.849656) (xy 348.407946 -232.869128) (xy 348.355984 -232.880988) (xy 348.302834 -232.884972)
			(xy 348.249684 -232.880988) (xy 348.197722 -232.869128) (xy 348.148108 -232.849656) (xy 348.10195 -232.823007)
			(xy 348.060279 -232.789776) (xy 348.024027 -232.750705) (xy 347.994003 -232.706668) (xy 347.970877 -232.658647)
			(xy 347.955167 -232.607717) (xy 347.947224 -232.555013) (xy 347.718644 -232.555013) (xy 347.710701 -232.607717)
			(xy 347.694991 -232.658647) (xy 347.671865 -232.706668) (xy 347.641841 -232.750705) (xy 347.605589 -232.789776)
			(xy 347.563918 -232.823007) (xy 347.51776 -232.849656) (xy 347.468146 -232.869128) (xy 347.416184 -232.880988)
			(xy 347.363034 -232.884972) (xy 347.309884 -232.880988) (xy 347.257922 -232.869128) (xy 347.208308 -232.849656)
			(xy 347.16215 -232.823007) (xy 347.120479 -232.789776) (xy 347.084227 -232.750705) (xy 347.054203 -232.706668)
			(xy 347.031077 -232.658647) (xy 347.015367 -232.607717) (xy 347.007424 -232.555013) (xy 346.77859 -232.555013)
			(xy 346.770647 -232.607717) (xy 346.754937 -232.658647) (xy 346.731811 -232.706668) (xy 346.701787 -232.750705)
			(xy 346.665535 -232.789776) (xy 346.623864 -232.823007) (xy 346.577706 -232.849656) (xy 346.528092 -232.869128)
			(xy 346.47613 -232.880988) (xy 346.42298 -232.884972) (xy 346.36983 -232.880988) (xy 346.317868 -232.869128)
			(xy 346.268254 -232.849656) (xy 346.222096 -232.823007) (xy 346.180425 -232.789776) (xy 346.144173 -232.750705)
			(xy 346.114149 -232.706668) (xy 346.091023 -232.658647) (xy 346.075313 -232.607717) (xy 346.06737 -232.555013)
			(xy 345.839044 -232.555013) (xy 345.831101 -232.607717) (xy 345.815391 -232.658647) (xy 345.792265 -232.706668)
			(xy 345.762241 -232.750705) (xy 345.725989 -232.789776) (xy 345.684318 -232.823007) (xy 345.63816 -232.849656)
			(xy 345.588546 -232.869128) (xy 345.536584 -232.880988) (xy 345.483434 -232.884972) (xy 345.430284 -232.880988)
			(xy 345.378322 -232.869128) (xy 345.328708 -232.849656) (xy 345.28255 -232.823007) (xy 345.240879 -232.789776)
			(xy 345.204627 -232.750705) (xy 345.174603 -232.706668) (xy 345.151477 -232.658647) (xy 345.135767 -232.607717)
			(xy 345.127824 -232.555013) (xy 344.899244 -232.555013) (xy 344.891301 -232.607717) (xy 344.875591 -232.658647)
			(xy 344.852465 -232.706668) (xy 344.822441 -232.750705) (xy 344.786189 -232.789776) (xy 344.744518 -232.823007)
			(xy 344.69836 -232.849656) (xy 344.648746 -232.869128) (xy 344.596784 -232.880988) (xy 344.543634 -232.884972)
			(xy 344.490484 -232.880988) (xy 344.438522 -232.869128) (xy 344.388908 -232.849656) (xy 344.34275 -232.823007)
			(xy 344.301079 -232.789776) (xy 344.264827 -232.750705) (xy 344.234803 -232.706668) (xy 344.211677 -232.658647)
			(xy 344.195967 -232.607717) (xy 344.188024 -232.555013) (xy 343.959444 -232.555013) (xy 343.951501 -232.607717)
			(xy 343.935791 -232.658647) (xy 343.912665 -232.706668) (xy 343.882641 -232.750705) (xy 343.846389 -232.789776)
			(xy 343.804718 -232.823007) (xy 343.75856 -232.849656) (xy 343.708946 -232.869128) (xy 343.656984 -232.880988)
			(xy 343.603834 -232.884972) (xy 343.550684 -232.880988) (xy 343.498722 -232.869128) (xy 343.449108 -232.849656)
			(xy 343.40295 -232.823007) (xy 343.361279 -232.789776) (xy 343.325027 -232.750705) (xy 343.295003 -232.706668)
			(xy 343.271877 -232.658647) (xy 343.256167 -232.607717) (xy 343.248224 -232.555013) (xy 343.019644 -232.555013)
			(xy 343.011701 -232.607717) (xy 342.995991 -232.658647) (xy 342.972865 -232.706668) (xy 342.942841 -232.750705)
			(xy 342.906589 -232.789776) (xy 342.864918 -232.823007) (xy 342.81876 -232.849656) (xy 342.769146 -232.869128)
			(xy 342.717184 -232.880988) (xy 342.664034 -232.884972) (xy 342.610884 -232.880988) (xy 342.558922 -232.869128)
			(xy 342.509308 -232.849656) (xy 342.46315 -232.823007) (xy 342.421479 -232.789776) (xy 342.385227 -232.750705)
			(xy 342.355203 -232.706668) (xy 342.332077 -232.658647) (xy 342.316367 -232.607717) (xy 342.308424 -232.555013)
			(xy 342.079844 -232.555013) (xy 342.071901 -232.607717) (xy 342.056191 -232.658647) (xy 342.033065 -232.706668)
			(xy 342.003041 -232.750705) (xy 341.966789 -232.789776) (xy 341.925118 -232.823007) (xy 341.87896 -232.849656)
			(xy 341.829346 -232.869128) (xy 341.777384 -232.880988) (xy 341.724234 -232.884972) (xy 341.671084 -232.880988)
			(xy 341.619122 -232.869128) (xy 341.569508 -232.849656) (xy 341.52335 -232.823007) (xy 341.481679 -232.789776)
			(xy 341.445427 -232.750705) (xy 341.415403 -232.706668) (xy 341.392277 -232.658647) (xy 341.376567 -232.607717)
			(xy 341.368624 -232.555013) (xy 341.140044 -232.555013) (xy 341.132101 -232.607717) (xy 341.116391 -232.658647)
			(xy 341.093265 -232.706668) (xy 341.063241 -232.750705) (xy 341.026989 -232.789776) (xy 340.985318 -232.823007)
			(xy 340.93916 -232.849656) (xy 340.889546 -232.869128) (xy 340.837584 -232.880988) (xy 340.784434 -232.884972)
			(xy 340.731284 -232.880988) (xy 340.679322 -232.869128) (xy 340.629708 -232.849656) (xy 340.58355 -232.823007)
			(xy 340.541879 -232.789776) (xy 340.505627 -232.750705) (xy 340.475603 -232.706668) (xy 340.452477 -232.658647)
			(xy 340.436767 -232.607717) (xy 340.428824 -232.555013) (xy 340.19999 -232.555013) (xy 340.192047 -232.607717)
			(xy 340.176337 -232.658647) (xy 340.153211 -232.706668) (xy 340.123187 -232.750705) (xy 340.086935 -232.789776)
			(xy 340.045264 -232.823007) (xy 339.999106 -232.849656) (xy 339.949492 -232.869128) (xy 339.89753 -232.880988)
			(xy 339.84438 -232.884972) (xy 339.79123 -232.880988) (xy 339.739268 -232.869128) (xy 339.689654 -232.849656)
			(xy 339.643496 -232.823007) (xy 339.601825 -232.789776) (xy 339.565573 -232.750705) (xy 339.535549 -232.706668)
			(xy 339.512423 -232.658647) (xy 339.496713 -232.607717) (xy 339.48877 -232.555013) (xy 339.37956 -232.555013)
			(xy 339.37956 -232.983278) (xy 339.423502 -232.989374) (xy 339.450066 -232.993543) (xy 339.501615 -233.008832)
			(xy 339.55028 -233.031696) (xy 339.594956 -233.061614) (xy 339.634628 -233.097908) (xy 339.668394 -233.139752)
			(xy 339.695487 -233.186196) (xy 339.715291 -233.236184) (xy 339.727356 -233.288582) (xy 339.731409 -233.342197)
			(xy 339.729396 -233.368829) (xy 339.95867 -233.368829) (xy 339.95867 -233.315531) (xy 339.966613 -233.262827)
			(xy 339.982323 -233.211897) (xy 340.005449 -233.163876) (xy 340.035473 -233.119839) (xy 340.071725 -233.080768)
			(xy 340.113396 -233.047537) (xy 340.159554 -233.020888) (xy 340.209168 -233.001416) (xy 340.26113 -232.989556)
			(xy 340.31428 -232.985573) (xy 340.36743 -232.989556) (xy 340.419392 -233.001416) (xy 340.469006 -233.020888)
			(xy 340.515164 -233.047537) (xy 340.556835 -233.080768) (xy 340.593087 -233.119839) (xy 340.623111 -233.163876)
			(xy 340.646237 -233.211897) (xy 340.661947 -233.262827) (xy 340.66989 -233.315531) (xy 340.670388 -233.34218)
			(xy 340.66989 -233.368829) (xy 340.89847 -233.368829) (xy 340.89847 -233.315531) (xy 340.906413 -233.262827)
			(xy 340.922123 -233.211897) (xy 340.945249 -233.163876) (xy 340.975273 -233.119839) (xy 341.011525 -233.080768)
			(xy 341.053196 -233.047537) (xy 341.099354 -233.020888) (xy 341.148968 -233.001416) (xy 341.20093 -232.989556)
			(xy 341.25408 -232.985573) (xy 341.30723 -232.989556) (xy 341.359192 -233.001416) (xy 341.408806 -233.020888)
			(xy 341.454964 -233.047537) (xy 341.496635 -233.080768) (xy 341.532887 -233.119839) (xy 341.562911 -233.163876)
			(xy 341.586037 -233.211897) (xy 341.601747 -233.262827) (xy 341.60969 -233.315531) (xy 341.610188 -233.34218)
			(xy 341.60969 -233.368829) (xy 341.83827 -233.368829) (xy 341.83827 -233.315531) (xy 341.846213 -233.262827)
			(xy 341.861923 -233.211897) (xy 341.885049 -233.163876) (xy 341.915073 -233.119839) (xy 341.951325 -233.080768)
			(xy 341.992996 -233.047537) (xy 342.039154 -233.020888) (xy 342.088768 -233.001416) (xy 342.14073 -232.989556)
			(xy 342.19388 -232.985573) (xy 342.24703 -232.989556) (xy 342.298992 -233.001416) (xy 342.348606 -233.020888)
			(xy 342.394764 -233.047537) (xy 342.436435 -233.080768) (xy 342.472687 -233.119839) (xy 342.502711 -233.163876)
			(xy 342.525837 -233.211897) (xy 342.541547 -233.262827) (xy 342.54949 -233.315531) (xy 342.549988 -233.34218)
			(xy 342.54949 -233.368829) (xy 342.77807 -233.368829) (xy 342.77807 -233.315531) (xy 342.786013 -233.262827)
			(xy 342.801723 -233.211897) (xy 342.824849 -233.163876) (xy 342.854873 -233.119839) (xy 342.891125 -233.080768)
			(xy 342.932796 -233.047537) (xy 342.978954 -233.020888) (xy 343.028568 -233.001416) (xy 343.08053 -232.989556)
			(xy 343.13368 -232.985573) (xy 343.18683 -232.989556) (xy 343.238792 -233.001416) (xy 343.288406 -233.020888)
			(xy 343.334564 -233.047537) (xy 343.376235 -233.080768) (xy 343.412487 -233.119839) (xy 343.442511 -233.163876)
			(xy 343.465637 -233.211897) (xy 343.481347 -233.262827) (xy 343.48929 -233.315531) (xy 343.489788 -233.34218)
			(xy 343.48929 -233.368829) (xy 343.71787 -233.368829) (xy 343.71787 -233.315531) (xy 343.725813 -233.262827)
			(xy 343.741523 -233.211897) (xy 343.764649 -233.163876) (xy 343.794673 -233.119839) (xy 343.830925 -233.080768)
			(xy 343.872596 -233.047537) (xy 343.918754 -233.020888) (xy 343.968368 -233.001416) (xy 344.02033 -232.989556)
			(xy 344.07348 -232.985573) (xy 344.12663 -232.989556) (xy 344.178592 -233.001416) (xy 344.228206 -233.020888)
			(xy 344.274364 -233.047537) (xy 344.316035 -233.080768) (xy 344.352287 -233.119839) (xy 344.382311 -233.163876)
			(xy 344.405437 -233.211897) (xy 344.421147 -233.262827) (xy 344.42909 -233.315531) (xy 344.429588 -233.34218)
			(xy 344.42909 -233.368829) (xy 344.65767 -233.368829) (xy 344.65767 -233.315531) (xy 344.665613 -233.262827)
			(xy 344.681323 -233.211897) (xy 344.704449 -233.163876) (xy 344.734473 -233.119839) (xy 344.770725 -233.080768)
			(xy 344.812396 -233.047537) (xy 344.858554 -233.020888) (xy 344.908168 -233.001416) (xy 344.96013 -232.989556)
			(xy 345.01328 -232.985573) (xy 345.06643 -232.989556) (xy 345.118392 -233.001416) (xy 345.168006 -233.020888)
			(xy 345.214164 -233.047537) (xy 345.255835 -233.080768) (xy 345.292087 -233.119839) (xy 345.322111 -233.163876)
			(xy 345.345237 -233.211897) (xy 345.360947 -233.262827) (xy 345.36889 -233.315531) (xy 345.369388 -233.34218)
			(xy 345.36889 -233.368829) (xy 345.597724 -233.368829) (xy 345.597724 -233.315531) (xy 345.605667 -233.262827)
			(xy 345.621377 -233.211897) (xy 345.644503 -233.163876) (xy 345.674527 -233.119839) (xy 345.710779 -233.080768)
			(xy 345.75245 -233.047537) (xy 345.798608 -233.020888) (xy 345.848222 -233.001416) (xy 345.900184 -232.989556)
			(xy 345.953334 -232.985573) (xy 346.006484 -232.989556) (xy 346.058446 -233.001416) (xy 346.10806 -233.020888)
			(xy 346.154218 -233.047537) (xy 346.195889 -233.080768) (xy 346.232141 -233.119839) (xy 346.262165 -233.163876)
			(xy 346.285291 -233.211897) (xy 346.301001 -233.262827) (xy 346.308944 -233.315531) (xy 346.309442 -233.34218)
			(xy 346.308944 -233.368829) (xy 346.53727 -233.368829) (xy 346.53727 -233.315531) (xy 346.545213 -233.262827)
			(xy 346.560923 -233.211897) (xy 346.584049 -233.163876) (xy 346.614073 -233.119839) (xy 346.650325 -233.080768)
			(xy 346.691996 -233.047537) (xy 346.738154 -233.020888) (xy 346.787768 -233.001416) (xy 346.83973 -232.989556)
			(xy 346.89288 -232.985573) (xy 346.94603 -232.989556) (xy 346.997992 -233.001416) (xy 347.047606 -233.020888)
			(xy 347.093764 -233.047537) (xy 347.135435 -233.080768) (xy 347.171687 -233.119839) (xy 347.201711 -233.163876)
			(xy 347.224837 -233.211897) (xy 347.240547 -233.262827) (xy 347.24849 -233.315531) (xy 347.248988 -233.34218)
			(xy 347.24849 -233.368829) (xy 347.47707 -233.368829) (xy 347.47707 -233.315531) (xy 347.485013 -233.262827)
			(xy 347.500723 -233.211897) (xy 347.523849 -233.163876) (xy 347.553873 -233.119839) (xy 347.590125 -233.080768)
			(xy 347.631796 -233.047537) (xy 347.677954 -233.020888) (xy 347.727568 -233.001416) (xy 347.77953 -232.989556)
			(xy 347.83268 -232.985573) (xy 347.88583 -232.989556) (xy 347.937792 -233.001416) (xy 347.987406 -233.020888)
			(xy 348.033564 -233.047537) (xy 348.075235 -233.080768) (xy 348.111487 -233.119839) (xy 348.141511 -233.163876)
			(xy 348.164637 -233.211897) (xy 348.180347 -233.262827) (xy 348.18829 -233.315531) (xy 348.188788 -233.34218)
			(xy 348.18829 -233.368829) (xy 348.41687 -233.368829) (xy 348.41687 -233.315531) (xy 348.424813 -233.262827)
			(xy 348.440523 -233.211897) (xy 348.463649 -233.163876) (xy 348.493673 -233.119839) (xy 348.529925 -233.080768)
			(xy 348.571596 -233.047537) (xy 348.617754 -233.020888) (xy 348.667368 -233.001416) (xy 348.71933 -232.989556)
			(xy 348.77248 -232.985573) (xy 348.82563 -232.989556) (xy 348.877592 -233.001416) (xy 348.927206 -233.020888)
			(xy 348.973364 -233.047537) (xy 349.015035 -233.080768) (xy 349.051287 -233.119839) (xy 349.081311 -233.163876)
			(xy 349.104437 -233.211897) (xy 349.120147 -233.262827) (xy 349.12809 -233.315531) (xy 349.128588 -233.34218)
			(xy 349.12809 -233.368829) (xy 350.29647 -233.368829) (xy 350.29647 -233.315531) (xy 350.304413 -233.262827)
			(xy 350.320123 -233.211897) (xy 350.343249 -233.163876) (xy 350.373273 -233.119839) (xy 350.409525 -233.080768)
			(xy 350.451196 -233.047537) (xy 350.497354 -233.020888) (xy 350.546968 -233.001416) (xy 350.59893 -232.989556)
			(xy 350.65208 -232.985573) (xy 350.70523 -232.989556) (xy 350.757192 -233.001416) (xy 350.806806 -233.020888)
			(xy 350.852964 -233.047537) (xy 350.894635 -233.080768) (xy 350.930887 -233.119839) (xy 350.960911 -233.163876)
			(xy 350.984037 -233.211897) (xy 350.999747 -233.262827) (xy 351.00769 -233.315531) (xy 351.008188 -233.34218)
			(xy 351.00769 -233.368829) (xy 351.23627 -233.368829) (xy 351.23627 -233.315531) (xy 351.244213 -233.262827)
			(xy 351.259923 -233.211897) (xy 351.283049 -233.163876) (xy 351.313073 -233.119839) (xy 351.349325 -233.080768)
			(xy 351.390996 -233.047537) (xy 351.437154 -233.020888) (xy 351.486768 -233.001416) (xy 351.53873 -232.989556)
			(xy 351.59188 -232.985573) (xy 351.64503 -232.989556) (xy 351.696992 -233.001416) (xy 351.746606 -233.020888)
			(xy 351.792764 -233.047537) (xy 351.834435 -233.080768) (xy 351.870687 -233.119839) (xy 351.900711 -233.163876)
			(xy 351.923837 -233.211897) (xy 351.939547 -233.262827) (xy 351.94749 -233.315531) (xy 351.947988 -233.34218)
			(xy 351.94749 -233.368829) (xy 352.176324 -233.368829) (xy 352.176324 -233.315531) (xy 352.184267 -233.262827)
			(xy 352.199977 -233.211897) (xy 352.223103 -233.163876) (xy 352.253127 -233.119839) (xy 352.289379 -233.080768)
			(xy 352.33105 -233.047537) (xy 352.377208 -233.020888) (xy 352.426822 -233.001416) (xy 352.478784 -232.989556)
			(xy 352.531934 -232.985573) (xy 352.585084 -232.989556) (xy 352.637046 -233.001416) (xy 352.68666 -233.020888)
			(xy 352.732818 -233.047537) (xy 352.774489 -233.080768) (xy 352.810741 -233.119839) (xy 352.840765 -233.163876)
			(xy 352.863891 -233.211897) (xy 352.879601 -233.262827) (xy 352.887544 -233.315531) (xy 352.888042 -233.34218)
			(xy 352.887544 -233.368829) (xy 353.116124 -233.368829) (xy 353.116124 -233.315531) (xy 353.124067 -233.262827)
			(xy 353.139777 -233.211897) (xy 353.162903 -233.163876) (xy 353.192927 -233.119839) (xy 353.229179 -233.080768)
			(xy 353.27085 -233.047537) (xy 353.317008 -233.020888) (xy 353.366622 -233.001416) (xy 353.418584 -232.989556)
			(xy 353.471734 -232.985573) (xy 353.524884 -232.989556) (xy 353.576846 -233.001416) (xy 353.62646 -233.020888)
			(xy 353.672618 -233.047537) (xy 353.714289 -233.080768) (xy 353.750541 -233.119839) (xy 353.780565 -233.163876)
			(xy 353.803691 -233.211897) (xy 353.819401 -233.262827) (xy 353.827344 -233.315531) (xy 353.827842 -233.34218)
			(xy 353.827344 -233.368829) (xy 354.05567 -233.368829) (xy 354.05567 -233.315531) (xy 354.063613 -233.262827)
			(xy 354.079323 -233.211897) (xy 354.102449 -233.163876) (xy 354.132473 -233.119839) (xy 354.168725 -233.080768)
			(xy 354.210396 -233.047537) (xy 354.256554 -233.020888) (xy 354.306168 -233.001416) (xy 354.35813 -232.989556)
			(xy 354.41128 -232.985573) (xy 354.46443 -232.989556) (xy 354.516392 -233.001416) (xy 354.566006 -233.020888)
			(xy 354.612164 -233.047537) (xy 354.653835 -233.080768) (xy 354.690087 -233.119839) (xy 354.720111 -233.163876)
			(xy 354.743237 -233.211897) (xy 354.758947 -233.262827) (xy 354.76689 -233.315531) (xy 354.767388 -233.34218)
			(xy 354.76689 -233.368829) (xy 354.99547 -233.368829) (xy 354.99547 -233.315531) (xy 355.003413 -233.262827)
			(xy 355.019123 -233.211897) (xy 355.042249 -233.163876) (xy 355.072273 -233.119839) (xy 355.108525 -233.080768)
			(xy 355.150196 -233.047537) (xy 355.196354 -233.020888) (xy 355.245968 -233.001416) (xy 355.29793 -232.989556)
			(xy 355.35108 -232.985573) (xy 355.40423 -232.989556) (xy 355.456192 -233.001416) (xy 355.505806 -233.020888)
			(xy 355.551964 -233.047537) (xy 355.593635 -233.080768) (xy 355.629887 -233.119839) (xy 355.659911 -233.163876)
			(xy 355.683037 -233.211897) (xy 355.698747 -233.262827) (xy 355.70669 -233.315531) (xy 355.707188 -233.34218)
			(xy 355.70669 -233.368829) (xy 355.93527 -233.368829) (xy 355.93527 -233.315531) (xy 355.943213 -233.262827)
			(xy 355.958923 -233.211897) (xy 355.982049 -233.163876) (xy 356.012073 -233.119839) (xy 356.048325 -233.080768)
			(xy 356.089996 -233.047537) (xy 356.136154 -233.020888) (xy 356.185768 -233.001416) (xy 356.23773 -232.989556)
			(xy 356.29088 -232.985573) (xy 356.34403 -232.989556) (xy 356.395992 -233.001416) (xy 356.445606 -233.020888)
			(xy 356.491764 -233.047537) (xy 356.533435 -233.080768) (xy 356.569687 -233.119839) (xy 356.599711 -233.163876)
			(xy 356.622837 -233.211897) (xy 356.638547 -233.262827) (xy 356.64649 -233.315531) (xy 356.646988 -233.34218)
			(xy 356.64649 -233.368829) (xy 356.87507 -233.368829) (xy 356.87507 -233.315531) (xy 356.883013 -233.262827)
			(xy 356.898723 -233.211897) (xy 356.921849 -233.163876) (xy 356.951873 -233.119839) (xy 356.988125 -233.080768)
			(xy 357.029796 -233.047537) (xy 357.075954 -233.020888) (xy 357.125568 -233.001416) (xy 357.17753 -232.989556)
			(xy 357.23068 -232.985573) (xy 357.28383 -232.989556) (xy 357.335792 -233.001416) (xy 357.385406 -233.020888)
			(xy 357.431564 -233.047537) (xy 357.473235 -233.080768) (xy 357.509487 -233.119839) (xy 357.539511 -233.163876)
			(xy 357.562637 -233.211897) (xy 357.578347 -233.262827) (xy 357.58629 -233.315531) (xy 357.586788 -233.34218)
			(xy 357.58629 -233.368829) (xy 357.815124 -233.368829) (xy 357.815124 -233.315531) (xy 357.823067 -233.262827)
			(xy 357.838777 -233.211897) (xy 357.861903 -233.163876) (xy 357.891927 -233.119839) (xy 357.928179 -233.080768)
			(xy 357.96985 -233.047537) (xy 358.016008 -233.020888) (xy 358.065622 -233.001416) (xy 358.117584 -232.989556)
			(xy 358.170734 -232.985573) (xy 358.223884 -232.989556) (xy 358.275846 -233.001416) (xy 358.32546 -233.020888)
			(xy 358.371618 -233.047537) (xy 358.413289 -233.080768) (xy 358.449541 -233.119839) (xy 358.479565 -233.163876)
			(xy 358.502691 -233.211897) (xy 358.518401 -233.262827) (xy 358.526344 -233.315531) (xy 358.526842 -233.34218)
			(xy 358.526344 -233.368829) (xy 358.75467 -233.368829) (xy 358.75467 -233.315531) (xy 358.762613 -233.262827)
			(xy 358.778323 -233.211897) (xy 358.801449 -233.163876) (xy 358.831473 -233.119839) (xy 358.867725 -233.080768)
			(xy 358.909396 -233.047537) (xy 358.955554 -233.020888) (xy 359.005168 -233.001416) (xy 359.05713 -232.989556)
			(xy 359.11028 -232.985573) (xy 359.16343 -232.989556) (xy 359.215392 -233.001416) (xy 359.265006 -233.020888)
			(xy 359.311164 -233.047537) (xy 359.352835 -233.080768) (xy 359.389087 -233.119839) (xy 359.419111 -233.163876)
			(xy 359.442237 -233.211897) (xy 359.457947 -233.262827) (xy 359.46589 -233.315531) (xy 359.466388 -233.34218)
			(xy 359.46589 -233.368829) (xy 359.69447 -233.368829) (xy 359.69447 -233.315531) (xy 359.702413 -233.262827)
			(xy 359.718123 -233.211897) (xy 359.741249 -233.163876) (xy 359.771273 -233.119839) (xy 359.807525 -233.080768)
			(xy 359.849196 -233.047537) (xy 359.895354 -233.020888) (xy 359.944968 -233.001416) (xy 359.99693 -232.989556)
			(xy 360.05008 -232.985573) (xy 360.10323 -232.989556) (xy 360.155192 -233.001416) (xy 360.204806 -233.020888)
			(xy 360.250964 -233.047537) (xy 360.292635 -233.080768) (xy 360.328887 -233.119839) (xy 360.358911 -233.163876)
			(xy 360.382037 -233.211897) (xy 360.397747 -233.262827) (xy 360.40569 -233.315531) (xy 360.406188 -233.34218)
			(xy 360.40569 -233.368829) (xy 360.63427 -233.368829) (xy 360.63427 -233.315531) (xy 360.642213 -233.262827)
			(xy 360.657923 -233.211897) (xy 360.681049 -233.163876) (xy 360.711073 -233.119839) (xy 360.747325 -233.080768)
			(xy 360.788996 -233.047537) (xy 360.835154 -233.020888) (xy 360.884768 -233.001416) (xy 360.93673 -232.989556)
			(xy 360.98988 -232.985573) (xy 361.04303 -232.989556) (xy 361.094992 -233.001416) (xy 361.144606 -233.020888)
			(xy 361.190764 -233.047537) (xy 361.232435 -233.080768) (xy 361.268687 -233.119839) (xy 361.298711 -233.163876)
			(xy 361.321837 -233.211897) (xy 361.337547 -233.262827) (xy 361.34549 -233.315531) (xy 361.345988 -233.34218)
			(xy 361.34549 -233.368829) (xy 361.574324 -233.368829) (xy 361.574324 -233.315531) (xy 361.582267 -233.262827)
			(xy 361.597977 -233.211897) (xy 361.621103 -233.163876) (xy 361.651127 -233.119839) (xy 361.687379 -233.080768)
			(xy 361.72905 -233.047537) (xy 361.775208 -233.020888) (xy 361.824822 -233.001416) (xy 361.876784 -232.989556)
			(xy 361.929934 -232.985573) (xy 361.983084 -232.989556) (xy 362.035046 -233.001416) (xy 362.08466 -233.020888)
			(xy 362.130818 -233.047537) (xy 362.172489 -233.080768) (xy 362.208741 -233.119839) (xy 362.238765 -233.163876)
			(xy 362.261891 -233.211897) (xy 362.277601 -233.262827) (xy 362.285544 -233.315531) (xy 362.286042 -233.34218)
			(xy 362.285544 -233.368829) (xy 362.51387 -233.368829) (xy 362.51387 -233.315531) (xy 362.521813 -233.262827)
			(xy 362.537523 -233.211897) (xy 362.560649 -233.163876) (xy 362.590673 -233.119839) (xy 362.626925 -233.080768)
			(xy 362.668596 -233.047537) (xy 362.714754 -233.020888) (xy 362.764368 -233.001416) (xy 362.81633 -232.989556)
			(xy 362.86948 -232.985573) (xy 362.92263 -232.989556) (xy 362.974592 -233.001416) (xy 363.024206 -233.020888)
			(xy 363.070364 -233.047537) (xy 363.112035 -233.080768) (xy 363.148287 -233.119839) (xy 363.178311 -233.163876)
			(xy 363.201437 -233.211897) (xy 363.217147 -233.262827) (xy 363.22509 -233.315531) (xy 363.225588 -233.34218)
			(xy 363.22509 -233.368829) (xy 363.45367 -233.368829) (xy 363.45367 -233.315531) (xy 363.461613 -233.262827)
			(xy 363.477323 -233.211897) (xy 363.500449 -233.163876) (xy 363.530473 -233.119839) (xy 363.566725 -233.080768)
			(xy 363.608396 -233.047537) (xy 363.654554 -233.020888) (xy 363.704168 -233.001416) (xy 363.75613 -232.989556)
			(xy 363.80928 -232.985573) (xy 363.86243 -232.989556) (xy 363.914392 -233.001416) (xy 363.964006 -233.020888)
			(xy 364.010164 -233.047537) (xy 364.051835 -233.080768) (xy 364.088087 -233.119839) (xy 364.118111 -233.163876)
			(xy 364.141237 -233.211897) (xy 364.156947 -233.262827) (xy 364.16489 -233.315531) (xy 364.165388 -233.34218)
			(xy 364.16489 -233.368829) (xy 364.39347 -233.368829) (xy 364.39347 -233.315531) (xy 364.401413 -233.262827)
			(xy 364.417123 -233.211897) (xy 364.440249 -233.163876) (xy 364.470273 -233.119839) (xy 364.506525 -233.080768)
			(xy 364.548196 -233.047537) (xy 364.594354 -233.020888) (xy 364.643968 -233.001416) (xy 364.69593 -232.989556)
			(xy 364.74908 -232.985573) (xy 364.80223 -232.989556) (xy 364.854192 -233.001416) (xy 364.903806 -233.020888)
			(xy 364.949964 -233.047537) (xy 364.991635 -233.080768) (xy 365.027887 -233.119839) (xy 365.057911 -233.163876)
			(xy 365.081037 -233.211897) (xy 365.096747 -233.262827) (xy 365.10469 -233.315531) (xy 365.105188 -233.34218)
			(xy 365.10469 -233.368829) (xy 365.33327 -233.368829) (xy 365.33327 -233.315531) (xy 365.341213 -233.262827)
			(xy 365.356923 -233.211897) (xy 365.380049 -233.163876) (xy 365.410073 -233.119839) (xy 365.446325 -233.080768)
			(xy 365.487996 -233.047537) (xy 365.534154 -233.020888) (xy 365.583768 -233.001416) (xy 365.63573 -232.989556)
			(xy 365.68888 -232.985573) (xy 365.74203 -232.989556) (xy 365.793992 -233.001416) (xy 365.843606 -233.020888)
			(xy 365.889764 -233.047537) (xy 365.931435 -233.080768) (xy 365.967687 -233.119839) (xy 365.997711 -233.163876)
			(xy 366.020837 -233.211897) (xy 366.036547 -233.262827) (xy 366.04449 -233.315531) (xy 366.044988 -233.34218)
			(xy 366.04449 -233.368829) (xy 366.27307 -233.368829) (xy 366.27307 -233.315531) (xy 366.281013 -233.262827)
			(xy 366.296723 -233.211897) (xy 366.319849 -233.163876) (xy 366.349873 -233.119839) (xy 366.386125 -233.080768)
			(xy 366.427796 -233.047537) (xy 366.473954 -233.020888) (xy 366.523568 -233.001416) (xy 366.57553 -232.989556)
			(xy 366.62868 -232.985573) (xy 366.68183 -232.989556) (xy 366.733792 -233.001416) (xy 366.783406 -233.020888)
			(xy 366.829564 -233.047537) (xy 366.871235 -233.080768) (xy 366.907487 -233.119839) (xy 366.937511 -233.163876)
			(xy 366.960637 -233.211897) (xy 366.976347 -233.262827) (xy 366.98429 -233.315531) (xy 366.984788 -233.34218)
			(xy 366.98429 -233.368829) (xy 367.21287 -233.368829) (xy 367.21287 -233.315531) (xy 367.220813 -233.262827)
			(xy 367.236523 -233.211897) (xy 367.259649 -233.163876) (xy 367.289673 -233.119839) (xy 367.325925 -233.080768)
			(xy 367.367596 -233.047537) (xy 367.413754 -233.020888) (xy 367.463368 -233.001416) (xy 367.51533 -232.989556)
			(xy 367.56848 -232.985573) (xy 367.62163 -232.989556) (xy 367.673592 -233.001416) (xy 367.723206 -233.020888)
			(xy 367.769364 -233.047537) (xy 367.811035 -233.080768) (xy 367.847287 -233.119839) (xy 367.877311 -233.163876)
			(xy 367.900437 -233.211897) (xy 367.916147 -233.262827) (xy 367.92409 -233.315531) (xy 367.924588 -233.34218)
			(xy 367.92409 -233.368829) (xy 368.15267 -233.368829) (xy 368.15267 -233.315531) (xy 368.160613 -233.262827)
			(xy 368.176323 -233.211897) (xy 368.199449 -233.163876) (xy 368.229473 -233.119839) (xy 368.265725 -233.080768)
			(xy 368.307396 -233.047537) (xy 368.353554 -233.020888) (xy 368.403168 -233.001416) (xy 368.45513 -232.989556)
			(xy 368.50828 -232.985573) (xy 368.56143 -232.989556) (xy 368.613392 -233.001416) (xy 368.663006 -233.020888)
			(xy 368.709164 -233.047537) (xy 368.750835 -233.080768) (xy 368.787087 -233.119839) (xy 368.817111 -233.163876)
			(xy 368.840237 -233.211897) (xy 368.855947 -233.262827) (xy 368.86389 -233.315531) (xy 368.864388 -233.34218)
			(xy 368.86389 -233.368829) (xy 369.092724 -233.368829) (xy 369.092724 -233.315531) (xy 369.100667 -233.262827)
			(xy 369.116377 -233.211897) (xy 369.139503 -233.163876) (xy 369.169527 -233.119839) (xy 369.205779 -233.080768)
			(xy 369.24745 -233.047537) (xy 369.293608 -233.020888) (xy 369.343222 -233.001416) (xy 369.395184 -232.989556)
			(xy 369.448334 -232.985573) (xy 369.501484 -232.989556) (xy 369.553446 -233.001416) (xy 369.60306 -233.020888)
			(xy 369.649218 -233.047537) (xy 369.690889 -233.080768) (xy 369.727141 -233.119839) (xy 369.757165 -233.163876)
			(xy 369.780291 -233.211897) (xy 369.796001 -233.262827) (xy 369.803944 -233.315531) (xy 369.804442 -233.34218)
			(xy 369.803944 -233.368829) (xy 370.03227 -233.368829) (xy 370.03227 -233.315531) (xy 370.040213 -233.262827)
			(xy 370.055923 -233.211897) (xy 370.079049 -233.163876) (xy 370.109073 -233.119839) (xy 370.145325 -233.080768)
			(xy 370.186996 -233.047537) (xy 370.233154 -233.020888) (xy 370.282768 -233.001416) (xy 370.33473 -232.989556)
			(xy 370.38788 -232.985573) (xy 370.44103 -232.989556) (xy 370.492992 -233.001416) (xy 370.542606 -233.020888)
			(xy 370.588764 -233.047537) (xy 370.630435 -233.080768) (xy 370.666687 -233.119839) (xy 370.696711 -233.163876)
			(xy 370.719837 -233.211897) (xy 370.735547 -233.262827) (xy 370.74349 -233.315531) (xy 370.743988 -233.34218)
			(xy 370.74349 -233.368829) (xy 370.97207 -233.368829) (xy 370.97207 -233.315531) (xy 370.980013 -233.262827)
			(xy 370.995723 -233.211897) (xy 371.018849 -233.163876) (xy 371.048873 -233.119839) (xy 371.085125 -233.080768)
			(xy 371.126796 -233.047537) (xy 371.172954 -233.020888) (xy 371.222568 -233.001416) (xy 371.27453 -232.989556)
			(xy 371.32768 -232.985573) (xy 371.38083 -232.989556) (xy 371.432792 -233.001416) (xy 371.482406 -233.020888)
			(xy 371.528564 -233.047537) (xy 371.570235 -233.080768) (xy 371.606487 -233.119839) (xy 371.636511 -233.163876)
			(xy 371.659637 -233.211897) (xy 371.675347 -233.262827) (xy 371.68329 -233.315531) (xy 371.683788 -233.34218)
			(xy 371.68329 -233.368829) (xy 371.91187 -233.368829) (xy 371.91187 -233.315531) (xy 371.919813 -233.262827)
			(xy 371.935523 -233.211897) (xy 371.958649 -233.163876) (xy 371.988673 -233.119839) (xy 372.024925 -233.080768)
			(xy 372.066596 -233.047537) (xy 372.112754 -233.020888) (xy 372.162368 -233.001416) (xy 372.21433 -232.989556)
			(xy 372.26748 -232.985573) (xy 372.32063 -232.989556) (xy 372.372592 -233.001416) (xy 372.422206 -233.020888)
			(xy 372.468364 -233.047537) (xy 372.510035 -233.080768) (xy 372.546287 -233.119839) (xy 372.576311 -233.163876)
			(xy 372.599437 -233.211897) (xy 372.615147 -233.262827) (xy 372.62309 -233.315531) (xy 372.623588 -233.34218)
			(xy 372.62309 -233.368829) (xy 372.85167 -233.368829) (xy 372.85167 -233.315531) (xy 372.859613 -233.262827)
			(xy 372.875323 -233.211897) (xy 372.898449 -233.163876) (xy 372.928473 -233.119839) (xy 372.964725 -233.080768)
			(xy 373.006396 -233.047537) (xy 373.052554 -233.020888) (xy 373.102168 -233.001416) (xy 373.15413 -232.989556)
			(xy 373.20728 -232.985573) (xy 373.26043 -232.989556) (xy 373.312392 -233.001416) (xy 373.362006 -233.020888)
			(xy 373.408164 -233.047537) (xy 373.449835 -233.080768) (xy 373.486087 -233.119839) (xy 373.516111 -233.163876)
			(xy 373.539237 -233.211897) (xy 373.554947 -233.262827) (xy 373.56289 -233.315531) (xy 373.563388 -233.34218)
			(xy 373.56289 -233.368829) (xy 373.791724 -233.368829) (xy 373.791724 -233.315531) (xy 373.799667 -233.262827)
			(xy 373.815377 -233.211897) (xy 373.838503 -233.163876) (xy 373.868527 -233.119839) (xy 373.904779 -233.080768)
			(xy 373.94645 -233.047537) (xy 373.992608 -233.020888) (xy 374.042222 -233.001416) (xy 374.094184 -232.989556)
			(xy 374.147334 -232.985573) (xy 374.200484 -232.989556) (xy 374.252446 -233.001416) (xy 374.30206 -233.020888)
			(xy 374.348218 -233.047537) (xy 374.389889 -233.080768) (xy 374.426141 -233.119839) (xy 374.456165 -233.163876)
			(xy 374.479291 -233.211897) (xy 374.495001 -233.262827) (xy 374.502944 -233.315531) (xy 374.503442 -233.34218)
			(xy 374.502944 -233.368829) (xy 374.73127 -233.368829) (xy 374.73127 -233.315531) (xy 374.739213 -233.262827)
			(xy 374.754923 -233.211897) (xy 374.778049 -233.163876) (xy 374.808073 -233.119839) (xy 374.844325 -233.080768)
			(xy 374.885996 -233.047537) (xy 374.932154 -233.020888) (xy 374.981768 -233.001416) (xy 375.03373 -232.989556)
			(xy 375.08688 -232.985573) (xy 375.14003 -232.989556) (xy 375.191992 -233.001416) (xy 375.241606 -233.020888)
			(xy 375.287764 -233.047537) (xy 375.329435 -233.080768) (xy 375.365687 -233.119839) (xy 375.395711 -233.163876)
			(xy 375.418837 -233.211897) (xy 375.434547 -233.262827) (xy 375.44249 -233.315531) (xy 375.442988 -233.34218)
			(xy 375.44249 -233.368829) (xy 375.67107 -233.368829) (xy 375.67107 -233.315531) (xy 375.679013 -233.262827)
			(xy 375.694723 -233.211897) (xy 375.717849 -233.163876) (xy 375.747873 -233.119839) (xy 375.784125 -233.080768)
			(xy 375.825796 -233.047537) (xy 375.871954 -233.020888) (xy 375.921568 -233.001416) (xy 375.97353 -232.989556)
			(xy 376.02668 -232.985573) (xy 376.07983 -232.989556) (xy 376.131792 -233.001416) (xy 376.181406 -233.020888)
			(xy 376.227564 -233.047537) (xy 376.269235 -233.080768) (xy 376.305487 -233.119839) (xy 376.335511 -233.163876)
			(xy 376.358637 -233.211897) (xy 376.374347 -233.262827) (xy 376.38229 -233.315531) (xy 376.382788 -233.34218)
			(xy 376.38229 -233.368829) (xy 376.61087 -233.368829) (xy 376.61087 -233.315531) (xy 376.618813 -233.262827)
			(xy 376.634523 -233.211897) (xy 376.657649 -233.163876) (xy 376.687673 -233.119839) (xy 376.723925 -233.080768)
			(xy 376.765596 -233.047537) (xy 376.811754 -233.020888) (xy 376.861368 -233.001416) (xy 376.91333 -232.989556)
			(xy 376.96648 -232.985573) (xy 377.01963 -232.989556) (xy 377.071592 -233.001416) (xy 377.121206 -233.020888)
			(xy 377.167364 -233.047537) (xy 377.209035 -233.080768) (xy 377.245287 -233.119839) (xy 377.275311 -233.163876)
			(xy 377.298437 -233.211897) (xy 377.314147 -233.262827) (xy 377.32209 -233.315531) (xy 377.322588 -233.34218)
			(xy 377.32209 -233.368829) (xy 377.55067 -233.368829) (xy 377.55067 -233.315531) (xy 377.558613 -233.262827)
			(xy 377.574323 -233.211897) (xy 377.597449 -233.163876) (xy 377.627473 -233.119839) (xy 377.663725 -233.080768)
			(xy 377.705396 -233.047537) (xy 377.751554 -233.020888) (xy 377.801168 -233.001416) (xy 377.85313 -232.989556)
			(xy 377.90628 -232.985573) (xy 377.95943 -232.989556) (xy 378.011392 -233.001416) (xy 378.061006 -233.020888)
			(xy 378.107164 -233.047537) (xy 378.148835 -233.080768) (xy 378.185087 -233.119839) (xy 378.215111 -233.163876)
			(xy 378.238237 -233.211897) (xy 378.253947 -233.262827) (xy 378.26189 -233.315531) (xy 378.262388 -233.34218)
			(xy 378.26189 -233.368829) (xy 378.49047 -233.368829) (xy 378.49047 -233.315531) (xy 378.498413 -233.262827)
			(xy 378.514123 -233.211897) (xy 378.537249 -233.163876) (xy 378.567273 -233.119839) (xy 378.603525 -233.080768)
			(xy 378.645196 -233.047537) (xy 378.691354 -233.020888) (xy 378.740968 -233.001416) (xy 378.79293 -232.989556)
			(xy 378.84608 -232.985573) (xy 378.89923 -232.989556) (xy 378.951192 -233.001416) (xy 379.000806 -233.020888)
			(xy 379.046964 -233.047537) (xy 379.088635 -233.080768) (xy 379.124887 -233.119839) (xy 379.154911 -233.163876)
			(xy 379.178037 -233.211897) (xy 379.193747 -233.262827) (xy 379.20169 -233.315531) (xy 379.202188 -233.34218)
			(xy 379.20169 -233.368829) (xy 379.43027 -233.368829) (xy 379.43027 -233.315531) (xy 379.438213 -233.262827)
			(xy 379.453923 -233.211897) (xy 379.477049 -233.163876) (xy 379.507073 -233.119839) (xy 379.543325 -233.080768)
			(xy 379.584996 -233.047537) (xy 379.631154 -233.020888) (xy 379.680768 -233.001416) (xy 379.73273 -232.989556)
			(xy 379.78588 -232.985573) (xy 379.83903 -232.989556) (xy 379.890992 -233.001416) (xy 379.940606 -233.020888)
			(xy 379.986764 -233.047537) (xy 380.028435 -233.080768) (xy 380.064687 -233.119839) (xy 380.094711 -233.163876)
			(xy 380.117837 -233.211897) (xy 380.133547 -233.262827) (xy 380.14149 -233.315531) (xy 380.141988 -233.34218)
			(xy 380.14149 -233.368829) (xy 380.370324 -233.368829) (xy 380.370324 -233.315531) (xy 380.378267 -233.262827)
			(xy 380.393977 -233.211897) (xy 380.417103 -233.163876) (xy 380.447127 -233.119839) (xy 380.483379 -233.080768)
			(xy 380.52505 -233.047537) (xy 380.571208 -233.020888) (xy 380.620822 -233.001416) (xy 380.672784 -232.989556)
			(xy 380.725934 -232.985573) (xy 380.779084 -232.989556) (xy 380.831046 -233.001416) (xy 380.88066 -233.020888)
			(xy 380.926818 -233.047537) (xy 380.968489 -233.080768) (xy 381.004741 -233.119839) (xy 381.034765 -233.163876)
			(xy 381.057891 -233.211897) (xy 381.073601 -233.262827) (xy 381.081544 -233.315531) (xy 381.082042 -233.34218)
			(xy 381.081544 -233.368829) (xy 381.073601 -233.421533) (xy 381.057891 -233.472463) (xy 381.034765 -233.520484)
			(xy 381.004741 -233.564521) (xy 380.968489 -233.603592) (xy 380.926818 -233.636823) (xy 380.88066 -233.663472)
			(xy 380.831046 -233.682944) (xy 380.779084 -233.694804) (xy 380.725934 -233.698788) (xy 380.672784 -233.694804)
			(xy 380.620822 -233.682944) (xy 380.571208 -233.663472) (xy 380.52505 -233.636823) (xy 380.483379 -233.603592)
			(xy 380.447127 -233.564521) (xy 380.417103 -233.520484) (xy 380.393977 -233.472463) (xy 380.378267 -233.421533)
			(xy 380.370324 -233.368829) (xy 380.14149 -233.368829) (xy 380.133547 -233.421533) (xy 380.117837 -233.472463)
			(xy 380.094711 -233.520484) (xy 380.064687 -233.564521) (xy 380.028435 -233.603592) (xy 379.986764 -233.636823)
			(xy 379.940606 -233.663472) (xy 379.890992 -233.682944) (xy 379.83903 -233.694804) (xy 379.78588 -233.698788)
			(xy 379.73273 -233.694804) (xy 379.680768 -233.682944) (xy 379.631154 -233.663472) (xy 379.584996 -233.636823)
			(xy 379.543325 -233.603592) (xy 379.507073 -233.564521) (xy 379.477049 -233.520484) (xy 379.453923 -233.472463)
			(xy 379.438213 -233.421533) (xy 379.43027 -233.368829) (xy 379.20169 -233.368829) (xy 379.193747 -233.421533)
			(xy 379.178037 -233.472463) (xy 379.154911 -233.520484) (xy 379.124887 -233.564521) (xy 379.088635 -233.603592)
			(xy 379.046964 -233.636823) (xy 379.000806 -233.663472) (xy 378.951192 -233.682944) (xy 378.89923 -233.694804)
			(xy 378.84608 -233.698788) (xy 378.79293 -233.694804) (xy 378.740968 -233.682944) (xy 378.691354 -233.663472)
			(xy 378.645196 -233.636823) (xy 378.603525 -233.603592) (xy 378.567273 -233.564521) (xy 378.537249 -233.520484)
			(xy 378.514123 -233.472463) (xy 378.498413 -233.421533) (xy 378.49047 -233.368829) (xy 378.26189 -233.368829)
			(xy 378.253947 -233.421533) (xy 378.238237 -233.472463) (xy 378.215111 -233.520484) (xy 378.185087 -233.564521)
			(xy 378.148835 -233.603592) (xy 378.107164 -233.636823) (xy 378.061006 -233.663472) (xy 378.011392 -233.682944)
			(xy 377.95943 -233.694804) (xy 377.90628 -233.698788) (xy 377.85313 -233.694804) (xy 377.801168 -233.682944)
			(xy 377.751554 -233.663472) (xy 377.705396 -233.636823) (xy 377.663725 -233.603592) (xy 377.627473 -233.564521)
			(xy 377.597449 -233.520484) (xy 377.574323 -233.472463) (xy 377.558613 -233.421533) (xy 377.55067 -233.368829)
			(xy 377.32209 -233.368829) (xy 377.314147 -233.421533) (xy 377.298437 -233.472463) (xy 377.275311 -233.520484)
			(xy 377.245287 -233.564521) (xy 377.209035 -233.603592) (xy 377.167364 -233.636823) (xy 377.121206 -233.663472)
			(xy 377.071592 -233.682944) (xy 377.01963 -233.694804) (xy 376.96648 -233.698788) (xy 376.91333 -233.694804)
			(xy 376.861368 -233.682944) (xy 376.811754 -233.663472) (xy 376.765596 -233.636823) (xy 376.723925 -233.603592)
			(xy 376.687673 -233.564521) (xy 376.657649 -233.520484) (xy 376.634523 -233.472463) (xy 376.618813 -233.421533)
			(xy 376.61087 -233.368829) (xy 376.38229 -233.368829) (xy 376.374347 -233.421533) (xy 376.358637 -233.472463)
			(xy 376.335511 -233.520484) (xy 376.305487 -233.564521) (xy 376.269235 -233.603592) (xy 376.227564 -233.636823)
			(xy 376.181406 -233.663472) (xy 376.131792 -233.682944) (xy 376.07983 -233.694804) (xy 376.02668 -233.698788)
			(xy 375.97353 -233.694804) (xy 375.921568 -233.682944) (xy 375.871954 -233.663472) (xy 375.825796 -233.636823)
			(xy 375.784125 -233.603592) (xy 375.747873 -233.564521) (xy 375.717849 -233.520484) (xy 375.694723 -233.472463)
			(xy 375.679013 -233.421533) (xy 375.67107 -233.368829) (xy 375.44249 -233.368829) (xy 375.434547 -233.421533)
			(xy 375.418837 -233.472463) (xy 375.395711 -233.520484) (xy 375.365687 -233.564521) (xy 375.329435 -233.603592)
			(xy 375.287764 -233.636823) (xy 375.241606 -233.663472) (xy 375.191992 -233.682944) (xy 375.14003 -233.694804)
			(xy 375.08688 -233.698788) (xy 375.03373 -233.694804) (xy 374.981768 -233.682944) (xy 374.932154 -233.663472)
			(xy 374.885996 -233.636823) (xy 374.844325 -233.603592) (xy 374.808073 -233.564521) (xy 374.778049 -233.520484)
			(xy 374.754923 -233.472463) (xy 374.739213 -233.421533) (xy 374.73127 -233.368829) (xy 374.502944 -233.368829)
			(xy 374.495001 -233.421533) (xy 374.479291 -233.472463) (xy 374.456165 -233.520484) (xy 374.426141 -233.564521)
			(xy 374.389889 -233.603592) (xy 374.348218 -233.636823) (xy 374.30206 -233.663472) (xy 374.252446 -233.682944)
			(xy 374.200484 -233.694804) (xy 374.147334 -233.698788) (xy 374.094184 -233.694804) (xy 374.042222 -233.682944)
			(xy 373.992608 -233.663472) (xy 373.94645 -233.636823) (xy 373.904779 -233.603592) (xy 373.868527 -233.564521)
			(xy 373.838503 -233.520484) (xy 373.815377 -233.472463) (xy 373.799667 -233.421533) (xy 373.791724 -233.368829)
			(xy 373.56289 -233.368829) (xy 373.554947 -233.421533) (xy 373.539237 -233.472463) (xy 373.516111 -233.520484)
			(xy 373.486087 -233.564521) (xy 373.449835 -233.603592) (xy 373.408164 -233.636823) (xy 373.362006 -233.663472)
			(xy 373.312392 -233.682944) (xy 373.26043 -233.694804) (xy 373.20728 -233.698788) (xy 373.15413 -233.694804)
			(xy 373.102168 -233.682944) (xy 373.052554 -233.663472) (xy 373.006396 -233.636823) (xy 372.964725 -233.603592)
			(xy 372.928473 -233.564521) (xy 372.898449 -233.520484) (xy 372.875323 -233.472463) (xy 372.859613 -233.421533)
			(xy 372.85167 -233.368829) (xy 372.62309 -233.368829) (xy 372.615147 -233.421533) (xy 372.599437 -233.472463)
			(xy 372.576311 -233.520484) (xy 372.546287 -233.564521) (xy 372.510035 -233.603592) (xy 372.468364 -233.636823)
			(xy 372.422206 -233.663472) (xy 372.372592 -233.682944) (xy 372.32063 -233.694804) (xy 372.26748 -233.698788)
			(xy 372.21433 -233.694804) (xy 372.162368 -233.682944) (xy 372.112754 -233.663472) (xy 372.066596 -233.636823)
			(xy 372.024925 -233.603592) (xy 371.988673 -233.564521) (xy 371.958649 -233.520484) (xy 371.935523 -233.472463)
			(xy 371.919813 -233.421533) (xy 371.91187 -233.368829) (xy 371.68329 -233.368829) (xy 371.675347 -233.421533)
			(xy 371.659637 -233.472463) (xy 371.636511 -233.520484) (xy 371.606487 -233.564521) (xy 371.570235 -233.603592)
			(xy 371.528564 -233.636823) (xy 371.482406 -233.663472) (xy 371.432792 -233.682944) (xy 371.38083 -233.694804)
			(xy 371.32768 -233.698788) (xy 371.27453 -233.694804) (xy 371.222568 -233.682944) (xy 371.172954 -233.663472)
			(xy 371.126796 -233.636823) (xy 371.085125 -233.603592) (xy 371.048873 -233.564521) (xy 371.018849 -233.520484)
			(xy 370.995723 -233.472463) (xy 370.980013 -233.421533) (xy 370.97207 -233.368829) (xy 370.74349 -233.368829)
			(xy 370.735547 -233.421533) (xy 370.719837 -233.472463) (xy 370.696711 -233.520484) (xy 370.666687 -233.564521)
			(xy 370.630435 -233.603592) (xy 370.588764 -233.636823) (xy 370.542606 -233.663472) (xy 370.492992 -233.682944)
			(xy 370.44103 -233.694804) (xy 370.38788 -233.698788) (xy 370.33473 -233.694804) (xy 370.282768 -233.682944)
			(xy 370.233154 -233.663472) (xy 370.186996 -233.636823) (xy 370.145325 -233.603592) (xy 370.109073 -233.564521)
			(xy 370.079049 -233.520484) (xy 370.055923 -233.472463) (xy 370.040213 -233.421533) (xy 370.03227 -233.368829)
			(xy 369.803944 -233.368829) (xy 369.796001 -233.421533) (xy 369.780291 -233.472463) (xy 369.757165 -233.520484)
			(xy 369.727141 -233.564521) (xy 369.690889 -233.603592) (xy 369.649218 -233.636823) (xy 369.60306 -233.663472)
			(xy 369.553446 -233.682944) (xy 369.501484 -233.694804) (xy 369.448334 -233.698788) (xy 369.395184 -233.694804)
			(xy 369.343222 -233.682944) (xy 369.293608 -233.663472) (xy 369.24745 -233.636823) (xy 369.205779 -233.603592)
			(xy 369.169527 -233.564521) (xy 369.139503 -233.520484) (xy 369.116377 -233.472463) (xy 369.100667 -233.421533)
			(xy 369.092724 -233.368829) (xy 368.86389 -233.368829) (xy 368.855947 -233.421533) (xy 368.840237 -233.472463)
			(xy 368.817111 -233.520484) (xy 368.787087 -233.564521) (xy 368.750835 -233.603592) (xy 368.709164 -233.636823)
			(xy 368.663006 -233.663472) (xy 368.613392 -233.682944) (xy 368.56143 -233.694804) (xy 368.50828 -233.698788)
			(xy 368.45513 -233.694804) (xy 368.403168 -233.682944) (xy 368.353554 -233.663472) (xy 368.307396 -233.636823)
			(xy 368.265725 -233.603592) (xy 368.229473 -233.564521) (xy 368.199449 -233.520484) (xy 368.176323 -233.472463)
			(xy 368.160613 -233.421533) (xy 368.15267 -233.368829) (xy 367.92409 -233.368829) (xy 367.916147 -233.421533)
			(xy 367.900437 -233.472463) (xy 367.877311 -233.520484) (xy 367.847287 -233.564521) (xy 367.811035 -233.603592)
			(xy 367.769364 -233.636823) (xy 367.723206 -233.663472) (xy 367.673592 -233.682944) (xy 367.62163 -233.694804)
			(xy 367.56848 -233.698788) (xy 367.51533 -233.694804) (xy 367.463368 -233.682944) (xy 367.413754 -233.663472)
			(xy 367.367596 -233.636823) (xy 367.325925 -233.603592) (xy 367.289673 -233.564521) (xy 367.259649 -233.520484)
			(xy 367.236523 -233.472463) (xy 367.220813 -233.421533) (xy 367.21287 -233.368829) (xy 366.98429 -233.368829)
			(xy 366.976347 -233.421533) (xy 366.960637 -233.472463) (xy 366.937511 -233.520484) (xy 366.907487 -233.564521)
			(xy 366.871235 -233.603592) (xy 366.829564 -233.636823) (xy 366.783406 -233.663472) (xy 366.733792 -233.682944)
			(xy 366.68183 -233.694804) (xy 366.62868 -233.698788) (xy 366.57553 -233.694804) (xy 366.523568 -233.682944)
			(xy 366.473954 -233.663472) (xy 366.427796 -233.636823) (xy 366.386125 -233.603592) (xy 366.349873 -233.564521)
			(xy 366.319849 -233.520484) (xy 366.296723 -233.472463) (xy 366.281013 -233.421533) (xy 366.27307 -233.368829)
			(xy 366.04449 -233.368829) (xy 366.036547 -233.421533) (xy 366.020837 -233.472463) (xy 365.997711 -233.520484)
			(xy 365.967687 -233.564521) (xy 365.931435 -233.603592) (xy 365.889764 -233.636823) (xy 365.843606 -233.663472)
			(xy 365.793992 -233.682944) (xy 365.74203 -233.694804) (xy 365.68888 -233.698788) (xy 365.63573 -233.694804)
			(xy 365.583768 -233.682944) (xy 365.534154 -233.663472) (xy 365.487996 -233.636823) (xy 365.446325 -233.603592)
			(xy 365.410073 -233.564521) (xy 365.380049 -233.520484) (xy 365.356923 -233.472463) (xy 365.341213 -233.421533)
			(xy 365.33327 -233.368829) (xy 365.10469 -233.368829) (xy 365.096747 -233.421533) (xy 365.081037 -233.472463)
			(xy 365.057911 -233.520484) (xy 365.027887 -233.564521) (xy 364.991635 -233.603592) (xy 364.949964 -233.636823)
			(xy 364.903806 -233.663472) (xy 364.854192 -233.682944) (xy 364.80223 -233.694804) (xy 364.74908 -233.698788)
			(xy 364.69593 -233.694804) (xy 364.643968 -233.682944) (xy 364.594354 -233.663472) (xy 364.548196 -233.636823)
			(xy 364.506525 -233.603592) (xy 364.470273 -233.564521) (xy 364.440249 -233.520484) (xy 364.417123 -233.472463)
			(xy 364.401413 -233.421533) (xy 364.39347 -233.368829) (xy 364.16489 -233.368829) (xy 364.156947 -233.421533)
			(xy 364.141237 -233.472463) (xy 364.118111 -233.520484) (xy 364.088087 -233.564521) (xy 364.051835 -233.603592)
			(xy 364.010164 -233.636823) (xy 363.964006 -233.663472) (xy 363.914392 -233.682944) (xy 363.86243 -233.694804)
			(xy 363.80928 -233.698788) (xy 363.75613 -233.694804) (xy 363.704168 -233.682944) (xy 363.654554 -233.663472)
			(xy 363.608396 -233.636823) (xy 363.566725 -233.603592) (xy 363.530473 -233.564521) (xy 363.500449 -233.520484)
			(xy 363.477323 -233.472463) (xy 363.461613 -233.421533) (xy 363.45367 -233.368829) (xy 363.22509 -233.368829)
			(xy 363.217147 -233.421533) (xy 363.201437 -233.472463) (xy 363.178311 -233.520484) (xy 363.148287 -233.564521)
			(xy 363.112035 -233.603592) (xy 363.070364 -233.636823) (xy 363.024206 -233.663472) (xy 362.974592 -233.682944)
			(xy 362.92263 -233.694804) (xy 362.86948 -233.698788) (xy 362.81633 -233.694804) (xy 362.764368 -233.682944)
			(xy 362.714754 -233.663472) (xy 362.668596 -233.636823) (xy 362.626925 -233.603592) (xy 362.590673 -233.564521)
			(xy 362.560649 -233.520484) (xy 362.537523 -233.472463) (xy 362.521813 -233.421533) (xy 362.51387 -233.368829)
			(xy 362.285544 -233.368829) (xy 362.277601 -233.421533) (xy 362.261891 -233.472463) (xy 362.238765 -233.520484)
			(xy 362.208741 -233.564521) (xy 362.172489 -233.603592) (xy 362.130818 -233.636823) (xy 362.08466 -233.663472)
			(xy 362.035046 -233.682944) (xy 361.983084 -233.694804) (xy 361.929934 -233.698788) (xy 361.876784 -233.694804)
			(xy 361.824822 -233.682944) (xy 361.775208 -233.663472) (xy 361.72905 -233.636823) (xy 361.687379 -233.603592)
			(xy 361.651127 -233.564521) (xy 361.621103 -233.520484) (xy 361.597977 -233.472463) (xy 361.582267 -233.421533)
			(xy 361.574324 -233.368829) (xy 361.34549 -233.368829) (xy 361.337547 -233.421533) (xy 361.321837 -233.472463)
			(xy 361.298711 -233.520484) (xy 361.268687 -233.564521) (xy 361.232435 -233.603592) (xy 361.190764 -233.636823)
			(xy 361.144606 -233.663472) (xy 361.094992 -233.682944) (xy 361.04303 -233.694804) (xy 360.98988 -233.698788)
			(xy 360.93673 -233.694804) (xy 360.884768 -233.682944) (xy 360.835154 -233.663472) (xy 360.788996 -233.636823)
			(xy 360.747325 -233.603592) (xy 360.711073 -233.564521) (xy 360.681049 -233.520484) (xy 360.657923 -233.472463)
			(xy 360.642213 -233.421533) (xy 360.63427 -233.368829) (xy 360.40569 -233.368829) (xy 360.397747 -233.421533)
			(xy 360.382037 -233.472463) (xy 360.358911 -233.520484) (xy 360.328887 -233.564521) (xy 360.292635 -233.603592)
			(xy 360.250964 -233.636823) (xy 360.204806 -233.663472) (xy 360.155192 -233.682944) (xy 360.10323 -233.694804)
			(xy 360.05008 -233.698788) (xy 359.99693 -233.694804) (xy 359.944968 -233.682944) (xy 359.895354 -233.663472)
			(xy 359.849196 -233.636823) (xy 359.807525 -233.603592) (xy 359.771273 -233.564521) (xy 359.741249 -233.520484)
			(xy 359.718123 -233.472463) (xy 359.702413 -233.421533) (xy 359.69447 -233.368829) (xy 359.46589 -233.368829)
			(xy 359.457947 -233.421533) (xy 359.442237 -233.472463) (xy 359.419111 -233.520484) (xy 359.389087 -233.564521)
			(xy 359.352835 -233.603592) (xy 359.311164 -233.636823) (xy 359.265006 -233.663472) (xy 359.215392 -233.682944)
			(xy 359.16343 -233.694804) (xy 359.11028 -233.698788) (xy 359.05713 -233.694804) (xy 359.005168 -233.682944)
			(xy 358.955554 -233.663472) (xy 358.909396 -233.636823) (xy 358.867725 -233.603592) (xy 358.831473 -233.564521)
			(xy 358.801449 -233.520484) (xy 358.778323 -233.472463) (xy 358.762613 -233.421533) (xy 358.75467 -233.368829)
			(xy 358.526344 -233.368829) (xy 358.518401 -233.421533) (xy 358.502691 -233.472463) (xy 358.479565 -233.520484)
			(xy 358.449541 -233.564521) (xy 358.413289 -233.603592) (xy 358.371618 -233.636823) (xy 358.32546 -233.663472)
			(xy 358.275846 -233.682944) (xy 358.223884 -233.694804) (xy 358.170734 -233.698788) (xy 358.117584 -233.694804)
			(xy 358.065622 -233.682944) (xy 358.016008 -233.663472) (xy 357.96985 -233.636823) (xy 357.928179 -233.603592)
			(xy 357.891927 -233.564521) (xy 357.861903 -233.520484) (xy 357.838777 -233.472463) (xy 357.823067 -233.421533)
			(xy 357.815124 -233.368829) (xy 357.58629 -233.368829) (xy 357.578347 -233.421533) (xy 357.562637 -233.472463)
			(xy 357.539511 -233.520484) (xy 357.509487 -233.564521) (xy 357.473235 -233.603592) (xy 357.431564 -233.636823)
			(xy 357.385406 -233.663472) (xy 357.335792 -233.682944) (xy 357.28383 -233.694804) (xy 357.23068 -233.698788)
			(xy 357.17753 -233.694804) (xy 357.125568 -233.682944) (xy 357.075954 -233.663472) (xy 357.029796 -233.636823)
			(xy 356.988125 -233.603592) (xy 356.951873 -233.564521) (xy 356.921849 -233.520484) (xy 356.898723 -233.472463)
			(xy 356.883013 -233.421533) (xy 356.87507 -233.368829) (xy 356.64649 -233.368829) (xy 356.638547 -233.421533)
			(xy 356.622837 -233.472463) (xy 356.599711 -233.520484) (xy 356.569687 -233.564521) (xy 356.533435 -233.603592)
			(xy 356.491764 -233.636823) (xy 356.445606 -233.663472) (xy 356.395992 -233.682944) (xy 356.34403 -233.694804)
			(xy 356.29088 -233.698788) (xy 356.23773 -233.694804) (xy 356.185768 -233.682944) (xy 356.136154 -233.663472)
			(xy 356.089996 -233.636823) (xy 356.048325 -233.603592) (xy 356.012073 -233.564521) (xy 355.982049 -233.520484)
			(xy 355.958923 -233.472463) (xy 355.943213 -233.421533) (xy 355.93527 -233.368829) (xy 355.70669 -233.368829)
			(xy 355.698747 -233.421533) (xy 355.683037 -233.472463) (xy 355.659911 -233.520484) (xy 355.629887 -233.564521)
			(xy 355.593635 -233.603592) (xy 355.551964 -233.636823) (xy 355.505806 -233.663472) (xy 355.456192 -233.682944)
			(xy 355.40423 -233.694804) (xy 355.35108 -233.698788) (xy 355.29793 -233.694804) (xy 355.245968 -233.682944)
			(xy 355.196354 -233.663472) (xy 355.150196 -233.636823) (xy 355.108525 -233.603592) (xy 355.072273 -233.564521)
			(xy 355.042249 -233.520484) (xy 355.019123 -233.472463) (xy 355.003413 -233.421533) (xy 354.99547 -233.368829)
			(xy 354.76689 -233.368829) (xy 354.758947 -233.421533) (xy 354.743237 -233.472463) (xy 354.720111 -233.520484)
			(xy 354.690087 -233.564521) (xy 354.653835 -233.603592) (xy 354.612164 -233.636823) (xy 354.566006 -233.663472)
			(xy 354.516392 -233.682944) (xy 354.46443 -233.694804) (xy 354.41128 -233.698788) (xy 354.35813 -233.694804)
			(xy 354.306168 -233.682944) (xy 354.256554 -233.663472) (xy 354.210396 -233.636823) (xy 354.168725 -233.603592)
			(xy 354.132473 -233.564521) (xy 354.102449 -233.520484) (xy 354.079323 -233.472463) (xy 354.063613 -233.421533)
			(xy 354.05567 -233.368829) (xy 353.827344 -233.368829) (xy 353.819401 -233.421533) (xy 353.803691 -233.472463)
			(xy 353.780565 -233.520484) (xy 353.750541 -233.564521) (xy 353.714289 -233.603592) (xy 353.672618 -233.636823)
			(xy 353.62646 -233.663472) (xy 353.576846 -233.682944) (xy 353.524884 -233.694804) (xy 353.471734 -233.698788)
			(xy 353.418584 -233.694804) (xy 353.366622 -233.682944) (xy 353.317008 -233.663472) (xy 353.27085 -233.636823)
			(xy 353.229179 -233.603592) (xy 353.192927 -233.564521) (xy 353.162903 -233.520484) (xy 353.139777 -233.472463)
			(xy 353.124067 -233.421533) (xy 353.116124 -233.368829) (xy 352.887544 -233.368829) (xy 352.879601 -233.421533)
			(xy 352.863891 -233.472463) (xy 352.840765 -233.520484) (xy 352.810741 -233.564521) (xy 352.774489 -233.603592)
			(xy 352.732818 -233.636823) (xy 352.68666 -233.663472) (xy 352.637046 -233.682944) (xy 352.585084 -233.694804)
			(xy 352.531934 -233.698788) (xy 352.478784 -233.694804) (xy 352.426822 -233.682944) (xy 352.377208 -233.663472)
			(xy 352.33105 -233.636823) (xy 352.289379 -233.603592) (xy 352.253127 -233.564521) (xy 352.223103 -233.520484)
			(xy 352.199977 -233.472463) (xy 352.184267 -233.421533) (xy 352.176324 -233.368829) (xy 351.94749 -233.368829)
			(xy 351.939547 -233.421533) (xy 351.923837 -233.472463) (xy 351.900711 -233.520484) (xy 351.870687 -233.564521)
			(xy 351.834435 -233.603592) (xy 351.792764 -233.636823) (xy 351.746606 -233.663472) (xy 351.696992 -233.682944)
			(xy 351.64503 -233.694804) (xy 351.59188 -233.698788) (xy 351.53873 -233.694804) (xy 351.486768 -233.682944)
			(xy 351.437154 -233.663472) (xy 351.390996 -233.636823) (xy 351.349325 -233.603592) (xy 351.313073 -233.564521)
			(xy 351.283049 -233.520484) (xy 351.259923 -233.472463) (xy 351.244213 -233.421533) (xy 351.23627 -233.368829)
			(xy 351.00769 -233.368829) (xy 350.999747 -233.421533) (xy 350.984037 -233.472463) (xy 350.960911 -233.520484)
			(xy 350.930887 -233.564521) (xy 350.894635 -233.603592) (xy 350.852964 -233.636823) (xy 350.806806 -233.663472)
			(xy 350.757192 -233.682944) (xy 350.70523 -233.694804) (xy 350.65208 -233.698788) (xy 350.59893 -233.694804)
			(xy 350.546968 -233.682944) (xy 350.497354 -233.663472) (xy 350.451196 -233.636823) (xy 350.409525 -233.603592)
			(xy 350.373273 -233.564521) (xy 350.343249 -233.520484) (xy 350.320123 -233.472463) (xy 350.304413 -233.421533)
			(xy 350.29647 -233.368829) (xy 349.12809 -233.368829) (xy 349.120147 -233.421533) (xy 349.104437 -233.472463)
			(xy 349.081311 -233.520484) (xy 349.051287 -233.564521) (xy 349.015035 -233.603592) (xy 348.973364 -233.636823)
			(xy 348.927206 -233.663472) (xy 348.877592 -233.682944) (xy 348.82563 -233.694804) (xy 348.77248 -233.698788)
			(xy 348.71933 -233.694804) (xy 348.667368 -233.682944) (xy 348.617754 -233.663472) (xy 348.571596 -233.636823)
			(xy 348.529925 -233.603592) (xy 348.493673 -233.564521) (xy 348.463649 -233.520484) (xy 348.440523 -233.472463)
			(xy 348.424813 -233.421533) (xy 348.41687 -233.368829) (xy 348.18829 -233.368829) (xy 348.180347 -233.421533)
			(xy 348.164637 -233.472463) (xy 348.141511 -233.520484) (xy 348.111487 -233.564521) (xy 348.075235 -233.603592)
			(xy 348.033564 -233.636823) (xy 347.987406 -233.663472) (xy 347.937792 -233.682944) (xy 347.88583 -233.694804)
			(xy 347.83268 -233.698788) (xy 347.77953 -233.694804) (xy 347.727568 -233.682944) (xy 347.677954 -233.663472)
			(xy 347.631796 -233.636823) (xy 347.590125 -233.603592) (xy 347.553873 -233.564521) (xy 347.523849 -233.520484)
			(xy 347.500723 -233.472463) (xy 347.485013 -233.421533) (xy 347.47707 -233.368829) (xy 347.24849 -233.368829)
			(xy 347.240547 -233.421533) (xy 347.224837 -233.472463) (xy 347.201711 -233.520484) (xy 347.171687 -233.564521)
			(xy 347.135435 -233.603592) (xy 347.093764 -233.636823) (xy 347.047606 -233.663472) (xy 346.997992 -233.682944)
			(xy 346.94603 -233.694804) (xy 346.89288 -233.698788) (xy 346.83973 -233.694804) (xy 346.787768 -233.682944)
			(xy 346.738154 -233.663472) (xy 346.691996 -233.636823) (xy 346.650325 -233.603592) (xy 346.614073 -233.564521)
			(xy 346.584049 -233.520484) (xy 346.560923 -233.472463) (xy 346.545213 -233.421533) (xy 346.53727 -233.368829)
			(xy 346.308944 -233.368829) (xy 346.301001 -233.421533) (xy 346.285291 -233.472463) (xy 346.262165 -233.520484)
			(xy 346.232141 -233.564521) (xy 346.195889 -233.603592) (xy 346.154218 -233.636823) (xy 346.10806 -233.663472)
			(xy 346.058446 -233.682944) (xy 346.006484 -233.694804) (xy 345.953334 -233.698788) (xy 345.900184 -233.694804)
			(xy 345.848222 -233.682944) (xy 345.798608 -233.663472) (xy 345.75245 -233.636823) (xy 345.710779 -233.603592)
			(xy 345.674527 -233.564521) (xy 345.644503 -233.520484) (xy 345.621377 -233.472463) (xy 345.605667 -233.421533)
			(xy 345.597724 -233.368829) (xy 345.36889 -233.368829) (xy 345.360947 -233.421533) (xy 345.345237 -233.472463)
			(xy 345.322111 -233.520484) (xy 345.292087 -233.564521) (xy 345.255835 -233.603592) (xy 345.214164 -233.636823)
			(xy 345.168006 -233.663472) (xy 345.118392 -233.682944) (xy 345.06643 -233.694804) (xy 345.01328 -233.698788)
			(xy 344.96013 -233.694804) (xy 344.908168 -233.682944) (xy 344.858554 -233.663472) (xy 344.812396 -233.636823)
			(xy 344.770725 -233.603592) (xy 344.734473 -233.564521) (xy 344.704449 -233.520484) (xy 344.681323 -233.472463)
			(xy 344.665613 -233.421533) (xy 344.65767 -233.368829) (xy 344.42909 -233.368829) (xy 344.421147 -233.421533)
			(xy 344.405437 -233.472463) (xy 344.382311 -233.520484) (xy 344.352287 -233.564521) (xy 344.316035 -233.603592)
			(xy 344.274364 -233.636823) (xy 344.228206 -233.663472) (xy 344.178592 -233.682944) (xy 344.12663 -233.694804)
			(xy 344.07348 -233.698788) (xy 344.02033 -233.694804) (xy 343.968368 -233.682944) (xy 343.918754 -233.663472)
			(xy 343.872596 -233.636823) (xy 343.830925 -233.603592) (xy 343.794673 -233.564521) (xy 343.764649 -233.520484)
			(xy 343.741523 -233.472463) (xy 343.725813 -233.421533) (xy 343.71787 -233.368829) (xy 343.48929 -233.368829)
			(xy 343.481347 -233.421533) (xy 343.465637 -233.472463) (xy 343.442511 -233.520484) (xy 343.412487 -233.564521)
			(xy 343.376235 -233.603592) (xy 343.334564 -233.636823) (xy 343.288406 -233.663472) (xy 343.238792 -233.682944)
			(xy 343.18683 -233.694804) (xy 343.13368 -233.698788) (xy 343.08053 -233.694804) (xy 343.028568 -233.682944)
			(xy 342.978954 -233.663472) (xy 342.932796 -233.636823) (xy 342.891125 -233.603592) (xy 342.854873 -233.564521)
			(xy 342.824849 -233.520484) (xy 342.801723 -233.472463) (xy 342.786013 -233.421533) (xy 342.77807 -233.368829)
			(xy 342.54949 -233.368829) (xy 342.541547 -233.421533) (xy 342.525837 -233.472463) (xy 342.502711 -233.520484)
			(xy 342.472687 -233.564521) (xy 342.436435 -233.603592) (xy 342.394764 -233.636823) (xy 342.348606 -233.663472)
			(xy 342.298992 -233.682944) (xy 342.24703 -233.694804) (xy 342.19388 -233.698788) (xy 342.14073 -233.694804)
			(xy 342.088768 -233.682944) (xy 342.039154 -233.663472) (xy 341.992996 -233.636823) (xy 341.951325 -233.603592)
			(xy 341.915073 -233.564521) (xy 341.885049 -233.520484) (xy 341.861923 -233.472463) (xy 341.846213 -233.421533)
			(xy 341.83827 -233.368829) (xy 341.60969 -233.368829) (xy 341.601747 -233.421533) (xy 341.586037 -233.472463)
			(xy 341.562911 -233.520484) (xy 341.532887 -233.564521) (xy 341.496635 -233.603592) (xy 341.454964 -233.636823)
			(xy 341.408806 -233.663472) (xy 341.359192 -233.682944) (xy 341.30723 -233.694804) (xy 341.25408 -233.698788)
			(xy 341.20093 -233.694804) (xy 341.148968 -233.682944) (xy 341.099354 -233.663472) (xy 341.053196 -233.636823)
			(xy 341.011525 -233.603592) (xy 340.975273 -233.564521) (xy 340.945249 -233.520484) (xy 340.922123 -233.472463)
			(xy 340.906413 -233.421533) (xy 340.89847 -233.368829) (xy 340.66989 -233.368829) (xy 340.661947 -233.421533)
			(xy 340.646237 -233.472463) (xy 340.623111 -233.520484) (xy 340.593087 -233.564521) (xy 340.556835 -233.603592)
			(xy 340.515164 -233.636823) (xy 340.469006 -233.663472) (xy 340.419392 -233.682944) (xy 340.36743 -233.694804)
			(xy 340.31428 -233.698788) (xy 340.26113 -233.694804) (xy 340.209168 -233.682944) (xy 340.159554 -233.663472)
			(xy 340.113396 -233.636823) (xy 340.071725 -233.603592) (xy 340.035473 -233.564521) (xy 340.005449 -233.520484)
			(xy 339.982323 -233.472463) (xy 339.966613 -233.421533) (xy 339.95867 -233.368829) (xy 339.729396 -233.368829)
			(xy 339.727357 -233.395813) (xy 339.715292 -233.448211) (xy 339.695489 -233.498199) (xy 339.668397 -233.544644)
			(xy 339.634632 -233.586488) (xy 339.594961 -233.622783) (xy 339.550285 -233.652702) (xy 339.50162 -233.675566)
			(xy 339.450071 -233.690855) (xy 339.423502 -233.694986) (xy 339.37956 -233.701082) (xy 339.37956 -234.182899)
			(xy 339.489024 -234.182899) (xy 339.489024 -234.129601) (xy 339.496967 -234.076897) (xy 339.512677 -234.025967)
			(xy 339.535803 -233.977946) (xy 339.565827 -233.933909) (xy 339.602079 -233.894838) (xy 339.64375 -233.861607)
			(xy 339.689908 -233.834958) (xy 339.739522 -233.815486) (xy 339.791484 -233.803626) (xy 339.844634 -233.799643)
			(xy 339.897784 -233.803626) (xy 339.949746 -233.815486) (xy 339.99936 -233.834958) (xy 340.045518 -233.861607)
			(xy 340.087189 -233.894838) (xy 340.123441 -233.933909) (xy 340.153465 -233.977946) (xy 340.176591 -234.025967)
			(xy 340.192301 -234.076897) (xy 340.200244 -234.129601) (xy 340.200742 -234.15625) (xy 340.200244 -234.182899)
			(xy 340.428824 -234.182899) (xy 340.428824 -234.129601) (xy 340.436767 -234.076897) (xy 340.452477 -234.025967)
			(xy 340.475603 -233.977946) (xy 340.505627 -233.933909) (xy 340.541879 -233.894838) (xy 340.58355 -233.861607)
			(xy 340.629708 -233.834958) (xy 340.679322 -233.815486) (xy 340.731284 -233.803626) (xy 340.784434 -233.799643)
			(xy 340.837584 -233.803626) (xy 340.889546 -233.815486) (xy 340.93916 -233.834958) (xy 340.985318 -233.861607)
			(xy 341.026989 -233.894838) (xy 341.063241 -233.933909) (xy 341.093265 -233.977946) (xy 341.116391 -234.025967)
			(xy 341.132101 -234.076897) (xy 341.140044 -234.129601) (xy 341.140542 -234.15625) (xy 341.140044 -234.182899)
			(xy 341.368624 -234.182899) (xy 341.368624 -234.129601) (xy 341.376567 -234.076897) (xy 341.392277 -234.025967)
			(xy 341.415403 -233.977946) (xy 341.445427 -233.933909) (xy 341.481679 -233.894838) (xy 341.52335 -233.861607)
			(xy 341.569508 -233.834958) (xy 341.619122 -233.815486) (xy 341.671084 -233.803626) (xy 341.724234 -233.799643)
			(xy 341.777384 -233.803626) (xy 341.829346 -233.815486) (xy 341.87896 -233.834958) (xy 341.925118 -233.861607)
			(xy 341.966789 -233.894838) (xy 342.003041 -233.933909) (xy 342.033065 -233.977946) (xy 342.056191 -234.025967)
			(xy 342.071901 -234.076897) (xy 342.079844 -234.129601) (xy 342.080342 -234.15625) (xy 342.079844 -234.182899)
			(xy 342.30817 -234.182899) (xy 342.30817 -234.129601) (xy 342.316113 -234.076897) (xy 342.331823 -234.025967)
			(xy 342.354949 -233.977946) (xy 342.384973 -233.933909) (xy 342.421225 -233.894838) (xy 342.462896 -233.861607)
			(xy 342.509054 -233.834958) (xy 342.558668 -233.815486) (xy 342.61063 -233.803626) (xy 342.66378 -233.799643)
			(xy 342.71693 -233.803626) (xy 342.768892 -233.815486) (xy 342.818506 -233.834958) (xy 342.864664 -233.861607)
			(xy 342.906335 -233.894838) (xy 342.942587 -233.933909) (xy 342.972611 -233.977946) (xy 342.995737 -234.025967)
			(xy 343.011447 -234.076897) (xy 343.01939 -234.129601) (xy 343.019888 -234.15625) (xy 343.01939 -234.182899)
			(xy 343.248224 -234.182899) (xy 343.248224 -234.129601) (xy 343.256167 -234.076897) (xy 343.271877 -234.025967)
			(xy 343.295003 -233.977946) (xy 343.325027 -233.933909) (xy 343.361279 -233.894838) (xy 343.40295 -233.861607)
			(xy 343.449108 -233.834958) (xy 343.498722 -233.815486) (xy 343.550684 -233.803626) (xy 343.603834 -233.799643)
			(xy 343.656984 -233.803626) (xy 343.708946 -233.815486) (xy 343.75856 -233.834958) (xy 343.804718 -233.861607)
			(xy 343.846389 -233.894838) (xy 343.882641 -233.933909) (xy 343.912665 -233.977946) (xy 343.935791 -234.025967)
			(xy 343.951501 -234.076897) (xy 343.959444 -234.129601) (xy 343.959942 -234.15625) (xy 343.959444 -234.182899)
			(xy 344.188024 -234.182899) (xy 344.188024 -234.129601) (xy 344.195967 -234.076897) (xy 344.211677 -234.025967)
			(xy 344.234803 -233.977946) (xy 344.264827 -233.933909) (xy 344.301079 -233.894838) (xy 344.34275 -233.861607)
			(xy 344.388908 -233.834958) (xy 344.438522 -233.815486) (xy 344.490484 -233.803626) (xy 344.543634 -233.799643)
			(xy 344.596784 -233.803626) (xy 344.648746 -233.815486) (xy 344.69836 -233.834958) (xy 344.744518 -233.861607)
			(xy 344.786189 -233.894838) (xy 344.822441 -233.933909) (xy 344.852465 -233.977946) (xy 344.875591 -234.025967)
			(xy 344.891301 -234.076897) (xy 344.899244 -234.129601) (xy 344.899742 -234.15625) (xy 344.899244 -234.182899)
			(xy 345.127824 -234.182899) (xy 345.127824 -234.129601) (xy 345.135767 -234.076897) (xy 345.151477 -234.025967)
			(xy 345.174603 -233.977946) (xy 345.204627 -233.933909) (xy 345.240879 -233.894838) (xy 345.28255 -233.861607)
			(xy 345.328708 -233.834958) (xy 345.378322 -233.815486) (xy 345.430284 -233.803626) (xy 345.483434 -233.799643)
			(xy 345.536584 -233.803626) (xy 345.588546 -233.815486) (xy 345.63816 -233.834958) (xy 345.684318 -233.861607)
			(xy 345.725989 -233.894838) (xy 345.762241 -233.933909) (xy 345.792265 -233.977946) (xy 345.815391 -234.025967)
			(xy 345.831101 -234.076897) (xy 345.839044 -234.129601) (xy 345.839542 -234.15625) (xy 345.839044 -234.182899)
			(xy 346.067624 -234.182899) (xy 346.067624 -234.129601) (xy 346.075567 -234.076897) (xy 346.091277 -234.025967)
			(xy 346.114403 -233.977946) (xy 346.144427 -233.933909) (xy 346.180679 -233.894838) (xy 346.22235 -233.861607)
			(xy 346.268508 -233.834958) (xy 346.318122 -233.815486) (xy 346.370084 -233.803626) (xy 346.423234 -233.799643)
			(xy 346.476384 -233.803626) (xy 346.528346 -233.815486) (xy 346.57796 -233.834958) (xy 346.624118 -233.861607)
			(xy 346.665789 -233.894838) (xy 346.702041 -233.933909) (xy 346.732065 -233.977946) (xy 346.755191 -234.025967)
			(xy 346.770901 -234.076897) (xy 346.778844 -234.129601) (xy 346.779342 -234.15625) (xy 346.778844 -234.182899)
			(xy 347.007424 -234.182899) (xy 347.007424 -234.129601) (xy 347.015367 -234.076897) (xy 347.031077 -234.025967)
			(xy 347.054203 -233.977946) (xy 347.084227 -233.933909) (xy 347.120479 -233.894838) (xy 347.16215 -233.861607)
			(xy 347.208308 -233.834958) (xy 347.257922 -233.815486) (xy 347.309884 -233.803626) (xy 347.363034 -233.799643)
			(xy 347.416184 -233.803626) (xy 347.468146 -233.815486) (xy 347.51776 -233.834958) (xy 347.563918 -233.861607)
			(xy 347.605589 -233.894838) (xy 347.641841 -233.933909) (xy 347.671865 -233.977946) (xy 347.694991 -234.025967)
			(xy 347.710701 -234.076897) (xy 347.718644 -234.129601) (xy 347.719142 -234.15625) (xy 347.718644 -234.182899)
			(xy 347.947224 -234.182899) (xy 347.947224 -234.129601) (xy 347.955167 -234.076897) (xy 347.970877 -234.025967)
			(xy 347.994003 -233.977946) (xy 348.024027 -233.933909) (xy 348.060279 -233.894838) (xy 348.10195 -233.861607)
			(xy 348.148108 -233.834958) (xy 348.197722 -233.815486) (xy 348.249684 -233.803626) (xy 348.302834 -233.799643)
			(xy 348.355984 -233.803626) (xy 348.407946 -233.815486) (xy 348.45756 -233.834958) (xy 348.503718 -233.861607)
			(xy 348.545389 -233.894838) (xy 348.581641 -233.933909) (xy 348.611665 -233.977946) (xy 348.634791 -234.025967)
			(xy 348.650501 -234.076897) (xy 348.658444 -234.129601) (xy 348.658942 -234.15625) (xy 348.658444 -234.182899)
			(xy 348.88677 -234.182899) (xy 348.88677 -234.129601) (xy 348.894713 -234.076897) (xy 348.910423 -234.025967)
			(xy 348.933549 -233.977946) (xy 348.963573 -233.933909) (xy 348.999825 -233.894838) (xy 349.041496 -233.861607)
			(xy 349.087654 -233.834958) (xy 349.137268 -233.815486) (xy 349.18923 -233.803626) (xy 349.24238 -233.799643)
			(xy 349.29553 -233.803626) (xy 349.347492 -233.815486) (xy 349.397106 -233.834958) (xy 349.443264 -233.861607)
			(xy 349.484935 -233.894838) (xy 349.521187 -233.933909) (xy 349.551211 -233.977946) (xy 349.574337 -234.025967)
			(xy 349.590047 -234.076897) (xy 349.59799 -234.129601) (xy 349.598488 -234.15625) (xy 349.59799 -234.182899)
			(xy 349.826824 -234.182899) (xy 349.826824 -234.129601) (xy 349.834767 -234.076897) (xy 349.850477 -234.025967)
			(xy 349.873603 -233.977946) (xy 349.903627 -233.933909) (xy 349.939879 -233.894838) (xy 349.98155 -233.861607)
			(xy 350.027708 -233.834958) (xy 350.077322 -233.815486) (xy 350.129284 -233.803626) (xy 350.182434 -233.799643)
			(xy 350.235584 -233.803626) (xy 350.287546 -233.815486) (xy 350.33716 -233.834958) (xy 350.383318 -233.861607)
			(xy 350.424989 -233.894838) (xy 350.461241 -233.933909) (xy 350.491265 -233.977946) (xy 350.514391 -234.025967)
			(xy 350.530101 -234.076897) (xy 350.538044 -234.129601) (xy 350.538542 -234.15625) (xy 350.538044 -234.182899)
			(xy 350.766624 -234.182899) (xy 350.766624 -234.129601) (xy 350.774567 -234.076897) (xy 350.790277 -234.025967)
			(xy 350.813403 -233.977946) (xy 350.843427 -233.933909) (xy 350.879679 -233.894838) (xy 350.92135 -233.861607)
			(xy 350.967508 -233.834958) (xy 351.017122 -233.815486) (xy 351.069084 -233.803626) (xy 351.122234 -233.799643)
			(xy 351.175384 -233.803626) (xy 351.227346 -233.815486) (xy 351.27696 -233.834958) (xy 351.323118 -233.861607)
			(xy 351.364789 -233.894838) (xy 351.401041 -233.933909) (xy 351.431065 -233.977946) (xy 351.454191 -234.025967)
			(xy 351.469901 -234.076897) (xy 351.477844 -234.129601) (xy 351.478342 -234.15625) (xy 351.477844 -234.182899)
			(xy 351.706424 -234.182899) (xy 351.706424 -234.129601) (xy 351.714367 -234.076897) (xy 351.730077 -234.025967)
			(xy 351.753203 -233.977946) (xy 351.783227 -233.933909) (xy 351.819479 -233.894838) (xy 351.86115 -233.861607)
			(xy 351.907308 -233.834958) (xy 351.956922 -233.815486) (xy 352.008884 -233.803626) (xy 352.062034 -233.799643)
			(xy 352.115184 -233.803626) (xy 352.167146 -233.815486) (xy 352.21676 -233.834958) (xy 352.262918 -233.861607)
			(xy 352.304589 -233.894838) (xy 352.340841 -233.933909) (xy 352.370865 -233.977946) (xy 352.393991 -234.025967)
			(xy 352.409701 -234.076897) (xy 352.417644 -234.129601) (xy 352.418142 -234.15625) (xy 352.417644 -234.182899)
			(xy 353.586024 -234.182899) (xy 353.586024 -234.129601) (xy 353.593967 -234.076897) (xy 353.609677 -234.025967)
			(xy 353.632803 -233.977946) (xy 353.662827 -233.933909) (xy 353.699079 -233.894838) (xy 353.74075 -233.861607)
			(xy 353.786908 -233.834958) (xy 353.836522 -233.815486) (xy 353.888484 -233.803626) (xy 353.941634 -233.799643)
			(xy 353.994784 -233.803626) (xy 354.046746 -233.815486) (xy 354.09636 -233.834958) (xy 354.142518 -233.861607)
			(xy 354.184189 -233.894838) (xy 354.220441 -233.933909) (xy 354.250465 -233.977946) (xy 354.273591 -234.025967)
			(xy 354.289301 -234.076897) (xy 354.297244 -234.129601) (xy 354.297742 -234.15625) (xy 354.297244 -234.182899)
			(xy 354.525824 -234.182899) (xy 354.525824 -234.129601) (xy 354.533767 -234.076897) (xy 354.549477 -234.025967)
			(xy 354.572603 -233.977946) (xy 354.602627 -233.933909) (xy 354.638879 -233.894838) (xy 354.68055 -233.861607)
			(xy 354.726708 -233.834958) (xy 354.776322 -233.815486) (xy 354.828284 -233.803626) (xy 354.881434 -233.799643)
			(xy 354.934584 -233.803626) (xy 354.986546 -233.815486) (xy 355.03616 -233.834958) (xy 355.082318 -233.861607)
			(xy 355.123989 -233.894838) (xy 355.160241 -233.933909) (xy 355.190265 -233.977946) (xy 355.213391 -234.025967)
			(xy 355.229101 -234.076897) (xy 355.237044 -234.129601) (xy 355.237542 -234.15625) (xy 355.237044 -234.182899)
			(xy 355.465624 -234.182899) (xy 355.465624 -234.129601) (xy 355.473567 -234.076897) (xy 355.489277 -234.025967)
			(xy 355.512403 -233.977946) (xy 355.542427 -233.933909) (xy 355.578679 -233.894838) (xy 355.62035 -233.861607)
			(xy 355.666508 -233.834958) (xy 355.716122 -233.815486) (xy 355.768084 -233.803626) (xy 355.821234 -233.799643)
			(xy 355.874384 -233.803626) (xy 355.926346 -233.815486) (xy 355.97596 -233.834958) (xy 356.022118 -233.861607)
			(xy 356.063789 -233.894838) (xy 356.100041 -233.933909) (xy 356.130065 -233.977946) (xy 356.153191 -234.025967)
			(xy 356.168901 -234.076897) (xy 356.176844 -234.129601) (xy 356.177342 -234.15625) (xy 356.176844 -234.182899)
			(xy 356.405424 -234.182899) (xy 356.405424 -234.129601) (xy 356.413367 -234.076897) (xy 356.429077 -234.025967)
			(xy 356.452203 -233.977946) (xy 356.482227 -233.933909) (xy 356.518479 -233.894838) (xy 356.56015 -233.861607)
			(xy 356.606308 -233.834958) (xy 356.655922 -233.815486) (xy 356.707884 -233.803626) (xy 356.761034 -233.799643)
			(xy 356.814184 -233.803626) (xy 356.866146 -233.815486) (xy 356.91576 -233.834958) (xy 356.961918 -233.861607)
			(xy 357.003589 -233.894838) (xy 357.039841 -233.933909) (xy 357.069865 -233.977946) (xy 357.092991 -234.025967)
			(xy 357.108701 -234.076897) (xy 357.116644 -234.129601) (xy 357.117142 -234.15625) (xy 357.116644 -234.182899)
			(xy 357.345224 -234.182899) (xy 357.345224 -234.129601) (xy 357.353167 -234.076897) (xy 357.368877 -234.025967)
			(xy 357.392003 -233.977946) (xy 357.422027 -233.933909) (xy 357.458279 -233.894838) (xy 357.49995 -233.861607)
			(xy 357.546108 -233.834958) (xy 357.595722 -233.815486) (xy 357.647684 -233.803626) (xy 357.700834 -233.799643)
			(xy 357.753984 -233.803626) (xy 357.805946 -233.815486) (xy 357.85556 -233.834958) (xy 357.901718 -233.861607)
			(xy 357.943389 -233.894838) (xy 357.979641 -233.933909) (xy 358.009665 -233.977946) (xy 358.032791 -234.025967)
			(xy 358.048501 -234.076897) (xy 358.056444 -234.129601) (xy 358.056942 -234.15625) (xy 358.056444 -234.182899)
			(xy 358.285024 -234.182899) (xy 358.285024 -234.129601) (xy 358.292967 -234.076897) (xy 358.308677 -234.025967)
			(xy 358.331803 -233.977946) (xy 358.361827 -233.933909) (xy 358.398079 -233.894838) (xy 358.43975 -233.861607)
			(xy 358.485908 -233.834958) (xy 358.535522 -233.815486) (xy 358.587484 -233.803626) (xy 358.640634 -233.799643)
			(xy 358.693784 -233.803626) (xy 358.745746 -233.815486) (xy 358.79536 -233.834958) (xy 358.841518 -233.861607)
			(xy 358.883189 -233.894838) (xy 358.919441 -233.933909) (xy 358.949465 -233.977946) (xy 358.972591 -234.025967)
			(xy 358.988301 -234.076897) (xy 358.996244 -234.129601) (xy 358.996742 -234.15625) (xy 358.996244 -234.182899)
			(xy 359.224824 -234.182899) (xy 359.224824 -234.129601) (xy 359.232767 -234.076897) (xy 359.248477 -234.025967)
			(xy 359.271603 -233.977946) (xy 359.301627 -233.933909) (xy 359.337879 -233.894838) (xy 359.37955 -233.861607)
			(xy 359.425708 -233.834958) (xy 359.475322 -233.815486) (xy 359.527284 -233.803626) (xy 359.580434 -233.799643)
			(xy 359.633584 -233.803626) (xy 359.685546 -233.815486) (xy 359.73516 -233.834958) (xy 359.781318 -233.861607)
			(xy 359.822989 -233.894838) (xy 359.859241 -233.933909) (xy 359.889265 -233.977946) (xy 359.912391 -234.025967)
			(xy 359.928101 -234.076897) (xy 359.936044 -234.129601) (xy 359.936542 -234.15625) (xy 359.936044 -234.182899)
			(xy 360.164624 -234.182899) (xy 360.164624 -234.129601) (xy 360.172567 -234.076897) (xy 360.188277 -234.025967)
			(xy 360.211403 -233.977946) (xy 360.241427 -233.933909) (xy 360.277679 -233.894838) (xy 360.31935 -233.861607)
			(xy 360.365508 -233.834958) (xy 360.415122 -233.815486) (xy 360.467084 -233.803626) (xy 360.520234 -233.799643)
			(xy 360.573384 -233.803626) (xy 360.625346 -233.815486) (xy 360.67496 -233.834958) (xy 360.721118 -233.861607)
			(xy 360.762789 -233.894838) (xy 360.799041 -233.933909) (xy 360.829065 -233.977946) (xy 360.852191 -234.025967)
			(xy 360.867901 -234.076897) (xy 360.875844 -234.129601) (xy 360.876342 -234.15625) (xy 360.875844 -234.182899)
			(xy 361.104424 -234.182899) (xy 361.104424 -234.129601) (xy 361.112367 -234.076897) (xy 361.128077 -234.025967)
			(xy 361.151203 -233.977946) (xy 361.181227 -233.933909) (xy 361.217479 -233.894838) (xy 361.25915 -233.861607)
			(xy 361.305308 -233.834958) (xy 361.354922 -233.815486) (xy 361.406884 -233.803626) (xy 361.460034 -233.799643)
			(xy 361.513184 -233.803626) (xy 361.565146 -233.815486) (xy 361.61476 -233.834958) (xy 361.660918 -233.861607)
			(xy 361.702589 -233.894838) (xy 361.738841 -233.933909) (xy 361.768865 -233.977946) (xy 361.791991 -234.025967)
			(xy 361.807701 -234.076897) (xy 361.815644 -234.129601) (xy 361.816142 -234.15625) (xy 361.815644 -234.182899)
			(xy 362.044224 -234.182899) (xy 362.044224 -234.129601) (xy 362.052167 -234.076897) (xy 362.067877 -234.025967)
			(xy 362.091003 -233.977946) (xy 362.121027 -233.933909) (xy 362.157279 -233.894838) (xy 362.19895 -233.861607)
			(xy 362.245108 -233.834958) (xy 362.294722 -233.815486) (xy 362.346684 -233.803626) (xy 362.399834 -233.799643)
			(xy 362.452984 -233.803626) (xy 362.504946 -233.815486) (xy 362.55456 -233.834958) (xy 362.600718 -233.861607)
			(xy 362.642389 -233.894838) (xy 362.678641 -233.933909) (xy 362.708665 -233.977946) (xy 362.731791 -234.025967)
			(xy 362.747501 -234.076897) (xy 362.755444 -234.129601) (xy 362.755942 -234.15625) (xy 362.755444 -234.182899)
			(xy 362.984024 -234.182899) (xy 362.984024 -234.129601) (xy 362.991967 -234.076897) (xy 363.007677 -234.025967)
			(xy 363.030803 -233.977946) (xy 363.060827 -233.933909) (xy 363.097079 -233.894838) (xy 363.13875 -233.861607)
			(xy 363.184908 -233.834958) (xy 363.234522 -233.815486) (xy 363.286484 -233.803626) (xy 363.339634 -233.799643)
			(xy 363.392784 -233.803626) (xy 363.444746 -233.815486) (xy 363.49436 -233.834958) (xy 363.540518 -233.861607)
			(xy 363.582189 -233.894838) (xy 363.618441 -233.933909) (xy 363.648465 -233.977946) (xy 363.671591 -234.025967)
			(xy 363.687301 -234.076897) (xy 363.695244 -234.129601) (xy 363.695742 -234.15625) (xy 363.695244 -234.182899)
			(xy 363.923824 -234.182899) (xy 363.923824 -234.129601) (xy 363.931767 -234.076897) (xy 363.947477 -234.025967)
			(xy 363.970603 -233.977946) (xy 364.000627 -233.933909) (xy 364.036879 -233.894838) (xy 364.07855 -233.861607)
			(xy 364.124708 -233.834958) (xy 364.174322 -233.815486) (xy 364.226284 -233.803626) (xy 364.279434 -233.799643)
			(xy 364.332584 -233.803626) (xy 364.384546 -233.815486) (xy 364.43416 -233.834958) (xy 364.480318 -233.861607)
			(xy 364.521989 -233.894838) (xy 364.558241 -233.933909) (xy 364.588265 -233.977946) (xy 364.611391 -234.025967)
			(xy 364.627101 -234.076897) (xy 364.635044 -234.129601) (xy 364.635542 -234.15625) (xy 364.635044 -234.182899)
			(xy 364.863624 -234.182899) (xy 364.863624 -234.129601) (xy 364.871567 -234.076897) (xy 364.887277 -234.025967)
			(xy 364.910403 -233.977946) (xy 364.940427 -233.933909) (xy 364.976679 -233.894838) (xy 365.01835 -233.861607)
			(xy 365.064508 -233.834958) (xy 365.114122 -233.815486) (xy 365.166084 -233.803626) (xy 365.219234 -233.799643)
			(xy 365.272384 -233.803626) (xy 365.324346 -233.815486) (xy 365.37396 -233.834958) (xy 365.420118 -233.861607)
			(xy 365.461789 -233.894838) (xy 365.498041 -233.933909) (xy 365.528065 -233.977946) (xy 365.551191 -234.025967)
			(xy 365.566901 -234.076897) (xy 365.574844 -234.129601) (xy 365.575342 -234.15625) (xy 365.574844 -234.182899)
			(xy 365.803424 -234.182899) (xy 365.803424 -234.129601) (xy 365.811367 -234.076897) (xy 365.827077 -234.025967)
			(xy 365.850203 -233.977946) (xy 365.880227 -233.933909) (xy 365.916479 -233.894838) (xy 365.95815 -233.861607)
			(xy 366.004308 -233.834958) (xy 366.053922 -233.815486) (xy 366.105884 -233.803626) (xy 366.159034 -233.799643)
			(xy 366.212184 -233.803626) (xy 366.264146 -233.815486) (xy 366.31376 -233.834958) (xy 366.359918 -233.861607)
			(xy 366.401589 -233.894838) (xy 366.437841 -233.933909) (xy 366.467865 -233.977946) (xy 366.490991 -234.025967)
			(xy 366.506701 -234.076897) (xy 366.514644 -234.129601) (xy 366.515142 -234.15625) (xy 366.514644 -234.182899)
			(xy 366.743224 -234.182899) (xy 366.743224 -234.129601) (xy 366.751167 -234.076897) (xy 366.766877 -234.025967)
			(xy 366.790003 -233.977946) (xy 366.820027 -233.933909) (xy 366.856279 -233.894838) (xy 366.89795 -233.861607)
			(xy 366.944108 -233.834958) (xy 366.993722 -233.815486) (xy 367.045684 -233.803626) (xy 367.098834 -233.799643)
			(xy 367.151984 -233.803626) (xy 367.203946 -233.815486) (xy 367.25356 -233.834958) (xy 367.299718 -233.861607)
			(xy 367.341389 -233.894838) (xy 367.377641 -233.933909) (xy 367.407665 -233.977946) (xy 367.430791 -234.025967)
			(xy 367.446501 -234.076897) (xy 367.454444 -234.129601) (xy 367.454942 -234.15625) (xy 367.454444 -234.182899)
			(xy 367.683024 -234.182899) (xy 367.683024 -234.129601) (xy 367.690967 -234.076897) (xy 367.706677 -234.025967)
			(xy 367.729803 -233.977946) (xy 367.759827 -233.933909) (xy 367.796079 -233.894838) (xy 367.83775 -233.861607)
			(xy 367.883908 -233.834958) (xy 367.933522 -233.815486) (xy 367.985484 -233.803626) (xy 368.038634 -233.799643)
			(xy 368.091784 -233.803626) (xy 368.143746 -233.815486) (xy 368.19336 -233.834958) (xy 368.239518 -233.861607)
			(xy 368.281189 -233.894838) (xy 368.317441 -233.933909) (xy 368.347465 -233.977946) (xy 368.370591 -234.025967)
			(xy 368.386301 -234.076897) (xy 368.394244 -234.129601) (xy 368.394742 -234.15625) (xy 368.394244 -234.182899)
			(xy 368.62257 -234.182899) (xy 368.62257 -234.129601) (xy 368.630513 -234.076897) (xy 368.646223 -234.025967)
			(xy 368.669349 -233.977946) (xy 368.699373 -233.933909) (xy 368.735625 -233.894838) (xy 368.777296 -233.861607)
			(xy 368.823454 -233.834958) (xy 368.873068 -233.815486) (xy 368.92503 -233.803626) (xy 368.97818 -233.799643)
			(xy 369.03133 -233.803626) (xy 369.083292 -233.815486) (xy 369.132906 -233.834958) (xy 369.179064 -233.861607)
			(xy 369.220735 -233.894838) (xy 369.256987 -233.933909) (xy 369.287011 -233.977946) (xy 369.310137 -234.025967)
			(xy 369.325847 -234.076897) (xy 369.33379 -234.129601) (xy 369.334288 -234.15625) (xy 369.33379 -234.182899)
			(xy 369.562624 -234.182899) (xy 369.562624 -234.129601) (xy 369.570567 -234.076897) (xy 369.586277 -234.025967)
			(xy 369.609403 -233.977946) (xy 369.639427 -233.933909) (xy 369.675679 -233.894838) (xy 369.71735 -233.861607)
			(xy 369.763508 -233.834958) (xy 369.813122 -233.815486) (xy 369.865084 -233.803626) (xy 369.918234 -233.799643)
			(xy 369.971384 -233.803626) (xy 370.023346 -233.815486) (xy 370.07296 -233.834958) (xy 370.119118 -233.861607)
			(xy 370.160789 -233.894838) (xy 370.197041 -233.933909) (xy 370.227065 -233.977946) (xy 370.250191 -234.025967)
			(xy 370.265901 -234.076897) (xy 370.273844 -234.129601) (xy 370.274342 -234.15625) (xy 370.273844 -234.182899)
			(xy 370.50217 -234.182899) (xy 370.50217 -234.129601) (xy 370.510113 -234.076897) (xy 370.525823 -234.025967)
			(xy 370.548949 -233.977946) (xy 370.578973 -233.933909) (xy 370.615225 -233.894838) (xy 370.656896 -233.861607)
			(xy 370.703054 -233.834958) (xy 370.752668 -233.815486) (xy 370.80463 -233.803626) (xy 370.85778 -233.799643)
			(xy 370.91093 -233.803626) (xy 370.962892 -233.815486) (xy 371.012506 -233.834958) (xy 371.058664 -233.861607)
			(xy 371.100335 -233.894838) (xy 371.136587 -233.933909) (xy 371.166611 -233.977946) (xy 371.189737 -234.025967)
			(xy 371.205447 -234.076897) (xy 371.21339 -234.129601) (xy 371.213888 -234.15625) (xy 371.21339 -234.182899)
			(xy 371.442224 -234.182899) (xy 371.442224 -234.129601) (xy 371.450167 -234.076897) (xy 371.465877 -234.025967)
			(xy 371.489003 -233.977946) (xy 371.519027 -233.933909) (xy 371.555279 -233.894838) (xy 371.59695 -233.861607)
			(xy 371.643108 -233.834958) (xy 371.692722 -233.815486) (xy 371.744684 -233.803626) (xy 371.797834 -233.799643)
			(xy 371.850984 -233.803626) (xy 371.902946 -233.815486) (xy 371.95256 -233.834958) (xy 371.998718 -233.861607)
			(xy 372.040389 -233.894838) (xy 372.076641 -233.933909) (xy 372.106665 -233.977946) (xy 372.129791 -234.025967)
			(xy 372.145501 -234.076897) (xy 372.153444 -234.129601) (xy 372.153942 -234.15625) (xy 372.153444 -234.182899)
			(xy 372.382024 -234.182899) (xy 372.382024 -234.129601) (xy 372.389967 -234.076897) (xy 372.405677 -234.025967)
			(xy 372.428803 -233.977946) (xy 372.458827 -233.933909) (xy 372.495079 -233.894838) (xy 372.53675 -233.861607)
			(xy 372.582908 -233.834958) (xy 372.632522 -233.815486) (xy 372.684484 -233.803626) (xy 372.737634 -233.799643)
			(xy 372.790784 -233.803626) (xy 372.842746 -233.815486) (xy 372.89236 -233.834958) (xy 372.938518 -233.861607)
			(xy 372.980189 -233.894838) (xy 373.016441 -233.933909) (xy 373.046465 -233.977946) (xy 373.069591 -234.025967)
			(xy 373.085301 -234.076897) (xy 373.093244 -234.129601) (xy 373.093742 -234.15625) (xy 373.093244 -234.182899)
			(xy 373.321824 -234.182899) (xy 373.321824 -234.129601) (xy 373.329767 -234.076897) (xy 373.345477 -234.025967)
			(xy 373.368603 -233.977946) (xy 373.398627 -233.933909) (xy 373.434879 -233.894838) (xy 373.47655 -233.861607)
			(xy 373.522708 -233.834958) (xy 373.572322 -233.815486) (xy 373.624284 -233.803626) (xy 373.677434 -233.799643)
			(xy 373.730584 -233.803626) (xy 373.782546 -233.815486) (xy 373.83216 -233.834958) (xy 373.878318 -233.861607)
			(xy 373.919989 -233.894838) (xy 373.956241 -233.933909) (xy 373.986265 -233.977946) (xy 374.009391 -234.025967)
			(xy 374.025101 -234.076897) (xy 374.033044 -234.129601) (xy 374.033542 -234.15625) (xy 374.033044 -234.182899)
			(xy 374.261624 -234.182899) (xy 374.261624 -234.129601) (xy 374.269567 -234.076897) (xy 374.285277 -234.025967)
			(xy 374.308403 -233.977946) (xy 374.338427 -233.933909) (xy 374.374679 -233.894838) (xy 374.41635 -233.861607)
			(xy 374.462508 -233.834958) (xy 374.512122 -233.815486) (xy 374.564084 -233.803626) (xy 374.617234 -233.799643)
			(xy 374.670384 -233.803626) (xy 374.722346 -233.815486) (xy 374.77196 -233.834958) (xy 374.818118 -233.861607)
			(xy 374.859789 -233.894838) (xy 374.896041 -233.933909) (xy 374.926065 -233.977946) (xy 374.949191 -234.025967)
			(xy 374.964901 -234.076897) (xy 374.972844 -234.129601) (xy 374.973342 -234.15625) (xy 374.972844 -234.182899)
			(xy 375.201424 -234.182899) (xy 375.201424 -234.129601) (xy 375.209367 -234.076897) (xy 375.225077 -234.025967)
			(xy 375.248203 -233.977946) (xy 375.278227 -233.933909) (xy 375.314479 -233.894838) (xy 375.35615 -233.861607)
			(xy 375.402308 -233.834958) (xy 375.451922 -233.815486) (xy 375.503884 -233.803626) (xy 375.557034 -233.799643)
			(xy 375.610184 -233.803626) (xy 375.662146 -233.815486) (xy 375.71176 -233.834958) (xy 375.757918 -233.861607)
			(xy 375.799589 -233.894838) (xy 375.835841 -233.933909) (xy 375.865865 -233.977946) (xy 375.888991 -234.025967)
			(xy 375.904701 -234.076897) (xy 375.912644 -234.129601) (xy 375.913142 -234.15625) (xy 375.912644 -234.182899)
			(xy 376.141224 -234.182899) (xy 376.141224 -234.129601) (xy 376.149167 -234.076897) (xy 376.164877 -234.025967)
			(xy 376.188003 -233.977946) (xy 376.218027 -233.933909) (xy 376.254279 -233.894838) (xy 376.29595 -233.861607)
			(xy 376.342108 -233.834958) (xy 376.391722 -233.815486) (xy 376.443684 -233.803626) (xy 376.496834 -233.799643)
			(xy 376.549984 -233.803626) (xy 376.601946 -233.815486) (xy 376.65156 -233.834958) (xy 376.697718 -233.861607)
			(xy 376.739389 -233.894838) (xy 376.775641 -233.933909) (xy 376.805665 -233.977946) (xy 376.828791 -234.025967)
			(xy 376.844501 -234.076897) (xy 376.852444 -234.129601) (xy 376.852942 -234.15625) (xy 376.852444 -234.182899)
			(xy 377.08077 -234.182899) (xy 377.08077 -234.129601) (xy 377.088713 -234.076897) (xy 377.104423 -234.025967)
			(xy 377.127549 -233.977946) (xy 377.157573 -233.933909) (xy 377.193825 -233.894838) (xy 377.235496 -233.861607)
			(xy 377.281654 -233.834958) (xy 377.331268 -233.815486) (xy 377.38323 -233.803626) (xy 377.43638 -233.799643)
			(xy 377.48953 -233.803626) (xy 377.541492 -233.815486) (xy 377.591106 -233.834958) (xy 377.637264 -233.861607)
			(xy 377.678935 -233.894838) (xy 377.715187 -233.933909) (xy 377.745211 -233.977946) (xy 377.768337 -234.025967)
			(xy 377.784047 -234.076897) (xy 377.79199 -234.129601) (xy 377.792488 -234.15625) (xy 377.79199 -234.182899)
			(xy 378.020824 -234.182899) (xy 378.020824 -234.129601) (xy 378.028767 -234.076897) (xy 378.044477 -234.025967)
			(xy 378.067603 -233.977946) (xy 378.097627 -233.933909) (xy 378.133879 -233.894838) (xy 378.17555 -233.861607)
			(xy 378.221708 -233.834958) (xy 378.271322 -233.815486) (xy 378.323284 -233.803626) (xy 378.376434 -233.799643)
			(xy 378.429584 -233.803626) (xy 378.481546 -233.815486) (xy 378.53116 -233.834958) (xy 378.577318 -233.861607)
			(xy 378.618989 -233.894838) (xy 378.655241 -233.933909) (xy 378.685265 -233.977946) (xy 378.708391 -234.025967)
			(xy 378.724101 -234.076897) (xy 378.732044 -234.129601) (xy 378.732542 -234.15625) (xy 378.732044 -234.182899)
			(xy 378.960624 -234.182899) (xy 378.960624 -234.129601) (xy 378.968567 -234.076897) (xy 378.984277 -234.025967)
			(xy 379.007403 -233.977946) (xy 379.037427 -233.933909) (xy 379.073679 -233.894838) (xy 379.11535 -233.861607)
			(xy 379.161508 -233.834958) (xy 379.211122 -233.815486) (xy 379.263084 -233.803626) (xy 379.316234 -233.799643)
			(xy 379.369384 -233.803626) (xy 379.421346 -233.815486) (xy 379.47096 -233.834958) (xy 379.517118 -233.861607)
			(xy 379.558789 -233.894838) (xy 379.595041 -233.933909) (xy 379.625065 -233.977946) (xy 379.648191 -234.025967)
			(xy 379.663901 -234.076897) (xy 379.671844 -234.129601) (xy 379.672342 -234.15625) (xy 379.671844 -234.182899)
			(xy 379.900424 -234.182899) (xy 379.900424 -234.129601) (xy 379.908367 -234.076897) (xy 379.924077 -234.025967)
			(xy 379.947203 -233.977946) (xy 379.977227 -233.933909) (xy 380.013479 -233.894838) (xy 380.05515 -233.861607)
			(xy 380.101308 -233.834958) (xy 380.150922 -233.815486) (xy 380.202884 -233.803626) (xy 380.256034 -233.799643)
			(xy 380.309184 -233.803626) (xy 380.361146 -233.815486) (xy 380.41076 -233.834958) (xy 380.456918 -233.861607)
			(xy 380.498589 -233.894838) (xy 380.534841 -233.933909) (xy 380.564865 -233.977946) (xy 380.587991 -234.025967)
			(xy 380.603701 -234.076897) (xy 380.611644 -234.129601) (xy 380.612142 -234.15625) (xy 380.611644 -234.182899)
			(xy 380.840224 -234.182899) (xy 380.840224 -234.129601) (xy 380.848167 -234.076897) (xy 380.863877 -234.025967)
			(xy 380.887003 -233.977946) (xy 380.917027 -233.933909) (xy 380.953279 -233.894838) (xy 380.99495 -233.861607)
			(xy 381.041108 -233.834958) (xy 381.090722 -233.815486) (xy 381.142684 -233.803626) (xy 381.195834 -233.799643)
			(xy 381.248984 -233.803626) (xy 381.300946 -233.815486) (xy 381.35056 -233.834958) (xy 381.396718 -233.861607)
			(xy 381.438389 -233.894838) (xy 381.474641 -233.933909) (xy 381.504665 -233.977946) (xy 381.527791 -234.025967)
			(xy 381.543501 -234.076897) (xy 381.551444 -234.129601) (xy 381.551942 -234.15625) (xy 381.551444 -234.182899)
			(xy 381.543501 -234.235603) (xy 381.527791 -234.286533) (xy 381.504665 -234.334554) (xy 381.474641 -234.378591)
			(xy 381.438389 -234.417662) (xy 381.396718 -234.450893) (xy 381.35056 -234.477542) (xy 381.300946 -234.497014)
			(xy 381.248984 -234.508874) (xy 381.195834 -234.512858) (xy 381.142684 -234.508874) (xy 381.090722 -234.497014)
			(xy 381.041108 -234.477542) (xy 380.99495 -234.450893) (xy 380.953279 -234.417662) (xy 380.917027 -234.378591)
			(xy 380.887003 -234.334554) (xy 380.863877 -234.286533) (xy 380.848167 -234.235603) (xy 380.840224 -234.182899)
			(xy 380.611644 -234.182899) (xy 380.603701 -234.235603) (xy 380.587991 -234.286533) (xy 380.564865 -234.334554)
			(xy 380.534841 -234.378591) (xy 380.498589 -234.417662) (xy 380.456918 -234.450893) (xy 380.41076 -234.477542)
			(xy 380.361146 -234.497014) (xy 380.309184 -234.508874) (xy 380.256034 -234.512858) (xy 380.202884 -234.508874)
			(xy 380.150922 -234.497014) (xy 380.101308 -234.477542) (xy 380.05515 -234.450893) (xy 380.013479 -234.417662)
			(xy 379.977227 -234.378591) (xy 379.947203 -234.334554) (xy 379.924077 -234.286533) (xy 379.908367 -234.235603)
			(xy 379.900424 -234.182899) (xy 379.671844 -234.182899) (xy 379.663901 -234.235603) (xy 379.648191 -234.286533)
			(xy 379.625065 -234.334554) (xy 379.595041 -234.378591) (xy 379.558789 -234.417662) (xy 379.517118 -234.450893)
			(xy 379.47096 -234.477542) (xy 379.421346 -234.497014) (xy 379.369384 -234.508874) (xy 379.316234 -234.512858)
			(xy 379.263084 -234.508874) (xy 379.211122 -234.497014) (xy 379.161508 -234.477542) (xy 379.11535 -234.450893)
			(xy 379.073679 -234.417662) (xy 379.037427 -234.378591) (xy 379.007403 -234.334554) (xy 378.984277 -234.286533)
			(xy 378.968567 -234.235603) (xy 378.960624 -234.182899) (xy 378.732044 -234.182899) (xy 378.724101 -234.235603)
			(xy 378.708391 -234.286533) (xy 378.685265 -234.334554) (xy 378.655241 -234.378591) (xy 378.618989 -234.417662)
			(xy 378.577318 -234.450893) (xy 378.53116 -234.477542) (xy 378.481546 -234.497014) (xy 378.429584 -234.508874)
			(xy 378.376434 -234.512858) (xy 378.323284 -234.508874) (xy 378.271322 -234.497014) (xy 378.221708 -234.477542)
			(xy 378.17555 -234.450893) (xy 378.133879 -234.417662) (xy 378.097627 -234.378591) (xy 378.067603 -234.334554)
			(xy 378.044477 -234.286533) (xy 378.028767 -234.235603) (xy 378.020824 -234.182899) (xy 377.79199 -234.182899)
			(xy 377.784047 -234.235603) (xy 377.768337 -234.286533) (xy 377.745211 -234.334554) (xy 377.715187 -234.378591)
			(xy 377.678935 -234.417662) (xy 377.637264 -234.450893) (xy 377.591106 -234.477542) (xy 377.541492 -234.497014)
			(xy 377.48953 -234.508874) (xy 377.43638 -234.512858) (xy 377.38323 -234.508874) (xy 377.331268 -234.497014)
			(xy 377.281654 -234.477542) (xy 377.235496 -234.450893) (xy 377.193825 -234.417662) (xy 377.157573 -234.378591)
			(xy 377.127549 -234.334554) (xy 377.104423 -234.286533) (xy 377.088713 -234.235603) (xy 377.08077 -234.182899)
			(xy 376.852444 -234.182899) (xy 376.844501 -234.235603) (xy 376.828791 -234.286533) (xy 376.805665 -234.334554)
			(xy 376.775641 -234.378591) (xy 376.739389 -234.417662) (xy 376.697718 -234.450893) (xy 376.65156 -234.477542)
			(xy 376.601946 -234.497014) (xy 376.549984 -234.508874) (xy 376.496834 -234.512858) (xy 376.443684 -234.508874)
			(xy 376.391722 -234.497014) (xy 376.342108 -234.477542) (xy 376.29595 -234.450893) (xy 376.254279 -234.417662)
			(xy 376.218027 -234.378591) (xy 376.188003 -234.334554) (xy 376.164877 -234.286533) (xy 376.149167 -234.235603)
			(xy 376.141224 -234.182899) (xy 375.912644 -234.182899) (xy 375.904701 -234.235603) (xy 375.888991 -234.286533)
			(xy 375.865865 -234.334554) (xy 375.835841 -234.378591) (xy 375.799589 -234.417662) (xy 375.757918 -234.450893)
			(xy 375.71176 -234.477542) (xy 375.662146 -234.497014) (xy 375.610184 -234.508874) (xy 375.557034 -234.512858)
			(xy 375.503884 -234.508874) (xy 375.451922 -234.497014) (xy 375.402308 -234.477542) (xy 375.35615 -234.450893)
			(xy 375.314479 -234.417662) (xy 375.278227 -234.378591) (xy 375.248203 -234.334554) (xy 375.225077 -234.286533)
			(xy 375.209367 -234.235603) (xy 375.201424 -234.182899) (xy 374.972844 -234.182899) (xy 374.964901 -234.235603)
			(xy 374.949191 -234.286533) (xy 374.926065 -234.334554) (xy 374.896041 -234.378591) (xy 374.859789 -234.417662)
			(xy 374.818118 -234.450893) (xy 374.77196 -234.477542) (xy 374.722346 -234.497014) (xy 374.670384 -234.508874)
			(xy 374.617234 -234.512858) (xy 374.564084 -234.508874) (xy 374.512122 -234.497014) (xy 374.462508 -234.477542)
			(xy 374.41635 -234.450893) (xy 374.374679 -234.417662) (xy 374.338427 -234.378591) (xy 374.308403 -234.334554)
			(xy 374.285277 -234.286533) (xy 374.269567 -234.235603) (xy 374.261624 -234.182899) (xy 374.033044 -234.182899)
			(xy 374.025101 -234.235603) (xy 374.009391 -234.286533) (xy 373.986265 -234.334554) (xy 373.956241 -234.378591)
			(xy 373.919989 -234.417662) (xy 373.878318 -234.450893) (xy 373.83216 -234.477542) (xy 373.782546 -234.497014)
			(xy 373.730584 -234.508874) (xy 373.677434 -234.512858) (xy 373.624284 -234.508874) (xy 373.572322 -234.497014)
			(xy 373.522708 -234.477542) (xy 373.47655 -234.450893) (xy 373.434879 -234.417662) (xy 373.398627 -234.378591)
			(xy 373.368603 -234.334554) (xy 373.345477 -234.286533) (xy 373.329767 -234.235603) (xy 373.321824 -234.182899)
			(xy 373.093244 -234.182899) (xy 373.085301 -234.235603) (xy 373.069591 -234.286533) (xy 373.046465 -234.334554)
			(xy 373.016441 -234.378591) (xy 372.980189 -234.417662) (xy 372.938518 -234.450893) (xy 372.89236 -234.477542)
			(xy 372.842746 -234.497014) (xy 372.790784 -234.508874) (xy 372.737634 -234.512858) (xy 372.684484 -234.508874)
			(xy 372.632522 -234.497014) (xy 372.582908 -234.477542) (xy 372.53675 -234.450893) (xy 372.495079 -234.417662)
			(xy 372.458827 -234.378591) (xy 372.428803 -234.334554) (xy 372.405677 -234.286533) (xy 372.389967 -234.235603)
			(xy 372.382024 -234.182899) (xy 372.153444 -234.182899) (xy 372.145501 -234.235603) (xy 372.129791 -234.286533)
			(xy 372.106665 -234.334554) (xy 372.076641 -234.378591) (xy 372.040389 -234.417662) (xy 371.998718 -234.450893)
			(xy 371.95256 -234.477542) (xy 371.902946 -234.497014) (xy 371.850984 -234.508874) (xy 371.797834 -234.512858)
			(xy 371.744684 -234.508874) (xy 371.692722 -234.497014) (xy 371.643108 -234.477542) (xy 371.59695 -234.450893)
			(xy 371.555279 -234.417662) (xy 371.519027 -234.378591) (xy 371.489003 -234.334554) (xy 371.465877 -234.286533)
			(xy 371.450167 -234.235603) (xy 371.442224 -234.182899) (xy 371.21339 -234.182899) (xy 371.205447 -234.235603)
			(xy 371.189737 -234.286533) (xy 371.166611 -234.334554) (xy 371.136587 -234.378591) (xy 371.100335 -234.417662)
			(xy 371.058664 -234.450893) (xy 371.012506 -234.477542) (xy 370.962892 -234.497014) (xy 370.91093 -234.508874)
			(xy 370.85778 -234.512858) (xy 370.80463 -234.508874) (xy 370.752668 -234.497014) (xy 370.703054 -234.477542)
			(xy 370.656896 -234.450893) (xy 370.615225 -234.417662) (xy 370.578973 -234.378591) (xy 370.548949 -234.334554)
			(xy 370.525823 -234.286533) (xy 370.510113 -234.235603) (xy 370.50217 -234.182899) (xy 370.273844 -234.182899)
			(xy 370.265901 -234.235603) (xy 370.250191 -234.286533) (xy 370.227065 -234.334554) (xy 370.197041 -234.378591)
			(xy 370.160789 -234.417662) (xy 370.119118 -234.450893) (xy 370.07296 -234.477542) (xy 370.023346 -234.497014)
			(xy 369.971384 -234.508874) (xy 369.918234 -234.512858) (xy 369.865084 -234.508874) (xy 369.813122 -234.497014)
			(xy 369.763508 -234.477542) (xy 369.71735 -234.450893) (xy 369.675679 -234.417662) (xy 369.639427 -234.378591)
			(xy 369.609403 -234.334554) (xy 369.586277 -234.286533) (xy 369.570567 -234.235603) (xy 369.562624 -234.182899)
			(xy 369.33379 -234.182899) (xy 369.325847 -234.235603) (xy 369.310137 -234.286533) (xy 369.287011 -234.334554)
			(xy 369.256987 -234.378591) (xy 369.220735 -234.417662) (xy 369.179064 -234.450893) (xy 369.132906 -234.477542)
			(xy 369.083292 -234.497014) (xy 369.03133 -234.508874) (xy 368.97818 -234.512858) (xy 368.92503 -234.508874)
			(xy 368.873068 -234.497014) (xy 368.823454 -234.477542) (xy 368.777296 -234.450893) (xy 368.735625 -234.417662)
			(xy 368.699373 -234.378591) (xy 368.669349 -234.334554) (xy 368.646223 -234.286533) (xy 368.630513 -234.235603)
			(xy 368.62257 -234.182899) (xy 368.394244 -234.182899) (xy 368.386301 -234.235603) (xy 368.370591 -234.286533)
			(xy 368.347465 -234.334554) (xy 368.317441 -234.378591) (xy 368.281189 -234.417662) (xy 368.239518 -234.450893)
			(xy 368.19336 -234.477542) (xy 368.143746 -234.497014) (xy 368.091784 -234.508874) (xy 368.038634 -234.512858)
			(xy 367.985484 -234.508874) (xy 367.933522 -234.497014) (xy 367.883908 -234.477542) (xy 367.83775 -234.450893)
			(xy 367.796079 -234.417662) (xy 367.759827 -234.378591) (xy 367.729803 -234.334554) (xy 367.706677 -234.286533)
			(xy 367.690967 -234.235603) (xy 367.683024 -234.182899) (xy 367.454444 -234.182899) (xy 367.446501 -234.235603)
			(xy 367.430791 -234.286533) (xy 367.407665 -234.334554) (xy 367.377641 -234.378591) (xy 367.341389 -234.417662)
			(xy 367.299718 -234.450893) (xy 367.25356 -234.477542) (xy 367.203946 -234.497014) (xy 367.151984 -234.508874)
			(xy 367.098834 -234.512858) (xy 367.045684 -234.508874) (xy 366.993722 -234.497014) (xy 366.944108 -234.477542)
			(xy 366.89795 -234.450893) (xy 366.856279 -234.417662) (xy 366.820027 -234.378591) (xy 366.790003 -234.334554)
			(xy 366.766877 -234.286533) (xy 366.751167 -234.235603) (xy 366.743224 -234.182899) (xy 366.514644 -234.182899)
			(xy 366.506701 -234.235603) (xy 366.490991 -234.286533) (xy 366.467865 -234.334554) (xy 366.437841 -234.378591)
			(xy 366.401589 -234.417662) (xy 366.359918 -234.450893) (xy 366.31376 -234.477542) (xy 366.264146 -234.497014)
			(xy 366.212184 -234.508874) (xy 366.159034 -234.512858) (xy 366.105884 -234.508874) (xy 366.053922 -234.497014)
			(xy 366.004308 -234.477542) (xy 365.95815 -234.450893) (xy 365.916479 -234.417662) (xy 365.880227 -234.378591)
			(xy 365.850203 -234.334554) (xy 365.827077 -234.286533) (xy 365.811367 -234.235603) (xy 365.803424 -234.182899)
			(xy 365.574844 -234.182899) (xy 365.566901 -234.235603) (xy 365.551191 -234.286533) (xy 365.528065 -234.334554)
			(xy 365.498041 -234.378591) (xy 365.461789 -234.417662) (xy 365.420118 -234.450893) (xy 365.37396 -234.477542)
			(xy 365.324346 -234.497014) (xy 365.272384 -234.508874) (xy 365.219234 -234.512858) (xy 365.166084 -234.508874)
			(xy 365.114122 -234.497014) (xy 365.064508 -234.477542) (xy 365.01835 -234.450893) (xy 364.976679 -234.417662)
			(xy 364.940427 -234.378591) (xy 364.910403 -234.334554) (xy 364.887277 -234.286533) (xy 364.871567 -234.235603)
			(xy 364.863624 -234.182899) (xy 364.635044 -234.182899) (xy 364.627101 -234.235603) (xy 364.611391 -234.286533)
			(xy 364.588265 -234.334554) (xy 364.558241 -234.378591) (xy 364.521989 -234.417662) (xy 364.480318 -234.450893)
			(xy 364.43416 -234.477542) (xy 364.384546 -234.497014) (xy 364.332584 -234.508874) (xy 364.279434 -234.512858)
			(xy 364.226284 -234.508874) (xy 364.174322 -234.497014) (xy 364.124708 -234.477542) (xy 364.07855 -234.450893)
			(xy 364.036879 -234.417662) (xy 364.000627 -234.378591) (xy 363.970603 -234.334554) (xy 363.947477 -234.286533)
			(xy 363.931767 -234.235603) (xy 363.923824 -234.182899) (xy 363.695244 -234.182899) (xy 363.687301 -234.235603)
			(xy 363.671591 -234.286533) (xy 363.648465 -234.334554) (xy 363.618441 -234.378591) (xy 363.582189 -234.417662)
			(xy 363.540518 -234.450893) (xy 363.49436 -234.477542) (xy 363.444746 -234.497014) (xy 363.392784 -234.508874)
			(xy 363.339634 -234.512858) (xy 363.286484 -234.508874) (xy 363.234522 -234.497014) (xy 363.184908 -234.477542)
			(xy 363.13875 -234.450893) (xy 363.097079 -234.417662) (xy 363.060827 -234.378591) (xy 363.030803 -234.334554)
			(xy 363.007677 -234.286533) (xy 362.991967 -234.235603) (xy 362.984024 -234.182899) (xy 362.755444 -234.182899)
			(xy 362.747501 -234.235603) (xy 362.731791 -234.286533) (xy 362.708665 -234.334554) (xy 362.678641 -234.378591)
			(xy 362.642389 -234.417662) (xy 362.600718 -234.450893) (xy 362.55456 -234.477542) (xy 362.504946 -234.497014)
			(xy 362.452984 -234.508874) (xy 362.399834 -234.512858) (xy 362.346684 -234.508874) (xy 362.294722 -234.497014)
			(xy 362.245108 -234.477542) (xy 362.19895 -234.450893) (xy 362.157279 -234.417662) (xy 362.121027 -234.378591)
			(xy 362.091003 -234.334554) (xy 362.067877 -234.286533) (xy 362.052167 -234.235603) (xy 362.044224 -234.182899)
			(xy 361.815644 -234.182899) (xy 361.807701 -234.235603) (xy 361.791991 -234.286533) (xy 361.768865 -234.334554)
			(xy 361.738841 -234.378591) (xy 361.702589 -234.417662) (xy 361.660918 -234.450893) (xy 361.61476 -234.477542)
			(xy 361.565146 -234.497014) (xy 361.513184 -234.508874) (xy 361.460034 -234.512858) (xy 361.406884 -234.508874)
			(xy 361.354922 -234.497014) (xy 361.305308 -234.477542) (xy 361.25915 -234.450893) (xy 361.217479 -234.417662)
			(xy 361.181227 -234.378591) (xy 361.151203 -234.334554) (xy 361.128077 -234.286533) (xy 361.112367 -234.235603)
			(xy 361.104424 -234.182899) (xy 360.875844 -234.182899) (xy 360.867901 -234.235603) (xy 360.852191 -234.286533)
			(xy 360.829065 -234.334554) (xy 360.799041 -234.378591) (xy 360.762789 -234.417662) (xy 360.721118 -234.450893)
			(xy 360.67496 -234.477542) (xy 360.625346 -234.497014) (xy 360.573384 -234.508874) (xy 360.520234 -234.512858)
			(xy 360.467084 -234.508874) (xy 360.415122 -234.497014) (xy 360.365508 -234.477542) (xy 360.31935 -234.450893)
			(xy 360.277679 -234.417662) (xy 360.241427 -234.378591) (xy 360.211403 -234.334554) (xy 360.188277 -234.286533)
			(xy 360.172567 -234.235603) (xy 360.164624 -234.182899) (xy 359.936044 -234.182899) (xy 359.928101 -234.235603)
			(xy 359.912391 -234.286533) (xy 359.889265 -234.334554) (xy 359.859241 -234.378591) (xy 359.822989 -234.417662)
			(xy 359.781318 -234.450893) (xy 359.73516 -234.477542) (xy 359.685546 -234.497014) (xy 359.633584 -234.508874)
			(xy 359.580434 -234.512858) (xy 359.527284 -234.508874) (xy 359.475322 -234.497014) (xy 359.425708 -234.477542)
			(xy 359.37955 -234.450893) (xy 359.337879 -234.417662) (xy 359.301627 -234.378591) (xy 359.271603 -234.334554)
			(xy 359.248477 -234.286533) (xy 359.232767 -234.235603) (xy 359.224824 -234.182899) (xy 358.996244 -234.182899)
			(xy 358.988301 -234.235603) (xy 358.972591 -234.286533) (xy 358.949465 -234.334554) (xy 358.919441 -234.378591)
			(xy 358.883189 -234.417662) (xy 358.841518 -234.450893) (xy 358.79536 -234.477542) (xy 358.745746 -234.497014)
			(xy 358.693784 -234.508874) (xy 358.640634 -234.512858) (xy 358.587484 -234.508874) (xy 358.535522 -234.497014)
			(xy 358.485908 -234.477542) (xy 358.43975 -234.450893) (xy 358.398079 -234.417662) (xy 358.361827 -234.378591)
			(xy 358.331803 -234.334554) (xy 358.308677 -234.286533) (xy 358.292967 -234.235603) (xy 358.285024 -234.182899)
			(xy 358.056444 -234.182899) (xy 358.048501 -234.235603) (xy 358.032791 -234.286533) (xy 358.009665 -234.334554)
			(xy 357.979641 -234.378591) (xy 357.943389 -234.417662) (xy 357.901718 -234.450893) (xy 357.85556 -234.477542)
			(xy 357.805946 -234.497014) (xy 357.753984 -234.508874) (xy 357.700834 -234.512858) (xy 357.647684 -234.508874)
			(xy 357.595722 -234.497014) (xy 357.546108 -234.477542) (xy 357.49995 -234.450893) (xy 357.458279 -234.417662)
			(xy 357.422027 -234.378591) (xy 357.392003 -234.334554) (xy 357.368877 -234.286533) (xy 357.353167 -234.235603)
			(xy 357.345224 -234.182899) (xy 357.116644 -234.182899) (xy 357.108701 -234.235603) (xy 357.092991 -234.286533)
			(xy 357.069865 -234.334554) (xy 357.039841 -234.378591) (xy 357.003589 -234.417662) (xy 356.961918 -234.450893)
			(xy 356.91576 -234.477542) (xy 356.866146 -234.497014) (xy 356.814184 -234.508874) (xy 356.761034 -234.512858)
			(xy 356.707884 -234.508874) (xy 356.655922 -234.497014) (xy 356.606308 -234.477542) (xy 356.56015 -234.450893)
			(xy 356.518479 -234.417662) (xy 356.482227 -234.378591) (xy 356.452203 -234.334554) (xy 356.429077 -234.286533)
			(xy 356.413367 -234.235603) (xy 356.405424 -234.182899) (xy 356.176844 -234.182899) (xy 356.168901 -234.235603)
			(xy 356.153191 -234.286533) (xy 356.130065 -234.334554) (xy 356.100041 -234.378591) (xy 356.063789 -234.417662)
			(xy 356.022118 -234.450893) (xy 355.97596 -234.477542) (xy 355.926346 -234.497014) (xy 355.874384 -234.508874)
			(xy 355.821234 -234.512858) (xy 355.768084 -234.508874) (xy 355.716122 -234.497014) (xy 355.666508 -234.477542)
			(xy 355.62035 -234.450893) (xy 355.578679 -234.417662) (xy 355.542427 -234.378591) (xy 355.512403 -234.334554)
			(xy 355.489277 -234.286533) (xy 355.473567 -234.235603) (xy 355.465624 -234.182899) (xy 355.237044 -234.182899)
			(xy 355.229101 -234.235603) (xy 355.213391 -234.286533) (xy 355.190265 -234.334554) (xy 355.160241 -234.378591)
			(xy 355.123989 -234.417662) (xy 355.082318 -234.450893) (xy 355.03616 -234.477542) (xy 354.986546 -234.497014)
			(xy 354.934584 -234.508874) (xy 354.881434 -234.512858) (xy 354.828284 -234.508874) (xy 354.776322 -234.497014)
			(xy 354.726708 -234.477542) (xy 354.68055 -234.450893) (xy 354.638879 -234.417662) (xy 354.602627 -234.378591)
			(xy 354.572603 -234.334554) (xy 354.549477 -234.286533) (xy 354.533767 -234.235603) (xy 354.525824 -234.182899)
			(xy 354.297244 -234.182899) (xy 354.289301 -234.235603) (xy 354.273591 -234.286533) (xy 354.250465 -234.334554)
			(xy 354.220441 -234.378591) (xy 354.184189 -234.417662) (xy 354.142518 -234.450893) (xy 354.09636 -234.477542)
			(xy 354.046746 -234.497014) (xy 353.994784 -234.508874) (xy 353.941634 -234.512858) (xy 353.888484 -234.508874)
			(xy 353.836522 -234.497014) (xy 353.786908 -234.477542) (xy 353.74075 -234.450893) (xy 353.699079 -234.417662)
			(xy 353.662827 -234.378591) (xy 353.632803 -234.334554) (xy 353.609677 -234.286533) (xy 353.593967 -234.235603)
			(xy 353.586024 -234.182899) (xy 352.417644 -234.182899) (xy 352.409701 -234.235603) (xy 352.393991 -234.286533)
			(xy 352.370865 -234.334554) (xy 352.340841 -234.378591) (xy 352.304589 -234.417662) (xy 352.262918 -234.450893)
			(xy 352.21676 -234.477542) (xy 352.167146 -234.497014) (xy 352.115184 -234.508874) (xy 352.062034 -234.512858)
			(xy 352.008884 -234.508874) (xy 351.956922 -234.497014) (xy 351.907308 -234.477542) (xy 351.86115 -234.450893)
			(xy 351.819479 -234.417662) (xy 351.783227 -234.378591) (xy 351.753203 -234.334554) (xy 351.730077 -234.286533)
			(xy 351.714367 -234.235603) (xy 351.706424 -234.182899) (xy 351.477844 -234.182899) (xy 351.469901 -234.235603)
			(xy 351.454191 -234.286533) (xy 351.431065 -234.334554) (xy 351.401041 -234.378591) (xy 351.364789 -234.417662)
			(xy 351.323118 -234.450893) (xy 351.27696 -234.477542) (xy 351.227346 -234.497014) (xy 351.175384 -234.508874)
			(xy 351.122234 -234.512858) (xy 351.069084 -234.508874) (xy 351.017122 -234.497014) (xy 350.967508 -234.477542)
			(xy 350.92135 -234.450893) (xy 350.879679 -234.417662) (xy 350.843427 -234.378591) (xy 350.813403 -234.334554)
			(xy 350.790277 -234.286533) (xy 350.774567 -234.235603) (xy 350.766624 -234.182899) (xy 350.538044 -234.182899)
			(xy 350.530101 -234.235603) (xy 350.514391 -234.286533) (xy 350.491265 -234.334554) (xy 350.461241 -234.378591)
			(xy 350.424989 -234.417662) (xy 350.383318 -234.450893) (xy 350.33716 -234.477542) (xy 350.287546 -234.497014)
			(xy 350.235584 -234.508874) (xy 350.182434 -234.512858) (xy 350.129284 -234.508874) (xy 350.077322 -234.497014)
			(xy 350.027708 -234.477542) (xy 349.98155 -234.450893) (xy 349.939879 -234.417662) (xy 349.903627 -234.378591)
			(xy 349.873603 -234.334554) (xy 349.850477 -234.286533) (xy 349.834767 -234.235603) (xy 349.826824 -234.182899)
			(xy 349.59799 -234.182899) (xy 349.590047 -234.235603) (xy 349.574337 -234.286533) (xy 349.551211 -234.334554)
			(xy 349.521187 -234.378591) (xy 349.484935 -234.417662) (xy 349.443264 -234.450893) (xy 349.397106 -234.477542)
			(xy 349.347492 -234.497014) (xy 349.29553 -234.508874) (xy 349.24238 -234.512858) (xy 349.18923 -234.508874)
			(xy 349.137268 -234.497014) (xy 349.087654 -234.477542) (xy 349.041496 -234.450893) (xy 348.999825 -234.417662)
			(xy 348.963573 -234.378591) (xy 348.933549 -234.334554) (xy 348.910423 -234.286533) (xy 348.894713 -234.235603)
			(xy 348.88677 -234.182899) (xy 348.658444 -234.182899) (xy 348.650501 -234.235603) (xy 348.634791 -234.286533)
			(xy 348.611665 -234.334554) (xy 348.581641 -234.378591) (xy 348.545389 -234.417662) (xy 348.503718 -234.450893)
			(xy 348.45756 -234.477542) (xy 348.407946 -234.497014) (xy 348.355984 -234.508874) (xy 348.302834 -234.512858)
			(xy 348.249684 -234.508874) (xy 348.197722 -234.497014) (xy 348.148108 -234.477542) (xy 348.10195 -234.450893)
			(xy 348.060279 -234.417662) (xy 348.024027 -234.378591) (xy 347.994003 -234.334554) (xy 347.970877 -234.286533)
			(xy 347.955167 -234.235603) (xy 347.947224 -234.182899) (xy 347.718644 -234.182899) (xy 347.710701 -234.235603)
			(xy 347.694991 -234.286533) (xy 347.671865 -234.334554) (xy 347.641841 -234.378591) (xy 347.605589 -234.417662)
			(xy 347.563918 -234.450893) (xy 347.51776 -234.477542) (xy 347.468146 -234.497014) (xy 347.416184 -234.508874)
			(xy 347.363034 -234.512858) (xy 347.309884 -234.508874) (xy 347.257922 -234.497014) (xy 347.208308 -234.477542)
			(xy 347.16215 -234.450893) (xy 347.120479 -234.417662) (xy 347.084227 -234.378591) (xy 347.054203 -234.334554)
			(xy 347.031077 -234.286533) (xy 347.015367 -234.235603) (xy 347.007424 -234.182899) (xy 346.778844 -234.182899)
			(xy 346.770901 -234.235603) (xy 346.755191 -234.286533) (xy 346.732065 -234.334554) (xy 346.702041 -234.378591)
			(xy 346.665789 -234.417662) (xy 346.624118 -234.450893) (xy 346.57796 -234.477542) (xy 346.528346 -234.497014)
			(xy 346.476384 -234.508874) (xy 346.423234 -234.512858) (xy 346.370084 -234.508874) (xy 346.318122 -234.497014)
			(xy 346.268508 -234.477542) (xy 346.22235 -234.450893) (xy 346.180679 -234.417662) (xy 346.144427 -234.378591)
			(xy 346.114403 -234.334554) (xy 346.091277 -234.286533) (xy 346.075567 -234.235603) (xy 346.067624 -234.182899)
			(xy 345.839044 -234.182899) (xy 345.831101 -234.235603) (xy 345.815391 -234.286533) (xy 345.792265 -234.334554)
			(xy 345.762241 -234.378591) (xy 345.725989 -234.417662) (xy 345.684318 -234.450893) (xy 345.63816 -234.477542)
			(xy 345.588546 -234.497014) (xy 345.536584 -234.508874) (xy 345.483434 -234.512858) (xy 345.430284 -234.508874)
			(xy 345.378322 -234.497014) (xy 345.328708 -234.477542) (xy 345.28255 -234.450893) (xy 345.240879 -234.417662)
			(xy 345.204627 -234.378591) (xy 345.174603 -234.334554) (xy 345.151477 -234.286533) (xy 345.135767 -234.235603)
			(xy 345.127824 -234.182899) (xy 344.899244 -234.182899) (xy 344.891301 -234.235603) (xy 344.875591 -234.286533)
			(xy 344.852465 -234.334554) (xy 344.822441 -234.378591) (xy 344.786189 -234.417662) (xy 344.744518 -234.450893)
			(xy 344.69836 -234.477542) (xy 344.648746 -234.497014) (xy 344.596784 -234.508874) (xy 344.543634 -234.512858)
			(xy 344.490484 -234.508874) (xy 344.438522 -234.497014) (xy 344.388908 -234.477542) (xy 344.34275 -234.450893)
			(xy 344.301079 -234.417662) (xy 344.264827 -234.378591) (xy 344.234803 -234.334554) (xy 344.211677 -234.286533)
			(xy 344.195967 -234.235603) (xy 344.188024 -234.182899) (xy 343.959444 -234.182899) (xy 343.951501 -234.235603)
			(xy 343.935791 -234.286533) (xy 343.912665 -234.334554) (xy 343.882641 -234.378591) (xy 343.846389 -234.417662)
			(xy 343.804718 -234.450893) (xy 343.75856 -234.477542) (xy 343.708946 -234.497014) (xy 343.656984 -234.508874)
			(xy 343.603834 -234.512858) (xy 343.550684 -234.508874) (xy 343.498722 -234.497014) (xy 343.449108 -234.477542)
			(xy 343.40295 -234.450893) (xy 343.361279 -234.417662) (xy 343.325027 -234.378591) (xy 343.295003 -234.334554)
			(xy 343.271877 -234.286533) (xy 343.256167 -234.235603) (xy 343.248224 -234.182899) (xy 343.01939 -234.182899)
			(xy 343.011447 -234.235603) (xy 342.995737 -234.286533) (xy 342.972611 -234.334554) (xy 342.942587 -234.378591)
			(xy 342.906335 -234.417662) (xy 342.864664 -234.450893) (xy 342.818506 -234.477542) (xy 342.768892 -234.497014)
			(xy 342.71693 -234.508874) (xy 342.66378 -234.512858) (xy 342.61063 -234.508874) (xy 342.558668 -234.497014)
			(xy 342.509054 -234.477542) (xy 342.462896 -234.450893) (xy 342.421225 -234.417662) (xy 342.384973 -234.378591)
			(xy 342.354949 -234.334554) (xy 342.331823 -234.286533) (xy 342.316113 -234.235603) (xy 342.30817 -234.182899)
			(xy 342.079844 -234.182899) (xy 342.071901 -234.235603) (xy 342.056191 -234.286533) (xy 342.033065 -234.334554)
			(xy 342.003041 -234.378591) (xy 341.966789 -234.417662) (xy 341.925118 -234.450893) (xy 341.87896 -234.477542)
			(xy 341.829346 -234.497014) (xy 341.777384 -234.508874) (xy 341.724234 -234.512858) (xy 341.671084 -234.508874)
			(xy 341.619122 -234.497014) (xy 341.569508 -234.477542) (xy 341.52335 -234.450893) (xy 341.481679 -234.417662)
			(xy 341.445427 -234.378591) (xy 341.415403 -234.334554) (xy 341.392277 -234.286533) (xy 341.376567 -234.235603)
			(xy 341.368624 -234.182899) (xy 341.140044 -234.182899) (xy 341.132101 -234.235603) (xy 341.116391 -234.286533)
			(xy 341.093265 -234.334554) (xy 341.063241 -234.378591) (xy 341.026989 -234.417662) (xy 340.985318 -234.450893)
			(xy 340.93916 -234.477542) (xy 340.889546 -234.497014) (xy 340.837584 -234.508874) (xy 340.784434 -234.512858)
			(xy 340.731284 -234.508874) (xy 340.679322 -234.497014) (xy 340.629708 -234.477542) (xy 340.58355 -234.450893)
			(xy 340.541879 -234.417662) (xy 340.505627 -234.378591) (xy 340.475603 -234.334554) (xy 340.452477 -234.286533)
			(xy 340.436767 -234.235603) (xy 340.428824 -234.182899) (xy 340.200244 -234.182899) (xy 340.192301 -234.235603)
			(xy 340.176591 -234.286533) (xy 340.153465 -234.334554) (xy 340.123441 -234.378591) (xy 340.087189 -234.417662)
			(xy 340.045518 -234.450893) (xy 339.99936 -234.477542) (xy 339.949746 -234.497014) (xy 339.897784 -234.508874)
			(xy 339.844634 -234.512858) (xy 339.791484 -234.508874) (xy 339.739522 -234.497014) (xy 339.689908 -234.477542)
			(xy 339.64375 -234.450893) (xy 339.602079 -234.417662) (xy 339.565827 -234.378591) (xy 339.535803 -234.334554)
			(xy 339.512677 -234.286533) (xy 339.496967 -234.235603) (xy 339.489024 -234.182899) (xy 339.37956 -234.182899)
			(xy 339.37956 -234.611164) (xy 339.423502 -234.61726) (xy 339.450056 -234.621442) (xy 339.501584 -234.636752)
			(xy 339.550226 -234.659631) (xy 339.594879 -234.689558) (xy 339.634528 -234.725854) (xy 339.668274 -234.767695)
			(xy 339.69535 -234.814132) (xy 339.715142 -234.86411) (xy 339.7272 -234.916494) (xy 339.73125 -234.970095)
			(xy 339.729239 -234.996715) (xy 339.95867 -234.996715) (xy 339.95867 -234.943417) (xy 339.966613 -234.890713)
			(xy 339.982323 -234.839783) (xy 340.005449 -234.791762) (xy 340.035473 -234.747725) (xy 340.071725 -234.708654)
			(xy 340.113396 -234.675423) (xy 340.159554 -234.648774) (xy 340.209168 -234.629302) (xy 340.26113 -234.617442)
			(xy 340.31428 -234.613459) (xy 340.36743 -234.617442) (xy 340.419392 -234.629302) (xy 340.469006 -234.648774)
			(xy 340.515164 -234.675423) (xy 340.556835 -234.708654) (xy 340.593087 -234.747725) (xy 340.623111 -234.791762)
			(xy 340.646237 -234.839783) (xy 340.661947 -234.890713) (xy 340.66989 -234.943417) (xy 340.670388 -234.970066)
			(xy 340.66989 -234.996715) (xy 340.89847 -234.996715) (xy 340.89847 -234.943417) (xy 340.906413 -234.890713)
			(xy 340.922123 -234.839783) (xy 340.945249 -234.791762) (xy 340.975273 -234.747725) (xy 341.011525 -234.708654)
			(xy 341.053196 -234.675423) (xy 341.099354 -234.648774) (xy 341.148968 -234.629302) (xy 341.20093 -234.617442)
			(xy 341.25408 -234.613459) (xy 341.30723 -234.617442) (xy 341.359192 -234.629302) (xy 341.408806 -234.648774)
			(xy 341.454964 -234.675423) (xy 341.496635 -234.708654) (xy 341.532887 -234.747725) (xy 341.562911 -234.791762)
			(xy 341.586037 -234.839783) (xy 341.601747 -234.890713) (xy 341.60969 -234.943417) (xy 341.610188 -234.970066)
			(xy 341.60969 -234.996715) (xy 341.83827 -234.996715) (xy 341.83827 -234.943417) (xy 341.846213 -234.890713)
			(xy 341.861923 -234.839783) (xy 341.885049 -234.791762) (xy 341.915073 -234.747725) (xy 341.951325 -234.708654)
			(xy 341.992996 -234.675423) (xy 342.039154 -234.648774) (xy 342.088768 -234.629302) (xy 342.14073 -234.617442)
			(xy 342.19388 -234.613459) (xy 342.24703 -234.617442) (xy 342.298992 -234.629302) (xy 342.348606 -234.648774)
			(xy 342.394764 -234.675423) (xy 342.436435 -234.708654) (xy 342.472687 -234.747725) (xy 342.502711 -234.791762)
			(xy 342.525837 -234.839783) (xy 342.541547 -234.890713) (xy 342.54949 -234.943417) (xy 342.549988 -234.970066)
			(xy 342.54949 -234.996715) (xy 342.77807 -234.996715) (xy 342.77807 -234.943417) (xy 342.786013 -234.890713)
			(xy 342.801723 -234.839783) (xy 342.824849 -234.791762) (xy 342.854873 -234.747725) (xy 342.891125 -234.708654)
			(xy 342.932796 -234.675423) (xy 342.978954 -234.648774) (xy 343.028568 -234.629302) (xy 343.08053 -234.617442)
			(xy 343.13368 -234.613459) (xy 343.18683 -234.617442) (xy 343.238792 -234.629302) (xy 343.288406 -234.648774)
			(xy 343.334564 -234.675423) (xy 343.376235 -234.708654) (xy 343.412487 -234.747725) (xy 343.442511 -234.791762)
			(xy 343.465637 -234.839783) (xy 343.481347 -234.890713) (xy 343.48929 -234.943417) (xy 343.489788 -234.970066)
			(xy 343.48929 -234.996715) (xy 343.71787 -234.996715) (xy 343.71787 -234.943417) (xy 343.725813 -234.890713)
			(xy 343.741523 -234.839783) (xy 343.764649 -234.791762) (xy 343.794673 -234.747725) (xy 343.830925 -234.708654)
			(xy 343.872596 -234.675423) (xy 343.918754 -234.648774) (xy 343.968368 -234.629302) (xy 344.02033 -234.617442)
			(xy 344.07348 -234.613459) (xy 344.12663 -234.617442) (xy 344.178592 -234.629302) (xy 344.228206 -234.648774)
			(xy 344.274364 -234.675423) (xy 344.316035 -234.708654) (xy 344.352287 -234.747725) (xy 344.382311 -234.791762)
			(xy 344.405437 -234.839783) (xy 344.421147 -234.890713) (xy 344.42909 -234.943417) (xy 344.429588 -234.970066)
			(xy 344.42909 -234.996715) (xy 344.657924 -234.996715) (xy 344.657924 -234.943417) (xy 344.665867 -234.890713)
			(xy 344.681577 -234.839783) (xy 344.704703 -234.791762) (xy 344.734727 -234.747725) (xy 344.770979 -234.708654)
			(xy 344.81265 -234.675423) (xy 344.858808 -234.648774) (xy 344.908422 -234.629302) (xy 344.960384 -234.617442)
			(xy 345.013534 -234.613459) (xy 345.066684 -234.617442) (xy 345.118646 -234.629302) (xy 345.16826 -234.648774)
			(xy 345.214418 -234.675423) (xy 345.256089 -234.708654) (xy 345.292341 -234.747725) (xy 345.322365 -234.791762)
			(xy 345.345491 -234.839783) (xy 345.361201 -234.890713) (xy 345.369144 -234.943417) (xy 345.369642 -234.970066)
			(xy 345.369144 -234.996715) (xy 345.59747 -234.996715) (xy 345.59747 -234.943417) (xy 345.605413 -234.890713)
			(xy 345.621123 -234.839783) (xy 345.644249 -234.791762) (xy 345.674273 -234.747725) (xy 345.710525 -234.708654)
			(xy 345.752196 -234.675423) (xy 345.798354 -234.648774) (xy 345.847968 -234.629302) (xy 345.89993 -234.617442)
			(xy 345.95308 -234.613459) (xy 346.00623 -234.617442) (xy 346.058192 -234.629302) (xy 346.107806 -234.648774)
			(xy 346.153964 -234.675423) (xy 346.195635 -234.708654) (xy 346.231887 -234.747725) (xy 346.261911 -234.791762)
			(xy 346.285037 -234.839783) (xy 346.300747 -234.890713) (xy 346.30869 -234.943417) (xy 346.309188 -234.970066)
			(xy 346.30869 -234.996715) (xy 346.53727 -234.996715) (xy 346.53727 -234.943417) (xy 346.545213 -234.890713)
			(xy 346.560923 -234.839783) (xy 346.584049 -234.791762) (xy 346.614073 -234.747725) (xy 346.650325 -234.708654)
			(xy 346.691996 -234.675423) (xy 346.738154 -234.648774) (xy 346.787768 -234.629302) (xy 346.83973 -234.617442)
			(xy 346.89288 -234.613459) (xy 346.94603 -234.617442) (xy 346.997992 -234.629302) (xy 347.047606 -234.648774)
			(xy 347.093764 -234.675423) (xy 347.135435 -234.708654) (xy 347.171687 -234.747725) (xy 347.201711 -234.791762)
			(xy 347.224837 -234.839783) (xy 347.240547 -234.890713) (xy 347.24849 -234.943417) (xy 347.248988 -234.970066)
			(xy 347.24849 -234.996715) (xy 347.47707 -234.996715) (xy 347.47707 -234.943417) (xy 347.485013 -234.890713)
			(xy 347.500723 -234.839783) (xy 347.523849 -234.791762) (xy 347.553873 -234.747725) (xy 347.590125 -234.708654)
			(xy 347.631796 -234.675423) (xy 347.677954 -234.648774) (xy 347.727568 -234.629302) (xy 347.77953 -234.617442)
			(xy 347.83268 -234.613459) (xy 347.88583 -234.617442) (xy 347.937792 -234.629302) (xy 347.987406 -234.648774)
			(xy 348.033564 -234.675423) (xy 348.075235 -234.708654) (xy 348.111487 -234.747725) (xy 348.141511 -234.791762)
			(xy 348.164637 -234.839783) (xy 348.180347 -234.890713) (xy 348.18829 -234.943417) (xy 348.188788 -234.970066)
			(xy 348.18829 -234.996715) (xy 348.41687 -234.996715) (xy 348.41687 -234.943417) (xy 348.424813 -234.890713)
			(xy 348.440523 -234.839783) (xy 348.463649 -234.791762) (xy 348.493673 -234.747725) (xy 348.529925 -234.708654)
			(xy 348.571596 -234.675423) (xy 348.617754 -234.648774) (xy 348.667368 -234.629302) (xy 348.71933 -234.617442)
			(xy 348.77248 -234.613459) (xy 348.82563 -234.617442) (xy 348.877592 -234.629302) (xy 348.927206 -234.648774)
			(xy 348.973364 -234.675423) (xy 349.015035 -234.708654) (xy 349.051287 -234.747725) (xy 349.081311 -234.791762)
			(xy 349.104437 -234.839783) (xy 349.120147 -234.890713) (xy 349.12809 -234.943417) (xy 349.128588 -234.970066)
			(xy 349.12809 -234.996715) (xy 349.35667 -234.996715) (xy 349.35667 -234.943417) (xy 349.364613 -234.890713)
			(xy 349.380323 -234.839783) (xy 349.403449 -234.791762) (xy 349.433473 -234.747725) (xy 349.469725 -234.708654)
			(xy 349.511396 -234.675423) (xy 349.557554 -234.648774) (xy 349.607168 -234.629302) (xy 349.65913 -234.617442)
			(xy 349.71228 -234.613459) (xy 349.76543 -234.617442) (xy 349.817392 -234.629302) (xy 349.867006 -234.648774)
			(xy 349.913164 -234.675423) (xy 349.954835 -234.708654) (xy 349.991087 -234.747725) (xy 350.021111 -234.791762)
			(xy 350.044237 -234.839783) (xy 350.059947 -234.890713) (xy 350.06789 -234.943417) (xy 350.068388 -234.970066)
			(xy 350.06789 -234.996715) (xy 350.062531 -235.032275) (xy 353.09809 -235.032275) (xy 353.09809 -234.978977)
			(xy 353.106033 -234.926273) (xy 353.121743 -234.875343) (xy 353.144869 -234.827322) (xy 353.174893 -234.783285)
			(xy 353.211145 -234.744214) (xy 353.252816 -234.710983) (xy 353.298974 -234.684334) (xy 353.348588 -234.664862)
			(xy 353.40055 -234.653002) (xy 353.4537 -234.649019) (xy 353.50685 -234.653002) (xy 353.558812 -234.664862)
			(xy 353.608426 -234.684334) (xy 353.654584 -234.710983) (xy 353.696255 -234.744214) (xy 353.732507 -234.783285)
			(xy 353.762531 -234.827322) (xy 353.785657 -234.875343) (xy 353.801367 -234.926273) (xy 353.80931 -234.978977)
			(xy 353.809808 -235.005626) (xy 353.80931 -235.032275) (xy 353.801367 -235.084979) (xy 353.785657 -235.135909)
			(xy 353.762531 -235.18393) (xy 353.732507 -235.227967) (xy 353.696255 -235.267038) (xy 353.657481 -235.297959)
			(xy 354.021888 -235.297959) (xy 354.021888 -235.244661) (xy 354.029831 -235.191957) (xy 354.045541 -235.141027)
			(xy 354.068667 -235.093006) (xy 354.098691 -235.048969) (xy 354.134943 -235.009898) (xy 354.176614 -234.976667)
			(xy 354.222772 -234.950018) (xy 354.272386 -234.930546) (xy 354.324348 -234.918686) (xy 354.377498 -234.914703)
			(xy 354.430648 -234.918686) (xy 354.48261 -234.930546) (xy 354.532224 -234.950018) (xy 354.578382 -234.976667)
			(xy 354.603522 -234.996715) (xy 356.87507 -234.996715) (xy 356.87507 -234.943417) (xy 356.883013 -234.890713)
			(xy 356.898723 -234.839783) (xy 356.921849 -234.791762) (xy 356.951873 -234.747725) (xy 356.988125 -234.708654)
			(xy 357.029796 -234.675423) (xy 357.075954 -234.648774) (xy 357.125568 -234.629302) (xy 357.17753 -234.617442)
			(xy 357.23068 -234.613459) (xy 357.28383 -234.617442) (xy 357.335792 -234.629302) (xy 357.385406 -234.648774)
			(xy 357.431564 -234.675423) (xy 357.473235 -234.708654) (xy 357.509487 -234.747725) (xy 357.539511 -234.791762)
			(xy 357.562637 -234.839783) (xy 357.578347 -234.890713) (xy 357.58629 -234.943417) (xy 357.586788 -234.970066)
			(xy 357.58629 -234.996715) (xy 357.815124 -234.996715) (xy 357.815124 -234.943417) (xy 357.823067 -234.890713)
			(xy 357.838777 -234.839783) (xy 357.861903 -234.791762) (xy 357.891927 -234.747725) (xy 357.928179 -234.708654)
			(xy 357.96985 -234.675423) (xy 358.016008 -234.648774) (xy 358.065622 -234.629302) (xy 358.117584 -234.617442)
			(xy 358.170734 -234.613459) (xy 358.223884 -234.617442) (xy 358.275846 -234.629302) (xy 358.32546 -234.648774)
			(xy 358.371618 -234.675423) (xy 358.413289 -234.708654) (xy 358.449541 -234.747725) (xy 358.479565 -234.791762)
			(xy 358.502691 -234.839783) (xy 358.518401 -234.890713) (xy 358.526344 -234.943417) (xy 358.526842 -234.970066)
			(xy 358.526344 -234.996715) (xy 358.75467 -234.996715) (xy 358.75467 -234.943417) (xy 358.762613 -234.890713)
			(xy 358.778323 -234.839783) (xy 358.801449 -234.791762) (xy 358.831473 -234.747725) (xy 358.867725 -234.708654)
			(xy 358.909396 -234.675423) (xy 358.955554 -234.648774) (xy 359.005168 -234.629302) (xy 359.05713 -234.617442)
			(xy 359.11028 -234.613459) (xy 359.16343 -234.617442) (xy 359.215392 -234.629302) (xy 359.265006 -234.648774)
			(xy 359.311164 -234.675423) (xy 359.352835 -234.708654) (xy 359.389087 -234.747725) (xy 359.419111 -234.791762)
			(xy 359.442237 -234.839783) (xy 359.457947 -234.890713) (xy 359.46589 -234.943417) (xy 359.466388 -234.970066)
			(xy 359.46589 -234.996715) (xy 359.69447 -234.996715) (xy 359.69447 -234.943417) (xy 359.702413 -234.890713)
			(xy 359.718123 -234.839783) (xy 359.741249 -234.791762) (xy 359.771273 -234.747725) (xy 359.807525 -234.708654)
			(xy 359.849196 -234.675423) (xy 359.895354 -234.648774) (xy 359.944968 -234.629302) (xy 359.99693 -234.617442)
			(xy 360.05008 -234.613459) (xy 360.10323 -234.617442) (xy 360.155192 -234.629302) (xy 360.204806 -234.648774)
			(xy 360.250964 -234.675423) (xy 360.292635 -234.708654) (xy 360.328887 -234.747725) (xy 360.358911 -234.791762)
			(xy 360.382037 -234.839783) (xy 360.397747 -234.890713) (xy 360.40569 -234.943417) (xy 360.406188 -234.970066)
			(xy 360.40569 -234.996715) (xy 360.63427 -234.996715) (xy 360.63427 -234.943417) (xy 360.642213 -234.890713)
			(xy 360.657923 -234.839783) (xy 360.681049 -234.791762) (xy 360.711073 -234.747725) (xy 360.747325 -234.708654)
			(xy 360.788996 -234.675423) (xy 360.835154 -234.648774) (xy 360.884768 -234.629302) (xy 360.93673 -234.617442)
			(xy 360.98988 -234.613459) (xy 361.04303 -234.617442) (xy 361.094992 -234.629302) (xy 361.144606 -234.648774)
			(xy 361.190764 -234.675423) (xy 361.232435 -234.708654) (xy 361.268687 -234.747725) (xy 361.298711 -234.791762)
			(xy 361.321837 -234.839783) (xy 361.337547 -234.890713) (xy 361.34549 -234.943417) (xy 361.345988 -234.970066)
			(xy 361.34549 -234.996715) (xy 361.574324 -234.996715) (xy 361.574324 -234.943417) (xy 361.582267 -234.890713)
			(xy 361.597977 -234.839783) (xy 361.621103 -234.791762) (xy 361.651127 -234.747725) (xy 361.687379 -234.708654)
			(xy 361.72905 -234.675423) (xy 361.775208 -234.648774) (xy 361.824822 -234.629302) (xy 361.876784 -234.617442)
			(xy 361.929934 -234.613459) (xy 361.983084 -234.617442) (xy 362.035046 -234.629302) (xy 362.08466 -234.648774)
			(xy 362.130818 -234.675423) (xy 362.172489 -234.708654) (xy 362.208741 -234.747725) (xy 362.238765 -234.791762)
			(xy 362.261891 -234.839783) (xy 362.277601 -234.890713) (xy 362.285544 -234.943417) (xy 362.286042 -234.970066)
			(xy 362.285544 -234.996715) (xy 369.09247 -234.996715) (xy 369.09247 -234.943417) (xy 369.100413 -234.890713)
			(xy 369.116123 -234.839783) (xy 369.139249 -234.791762) (xy 369.169273 -234.747725) (xy 369.205525 -234.708654)
			(xy 369.247196 -234.675423) (xy 369.293354 -234.648774) (xy 369.342968 -234.629302) (xy 369.39493 -234.617442)
			(xy 369.44808 -234.613459) (xy 369.50123 -234.617442) (xy 369.553192 -234.629302) (xy 369.602806 -234.648774)
			(xy 369.648964 -234.675423) (xy 369.690635 -234.708654) (xy 369.726887 -234.747725) (xy 369.756911 -234.791762)
			(xy 369.780037 -234.839783) (xy 369.795747 -234.890713) (xy 369.80369 -234.943417) (xy 369.804188 -234.970066)
			(xy 369.80369 -234.996715) (xy 370.03227 -234.996715) (xy 370.03227 -234.943417) (xy 370.040213 -234.890713)
			(xy 370.055923 -234.839783) (xy 370.079049 -234.791762) (xy 370.109073 -234.747725) (xy 370.145325 -234.708654)
			(xy 370.186996 -234.675423) (xy 370.233154 -234.648774) (xy 370.282768 -234.629302) (xy 370.33473 -234.617442)
			(xy 370.38788 -234.613459) (xy 370.44103 -234.617442) (xy 370.492992 -234.629302) (xy 370.542606 -234.648774)
			(xy 370.588764 -234.675423) (xy 370.630435 -234.708654) (xy 370.666687 -234.747725) (xy 370.696711 -234.791762)
			(xy 370.719837 -234.839783) (xy 370.735547 -234.890713) (xy 370.74349 -234.943417) (xy 370.743988 -234.970066)
			(xy 370.74349 -234.996715) (xy 370.97207 -234.996715) (xy 370.97207 -234.943417) (xy 370.980013 -234.890713)
			(xy 370.995723 -234.839783) (xy 371.018849 -234.791762) (xy 371.048873 -234.747725) (xy 371.085125 -234.708654)
			(xy 371.126796 -234.675423) (xy 371.172954 -234.648774) (xy 371.222568 -234.629302) (xy 371.27453 -234.617442)
			(xy 371.32768 -234.613459) (xy 371.38083 -234.617442) (xy 371.432792 -234.629302) (xy 371.482406 -234.648774)
			(xy 371.528564 -234.675423) (xy 371.570235 -234.708654) (xy 371.606487 -234.747725) (xy 371.636511 -234.791762)
			(xy 371.659637 -234.839783) (xy 371.675347 -234.890713) (xy 371.68329 -234.943417) (xy 371.683788 -234.970066)
			(xy 371.68329 -234.996715) (xy 371.91187 -234.996715) (xy 371.91187 -234.943417) (xy 371.919813 -234.890713)
			(xy 371.935523 -234.839783) (xy 371.958649 -234.791762) (xy 371.988673 -234.747725) (xy 372.024925 -234.708654)
			(xy 372.066596 -234.675423) (xy 372.112754 -234.648774) (xy 372.162368 -234.629302) (xy 372.21433 -234.617442)
			(xy 372.26748 -234.613459) (xy 372.32063 -234.617442) (xy 372.372592 -234.629302) (xy 372.422206 -234.648774)
			(xy 372.468364 -234.675423) (xy 372.510035 -234.708654) (xy 372.546287 -234.747725) (xy 372.576311 -234.791762)
			(xy 372.599437 -234.839783) (xy 372.615147 -234.890713) (xy 372.62309 -234.943417) (xy 372.623588 -234.970066)
			(xy 372.62309 -234.996715) (xy 372.851924 -234.996715) (xy 372.851924 -234.943417) (xy 372.859867 -234.890713)
			(xy 372.875577 -234.839783) (xy 372.898703 -234.791762) (xy 372.928727 -234.747725) (xy 372.964979 -234.708654)
			(xy 373.00665 -234.675423) (xy 373.052808 -234.648774) (xy 373.102422 -234.629302) (xy 373.154384 -234.617442)
			(xy 373.207534 -234.613459) (xy 373.260684 -234.617442) (xy 373.312646 -234.629302) (xy 373.36226 -234.648774)
			(xy 373.408418 -234.675423) (xy 373.450089 -234.708654) (xy 373.486341 -234.747725) (xy 373.516365 -234.791762)
			(xy 373.539491 -234.839783) (xy 373.555201 -234.890713) (xy 373.563144 -234.943417) (xy 373.563642 -234.970066)
			(xy 373.563144 -234.996715) (xy 373.79147 -234.996715) (xy 373.79147 -234.943417) (xy 373.799413 -234.890713)
			(xy 373.815123 -234.839783) (xy 373.838249 -234.791762) (xy 373.868273 -234.747725) (xy 373.904525 -234.708654)
			(xy 373.946196 -234.675423) (xy 373.992354 -234.648774) (xy 374.041968 -234.629302) (xy 374.09393 -234.617442)
			(xy 374.14708 -234.613459) (xy 374.20023 -234.617442) (xy 374.252192 -234.629302) (xy 374.301806 -234.648774)
			(xy 374.347964 -234.675423) (xy 374.389635 -234.708654) (xy 374.425887 -234.747725) (xy 374.455911 -234.791762)
			(xy 374.479037 -234.839783) (xy 374.494747 -234.890713) (xy 374.50269 -234.943417) (xy 374.503188 -234.970066)
			(xy 374.50269 -234.996715) (xy 374.73127 -234.996715) (xy 374.73127 -234.943417) (xy 374.739213 -234.890713)
			(xy 374.754923 -234.839783) (xy 374.778049 -234.791762) (xy 374.808073 -234.747725) (xy 374.844325 -234.708654)
			(xy 374.885996 -234.675423) (xy 374.932154 -234.648774) (xy 374.981768 -234.629302) (xy 375.03373 -234.617442)
			(xy 375.08688 -234.613459) (xy 375.14003 -234.617442) (xy 375.191992 -234.629302) (xy 375.241606 -234.648774)
			(xy 375.287764 -234.675423) (xy 375.329435 -234.708654) (xy 375.365687 -234.747725) (xy 375.395711 -234.791762)
			(xy 375.418837 -234.839783) (xy 375.434547 -234.890713) (xy 375.44249 -234.943417) (xy 375.442988 -234.970066)
			(xy 375.44249 -234.996715) (xy 375.67107 -234.996715) (xy 375.67107 -234.943417) (xy 375.679013 -234.890713)
			(xy 375.694723 -234.839783) (xy 375.717849 -234.791762) (xy 375.747873 -234.747725) (xy 375.784125 -234.708654)
			(xy 375.825796 -234.675423) (xy 375.871954 -234.648774) (xy 375.921568 -234.629302) (xy 375.97353 -234.617442)
			(xy 376.02668 -234.613459) (xy 376.07983 -234.617442) (xy 376.131792 -234.629302) (xy 376.181406 -234.648774)
			(xy 376.227564 -234.675423) (xy 376.269235 -234.708654) (xy 376.305487 -234.747725) (xy 376.335511 -234.791762)
			(xy 376.358637 -234.839783) (xy 376.374347 -234.890713) (xy 376.38229 -234.943417) (xy 376.382788 -234.970066)
			(xy 376.38229 -234.996715) (xy 376.61087 -234.996715) (xy 376.61087 -234.943417) (xy 376.618813 -234.890713)
			(xy 376.634523 -234.839783) (xy 376.657649 -234.791762) (xy 376.687673 -234.747725) (xy 376.723925 -234.708654)
			(xy 376.765596 -234.675423) (xy 376.811754 -234.648774) (xy 376.861368 -234.629302) (xy 376.91333 -234.617442)
			(xy 376.96648 -234.613459) (xy 377.01963 -234.617442) (xy 377.071592 -234.629302) (xy 377.121206 -234.648774)
			(xy 377.167364 -234.675423) (xy 377.209035 -234.708654) (xy 377.245287 -234.747725) (xy 377.275311 -234.791762)
			(xy 377.298437 -234.839783) (xy 377.314147 -234.890713) (xy 377.32209 -234.943417) (xy 377.322588 -234.970066)
			(xy 377.32209 -234.996715) (xy 377.55067 -234.996715) (xy 377.55067 -234.943417) (xy 377.558613 -234.890713)
			(xy 377.574323 -234.839783) (xy 377.597449 -234.791762) (xy 377.627473 -234.747725) (xy 377.663725 -234.708654)
			(xy 377.705396 -234.675423) (xy 377.751554 -234.648774) (xy 377.801168 -234.629302) (xy 377.85313 -234.617442)
			(xy 377.90628 -234.613459) (xy 377.95943 -234.617442) (xy 378.011392 -234.629302) (xy 378.061006 -234.648774)
			(xy 378.107164 -234.675423) (xy 378.148835 -234.708654) (xy 378.185087 -234.747725) (xy 378.215111 -234.791762)
			(xy 378.238237 -234.839783) (xy 378.253947 -234.890713) (xy 378.26189 -234.943417) (xy 378.262388 -234.970066)
			(xy 378.26189 -234.996715) (xy 378.49047 -234.996715) (xy 378.49047 -234.943417) (xy 378.498413 -234.890713)
			(xy 378.514123 -234.839783) (xy 378.537249 -234.791762) (xy 378.567273 -234.747725) (xy 378.603525 -234.708654)
			(xy 378.645196 -234.675423) (xy 378.691354 -234.648774) (xy 378.740968 -234.629302) (xy 378.79293 -234.617442)
			(xy 378.84608 -234.613459) (xy 378.89923 -234.617442) (xy 378.951192 -234.629302) (xy 379.000806 -234.648774)
			(xy 379.046964 -234.675423) (xy 379.088635 -234.708654) (xy 379.124887 -234.747725) (xy 379.154911 -234.791762)
			(xy 379.178037 -234.839783) (xy 379.193747 -234.890713) (xy 379.20169 -234.943417) (xy 379.202188 -234.970066)
			(xy 379.20169 -234.996715) (xy 379.430524 -234.996715) (xy 379.430524 -234.943417) (xy 379.438467 -234.890713)
			(xy 379.454177 -234.839783) (xy 379.477303 -234.791762) (xy 379.507327 -234.747725) (xy 379.543579 -234.708654)
			(xy 379.58525 -234.675423) (xy 379.631408 -234.648774) (xy 379.681022 -234.629302) (xy 379.732984 -234.617442)
			(xy 379.786134 -234.613459) (xy 379.839284 -234.617442) (xy 379.891246 -234.629302) (xy 379.94086 -234.648774)
			(xy 379.987018 -234.675423) (xy 380.028689 -234.708654) (xy 380.064941 -234.747725) (xy 380.094965 -234.791762)
			(xy 380.118091 -234.839783) (xy 380.133801 -234.890713) (xy 380.141744 -234.943417) (xy 380.142242 -234.970066)
			(xy 380.141744 -234.996715) (xy 380.37007 -234.996715) (xy 380.37007 -234.943417) (xy 380.378013 -234.890713)
			(xy 380.393723 -234.839783) (xy 380.416849 -234.791762) (xy 380.446873 -234.747725) (xy 380.483125 -234.708654)
			(xy 380.524796 -234.675423) (xy 380.570954 -234.648774) (xy 380.620568 -234.629302) (xy 380.67253 -234.617442)
			(xy 380.72568 -234.613459) (xy 380.77883 -234.617442) (xy 380.830792 -234.629302) (xy 380.880406 -234.648774)
			(xy 380.926564 -234.675423) (xy 380.968235 -234.708654) (xy 381.004487 -234.747725) (xy 381.034511 -234.791762)
			(xy 381.057637 -234.839783) (xy 381.073347 -234.890713) (xy 381.08129 -234.943417) (xy 381.081788 -234.970066)
			(xy 381.08129 -234.996715) (xy 381.073347 -235.049419) (xy 381.057637 -235.100349) (xy 381.034511 -235.14837)
			(xy 381.004487 -235.192407) (xy 380.968235 -235.231478) (xy 380.926564 -235.264709) (xy 380.880406 -235.291358)
			(xy 380.830792 -235.31083) (xy 380.77883 -235.32269) (xy 380.72568 -235.326674) (xy 380.67253 -235.32269)
			(xy 380.620568 -235.31083) (xy 380.570954 -235.291358) (xy 380.524796 -235.264709) (xy 380.483125 -235.231478)
			(xy 380.446873 -235.192407) (xy 380.416849 -235.14837) (xy 380.393723 -235.100349) (xy 380.378013 -235.049419)
			(xy 380.37007 -234.996715) (xy 380.141744 -234.996715) (xy 380.133801 -235.049419) (xy 380.118091 -235.100349)
			(xy 380.094965 -235.14837) (xy 380.064941 -235.192407) (xy 380.028689 -235.231478) (xy 379.987018 -235.264709)
			(xy 379.94086 -235.291358) (xy 379.891246 -235.31083) (xy 379.839284 -235.32269) (xy 379.786134 -235.326674)
			(xy 379.732984 -235.32269) (xy 379.681022 -235.31083) (xy 379.631408 -235.291358) (xy 379.58525 -235.264709)
			(xy 379.543579 -235.231478) (xy 379.507327 -235.192407) (xy 379.477303 -235.14837) (xy 379.454177 -235.100349)
			(xy 379.438467 -235.049419) (xy 379.430524 -234.996715) (xy 379.20169 -234.996715) (xy 379.193747 -235.049419)
			(xy 379.178037 -235.100349) (xy 379.154911 -235.14837) (xy 379.124887 -235.192407) (xy 379.088635 -235.231478)
			(xy 379.046964 -235.264709) (xy 379.000806 -235.291358) (xy 378.951192 -235.31083) (xy 378.89923 -235.32269)
			(xy 378.84608 -235.326674) (xy 378.79293 -235.32269) (xy 378.740968 -235.31083) (xy 378.691354 -235.291358)
			(xy 378.645196 -235.264709) (xy 378.603525 -235.231478) (xy 378.567273 -235.192407) (xy 378.537249 -235.14837)
			(xy 378.514123 -235.100349) (xy 378.498413 -235.049419) (xy 378.49047 -234.996715) (xy 378.26189 -234.996715)
			(xy 378.253947 -235.049419) (xy 378.238237 -235.100349) (xy 378.215111 -235.14837) (xy 378.185087 -235.192407)
			(xy 378.148835 -235.231478) (xy 378.107164 -235.264709) (xy 378.061006 -235.291358) (xy 378.011392 -235.31083)
			(xy 377.95943 -235.32269) (xy 377.90628 -235.326674) (xy 377.85313 -235.32269) (xy 377.801168 -235.31083)
			(xy 377.751554 -235.291358) (xy 377.705396 -235.264709) (xy 377.663725 -235.231478) (xy 377.627473 -235.192407)
			(xy 377.597449 -235.14837) (xy 377.574323 -235.100349) (xy 377.558613 -235.049419) (xy 377.55067 -234.996715)
			(xy 377.32209 -234.996715) (xy 377.314147 -235.049419) (xy 377.298437 -235.100349) (xy 377.275311 -235.14837)
			(xy 377.245287 -235.192407) (xy 377.209035 -235.231478) (xy 377.167364 -235.264709) (xy 377.121206 -235.291358)
			(xy 377.071592 -235.31083) (xy 377.01963 -235.32269) (xy 376.96648 -235.326674) (xy 376.91333 -235.32269)
			(xy 376.861368 -235.31083) (xy 376.811754 -235.291358) (xy 376.765596 -235.264709) (xy 376.723925 -235.231478)
			(xy 376.687673 -235.192407) (xy 376.657649 -235.14837) (xy 376.634523 -235.100349) (xy 376.618813 -235.049419)
			(xy 376.61087 -234.996715) (xy 376.38229 -234.996715) (xy 376.374347 -235.049419) (xy 376.358637 -235.100349)
			(xy 376.335511 -235.14837) (xy 376.305487 -235.192407) (xy 376.269235 -235.231478) (xy 376.227564 -235.264709)
			(xy 376.181406 -235.291358) (xy 376.131792 -235.31083) (xy 376.07983 -235.32269) (xy 376.02668 -235.326674)
			(xy 375.97353 -235.32269) (xy 375.921568 -235.31083) (xy 375.871954 -235.291358) (xy 375.825796 -235.264709)
			(xy 375.784125 -235.231478) (xy 375.747873 -235.192407) (xy 375.717849 -235.14837) (xy 375.694723 -235.100349)
			(xy 375.679013 -235.049419) (xy 375.67107 -234.996715) (xy 375.44249 -234.996715) (xy 375.434547 -235.049419)
			(xy 375.418837 -235.100349) (xy 375.395711 -235.14837) (xy 375.365687 -235.192407) (xy 375.329435 -235.231478)
			(xy 375.287764 -235.264709) (xy 375.241606 -235.291358) (xy 375.191992 -235.31083) (xy 375.14003 -235.32269)
			(xy 375.08688 -235.326674) (xy 375.03373 -235.32269) (xy 374.981768 -235.31083) (xy 374.932154 -235.291358)
			(xy 374.885996 -235.264709) (xy 374.844325 -235.231478) (xy 374.808073 -235.192407) (xy 374.778049 -235.14837)
			(xy 374.754923 -235.100349) (xy 374.739213 -235.049419) (xy 374.73127 -234.996715) (xy 374.50269 -234.996715)
			(xy 374.494747 -235.049419) (xy 374.479037 -235.100349) (xy 374.455911 -235.14837) (xy 374.425887 -235.192407)
			(xy 374.389635 -235.231478) (xy 374.347964 -235.264709) (xy 374.301806 -235.291358) (xy 374.252192 -235.31083)
			(xy 374.20023 -235.32269) (xy 374.14708 -235.326674) (xy 374.09393 -235.32269) (xy 374.041968 -235.31083)
			(xy 373.992354 -235.291358) (xy 373.946196 -235.264709) (xy 373.904525 -235.231478) (xy 373.868273 -235.192407)
			(xy 373.838249 -235.14837) (xy 373.815123 -235.100349) (xy 373.799413 -235.049419) (xy 373.79147 -234.996715)
			(xy 373.563144 -234.996715) (xy 373.555201 -235.049419) (xy 373.539491 -235.100349) (xy 373.516365 -235.14837)
			(xy 373.486341 -235.192407) (xy 373.450089 -235.231478) (xy 373.408418 -235.264709) (xy 373.36226 -235.291358)
			(xy 373.312646 -235.31083) (xy 373.260684 -235.32269) (xy 373.207534 -235.326674) (xy 373.154384 -235.32269)
			(xy 373.102422 -235.31083) (xy 373.052808 -235.291358) (xy 373.00665 -235.264709) (xy 372.964979 -235.231478)
			(xy 372.928727 -235.192407) (xy 372.898703 -235.14837) (xy 372.875577 -235.100349) (xy 372.859867 -235.049419)
			(xy 372.851924 -234.996715) (xy 372.62309 -234.996715) (xy 372.615147 -235.049419) (xy 372.599437 -235.100349)
			(xy 372.576311 -235.14837) (xy 372.546287 -235.192407) (xy 372.510035 -235.231478) (xy 372.468364 -235.264709)
			(xy 372.422206 -235.291358) (xy 372.372592 -235.31083) (xy 372.32063 -235.32269) (xy 372.26748 -235.326674)
			(xy 372.21433 -235.32269) (xy 372.162368 -235.31083) (xy 372.112754 -235.291358) (xy 372.066596 -235.264709)
			(xy 372.024925 -235.231478) (xy 371.988673 -235.192407) (xy 371.958649 -235.14837) (xy 371.935523 -235.100349)
			(xy 371.919813 -235.049419) (xy 371.91187 -234.996715) (xy 371.68329 -234.996715) (xy 371.675347 -235.049419)
			(xy 371.659637 -235.100349) (xy 371.636511 -235.14837) (xy 371.606487 -235.192407) (xy 371.570235 -235.231478)
			(xy 371.528564 -235.264709) (xy 371.482406 -235.291358) (xy 371.432792 -235.31083) (xy 371.38083 -235.32269)
			(xy 371.32768 -235.326674) (xy 371.27453 -235.32269) (xy 371.222568 -235.31083) (xy 371.172954 -235.291358)
			(xy 371.126796 -235.264709) (xy 371.085125 -235.231478) (xy 371.048873 -235.192407) (xy 371.018849 -235.14837)
			(xy 370.995723 -235.100349) (xy 370.980013 -235.049419) (xy 370.97207 -234.996715) (xy 370.74349 -234.996715)
			(xy 370.735547 -235.049419) (xy 370.719837 -235.100349) (xy 370.696711 -235.14837) (xy 370.666687 -235.192407)
			(xy 370.630435 -235.231478) (xy 370.588764 -235.264709) (xy 370.542606 -235.291358) (xy 370.492992 -235.31083)
			(xy 370.44103 -235.32269) (xy 370.38788 -235.326674) (xy 370.33473 -235.32269) (xy 370.282768 -235.31083)
			(xy 370.233154 -235.291358) (xy 370.186996 -235.264709) (xy 370.145325 -235.231478) (xy 370.109073 -235.192407)
			(xy 370.079049 -235.14837) (xy 370.055923 -235.100349) (xy 370.040213 -235.049419) (xy 370.03227 -234.996715)
			(xy 369.80369 -234.996715) (xy 369.795747 -235.049419) (xy 369.780037 -235.100349) (xy 369.756911 -235.14837)
			(xy 369.726887 -235.192407) (xy 369.690635 -235.231478) (xy 369.648964 -235.264709) (xy 369.602806 -235.291358)
			(xy 369.553192 -235.31083) (xy 369.50123 -235.32269) (xy 369.44808 -235.326674) (xy 369.39493 -235.32269)
			(xy 369.342968 -235.31083) (xy 369.293354 -235.291358) (xy 369.247196 -235.264709) (xy 369.205525 -235.231478)
			(xy 369.169273 -235.192407) (xy 369.139249 -235.14837) (xy 369.116123 -235.100349) (xy 369.100413 -235.049419)
			(xy 369.09247 -234.996715) (xy 362.285544 -234.996715) (xy 362.277601 -235.049419) (xy 362.261891 -235.100349)
			(xy 362.238765 -235.14837) (xy 362.208741 -235.192407) (xy 362.172489 -235.231478) (xy 362.130818 -235.264709)
			(xy 362.08466 -235.291358) (xy 362.035046 -235.31083) (xy 361.983084 -235.32269) (xy 361.929934 -235.326674)
			(xy 361.876784 -235.32269) (xy 361.824822 -235.31083) (xy 361.775208 -235.291358) (xy 361.72905 -235.264709)
			(xy 361.687379 -235.231478) (xy 361.651127 -235.192407) (xy 361.621103 -235.14837) (xy 361.597977 -235.100349)
			(xy 361.582267 -235.049419) (xy 361.574324 -234.996715) (xy 361.34549 -234.996715) (xy 361.337547 -235.049419)
			(xy 361.321837 -235.100349) (xy 361.298711 -235.14837) (xy 361.268687 -235.192407) (xy 361.232435 -235.231478)
			(xy 361.190764 -235.264709) (xy 361.144606 -235.291358) (xy 361.094992 -235.31083) (xy 361.04303 -235.32269)
			(xy 360.98988 -235.326674) (xy 360.93673 -235.32269) (xy 360.884768 -235.31083) (xy 360.835154 -235.291358)
			(xy 360.788996 -235.264709) (xy 360.747325 -235.231478) (xy 360.711073 -235.192407) (xy 360.681049 -235.14837)
			(xy 360.657923 -235.100349) (xy 360.642213 -235.049419) (xy 360.63427 -234.996715) (xy 360.40569 -234.996715)
			(xy 360.397747 -235.049419) (xy 360.382037 -235.100349) (xy 360.358911 -235.14837) (xy 360.328887 -235.192407)
			(xy 360.292635 -235.231478) (xy 360.250964 -235.264709) (xy 360.204806 -235.291358) (xy 360.155192 -235.31083)
			(xy 360.10323 -235.32269) (xy 360.05008 -235.326674) (xy 359.99693 -235.32269) (xy 359.944968 -235.31083)
			(xy 359.895354 -235.291358) (xy 359.849196 -235.264709) (xy 359.807525 -235.231478) (xy 359.771273 -235.192407)
			(xy 359.741249 -235.14837) (xy 359.718123 -235.100349) (xy 359.702413 -235.049419) (xy 359.69447 -234.996715)
			(xy 359.46589 -234.996715) (xy 359.457947 -235.049419) (xy 359.442237 -235.100349) (xy 359.419111 -235.14837)
			(xy 359.389087 -235.192407) (xy 359.352835 -235.231478) (xy 359.311164 -235.264709) (xy 359.265006 -235.291358)
			(xy 359.215392 -235.31083) (xy 359.16343 -235.32269) (xy 359.11028 -235.326674) (xy 359.05713 -235.32269)
			(xy 359.005168 -235.31083) (xy 358.955554 -235.291358) (xy 358.909396 -235.264709) (xy 358.867725 -235.231478)
			(xy 358.831473 -235.192407) (xy 358.801449 -235.14837) (xy 358.778323 -235.100349) (xy 358.762613 -235.049419)
			(xy 358.75467 -234.996715) (xy 358.526344 -234.996715) (xy 358.518401 -235.049419) (xy 358.502691 -235.100349)
			(xy 358.479565 -235.14837) (xy 358.449541 -235.192407) (xy 358.413289 -235.231478) (xy 358.371618 -235.264709)
			(xy 358.32546 -235.291358) (xy 358.275846 -235.31083) (xy 358.223884 -235.32269) (xy 358.170734 -235.326674)
			(xy 358.117584 -235.32269) (xy 358.065622 -235.31083) (xy 358.016008 -235.291358) (xy 357.96985 -235.264709)
			(xy 357.928179 -235.231478) (xy 357.891927 -235.192407) (xy 357.861903 -235.14837) (xy 357.838777 -235.100349)
			(xy 357.823067 -235.049419) (xy 357.815124 -234.996715) (xy 357.58629 -234.996715) (xy 357.578347 -235.049419)
			(xy 357.562637 -235.100349) (xy 357.539511 -235.14837) (xy 357.509487 -235.192407) (xy 357.473235 -235.231478)
			(xy 357.431564 -235.264709) (xy 357.385406 -235.291358) (xy 357.335792 -235.31083) (xy 357.28383 -235.32269)
			(xy 357.23068 -235.326674) (xy 357.17753 -235.32269) (xy 357.125568 -235.31083) (xy 357.075954 -235.291358)
			(xy 357.029796 -235.264709) (xy 356.988125 -235.231478) (xy 356.951873 -235.192407) (xy 356.921849 -235.14837)
			(xy 356.898723 -235.100349) (xy 356.883013 -235.049419) (xy 356.87507 -234.996715) (xy 354.603522 -234.996715)
			(xy 354.620053 -235.009898) (xy 354.656305 -235.048969) (xy 354.686329 -235.093006) (xy 354.709455 -235.141027)
			(xy 354.725165 -235.191957) (xy 354.733108 -235.244661) (xy 354.733606 -235.27131) (xy 354.733108 -235.297959)
			(xy 354.725165 -235.350663) (xy 354.709455 -235.401593) (xy 354.686329 -235.449614) (xy 354.656305 -235.493651)
			(xy 354.620053 -235.532722) (xy 354.578382 -235.565953) (xy 354.532224 -235.592602) (xy 354.48261 -235.612074)
			(xy 354.430648 -235.623934) (xy 354.377498 -235.627918) (xy 354.324348 -235.623934) (xy 354.272386 -235.612074)
			(xy 354.222772 -235.592602) (xy 354.176614 -235.565953) (xy 354.134943 -235.532722) (xy 354.098691 -235.493651)
			(xy 354.068667 -235.449614) (xy 354.045541 -235.401593) (xy 354.029831 -235.350663) (xy 354.021888 -235.297959)
			(xy 353.657481 -235.297959) (xy 353.654584 -235.300269) (xy 353.608426 -235.326918) (xy 353.558812 -235.34639)
			(xy 353.50685 -235.35825) (xy 353.4537 -235.362234) (xy 353.40055 -235.35825) (xy 353.348588 -235.34639)
			(xy 353.298974 -235.326918) (xy 353.252816 -235.300269) (xy 353.211145 -235.267038) (xy 353.174893 -235.227967)
			(xy 353.144869 -235.18393) (xy 353.121743 -235.135909) (xy 353.106033 -235.084979) (xy 353.09809 -235.032275)
			(xy 350.062531 -235.032275) (xy 350.059947 -235.049419) (xy 350.044237 -235.100349) (xy 350.021111 -235.14837)
			(xy 349.991087 -235.192407) (xy 349.954835 -235.231478) (xy 349.913164 -235.264709) (xy 349.867006 -235.291358)
			(xy 349.817392 -235.31083) (xy 349.76543 -235.32269) (xy 349.71228 -235.326674) (xy 349.65913 -235.32269)
			(xy 349.607168 -235.31083) (xy 349.557554 -235.291358) (xy 349.511396 -235.264709) (xy 349.469725 -235.231478)
			(xy 349.433473 -235.192407) (xy 349.403449 -235.14837) (xy 349.380323 -235.100349) (xy 349.364613 -235.049419)
			(xy 349.35667 -234.996715) (xy 349.12809 -234.996715) (xy 349.120147 -235.049419) (xy 349.104437 -235.100349)
			(xy 349.081311 -235.14837) (xy 349.051287 -235.192407) (xy 349.015035 -235.231478) (xy 348.973364 -235.264709)
			(xy 348.927206 -235.291358) (xy 348.877592 -235.31083) (xy 348.82563 -235.32269) (xy 348.77248 -235.326674)
			(xy 348.71933 -235.32269) (xy 348.667368 -235.31083) (xy 348.617754 -235.291358) (xy 348.571596 -235.264709)
			(xy 348.529925 -235.231478) (xy 348.493673 -235.192407) (xy 348.463649 -235.14837) (xy 348.440523 -235.100349)
			(xy 348.424813 -235.049419) (xy 348.41687 -234.996715) (xy 348.18829 -234.996715) (xy 348.180347 -235.049419)
			(xy 348.164637 -235.100349) (xy 348.141511 -235.14837) (xy 348.111487 -235.192407) (xy 348.075235 -235.231478)
			(xy 348.033564 -235.264709) (xy 347.987406 -235.291358) (xy 347.937792 -235.31083) (xy 347.88583 -235.32269)
			(xy 347.83268 -235.326674) (xy 347.77953 -235.32269) (xy 347.727568 -235.31083) (xy 347.677954 -235.291358)
			(xy 347.631796 -235.264709) (xy 347.590125 -235.231478) (xy 347.553873 -235.192407) (xy 347.523849 -235.14837)
			(xy 347.500723 -235.100349) (xy 347.485013 -235.049419) (xy 347.47707 -234.996715) (xy 347.24849 -234.996715)
			(xy 347.240547 -235.049419) (xy 347.224837 -235.100349) (xy 347.201711 -235.14837) (xy 347.171687 -235.192407)
			(xy 347.135435 -235.231478) (xy 347.093764 -235.264709) (xy 347.047606 -235.291358) (xy 346.997992 -235.31083)
			(xy 346.94603 -235.32269) (xy 346.89288 -235.326674) (xy 346.83973 -235.32269) (xy 346.787768 -235.31083)
			(xy 346.738154 -235.291358) (xy 346.691996 -235.264709) (xy 346.650325 -235.231478) (xy 346.614073 -235.192407)
			(xy 346.584049 -235.14837) (xy 346.560923 -235.100349) (xy 346.545213 -235.049419) (xy 346.53727 -234.996715)
			(xy 346.30869 -234.996715) (xy 346.300747 -235.049419) (xy 346.285037 -235.100349) (xy 346.261911 -235.14837)
			(xy 346.231887 -235.192407) (xy 346.195635 -235.231478) (xy 346.153964 -235.264709) (xy 346.107806 -235.291358)
			(xy 346.058192 -235.31083) (xy 346.00623 -235.32269) (xy 345.95308 -235.326674) (xy 345.89993 -235.32269)
			(xy 345.847968 -235.31083) (xy 345.798354 -235.291358) (xy 345.752196 -235.264709) (xy 345.710525 -235.231478)
			(xy 345.674273 -235.192407) (xy 345.644249 -235.14837) (xy 345.621123 -235.100349) (xy 345.605413 -235.049419)
			(xy 345.59747 -234.996715) (xy 345.369144 -234.996715) (xy 345.361201 -235.049419) (xy 345.345491 -235.100349)
			(xy 345.322365 -235.14837) (xy 345.292341 -235.192407) (xy 345.256089 -235.231478) (xy 345.214418 -235.264709)
			(xy 345.16826 -235.291358) (xy 345.118646 -235.31083) (xy 345.066684 -235.32269) (xy 345.013534 -235.326674)
			(xy 344.960384 -235.32269) (xy 344.908422 -235.31083) (xy 344.858808 -235.291358) (xy 344.81265 -235.264709)
			(xy 344.770979 -235.231478) (xy 344.734727 -235.192407) (xy 344.704703 -235.14837) (xy 344.681577 -235.100349)
			(xy 344.665867 -235.049419) (xy 344.657924 -234.996715) (xy 344.42909 -234.996715) (xy 344.421147 -235.049419)
			(xy 344.405437 -235.100349) (xy 344.382311 -235.14837) (xy 344.352287 -235.192407) (xy 344.316035 -235.231478)
			(xy 344.274364 -235.264709) (xy 344.228206 -235.291358) (xy 344.178592 -235.31083) (xy 344.12663 -235.32269)
			(xy 344.07348 -235.326674) (xy 344.02033 -235.32269) (xy 343.968368 -235.31083) (xy 343.918754 -235.291358)
			(xy 343.872596 -235.264709) (xy 343.830925 -235.231478) (xy 343.794673 -235.192407) (xy 343.764649 -235.14837)
			(xy 343.741523 -235.100349) (xy 343.725813 -235.049419) (xy 343.71787 -234.996715) (xy 343.48929 -234.996715)
			(xy 343.481347 -235.049419) (xy 343.465637 -235.100349) (xy 343.442511 -235.14837) (xy 343.412487 -235.192407)
			(xy 343.376235 -235.231478) (xy 343.334564 -235.264709) (xy 343.288406 -235.291358) (xy 343.238792 -235.31083)
			(xy 343.18683 -235.32269) (xy 343.13368 -235.326674) (xy 343.08053 -235.32269) (xy 343.028568 -235.31083)
			(xy 342.978954 -235.291358) (xy 342.932796 -235.264709) (xy 342.891125 -235.231478) (xy 342.854873 -235.192407)
			(xy 342.824849 -235.14837) (xy 342.801723 -235.100349) (xy 342.786013 -235.049419) (xy 342.77807 -234.996715)
			(xy 342.54949 -234.996715) (xy 342.541547 -235.049419) (xy 342.525837 -235.100349) (xy 342.502711 -235.14837)
			(xy 342.472687 -235.192407) (xy 342.436435 -235.231478) (xy 342.394764 -235.264709) (xy 342.348606 -235.291358)
			(xy 342.298992 -235.31083) (xy 342.24703 -235.32269) (xy 342.19388 -235.326674) (xy 342.14073 -235.32269)
			(xy 342.088768 -235.31083) (xy 342.039154 -235.291358) (xy 341.992996 -235.264709) (xy 341.951325 -235.231478)
			(xy 341.915073 -235.192407) (xy 341.885049 -235.14837) (xy 341.861923 -235.100349) (xy 341.846213 -235.049419)
			(xy 341.83827 -234.996715) (xy 341.60969 -234.996715) (xy 341.601747 -235.049419) (xy 341.586037 -235.100349)
			(xy 341.562911 -235.14837) (xy 341.532887 -235.192407) (xy 341.496635 -235.231478) (xy 341.454964 -235.264709)
			(xy 341.408806 -235.291358) (xy 341.359192 -235.31083) (xy 341.30723 -235.32269) (xy 341.25408 -235.326674)
			(xy 341.20093 -235.32269) (xy 341.148968 -235.31083) (xy 341.099354 -235.291358) (xy 341.053196 -235.264709)
			(xy 341.011525 -235.231478) (xy 340.975273 -235.192407) (xy 340.945249 -235.14837) (xy 340.922123 -235.100349)
			(xy 340.906413 -235.049419) (xy 340.89847 -234.996715) (xy 340.66989 -234.996715) (xy 340.661947 -235.049419)
			(xy 340.646237 -235.100349) (xy 340.623111 -235.14837) (xy 340.593087 -235.192407) (xy 340.556835 -235.231478)
			(xy 340.515164 -235.264709) (xy 340.469006 -235.291358) (xy 340.419392 -235.31083) (xy 340.36743 -235.32269)
			(xy 340.31428 -235.326674) (xy 340.26113 -235.32269) (xy 340.209168 -235.31083) (xy 340.159554 -235.291358)
			(xy 340.113396 -235.264709) (xy 340.071725 -235.231478) (xy 340.035473 -235.192407) (xy 340.005449 -235.14837)
			(xy 339.982323 -235.100349) (xy 339.966613 -235.049419) (xy 339.95867 -234.996715) (xy 339.729239 -234.996715)
			(xy 339.727201 -235.023697) (xy 339.715145 -235.076081) (xy 339.695354 -235.126059) (xy 339.668279 -235.172497)
			(xy 339.634535 -235.214339) (xy 339.594886 -235.250637) (xy 339.550234 -235.280565) (xy 339.501592 -235.303444)
			(xy 339.450065 -235.318756) (xy 339.423502 -235.322872) (xy 339.37956 -235.328968) (xy 339.37956 -235.810531)
			(xy 339.489024 -235.810531) (xy 339.489024 -235.757233) (xy 339.496967 -235.704529) (xy 339.512677 -235.653599)
			(xy 339.535803 -235.605578) (xy 339.565827 -235.561541) (xy 339.602079 -235.52247) (xy 339.64375 -235.489239)
			(xy 339.689908 -235.46259) (xy 339.739522 -235.443118) (xy 339.791484 -235.431258) (xy 339.844634 -235.427275)
			(xy 339.897784 -235.431258) (xy 339.949746 -235.443118) (xy 339.99936 -235.46259) (xy 340.045518 -235.489239)
			(xy 340.087189 -235.52247) (xy 340.123441 -235.561541) (xy 340.153465 -235.605578) (xy 340.176591 -235.653599)
			(xy 340.192301 -235.704529) (xy 340.200244 -235.757233) (xy 340.200742 -235.783882) (xy 340.200244 -235.810531)
			(xy 340.428824 -235.810531) (xy 340.428824 -235.757233) (xy 340.436767 -235.704529) (xy 340.452477 -235.653599)
			(xy 340.475603 -235.605578) (xy 340.505627 -235.561541) (xy 340.541879 -235.52247) (xy 340.58355 -235.489239)
			(xy 340.629708 -235.46259) (xy 340.679322 -235.443118) (xy 340.731284 -235.431258) (xy 340.784434 -235.427275)
			(xy 340.837584 -235.431258) (xy 340.889546 -235.443118) (xy 340.93916 -235.46259) (xy 340.985318 -235.489239)
			(xy 341.026989 -235.52247) (xy 341.063241 -235.561541) (xy 341.093265 -235.605578) (xy 341.116391 -235.653599)
			(xy 341.132101 -235.704529) (xy 341.140044 -235.757233) (xy 341.140542 -235.783882) (xy 341.140044 -235.810531)
			(xy 341.368624 -235.810531) (xy 341.368624 -235.757233) (xy 341.376567 -235.704529) (xy 341.392277 -235.653599)
			(xy 341.415403 -235.605578) (xy 341.445427 -235.561541) (xy 341.481679 -235.52247) (xy 341.52335 -235.489239)
			(xy 341.569508 -235.46259) (xy 341.619122 -235.443118) (xy 341.671084 -235.431258) (xy 341.724234 -235.427275)
			(xy 341.777384 -235.431258) (xy 341.829346 -235.443118) (xy 341.87896 -235.46259) (xy 341.925118 -235.489239)
			(xy 341.966789 -235.52247) (xy 342.003041 -235.561541) (xy 342.033065 -235.605578) (xy 342.056191 -235.653599)
			(xy 342.071901 -235.704529) (xy 342.079844 -235.757233) (xy 342.080342 -235.783882) (xy 342.079844 -235.810531)
			(xy 342.308424 -235.810531) (xy 342.308424 -235.757233) (xy 342.316367 -235.704529) (xy 342.332077 -235.653599)
			(xy 342.355203 -235.605578) (xy 342.385227 -235.561541) (xy 342.421479 -235.52247) (xy 342.46315 -235.489239)
			(xy 342.509308 -235.46259) (xy 342.558922 -235.443118) (xy 342.610884 -235.431258) (xy 342.664034 -235.427275)
			(xy 342.717184 -235.431258) (xy 342.769146 -235.443118) (xy 342.81876 -235.46259) (xy 342.864918 -235.489239)
			(xy 342.906589 -235.52247) (xy 342.942841 -235.561541) (xy 342.972865 -235.605578) (xy 342.995991 -235.653599)
			(xy 343.011701 -235.704529) (xy 343.019644 -235.757233) (xy 343.020142 -235.783882) (xy 343.019644 -235.810531)
			(xy 343.248224 -235.810531) (xy 343.248224 -235.757233) (xy 343.256167 -235.704529) (xy 343.271877 -235.653599)
			(xy 343.295003 -235.605578) (xy 343.325027 -235.561541) (xy 343.361279 -235.52247) (xy 343.40295 -235.489239)
			(xy 343.449108 -235.46259) (xy 343.498722 -235.443118) (xy 343.550684 -235.431258) (xy 343.603834 -235.427275)
			(xy 343.656984 -235.431258) (xy 343.708946 -235.443118) (xy 343.75856 -235.46259) (xy 343.804718 -235.489239)
			(xy 343.846389 -235.52247) (xy 343.882641 -235.561541) (xy 343.912665 -235.605578) (xy 343.935791 -235.653599)
			(xy 343.951501 -235.704529) (xy 343.959444 -235.757233) (xy 343.959942 -235.783882) (xy 343.959444 -235.810531)
			(xy 344.188024 -235.810531) (xy 344.188024 -235.757233) (xy 344.195967 -235.704529) (xy 344.211677 -235.653599)
			(xy 344.234803 -235.605578) (xy 344.264827 -235.561541) (xy 344.301079 -235.52247) (xy 344.34275 -235.489239)
			(xy 344.388908 -235.46259) (xy 344.438522 -235.443118) (xy 344.490484 -235.431258) (xy 344.543634 -235.427275)
			(xy 344.596784 -235.431258) (xy 344.648746 -235.443118) (xy 344.69836 -235.46259) (xy 344.744518 -235.489239)
			(xy 344.786189 -235.52247) (xy 344.822441 -235.561541) (xy 344.852465 -235.605578) (xy 344.875591 -235.653599)
			(xy 344.891301 -235.704529) (xy 344.899244 -235.757233) (xy 344.899742 -235.783882) (xy 344.899244 -235.810531)
			(xy 345.12757 -235.810531) (xy 345.12757 -235.757233) (xy 345.135513 -235.704529) (xy 345.151223 -235.653599)
			(xy 345.174349 -235.605578) (xy 345.204373 -235.561541) (xy 345.240625 -235.52247) (xy 345.282296 -235.489239)
			(xy 345.328454 -235.46259) (xy 345.378068 -235.443118) (xy 345.43003 -235.431258) (xy 345.48318 -235.427275)
			(xy 345.53633 -235.431258) (xy 345.588292 -235.443118) (xy 345.637906 -235.46259) (xy 345.684064 -235.489239)
			(xy 345.725735 -235.52247) (xy 345.761987 -235.561541) (xy 345.792011 -235.605578) (xy 345.815137 -235.653599)
			(xy 345.830847 -235.704529) (xy 345.83879 -235.757233) (xy 345.839288 -235.783882) (xy 345.83879 -235.810531)
			(xy 346.067624 -235.810531) (xy 346.067624 -235.757233) (xy 346.075567 -235.704529) (xy 346.091277 -235.653599)
			(xy 346.114403 -235.605578) (xy 346.144427 -235.561541) (xy 346.180679 -235.52247) (xy 346.22235 -235.489239)
			(xy 346.268508 -235.46259) (xy 346.318122 -235.443118) (xy 346.370084 -235.431258) (xy 346.423234 -235.427275)
			(xy 346.476384 -235.431258) (xy 346.528346 -235.443118) (xy 346.57796 -235.46259) (xy 346.624118 -235.489239)
			(xy 346.665789 -235.52247) (xy 346.702041 -235.561541) (xy 346.732065 -235.605578) (xy 346.755191 -235.653599)
			(xy 346.770901 -235.704529) (xy 346.778844 -235.757233) (xy 346.779342 -235.783882) (xy 346.778844 -235.810531)
			(xy 347.007424 -235.810531) (xy 347.007424 -235.757233) (xy 347.015367 -235.704529) (xy 347.031077 -235.653599)
			(xy 347.054203 -235.605578) (xy 347.084227 -235.561541) (xy 347.120479 -235.52247) (xy 347.16215 -235.489239)
			(xy 347.208308 -235.46259) (xy 347.257922 -235.443118) (xy 347.309884 -235.431258) (xy 347.363034 -235.427275)
			(xy 347.416184 -235.431258) (xy 347.468146 -235.443118) (xy 347.51776 -235.46259) (xy 347.563918 -235.489239)
			(xy 347.605589 -235.52247) (xy 347.641841 -235.561541) (xy 347.671865 -235.605578) (xy 347.694991 -235.653599)
			(xy 347.710701 -235.704529) (xy 347.718644 -235.757233) (xy 347.719142 -235.783882) (xy 347.718644 -235.810531)
			(xy 347.947224 -235.810531) (xy 347.947224 -235.757233) (xy 347.955167 -235.704529) (xy 347.970877 -235.653599)
			(xy 347.994003 -235.605578) (xy 348.024027 -235.561541) (xy 348.060279 -235.52247) (xy 348.10195 -235.489239)
			(xy 348.148108 -235.46259) (xy 348.197722 -235.443118) (xy 348.249684 -235.431258) (xy 348.302834 -235.427275)
			(xy 348.355984 -235.431258) (xy 348.407946 -235.443118) (xy 348.45756 -235.46259) (xy 348.503718 -235.489239)
			(xy 348.545389 -235.52247) (xy 348.581641 -235.561541) (xy 348.611665 -235.605578) (xy 348.634791 -235.653599)
			(xy 348.650501 -235.704529) (xy 348.658444 -235.757233) (xy 348.658942 -235.783882) (xy 348.658444 -235.810531)
			(xy 348.887024 -235.810531) (xy 348.887024 -235.757233) (xy 348.894967 -235.704529) (xy 348.910677 -235.653599)
			(xy 348.933803 -235.605578) (xy 348.963827 -235.561541) (xy 349.000079 -235.52247) (xy 349.04175 -235.489239)
			(xy 349.087908 -235.46259) (xy 349.137522 -235.443118) (xy 349.189484 -235.431258) (xy 349.242634 -235.427275)
			(xy 349.295784 -235.431258) (xy 349.347746 -235.443118) (xy 349.39736 -235.46259) (xy 349.443518 -235.489239)
			(xy 349.485189 -235.52247) (xy 349.521441 -235.561541) (xy 349.551465 -235.605578) (xy 349.574591 -235.653599)
			(xy 349.590301 -235.704529) (xy 349.598244 -235.757233) (xy 349.598742 -235.783882) (xy 349.598244 -235.810531)
			(xy 349.826824 -235.810531) (xy 349.826824 -235.757233) (xy 349.834767 -235.704529) (xy 349.850477 -235.653599)
			(xy 349.873603 -235.605578) (xy 349.903627 -235.561541) (xy 349.939879 -235.52247) (xy 349.98155 -235.489239)
			(xy 350.027708 -235.46259) (xy 350.077322 -235.443118) (xy 350.129284 -235.431258) (xy 350.182434 -235.427275)
			(xy 350.235584 -235.431258) (xy 350.287546 -235.443118) (xy 350.33716 -235.46259) (xy 350.383318 -235.489239)
			(xy 350.424989 -235.52247) (xy 350.461241 -235.561541) (xy 350.491265 -235.605578) (xy 350.514391 -235.653599)
			(xy 350.530101 -235.704529) (xy 350.530684 -235.7084) (xy 350.876937 -235.7084) (xy 350.880919 -235.655258)
			(xy 350.892777 -235.603304) (xy 350.912246 -235.553697) (xy 350.938891 -235.507545) (xy 350.972116 -235.46588)
			(xy 351.01118 -235.429633) (xy 351.05521 -235.399612) (xy 351.103223 -235.376489) (xy 351.154146 -235.360779)
			(xy 351.206841 -235.352835) (xy 351.233486 -235.352336) (xy 351.260406 -235.352854) (xy 351.31363 -235.360969)
			(xy 351.365028 -235.377) (xy 351.413427 -235.400583) (xy 351.457727 -235.43118) (xy 351.496919 -235.468096)
			(xy 351.513902 -235.488988) (xy 351.523002 -235.499874) (xy 351.545959 -235.516529) (xy 351.572611 -235.526232)
			(xy 351.600903 -235.528234) (xy 351.628655 -235.522382) (xy 351.64141 -235.516166) (xy 351.66719 -235.503146)
			(xy 351.721917 -235.484705) (xy 351.778905 -235.475343) (xy 351.80778 -235.474764) (xy 351.83443 -235.475292)
			(xy 351.887135 -235.483233) (xy 351.938068 -235.498941) (xy 351.98609 -235.522065) (xy 352.03013 -235.552089)
			(xy 352.069203 -235.588341) (xy 352.102436 -235.630012) (xy 352.129087 -235.67617) (xy 352.14856 -235.725785)
			(xy 352.160421 -235.777749) (xy 352.164404 -235.8309) (xy 352.160421 -235.884051) (xy 352.14856 -235.936015)
			(xy 352.129087 -235.98563) (xy 352.102436 -236.031788) (xy 352.069203 -236.073459) (xy 352.03013 -236.109711)
			(xy 351.98609 -236.139735) (xy 351.938068 -236.162859) (xy 351.887135 -236.178567) (xy 351.83443 -236.186508)
			(xy 351.80778 -236.18698) (xy 351.780858 -236.186518) (xy 351.727629 -236.178396) (xy 351.676229 -236.162356)
			(xy 351.627829 -236.138763) (xy 351.583531 -236.108154) (xy 351.544344 -236.071226) (xy 351.527364 -236.050328)
			(xy 351.518205 -236.039496) (xy 351.495266 -236.022835) (xy 351.468631 -236.013123) (xy 351.440352 -236.011107)
			(xy 351.412609 -236.016943) (xy 351.399856 -236.02315) (xy 351.374083 -236.036183) (xy 351.319352 -236.054619)
			(xy 351.262362 -236.063975) (xy 351.233486 -236.064552) (xy 351.206841 -236.063965) (xy 351.154146 -236.056021)
			(xy 351.103223 -236.040311) (xy 351.05521 -236.017188) (xy 351.01118 -235.987167) (xy 350.972116 -235.95092)
			(xy 350.938891 -235.909255) (xy 350.912246 -235.863103) (xy 350.892777 -235.813496) (xy 350.880919 -235.761542)
			(xy 350.876937 -235.7084) (xy 350.530684 -235.7084) (xy 350.538044 -235.757233) (xy 350.538542 -235.783882)
			(xy 350.538044 -235.810531) (xy 350.530101 -235.863235) (xy 350.514391 -235.914165) (xy 350.491265 -235.962186)
			(xy 350.461241 -236.006223) (xy 350.424989 -236.045294) (xy 350.383318 -236.078525) (xy 350.33716 -236.105174)
			(xy 350.287546 -236.124646) (xy 350.235584 -236.136506) (xy 350.182434 -236.14049) (xy 350.129284 -236.136506)
			(xy 350.077322 -236.124646) (xy 350.027708 -236.105174) (xy 349.98155 -236.078525) (xy 349.939879 -236.045294)
			(xy 349.903627 -236.006223) (xy 349.873603 -235.962186) (xy 349.850477 -235.914165) (xy 349.834767 -235.863235)
			(xy 349.826824 -235.810531) (xy 349.598244 -235.810531) (xy 349.590301 -235.863235) (xy 349.574591 -235.914165)
			(xy 349.551465 -235.962186) (xy 349.521441 -236.006223) (xy 349.485189 -236.045294) (xy 349.443518 -236.078525)
			(xy 349.39736 -236.105174) (xy 349.347746 -236.124646) (xy 349.295784 -236.136506) (xy 349.242634 -236.14049)
			(xy 349.189484 -236.136506) (xy 349.137522 -236.124646) (xy 349.087908 -236.105174) (xy 349.04175 -236.078525)
			(xy 349.000079 -236.045294) (xy 348.963827 -236.006223) (xy 348.933803 -235.962186) (xy 348.910677 -235.914165)
			(xy 348.894967 -235.863235) (xy 348.887024 -235.810531) (xy 348.658444 -235.810531) (xy 348.650501 -235.863235)
			(xy 348.634791 -235.914165) (xy 348.611665 -235.962186) (xy 348.581641 -236.006223) (xy 348.545389 -236.045294)
			(xy 348.503718 -236.078525) (xy 348.45756 -236.105174) (xy 348.407946 -236.124646) (xy 348.355984 -236.136506)
			(xy 348.302834 -236.14049) (xy 348.249684 -236.136506) (xy 348.197722 -236.124646) (xy 348.148108 -236.105174)
			(xy 348.10195 -236.078525) (xy 348.060279 -236.045294) (xy 348.024027 -236.006223) (xy 347.994003 -235.962186)
			(xy 347.970877 -235.914165) (xy 347.955167 -235.863235) (xy 347.947224 -235.810531) (xy 347.718644 -235.810531)
			(xy 347.710701 -235.863235) (xy 347.694991 -235.914165) (xy 347.671865 -235.962186) (xy 347.641841 -236.006223)
			(xy 347.605589 -236.045294) (xy 347.563918 -236.078525) (xy 347.51776 -236.105174) (xy 347.468146 -236.124646)
			(xy 347.416184 -236.136506) (xy 347.363034 -236.14049) (xy 347.309884 -236.136506) (xy 347.257922 -236.124646)
			(xy 347.208308 -236.105174) (xy 347.16215 -236.078525) (xy 347.120479 -236.045294) (xy 347.084227 -236.006223)
			(xy 347.054203 -235.962186) (xy 347.031077 -235.914165) (xy 347.015367 -235.863235) (xy 347.007424 -235.810531)
			(xy 346.778844 -235.810531) (xy 346.770901 -235.863235) (xy 346.755191 -235.914165) (xy 346.732065 -235.962186)
			(xy 346.702041 -236.006223) (xy 346.665789 -236.045294) (xy 346.624118 -236.078525) (xy 346.57796 -236.105174)
			(xy 346.528346 -236.124646) (xy 346.476384 -236.136506) (xy 346.423234 -236.14049) (xy 346.370084 -236.136506)
			(xy 346.318122 -236.124646) (xy 346.268508 -236.105174) (xy 346.22235 -236.078525) (xy 346.180679 -236.045294)
			(xy 346.144427 -236.006223) (xy 346.114403 -235.962186) (xy 346.091277 -235.914165) (xy 346.075567 -235.863235)
			(xy 346.067624 -235.810531) (xy 345.83879 -235.810531) (xy 345.830847 -235.863235) (xy 345.815137 -235.914165)
			(xy 345.792011 -235.962186) (xy 345.761987 -236.006223) (xy 345.725735 -236.045294) (xy 345.684064 -236.078525)
			(xy 345.637906 -236.105174) (xy 345.588292 -236.124646) (xy 345.53633 -236.136506) (xy 345.48318 -236.14049)
			(xy 345.43003 -236.136506) (xy 345.378068 -236.124646) (xy 345.328454 -236.105174) (xy 345.282296 -236.078525)
			(xy 345.240625 -236.045294) (xy 345.204373 -236.006223) (xy 345.174349 -235.962186) (xy 345.151223 -235.914165)
			(xy 345.135513 -235.863235) (xy 345.12757 -235.810531) (xy 344.899244 -235.810531) (xy 344.891301 -235.863235)
			(xy 344.875591 -235.914165) (xy 344.852465 -235.962186) (xy 344.822441 -236.006223) (xy 344.786189 -236.045294)
			(xy 344.744518 -236.078525) (xy 344.69836 -236.105174) (xy 344.648746 -236.124646) (xy 344.596784 -236.136506)
			(xy 344.543634 -236.14049) (xy 344.490484 -236.136506) (xy 344.438522 -236.124646) (xy 344.388908 -236.105174)
			(xy 344.34275 -236.078525) (xy 344.301079 -236.045294) (xy 344.264827 -236.006223) (xy 344.234803 -235.962186)
			(xy 344.211677 -235.914165) (xy 344.195967 -235.863235) (xy 344.188024 -235.810531) (xy 343.959444 -235.810531)
			(xy 343.951501 -235.863235) (xy 343.935791 -235.914165) (xy 343.912665 -235.962186) (xy 343.882641 -236.006223)
			(xy 343.846389 -236.045294) (xy 343.804718 -236.078525) (xy 343.75856 -236.105174) (xy 343.708946 -236.124646)
			(xy 343.656984 -236.136506) (xy 343.603834 -236.14049) (xy 343.550684 -236.136506) (xy 343.498722 -236.124646)
			(xy 343.449108 -236.105174) (xy 343.40295 -236.078525) (xy 343.361279 -236.045294) (xy 343.325027 -236.006223)
			(xy 343.295003 -235.962186) (xy 343.271877 -235.914165) (xy 343.256167 -235.863235) (xy 343.248224 -235.810531)
			(xy 343.019644 -235.810531) (xy 343.011701 -235.863235) (xy 342.995991 -235.914165) (xy 342.972865 -235.962186)
			(xy 342.942841 -236.006223) (xy 342.906589 -236.045294) (xy 342.864918 -236.078525) (xy 342.81876 -236.105174)
			(xy 342.769146 -236.124646) (xy 342.717184 -236.136506) (xy 342.664034 -236.14049) (xy 342.610884 -236.136506)
			(xy 342.558922 -236.124646) (xy 342.509308 -236.105174) (xy 342.46315 -236.078525) (xy 342.421479 -236.045294)
			(xy 342.385227 -236.006223) (xy 342.355203 -235.962186) (xy 342.332077 -235.914165) (xy 342.316367 -235.863235)
			(xy 342.308424 -235.810531) (xy 342.079844 -235.810531) (xy 342.071901 -235.863235) (xy 342.056191 -235.914165)
			(xy 342.033065 -235.962186) (xy 342.003041 -236.006223) (xy 341.966789 -236.045294) (xy 341.925118 -236.078525)
			(xy 341.87896 -236.105174) (xy 341.829346 -236.124646) (xy 341.777384 -236.136506) (xy 341.724234 -236.14049)
			(xy 341.671084 -236.136506) (xy 341.619122 -236.124646) (xy 341.569508 -236.105174) (xy 341.52335 -236.078525)
			(xy 341.481679 -236.045294) (xy 341.445427 -236.006223) (xy 341.415403 -235.962186) (xy 341.392277 -235.914165)
			(xy 341.376567 -235.863235) (xy 341.368624 -235.810531) (xy 341.140044 -235.810531) (xy 341.132101 -235.863235)
			(xy 341.116391 -235.914165) (xy 341.093265 -235.962186) (xy 341.063241 -236.006223) (xy 341.026989 -236.045294)
			(xy 340.985318 -236.078525) (xy 340.93916 -236.105174) (xy 340.889546 -236.124646) (xy 340.837584 -236.136506)
			(xy 340.784434 -236.14049) (xy 340.731284 -236.136506) (xy 340.679322 -236.124646) (xy 340.629708 -236.105174)
			(xy 340.58355 -236.078525) (xy 340.541879 -236.045294) (xy 340.505627 -236.006223) (xy 340.475603 -235.962186)
			(xy 340.452477 -235.914165) (xy 340.436767 -235.863235) (xy 340.428824 -235.810531) (xy 340.200244 -235.810531)
			(xy 340.192301 -235.863235) (xy 340.176591 -235.914165) (xy 340.153465 -235.962186) (xy 340.123441 -236.006223)
			(xy 340.087189 -236.045294) (xy 340.045518 -236.078525) (xy 339.99936 -236.105174) (xy 339.949746 -236.124646)
			(xy 339.897784 -236.136506) (xy 339.844634 -236.14049) (xy 339.791484 -236.136506) (xy 339.739522 -236.124646)
			(xy 339.689908 -236.105174) (xy 339.64375 -236.078525) (xy 339.602079 -236.045294) (xy 339.565827 -236.006223)
			(xy 339.535803 -235.962186) (xy 339.512677 -235.914165) (xy 339.496967 -235.863235) (xy 339.489024 -235.810531)
			(xy 339.37956 -235.810531) (xy 339.37956 -236.23905) (xy 339.423502 -236.245146) (xy 339.450057 -236.249328)
			(xy 339.501587 -236.264639) (xy 339.550231 -236.287518) (xy 339.594886 -236.317446) (xy 339.634537 -236.353743)
			(xy 339.668284 -236.395586) (xy 339.695362 -236.442024) (xy 339.715155 -236.492004) (xy 339.727213 -236.54439)
			(xy 339.731264 -236.597993) (xy 339.729254 -236.624601) (xy 339.95867 -236.624601) (xy 339.95867 -236.571303)
			(xy 339.966613 -236.518599) (xy 339.982323 -236.467669) (xy 340.005449 -236.419648) (xy 340.035473 -236.375611)
			(xy 340.071725 -236.33654) (xy 340.113396 -236.303309) (xy 340.159554 -236.27666) (xy 340.209168 -236.257188)
			(xy 340.26113 -236.245328) (xy 340.31428 -236.241345) (xy 340.36743 -236.245328) (xy 340.419392 -236.257188)
			(xy 340.469006 -236.27666) (xy 340.515164 -236.303309) (xy 340.556835 -236.33654) (xy 340.593087 -236.375611)
			(xy 340.623111 -236.419648) (xy 340.646237 -236.467669) (xy 340.661947 -236.518599) (xy 340.66989 -236.571303)
			(xy 340.670388 -236.597952) (xy 340.66989 -236.624601) (xy 340.89847 -236.624601) (xy 340.89847 -236.571303)
			(xy 340.906413 -236.518599) (xy 340.922123 -236.467669) (xy 340.945249 -236.419648) (xy 340.975273 -236.375611)
			(xy 341.011525 -236.33654) (xy 341.053196 -236.303309) (xy 341.099354 -236.27666) (xy 341.148968 -236.257188)
			(xy 341.20093 -236.245328) (xy 341.25408 -236.241345) (xy 341.30723 -236.245328) (xy 341.359192 -236.257188)
			(xy 341.408806 -236.27666) (xy 341.454964 -236.303309) (xy 341.496635 -236.33654) (xy 341.532887 -236.375611)
			(xy 341.562911 -236.419648) (xy 341.586037 -236.467669) (xy 341.601747 -236.518599) (xy 341.60969 -236.571303)
			(xy 341.610188 -236.597952) (xy 341.60969 -236.624601) (xy 341.838524 -236.624601) (xy 341.838524 -236.571303)
			(xy 341.846467 -236.518599) (xy 341.862177 -236.467669) (xy 341.885303 -236.419648) (xy 341.915327 -236.375611)
			(xy 341.951579 -236.33654) (xy 341.99325 -236.303309) (xy 342.039408 -236.27666) (xy 342.089022 -236.257188)
			(xy 342.140984 -236.245328) (xy 342.194134 -236.241345) (xy 342.247284 -236.245328) (xy 342.299246 -236.257188)
			(xy 342.34886 -236.27666) (xy 342.395018 -236.303309) (xy 342.436689 -236.33654) (xy 342.472941 -236.375611)
			(xy 342.502965 -236.419648) (xy 342.526091 -236.467669) (xy 342.541801 -236.518599) (xy 342.549744 -236.571303)
			(xy 342.550242 -236.597952) (xy 342.549744 -236.624601) (xy 342.77807 -236.624601) (xy 342.77807 -236.571303)
			(xy 342.786013 -236.518599) (xy 342.801723 -236.467669) (xy 342.824849 -236.419648) (xy 342.854873 -236.375611)
			(xy 342.891125 -236.33654) (xy 342.932796 -236.303309) (xy 342.978954 -236.27666) (xy 343.028568 -236.257188)
			(xy 343.08053 -236.245328) (xy 343.13368 -236.241345) (xy 343.18683 -236.245328) (xy 343.238792 -236.257188)
			(xy 343.288406 -236.27666) (xy 343.334564 -236.303309) (xy 343.376235 -236.33654) (xy 343.412487 -236.375611)
			(xy 343.442511 -236.419648) (xy 343.465637 -236.467669) (xy 343.481347 -236.518599) (xy 343.48929 -236.571303)
			(xy 343.489788 -236.597952) (xy 343.48929 -236.624601) (xy 343.71787 -236.624601) (xy 343.71787 -236.571303)
			(xy 343.725813 -236.518599) (xy 343.741523 -236.467669) (xy 343.764649 -236.419648) (xy 343.794673 -236.375611)
			(xy 343.830925 -236.33654) (xy 343.872596 -236.303309) (xy 343.918754 -236.27666) (xy 343.968368 -236.257188)
			(xy 344.02033 -236.245328) (xy 344.07348 -236.241345) (xy 344.12663 -236.245328) (xy 344.178592 -236.257188)
			(xy 344.228206 -236.27666) (xy 344.274364 -236.303309) (xy 344.316035 -236.33654) (xy 344.352287 -236.375611)
			(xy 344.382311 -236.419648) (xy 344.405437 -236.467669) (xy 344.421147 -236.518599) (xy 344.42909 -236.571303)
			(xy 344.429588 -236.597952) (xy 344.42909 -236.624601) (xy 344.65767 -236.624601) (xy 344.65767 -236.571303)
			(xy 344.665613 -236.518599) (xy 344.681323 -236.467669) (xy 344.704449 -236.419648) (xy 344.734473 -236.375611)
			(xy 344.770725 -236.33654) (xy 344.812396 -236.303309) (xy 344.858554 -236.27666) (xy 344.908168 -236.257188)
			(xy 344.96013 -236.245328) (xy 345.01328 -236.241345) (xy 345.06643 -236.245328) (xy 345.118392 -236.257188)
			(xy 345.168006 -236.27666) (xy 345.214164 -236.303309) (xy 345.255835 -236.33654) (xy 345.292087 -236.375611)
			(xy 345.322111 -236.419648) (xy 345.345237 -236.467669) (xy 345.360947 -236.518599) (xy 345.36889 -236.571303)
			(xy 345.369388 -236.597952) (xy 345.36889 -236.624601) (xy 345.59747 -236.624601) (xy 345.59747 -236.571303)
			(xy 345.605413 -236.518599) (xy 345.621123 -236.467669) (xy 345.644249 -236.419648) (xy 345.674273 -236.375611)
			(xy 345.710525 -236.33654) (xy 345.752196 -236.303309) (xy 345.798354 -236.27666) (xy 345.847968 -236.257188)
			(xy 345.89993 -236.245328) (xy 345.95308 -236.241345) (xy 346.00623 -236.245328) (xy 346.058192 -236.257188)
			(xy 346.107806 -236.27666) (xy 346.153964 -236.303309) (xy 346.195635 -236.33654) (xy 346.231887 -236.375611)
			(xy 346.261911 -236.419648) (xy 346.285037 -236.467669) (xy 346.300747 -236.518599) (xy 346.30869 -236.571303)
			(xy 346.309188 -236.597952) (xy 346.30869 -236.624601) (xy 346.53727 -236.624601) (xy 346.53727 -236.571303)
			(xy 346.545213 -236.518599) (xy 346.560923 -236.467669) (xy 346.584049 -236.419648) (xy 346.614073 -236.375611)
			(xy 346.650325 -236.33654) (xy 346.691996 -236.303309) (xy 346.738154 -236.27666) (xy 346.787768 -236.257188)
			(xy 346.83973 -236.245328) (xy 346.89288 -236.241345) (xy 346.94603 -236.245328) (xy 346.997992 -236.257188)
			(xy 347.047606 -236.27666) (xy 347.093764 -236.303309) (xy 347.135435 -236.33654) (xy 347.171687 -236.375611)
			(xy 347.201711 -236.419648) (xy 347.224837 -236.467669) (xy 347.240547 -236.518599) (xy 347.24849 -236.571303)
			(xy 347.248988 -236.597952) (xy 347.24849 -236.624601) (xy 347.47707 -236.624601) (xy 347.47707 -236.571303)
			(xy 347.485013 -236.518599) (xy 347.500723 -236.467669) (xy 347.523849 -236.419648) (xy 347.553873 -236.375611)
			(xy 347.590125 -236.33654) (xy 347.631796 -236.303309) (xy 347.677954 -236.27666) (xy 347.727568 -236.257188)
			(xy 347.77953 -236.245328) (xy 347.83268 -236.241345) (xy 347.88583 -236.245328) (xy 347.937792 -236.257188)
			(xy 347.987406 -236.27666) (xy 348.033564 -236.303309) (xy 348.075235 -236.33654) (xy 348.111487 -236.375611)
			(xy 348.141511 -236.419648) (xy 348.164637 -236.467669) (xy 348.180347 -236.518599) (xy 348.18829 -236.571303)
			(xy 348.188788 -236.597952) (xy 348.18829 -236.624601) (xy 348.41687 -236.624601) (xy 348.41687 -236.571303)
			(xy 348.424813 -236.518599) (xy 348.440523 -236.467669) (xy 348.463649 -236.419648) (xy 348.493673 -236.375611)
			(xy 348.529925 -236.33654) (xy 348.571596 -236.303309) (xy 348.617754 -236.27666) (xy 348.667368 -236.257188)
			(xy 348.71933 -236.245328) (xy 348.77248 -236.241345) (xy 348.82563 -236.245328) (xy 348.877592 -236.257188)
			(xy 348.927206 -236.27666) (xy 348.973364 -236.303309) (xy 349.015035 -236.33654) (xy 349.051287 -236.375611)
			(xy 349.081311 -236.419648) (xy 349.104437 -236.467669) (xy 349.120147 -236.518599) (xy 349.12809 -236.571303)
			(xy 349.128588 -236.597952) (xy 349.12809 -236.624601) (xy 349.120147 -236.677305) (xy 349.104437 -236.728235)
			(xy 349.081311 -236.776256) (xy 349.051287 -236.820293) (xy 349.015035 -236.859364) (xy 348.973364 -236.892595)
			(xy 348.927206 -236.919244) (xy 348.877592 -236.938716) (xy 348.82563 -236.950576) (xy 348.77248 -236.95456)
			(xy 348.71933 -236.950576) (xy 348.667368 -236.938716) (xy 348.617754 -236.919244) (xy 348.571596 -236.892595)
			(xy 348.529925 -236.859364) (xy 348.493673 -236.820293) (xy 348.463649 -236.776256) (xy 348.440523 -236.728235)
			(xy 348.424813 -236.677305) (xy 348.41687 -236.624601) (xy 348.18829 -236.624601) (xy 348.180347 -236.677305)
			(xy 348.164637 -236.728235) (xy 348.141511 -236.776256) (xy 348.111487 -236.820293) (xy 348.075235 -236.859364)
			(xy 348.033564 -236.892595) (xy 347.987406 -236.919244) (xy 347.937792 -236.938716) (xy 347.88583 -236.950576)
			(xy 347.83268 -236.95456) (xy 347.77953 -236.950576) (xy 347.727568 -236.938716) (xy 347.677954 -236.919244)
			(xy 347.631796 -236.892595) (xy 347.590125 -236.859364) (xy 347.553873 -236.820293) (xy 347.523849 -236.776256)
			(xy 347.500723 -236.728235) (xy 347.485013 -236.677305) (xy 347.47707 -236.624601) (xy 347.24849 -236.624601)
			(xy 347.240547 -236.677305) (xy 347.224837 -236.728235) (xy 347.201711 -236.776256) (xy 347.171687 -236.820293)
			(xy 347.135435 -236.859364) (xy 347.093764 -236.892595) (xy 347.047606 -236.919244) (xy 346.997992 -236.938716)
			(xy 346.94603 -236.950576) (xy 346.89288 -236.95456) (xy 346.83973 -236.950576) (xy 346.787768 -236.938716)
			(xy 346.738154 -236.919244) (xy 346.691996 -236.892595) (xy 346.650325 -236.859364) (xy 346.614073 -236.820293)
			(xy 346.584049 -236.776256) (xy 346.560923 -236.728235) (xy 346.545213 -236.677305) (xy 346.53727 -236.624601)
			(xy 346.30869 -236.624601) (xy 346.300747 -236.677305) (xy 346.285037 -236.728235) (xy 346.261911 -236.776256)
			(xy 346.231887 -236.820293) (xy 346.195635 -236.859364) (xy 346.153964 -236.892595) (xy 346.107806 -236.919244)
			(xy 346.058192 -236.938716) (xy 346.00623 -236.950576) (xy 345.95308 -236.95456) (xy 345.89993 -236.950576)
			(xy 345.847968 -236.938716) (xy 345.798354 -236.919244) (xy 345.752196 -236.892595) (xy 345.710525 -236.859364)
			(xy 345.674273 -236.820293) (xy 345.644249 -236.776256) (xy 345.621123 -236.728235) (xy 345.605413 -236.677305)
			(xy 345.59747 -236.624601) (xy 345.36889 -236.624601) (xy 345.360947 -236.677305) (xy 345.345237 -236.728235)
			(xy 345.322111 -236.776256) (xy 345.292087 -236.820293) (xy 345.255835 -236.859364) (xy 345.214164 -236.892595)
			(xy 345.168006 -236.919244) (xy 345.118392 -236.938716) (xy 345.06643 -236.950576) (xy 345.01328 -236.95456)
			(xy 344.96013 -236.950576) (xy 344.908168 -236.938716) (xy 344.858554 -236.919244) (xy 344.812396 -236.892595)
			(xy 344.770725 -236.859364) (xy 344.734473 -236.820293) (xy 344.704449 -236.776256) (xy 344.681323 -236.728235)
			(xy 344.665613 -236.677305) (xy 344.65767 -236.624601) (xy 344.42909 -236.624601) (xy 344.421147 -236.677305)
			(xy 344.405437 -236.728235) (xy 344.382311 -236.776256) (xy 344.352287 -236.820293) (xy 344.316035 -236.859364)
			(xy 344.274364 -236.892595) (xy 344.228206 -236.919244) (xy 344.178592 -236.938716) (xy 344.12663 -236.950576)
			(xy 344.07348 -236.95456) (xy 344.02033 -236.950576) (xy 343.968368 -236.938716) (xy 343.918754 -236.919244)
			(xy 343.872596 -236.892595) (xy 343.830925 -236.859364) (xy 343.794673 -236.820293) (xy 343.764649 -236.776256)
			(xy 343.741523 -236.728235) (xy 343.725813 -236.677305) (xy 343.71787 -236.624601) (xy 343.48929 -236.624601)
			(xy 343.481347 -236.677305) (xy 343.465637 -236.728235) (xy 343.442511 -236.776256) (xy 343.412487 -236.820293)
			(xy 343.376235 -236.859364) (xy 343.334564 -236.892595) (xy 343.288406 -236.919244) (xy 343.238792 -236.938716)
			(xy 343.18683 -236.950576) (xy 343.13368 -236.95456) (xy 343.08053 -236.950576) (xy 343.028568 -236.938716)
			(xy 342.978954 -236.919244) (xy 342.932796 -236.892595) (xy 342.891125 -236.859364) (xy 342.854873 -236.820293)
			(xy 342.824849 -236.776256) (xy 342.801723 -236.728235) (xy 342.786013 -236.677305) (xy 342.77807 -236.624601)
			(xy 342.549744 -236.624601) (xy 342.541801 -236.677305) (xy 342.526091 -236.728235) (xy 342.502965 -236.776256)
			(xy 342.472941 -236.820293) (xy 342.436689 -236.859364) (xy 342.395018 -236.892595) (xy 342.34886 -236.919244)
			(xy 342.299246 -236.938716) (xy 342.247284 -236.950576) (xy 342.194134 -236.95456) (xy 342.140984 -236.950576)
			(xy 342.089022 -236.938716) (xy 342.039408 -236.919244) (xy 341.99325 -236.892595) (xy 341.951579 -236.859364)
			(xy 341.915327 -236.820293) (xy 341.885303 -236.776256) (xy 341.862177 -236.728235) (xy 341.846467 -236.677305)
			(xy 341.838524 -236.624601) (xy 341.60969 -236.624601) (xy 341.601747 -236.677305) (xy 341.586037 -236.728235)
			(xy 341.562911 -236.776256) (xy 341.532887 -236.820293) (xy 341.496635 -236.859364) (xy 341.454964 -236.892595)
			(xy 341.408806 -236.919244) (xy 341.359192 -236.938716) (xy 341.30723 -236.950576) (xy 341.25408 -236.95456)
			(xy 341.20093 -236.950576) (xy 341.148968 -236.938716) (xy 341.099354 -236.919244) (xy 341.053196 -236.892595)
			(xy 341.011525 -236.859364) (xy 340.975273 -236.820293) (xy 340.945249 -236.776256) (xy 340.922123 -236.728235)
			(xy 340.906413 -236.677305) (xy 340.89847 -236.624601) (xy 340.66989 -236.624601) (xy 340.661947 -236.677305)
			(xy 340.646237 -236.728235) (xy 340.623111 -236.776256) (xy 340.593087 -236.820293) (xy 340.556835 -236.859364)
			(xy 340.515164 -236.892595) (xy 340.469006 -236.919244) (xy 340.419392 -236.938716) (xy 340.36743 -236.950576)
			(xy 340.31428 -236.95456) (xy 340.26113 -236.950576) (xy 340.209168 -236.938716) (xy 340.159554 -236.919244)
			(xy 340.113396 -236.892595) (xy 340.071725 -236.859364) (xy 340.035473 -236.820293) (xy 340.005449 -236.776256)
			(xy 339.982323 -236.728235) (xy 339.966613 -236.677305) (xy 339.95867 -236.624601) (xy 339.729254 -236.624601)
			(xy 339.727215 -236.651597) (xy 339.715159 -236.703983) (xy 339.695368 -236.753964) (xy 339.668292 -236.800403)
			(xy 339.634546 -236.842247) (xy 339.594896 -236.878546) (xy 339.550243 -236.908476) (xy 339.501599 -236.931356)
			(xy 339.45007 -236.946669) (xy 339.423502 -236.950758) (xy 339.37956 -236.956854) (xy 339.37956 -237.438163)
			(xy 339.48877 -237.438163) (xy 339.48877 -237.384865) (xy 339.496713 -237.332161) (xy 339.512423 -237.281231)
			(xy 339.535549 -237.23321) (xy 339.565573 -237.189173) (xy 339.601825 -237.150102) (xy 339.643496 -237.116871)
			(xy 339.689654 -237.090222) (xy 339.739268 -237.07075) (xy 339.79123 -237.05889) (xy 339.84438 -237.054907)
			(xy 339.89753 -237.05889) (xy 339.949492 -237.07075) (xy 339.999106 -237.090222) (xy 340.045264 -237.116871)
			(xy 340.086935 -237.150102) (xy 340.123187 -237.189173) (xy 340.153211 -237.23321) (xy 340.176337 -237.281231)
			(xy 340.192047 -237.332161) (xy 340.19999 -237.384865) (xy 340.200488 -237.411514) (xy 340.19999 -237.438163)
			(xy 340.428824 -237.438163) (xy 340.428824 -237.384865) (xy 340.436767 -237.332161) (xy 340.452477 -237.281231)
			(xy 340.475603 -237.23321) (xy 340.505627 -237.189173) (xy 340.541879 -237.150102) (xy 340.58355 -237.116871)
			(xy 340.629708 -237.090222) (xy 340.679322 -237.07075) (xy 340.731284 -237.05889) (xy 340.784434 -237.054907)
			(xy 340.837584 -237.05889) (xy 340.889546 -237.07075) (xy 340.93916 -237.090222) (xy 340.985318 -237.116871)
			(xy 341.026989 -237.150102) (xy 341.063241 -237.189173) (xy 341.093265 -237.23321) (xy 341.116391 -237.281231)
			(xy 341.132101 -237.332161) (xy 341.140044 -237.384865) (xy 341.140542 -237.411514) (xy 341.140044 -237.438163)
			(xy 341.368624 -237.438163) (xy 341.368624 -237.384865) (xy 341.376567 -237.332161) (xy 341.392277 -237.281231)
			(xy 341.415403 -237.23321) (xy 341.445427 -237.189173) (xy 341.481679 -237.150102) (xy 341.52335 -237.116871)
			(xy 341.569508 -237.090222) (xy 341.619122 -237.07075) (xy 341.671084 -237.05889) (xy 341.724234 -237.054907)
			(xy 341.777384 -237.05889) (xy 341.829346 -237.07075) (xy 341.87896 -237.090222) (xy 341.925118 -237.116871)
			(xy 341.966789 -237.150102) (xy 342.003041 -237.189173) (xy 342.033065 -237.23321) (xy 342.056191 -237.281231)
			(xy 342.071901 -237.332161) (xy 342.079844 -237.384865) (xy 342.080342 -237.411514) (xy 342.079844 -237.438163)
			(xy 342.308424 -237.438163) (xy 342.308424 -237.384865) (xy 342.316367 -237.332161) (xy 342.332077 -237.281231)
			(xy 342.355203 -237.23321) (xy 342.385227 -237.189173) (xy 342.421479 -237.150102) (xy 342.46315 -237.116871)
			(xy 342.509308 -237.090222) (xy 342.558922 -237.07075) (xy 342.610884 -237.05889) (xy 342.664034 -237.054907)
			(xy 342.717184 -237.05889) (xy 342.769146 -237.07075) (xy 342.81876 -237.090222) (xy 342.864918 -237.116871)
			(xy 342.906589 -237.150102) (xy 342.942841 -237.189173) (xy 342.972865 -237.23321) (xy 342.995991 -237.281231)
			(xy 343.011701 -237.332161) (xy 343.019644 -237.384865) (xy 343.020142 -237.411514) (xy 343.019644 -237.438163)
			(xy 343.248224 -237.438163) (xy 343.248224 -237.384865) (xy 343.256167 -237.332161) (xy 343.271877 -237.281231)
			(xy 343.295003 -237.23321) (xy 343.325027 -237.189173) (xy 343.361279 -237.150102) (xy 343.40295 -237.116871)
			(xy 343.449108 -237.090222) (xy 343.498722 -237.07075) (xy 343.550684 -237.05889) (xy 343.603834 -237.054907)
			(xy 343.656984 -237.05889) (xy 343.708946 -237.07075) (xy 343.75856 -237.090222) (xy 343.804718 -237.116871)
			(xy 343.846389 -237.150102) (xy 343.882641 -237.189173) (xy 343.912665 -237.23321) (xy 343.935791 -237.281231)
			(xy 343.951501 -237.332161) (xy 343.959444 -237.384865) (xy 343.959942 -237.411514) (xy 343.959444 -237.438163)
			(xy 344.188024 -237.438163) (xy 344.188024 -237.384865) (xy 344.195967 -237.332161) (xy 344.211677 -237.281231)
			(xy 344.234803 -237.23321) (xy 344.264827 -237.189173) (xy 344.301079 -237.150102) (xy 344.34275 -237.116871)
			(xy 344.388908 -237.090222) (xy 344.438522 -237.07075) (xy 344.490484 -237.05889) (xy 344.543634 -237.054907)
			(xy 344.596784 -237.05889) (xy 344.648746 -237.07075) (xy 344.69836 -237.090222) (xy 344.744518 -237.116871)
			(xy 344.786189 -237.150102) (xy 344.822441 -237.189173) (xy 344.852465 -237.23321) (xy 344.875591 -237.281231)
			(xy 344.891301 -237.332161) (xy 344.899244 -237.384865) (xy 344.899742 -237.411514) (xy 344.899244 -237.438163)
			(xy 345.127824 -237.438163) (xy 345.127824 -237.384865) (xy 345.135767 -237.332161) (xy 345.151477 -237.281231)
			(xy 345.174603 -237.23321) (xy 345.204627 -237.189173) (xy 345.240879 -237.150102) (xy 345.28255 -237.116871)
			(xy 345.328708 -237.090222) (xy 345.378322 -237.07075) (xy 345.430284 -237.05889) (xy 345.483434 -237.054907)
			(xy 345.536584 -237.05889) (xy 345.588546 -237.07075) (xy 345.63816 -237.090222) (xy 345.684318 -237.116871)
			(xy 345.725989 -237.150102) (xy 345.762241 -237.189173) (xy 345.792265 -237.23321) (xy 345.815391 -237.281231)
			(xy 345.831101 -237.332161) (xy 345.839044 -237.384865) (xy 345.839542 -237.411514) (xy 345.839044 -237.438163)
			(xy 346.06737 -237.438163) (xy 346.06737 -237.384865) (xy 346.075313 -237.332161) (xy 346.091023 -237.281231)
			(xy 346.114149 -237.23321) (xy 346.144173 -237.189173) (xy 346.180425 -237.150102) (xy 346.222096 -237.116871)
			(xy 346.268254 -237.090222) (xy 346.317868 -237.07075) (xy 346.36983 -237.05889) (xy 346.42298 -237.054907)
			(xy 346.47613 -237.05889) (xy 346.528092 -237.07075) (xy 346.577706 -237.090222) (xy 346.623864 -237.116871)
			(xy 346.665535 -237.150102) (xy 346.701787 -237.189173) (xy 346.731811 -237.23321) (xy 346.754937 -237.281231)
			(xy 346.770647 -237.332161) (xy 346.77859 -237.384865) (xy 346.779088 -237.411514) (xy 346.77859 -237.438163)
			(xy 347.007424 -237.438163) (xy 347.007424 -237.384865) (xy 347.015367 -237.332161) (xy 347.031077 -237.281231)
			(xy 347.054203 -237.23321) (xy 347.084227 -237.189173) (xy 347.120479 -237.150102) (xy 347.16215 -237.116871)
			(xy 347.208308 -237.090222) (xy 347.257922 -237.07075) (xy 347.309884 -237.05889) (xy 347.363034 -237.054907)
			(xy 347.416184 -237.05889) (xy 347.468146 -237.07075) (xy 347.51776 -237.090222) (xy 347.563918 -237.116871)
			(xy 347.605589 -237.150102) (xy 347.641841 -237.189173) (xy 347.671865 -237.23321) (xy 347.694991 -237.281231)
			(xy 347.710701 -237.332161) (xy 347.718644 -237.384865) (xy 347.719142 -237.411514) (xy 347.718644 -237.438163)
			(xy 347.947224 -237.438163) (xy 347.947224 -237.384865) (xy 347.955167 -237.332161) (xy 347.970877 -237.281231)
			(xy 347.994003 -237.23321) (xy 348.024027 -237.189173) (xy 348.060279 -237.150102) (xy 348.10195 -237.116871)
			(xy 348.148108 -237.090222) (xy 348.197722 -237.07075) (xy 348.249684 -237.05889) (xy 348.302834 -237.054907)
			(xy 348.355984 -237.05889) (xy 348.407946 -237.07075) (xy 348.45756 -237.090222) (xy 348.503718 -237.116871)
			(xy 348.545389 -237.150102) (xy 348.581641 -237.189173) (xy 348.611665 -237.23321) (xy 348.634791 -237.281231)
			(xy 348.650501 -237.332161) (xy 348.658444 -237.384865) (xy 348.658942 -237.411514) (xy 348.658444 -237.438163)
			(xy 348.650501 -237.490867) (xy 348.634791 -237.541797) (xy 348.611665 -237.589818) (xy 348.581641 -237.633855)
			(xy 348.545389 -237.672926) (xy 348.503718 -237.706157) (xy 348.45756 -237.732806) (xy 348.407946 -237.752278)
			(xy 348.355984 -237.764138) (xy 348.302834 -237.768122) (xy 348.249684 -237.764138) (xy 348.197722 -237.752278)
			(xy 348.148108 -237.732806) (xy 348.10195 -237.706157) (xy 348.060279 -237.672926) (xy 348.024027 -237.633855)
			(xy 347.994003 -237.589818) (xy 347.970877 -237.541797) (xy 347.955167 -237.490867) (xy 347.947224 -237.438163)
			(xy 347.718644 -237.438163) (xy 347.710701 -237.490867) (xy 347.694991 -237.541797) (xy 347.671865 -237.589818)
			(xy 347.641841 -237.633855) (xy 347.605589 -237.672926) (xy 347.563918 -237.706157) (xy 347.51776 -237.732806)
			(xy 347.468146 -237.752278) (xy 347.416184 -237.764138) (xy 347.363034 -237.768122) (xy 347.309884 -237.764138)
			(xy 347.257922 -237.752278) (xy 347.208308 -237.732806) (xy 347.16215 -237.706157) (xy 347.120479 -237.672926)
			(xy 347.084227 -237.633855) (xy 347.054203 -237.589818) (xy 347.031077 -237.541797) (xy 347.015367 -237.490867)
			(xy 347.007424 -237.438163) (xy 346.77859 -237.438163) (xy 346.770647 -237.490867) (xy 346.754937 -237.541797)
			(xy 346.731811 -237.589818) (xy 346.701787 -237.633855) (xy 346.665535 -237.672926) (xy 346.623864 -237.706157)
			(xy 346.577706 -237.732806) (xy 346.528092 -237.752278) (xy 346.47613 -237.764138) (xy 346.42298 -237.768122)
			(xy 346.36983 -237.764138) (xy 346.317868 -237.752278) (xy 346.268254 -237.732806) (xy 346.222096 -237.706157)
			(xy 346.180425 -237.672926) (xy 346.144173 -237.633855) (xy 346.114149 -237.589818) (xy 346.091023 -237.541797)
			(xy 346.075313 -237.490867) (xy 346.06737 -237.438163) (xy 345.839044 -237.438163) (xy 345.831101 -237.490867)
			(xy 345.815391 -237.541797) (xy 345.792265 -237.589818) (xy 345.762241 -237.633855) (xy 345.725989 -237.672926)
			(xy 345.684318 -237.706157) (xy 345.63816 -237.732806) (xy 345.588546 -237.752278) (xy 345.536584 -237.764138)
			(xy 345.483434 -237.768122) (xy 345.430284 -237.764138) (xy 345.378322 -237.752278) (xy 345.328708 -237.732806)
			(xy 345.28255 -237.706157) (xy 345.240879 -237.672926) (xy 345.204627 -237.633855) (xy 345.174603 -237.589818)
			(xy 345.151477 -237.541797) (xy 345.135767 -237.490867) (xy 345.127824 -237.438163) (xy 344.899244 -237.438163)
			(xy 344.891301 -237.490867) (xy 344.875591 -237.541797) (xy 344.852465 -237.589818) (xy 344.822441 -237.633855)
			(xy 344.786189 -237.672926) (xy 344.744518 -237.706157) (xy 344.69836 -237.732806) (xy 344.648746 -237.752278)
			(xy 344.596784 -237.764138) (xy 344.543634 -237.768122) (xy 344.490484 -237.764138) (xy 344.438522 -237.752278)
			(xy 344.388908 -237.732806) (xy 344.34275 -237.706157) (xy 344.301079 -237.672926) (xy 344.264827 -237.633855)
			(xy 344.234803 -237.589818) (xy 344.211677 -237.541797) (xy 344.195967 -237.490867) (xy 344.188024 -237.438163)
			(xy 343.959444 -237.438163) (xy 343.951501 -237.490867) (xy 343.935791 -237.541797) (xy 343.912665 -237.589818)
			(xy 343.882641 -237.633855) (xy 343.846389 -237.672926) (xy 343.804718 -237.706157) (xy 343.75856 -237.732806)
			(xy 343.708946 -237.752278) (xy 343.656984 -237.764138) (xy 343.603834 -237.768122) (xy 343.550684 -237.764138)
			(xy 343.498722 -237.752278) (xy 343.449108 -237.732806) (xy 343.40295 -237.706157) (xy 343.361279 -237.672926)
			(xy 343.325027 -237.633855) (xy 343.295003 -237.589818) (xy 343.271877 -237.541797) (xy 343.256167 -237.490867)
			(xy 343.248224 -237.438163) (xy 343.019644 -237.438163) (xy 343.011701 -237.490867) (xy 342.995991 -237.541797)
			(xy 342.972865 -237.589818) (xy 342.942841 -237.633855) (xy 342.906589 -237.672926) (xy 342.864918 -237.706157)
			(xy 342.81876 -237.732806) (xy 342.769146 -237.752278) (xy 342.717184 -237.764138) (xy 342.664034 -237.768122)
			(xy 342.610884 -237.764138) (xy 342.558922 -237.752278) (xy 342.509308 -237.732806) (xy 342.46315 -237.706157)
			(xy 342.421479 -237.672926) (xy 342.385227 -237.633855) (xy 342.355203 -237.589818) (xy 342.332077 -237.541797)
			(xy 342.316367 -237.490867) (xy 342.308424 -237.438163) (xy 342.079844 -237.438163) (xy 342.071901 -237.490867)
			(xy 342.056191 -237.541797) (xy 342.033065 -237.589818) (xy 342.003041 -237.633855) (xy 341.966789 -237.672926)
			(xy 341.925118 -237.706157) (xy 341.87896 -237.732806) (xy 341.829346 -237.752278) (xy 341.777384 -237.764138)
			(xy 341.724234 -237.768122) (xy 341.671084 -237.764138) (xy 341.619122 -237.752278) (xy 341.569508 -237.732806)
			(xy 341.52335 -237.706157) (xy 341.481679 -237.672926) (xy 341.445427 -237.633855) (xy 341.415403 -237.589818)
			(xy 341.392277 -237.541797) (xy 341.376567 -237.490867) (xy 341.368624 -237.438163) (xy 341.140044 -237.438163)
			(xy 341.132101 -237.490867) (xy 341.116391 -237.541797) (xy 341.093265 -237.589818) (xy 341.063241 -237.633855)
			(xy 341.026989 -237.672926) (xy 340.985318 -237.706157) (xy 340.93916 -237.732806) (xy 340.889546 -237.752278)
			(xy 340.837584 -237.764138) (xy 340.784434 -237.768122) (xy 340.731284 -237.764138) (xy 340.679322 -237.752278)
			(xy 340.629708 -237.732806) (xy 340.58355 -237.706157) (xy 340.541879 -237.672926) (xy 340.505627 -237.633855)
			(xy 340.475603 -237.589818) (xy 340.452477 -237.541797) (xy 340.436767 -237.490867) (xy 340.428824 -237.438163)
			(xy 340.19999 -237.438163) (xy 340.192047 -237.490867) (xy 340.176337 -237.541797) (xy 340.153211 -237.589818)
			(xy 340.123187 -237.633855) (xy 340.086935 -237.672926) (xy 340.045264 -237.706157) (xy 339.999106 -237.732806)
			(xy 339.949492 -237.752278) (xy 339.89753 -237.764138) (xy 339.84438 -237.768122) (xy 339.79123 -237.764138)
			(xy 339.739268 -237.752278) (xy 339.689654 -237.732806) (xy 339.643496 -237.706157) (xy 339.601825 -237.672926)
			(xy 339.565573 -237.633855) (xy 339.535549 -237.589818) (xy 339.512423 -237.541797) (xy 339.496713 -237.490867)
			(xy 339.48877 -237.438163) (xy 339.37956 -237.438163) (xy 339.37956 -237.866682) (xy 339.423502 -237.872778)
			(xy 339.450065 -237.876947) (xy 339.501614 -237.892236) (xy 339.550279 -237.915099) (xy 339.594954 -237.945017)
			(xy 339.634625 -237.981311) (xy 339.668391 -238.023154) (xy 339.695483 -238.069598) (xy 339.715287 -238.119586)
			(xy 339.727352 -238.171983) (xy 339.731405 -238.225598) (xy 339.729392 -238.252233) (xy 339.95867 -238.252233)
			(xy 339.95867 -238.198935) (xy 339.966613 -238.146231) (xy 339.982323 -238.095301) (xy 340.005449 -238.04728)
			(xy 340.035473 -238.003243) (xy 340.071725 -237.964172) (xy 340.113396 -237.930941) (xy 340.159554 -237.904292)
			(xy 340.209168 -237.88482) (xy 340.26113 -237.87296) (xy 340.31428 -237.868977) (xy 340.36743 -237.87296)
			(xy 340.419392 -237.88482) (xy 340.469006 -237.904292) (xy 340.515164 -237.930941) (xy 340.556835 -237.964172)
			(xy 340.593087 -238.003243) (xy 340.623111 -238.04728) (xy 340.646237 -238.095301) (xy 340.661947 -238.146231)
			(xy 340.66989 -238.198935) (xy 340.670388 -238.225584) (xy 340.66989 -238.252233) (xy 340.89847 -238.252233)
			(xy 340.89847 -238.198935) (xy 340.906413 -238.146231) (xy 340.922123 -238.095301) (xy 340.945249 -238.04728)
			(xy 340.975273 -238.003243) (xy 341.011525 -237.964172) (xy 341.053196 -237.930941) (xy 341.099354 -237.904292)
			(xy 341.148968 -237.88482) (xy 341.20093 -237.87296) (xy 341.25408 -237.868977) (xy 341.30723 -237.87296)
			(xy 341.359192 -237.88482) (xy 341.408806 -237.904292) (xy 341.454964 -237.930941) (xy 341.496635 -237.964172)
			(xy 341.532887 -238.003243) (xy 341.562911 -238.04728) (xy 341.586037 -238.095301) (xy 341.601747 -238.146231)
			(xy 341.60969 -238.198935) (xy 341.610188 -238.225584) (xy 341.60969 -238.252233) (xy 341.83827 -238.252233)
			(xy 341.83827 -238.198935) (xy 341.846213 -238.146231) (xy 341.861923 -238.095301) (xy 341.885049 -238.04728)
			(xy 341.915073 -238.003243) (xy 341.951325 -237.964172) (xy 341.992996 -237.930941) (xy 342.039154 -237.904292)
			(xy 342.088768 -237.88482) (xy 342.14073 -237.87296) (xy 342.19388 -237.868977) (xy 342.24703 -237.87296)
			(xy 342.298992 -237.88482) (xy 342.348606 -237.904292) (xy 342.394764 -237.930941) (xy 342.436435 -237.964172)
			(xy 342.472687 -238.003243) (xy 342.502711 -238.04728) (xy 342.525837 -238.095301) (xy 342.541547 -238.146231)
			(xy 342.54949 -238.198935) (xy 342.549988 -238.225584) (xy 342.54949 -238.252233) (xy 342.77807 -238.252233)
			(xy 342.77807 -238.198935) (xy 342.786013 -238.146231) (xy 342.801723 -238.095301) (xy 342.824849 -238.04728)
			(xy 342.854873 -238.003243) (xy 342.891125 -237.964172) (xy 342.932796 -237.930941) (xy 342.978954 -237.904292)
			(xy 343.028568 -237.88482) (xy 343.08053 -237.87296) (xy 343.13368 -237.868977) (xy 343.18683 -237.87296)
			(xy 343.238792 -237.88482) (xy 343.288406 -237.904292) (xy 343.334564 -237.930941) (xy 343.376235 -237.964172)
			(xy 343.412487 -238.003243) (xy 343.442511 -238.04728) (xy 343.465637 -238.095301) (xy 343.481347 -238.146231)
			(xy 343.48929 -238.198935) (xy 343.489788 -238.225584) (xy 343.48929 -238.252233) (xy 343.71787 -238.252233)
			(xy 343.71787 -238.198935) (xy 343.725813 -238.146231) (xy 343.741523 -238.095301) (xy 343.764649 -238.04728)
			(xy 343.794673 -238.003243) (xy 343.830925 -237.964172) (xy 343.872596 -237.930941) (xy 343.918754 -237.904292)
			(xy 343.968368 -237.88482) (xy 344.02033 -237.87296) (xy 344.07348 -237.868977) (xy 344.12663 -237.87296)
			(xy 344.178592 -237.88482) (xy 344.228206 -237.904292) (xy 344.274364 -237.930941) (xy 344.316035 -237.964172)
			(xy 344.352287 -238.003243) (xy 344.382311 -238.04728) (xy 344.405437 -238.095301) (xy 344.421147 -238.146231)
			(xy 344.42909 -238.198935) (xy 344.429588 -238.225584) (xy 344.42909 -238.252233) (xy 344.65767 -238.252233)
			(xy 344.65767 -238.198935) (xy 344.665613 -238.146231) (xy 344.681323 -238.095301) (xy 344.704449 -238.04728)
			(xy 344.734473 -238.003243) (xy 344.770725 -237.964172) (xy 344.812396 -237.930941) (xy 344.858554 -237.904292)
			(xy 344.908168 -237.88482) (xy 344.96013 -237.87296) (xy 345.01328 -237.868977) (xy 345.06643 -237.87296)
			(xy 345.118392 -237.88482) (xy 345.168006 -237.904292) (xy 345.214164 -237.930941) (xy 345.255835 -237.964172)
			(xy 345.292087 -238.003243) (xy 345.322111 -238.04728) (xy 345.345237 -238.095301) (xy 345.360947 -238.146231)
			(xy 345.36889 -238.198935) (xy 345.369388 -238.225584) (xy 345.36889 -238.252233) (xy 345.597724 -238.252233)
			(xy 345.597724 -238.198935) (xy 345.605667 -238.146231) (xy 345.621377 -238.095301) (xy 345.644503 -238.04728)
			(xy 345.674527 -238.003243) (xy 345.710779 -237.964172) (xy 345.75245 -237.930941) (xy 345.798608 -237.904292)
			(xy 345.848222 -237.88482) (xy 345.900184 -237.87296) (xy 345.953334 -237.868977) (xy 346.006484 -237.87296)
			(xy 346.058446 -237.88482) (xy 346.10806 -237.904292) (xy 346.154218 -237.930941) (xy 346.195889 -237.964172)
			(xy 346.232141 -238.003243) (xy 346.262165 -238.04728) (xy 346.285291 -238.095301) (xy 346.301001 -238.146231)
			(xy 346.308944 -238.198935) (xy 346.309442 -238.225584) (xy 346.308944 -238.252233) (xy 346.53727 -238.252233)
			(xy 346.53727 -238.198935) (xy 346.545213 -238.146231) (xy 346.560923 -238.095301) (xy 346.584049 -238.04728)
			(xy 346.614073 -238.003243) (xy 346.650325 -237.964172) (xy 346.691996 -237.930941) (xy 346.738154 -237.904292)
			(xy 346.787768 -237.88482) (xy 346.83973 -237.87296) (xy 346.89288 -237.868977) (xy 346.94603 -237.87296)
			(xy 346.997992 -237.88482) (xy 347.047606 -237.904292) (xy 347.093764 -237.930941) (xy 347.135435 -237.964172)
			(xy 347.171687 -238.003243) (xy 347.201711 -238.04728) (xy 347.224837 -238.095301) (xy 347.240547 -238.146231)
			(xy 347.24849 -238.198935) (xy 347.248988 -238.225584) (xy 347.24849 -238.252233) (xy 347.47707 -238.252233)
			(xy 347.47707 -238.198935) (xy 347.485013 -238.146231) (xy 347.500723 -238.095301) (xy 347.523849 -238.04728)
			(xy 347.553873 -238.003243) (xy 347.590125 -237.964172) (xy 347.631796 -237.930941) (xy 347.677954 -237.904292)
			(xy 347.727568 -237.88482) (xy 347.77953 -237.87296) (xy 347.83268 -237.868977) (xy 347.88583 -237.87296)
			(xy 347.937792 -237.88482) (xy 347.987406 -237.904292) (xy 348.033564 -237.930941) (xy 348.075235 -237.964172)
			(xy 348.111487 -238.003243) (xy 348.141511 -238.04728) (xy 348.164637 -238.095301) (xy 348.180347 -238.146231)
			(xy 348.18829 -238.198935) (xy 348.188788 -238.225584) (xy 348.18829 -238.252233) (xy 348.180347 -238.304937)
			(xy 348.164637 -238.355867) (xy 348.141511 -238.403888) (xy 348.111487 -238.447925) (xy 348.075235 -238.486996)
			(xy 348.033564 -238.520227) (xy 347.987406 -238.546876) (xy 347.937792 -238.566348) (xy 347.88583 -238.578208)
			(xy 347.83268 -238.582192) (xy 347.77953 -238.578208) (xy 347.727568 -238.566348) (xy 347.677954 -238.546876)
			(xy 347.631796 -238.520227) (xy 347.590125 -238.486996) (xy 347.553873 -238.447925) (xy 347.523849 -238.403888)
			(xy 347.500723 -238.355867) (xy 347.485013 -238.304937) (xy 347.47707 -238.252233) (xy 347.24849 -238.252233)
			(xy 347.240547 -238.304937) (xy 347.224837 -238.355867) (xy 347.201711 -238.403888) (xy 347.171687 -238.447925)
			(xy 347.135435 -238.486996) (xy 347.093764 -238.520227) (xy 347.047606 -238.546876) (xy 346.997992 -238.566348)
			(xy 346.94603 -238.578208) (xy 346.89288 -238.582192) (xy 346.83973 -238.578208) (xy 346.787768 -238.566348)
			(xy 346.738154 -238.546876) (xy 346.691996 -238.520227) (xy 346.650325 -238.486996) (xy 346.614073 -238.447925)
			(xy 346.584049 -238.403888) (xy 346.560923 -238.355867) (xy 346.545213 -238.304937) (xy 346.53727 -238.252233)
			(xy 346.308944 -238.252233) (xy 346.301001 -238.304937) (xy 346.285291 -238.355867) (xy 346.262165 -238.403888)
			(xy 346.232141 -238.447925) (xy 346.195889 -238.486996) (xy 346.154218 -238.520227) (xy 346.10806 -238.546876)
			(xy 346.058446 -238.566348) (xy 346.006484 -238.578208) (xy 345.953334 -238.582192) (xy 345.900184 -238.578208)
			(xy 345.848222 -238.566348) (xy 345.798608 -238.546876) (xy 345.75245 -238.520227) (xy 345.710779 -238.486996)
			(xy 345.674527 -238.447925) (xy 345.644503 -238.403888) (xy 345.621377 -238.355867) (xy 345.605667 -238.304937)
			(xy 345.597724 -238.252233) (xy 345.36889 -238.252233) (xy 345.360947 -238.304937) (xy 345.345237 -238.355867)
			(xy 345.322111 -238.403888) (xy 345.292087 -238.447925) (xy 345.255835 -238.486996) (xy 345.214164 -238.520227)
			(xy 345.168006 -238.546876) (xy 345.118392 -238.566348) (xy 345.06643 -238.578208) (xy 345.01328 -238.582192)
			(xy 344.96013 -238.578208) (xy 344.908168 -238.566348) (xy 344.858554 -238.546876) (xy 344.812396 -238.520227)
			(xy 344.770725 -238.486996) (xy 344.734473 -238.447925) (xy 344.704449 -238.403888) (xy 344.681323 -238.355867)
			(xy 344.665613 -238.304937) (xy 344.65767 -238.252233) (xy 344.42909 -238.252233) (xy 344.421147 -238.304937)
			(xy 344.405437 -238.355867) (xy 344.382311 -238.403888) (xy 344.352287 -238.447925) (xy 344.316035 -238.486996)
			(xy 344.274364 -238.520227) (xy 344.228206 -238.546876) (xy 344.178592 -238.566348) (xy 344.12663 -238.578208)
			(xy 344.07348 -238.582192) (xy 344.02033 -238.578208) (xy 343.968368 -238.566348) (xy 343.918754 -238.546876)
			(xy 343.872596 -238.520227) (xy 343.830925 -238.486996) (xy 343.794673 -238.447925) (xy 343.764649 -238.403888)
			(xy 343.741523 -238.355867) (xy 343.725813 -238.304937) (xy 343.71787 -238.252233) (xy 343.48929 -238.252233)
			(xy 343.481347 -238.304937) (xy 343.465637 -238.355867) (xy 343.442511 -238.403888) (xy 343.412487 -238.447925)
			(xy 343.376235 -238.486996) (xy 343.334564 -238.520227) (xy 343.288406 -238.546876) (xy 343.238792 -238.566348)
			(xy 343.18683 -238.578208) (xy 343.13368 -238.582192) (xy 343.08053 -238.578208) (xy 343.028568 -238.566348)
			(xy 342.978954 -238.546876) (xy 342.932796 -238.520227) (xy 342.891125 -238.486996) (xy 342.854873 -238.447925)
			(xy 342.824849 -238.403888) (xy 342.801723 -238.355867) (xy 342.786013 -238.304937) (xy 342.77807 -238.252233)
			(xy 342.54949 -238.252233) (xy 342.541547 -238.304937) (xy 342.525837 -238.355867) (xy 342.502711 -238.403888)
			(xy 342.472687 -238.447925) (xy 342.436435 -238.486996) (xy 342.394764 -238.520227) (xy 342.348606 -238.546876)
			(xy 342.298992 -238.566348) (xy 342.24703 -238.578208) (xy 342.19388 -238.582192) (xy 342.14073 -238.578208)
			(xy 342.088768 -238.566348) (xy 342.039154 -238.546876) (xy 341.992996 -238.520227) (xy 341.951325 -238.486996)
			(xy 341.915073 -238.447925) (xy 341.885049 -238.403888) (xy 341.861923 -238.355867) (xy 341.846213 -238.304937)
			(xy 341.83827 -238.252233) (xy 341.60969 -238.252233) (xy 341.601747 -238.304937) (xy 341.586037 -238.355867)
			(xy 341.562911 -238.403888) (xy 341.532887 -238.447925) (xy 341.496635 -238.486996) (xy 341.454964 -238.520227)
			(xy 341.408806 -238.546876) (xy 341.359192 -238.566348) (xy 341.30723 -238.578208) (xy 341.25408 -238.582192)
			(xy 341.20093 -238.578208) (xy 341.148968 -238.566348) (xy 341.099354 -238.546876) (xy 341.053196 -238.520227)
			(xy 341.011525 -238.486996) (xy 340.975273 -238.447925) (xy 340.945249 -238.403888) (xy 340.922123 -238.355867)
			(xy 340.906413 -238.304937) (xy 340.89847 -238.252233) (xy 340.66989 -238.252233) (xy 340.661947 -238.304937)
			(xy 340.646237 -238.355867) (xy 340.623111 -238.403888) (xy 340.593087 -238.447925) (xy 340.556835 -238.486996)
			(xy 340.515164 -238.520227) (xy 340.469006 -238.546876) (xy 340.419392 -238.566348) (xy 340.36743 -238.578208)
			(xy 340.31428 -238.582192) (xy 340.26113 -238.578208) (xy 340.209168 -238.566348) (xy 340.159554 -238.546876)
			(xy 340.113396 -238.520227) (xy 340.071725 -238.486996) (xy 340.035473 -238.447925) (xy 340.005449 -238.403888)
			(xy 339.982323 -238.355867) (xy 339.966613 -238.304937) (xy 339.95867 -238.252233) (xy 339.729392 -238.252233)
			(xy 339.727353 -238.279213) (xy 339.715288 -238.33161) (xy 339.695485 -238.381598) (xy 339.668393 -238.428042)
			(xy 339.634628 -238.469886) (xy 339.594958 -238.50618) (xy 339.550283 -238.536099) (xy 339.501618 -238.558962)
			(xy 339.45007 -238.574252) (xy 339.423502 -238.57839) (xy 339.37956 -238.584486) (xy 339.37956 -239.066049)
			(xy 339.489024 -239.066049) (xy 339.489024 -239.012751) (xy 339.496967 -238.960047) (xy 339.512677 -238.909117)
			(xy 339.535803 -238.861096) (xy 339.565827 -238.817059) (xy 339.602079 -238.777988) (xy 339.64375 -238.744757)
			(xy 339.689908 -238.718108) (xy 339.739522 -238.698636) (xy 339.791484 -238.686776) (xy 339.844634 -238.682793)
			(xy 339.897784 -238.686776) (xy 339.949746 -238.698636) (xy 339.99936 -238.718108) (xy 340.045518 -238.744757)
			(xy 340.087189 -238.777988) (xy 340.123441 -238.817059) (xy 340.153465 -238.861096) (xy 340.176591 -238.909117)
			(xy 340.192301 -238.960047) (xy 340.200244 -239.012751) (xy 340.200742 -239.0394) (xy 340.200244 -239.066049)
			(xy 340.428824 -239.066049) (xy 340.428824 -239.012751) (xy 340.436767 -238.960047) (xy 340.452477 -238.909117)
			(xy 340.475603 -238.861096) (xy 340.505627 -238.817059) (xy 340.541879 -238.777988) (xy 340.58355 -238.744757)
			(xy 340.629708 -238.718108) (xy 340.679322 -238.698636) (xy 340.731284 -238.686776) (xy 340.784434 -238.682793)
			(xy 340.837584 -238.686776) (xy 340.889546 -238.698636) (xy 340.93916 -238.718108) (xy 340.985318 -238.744757)
			(xy 341.026989 -238.777988) (xy 341.063241 -238.817059) (xy 341.093265 -238.861096) (xy 341.116391 -238.909117)
			(xy 341.132101 -238.960047) (xy 341.140044 -239.012751) (xy 341.140542 -239.0394) (xy 341.140044 -239.066049)
			(xy 341.368624 -239.066049) (xy 341.368624 -239.012751) (xy 341.376567 -238.960047) (xy 341.392277 -238.909117)
			(xy 341.415403 -238.861096) (xy 341.445427 -238.817059) (xy 341.481679 -238.777988) (xy 341.52335 -238.744757)
			(xy 341.569508 -238.718108) (xy 341.619122 -238.698636) (xy 341.671084 -238.686776) (xy 341.724234 -238.682793)
			(xy 341.777384 -238.686776) (xy 341.829346 -238.698636) (xy 341.87896 -238.718108) (xy 341.925118 -238.744757)
			(xy 341.966789 -238.777988) (xy 342.003041 -238.817059) (xy 342.033065 -238.861096) (xy 342.056191 -238.909117)
			(xy 342.071901 -238.960047) (xy 342.079844 -239.012751) (xy 342.080342 -239.0394) (xy 342.079844 -239.066049)
			(xy 342.30817 -239.066049) (xy 342.30817 -239.012751) (xy 342.316113 -238.960047) (xy 342.331823 -238.909117)
			(xy 342.354949 -238.861096) (xy 342.384973 -238.817059) (xy 342.421225 -238.777988) (xy 342.462896 -238.744757)
			(xy 342.509054 -238.718108) (xy 342.558668 -238.698636) (xy 342.61063 -238.686776) (xy 342.66378 -238.682793)
			(xy 342.71693 -238.686776) (xy 342.768892 -238.698636) (xy 342.818506 -238.718108) (xy 342.864664 -238.744757)
			(xy 342.906335 -238.777988) (xy 342.942587 -238.817059) (xy 342.972611 -238.861096) (xy 342.995737 -238.909117)
			(xy 343.011447 -238.960047) (xy 343.01939 -239.012751) (xy 343.019888 -239.0394) (xy 343.01939 -239.066049)
			(xy 343.248224 -239.066049) (xy 343.248224 -239.012751) (xy 343.256167 -238.960047) (xy 343.271877 -238.909117)
			(xy 343.295003 -238.861096) (xy 343.325027 -238.817059) (xy 343.361279 -238.777988) (xy 343.40295 -238.744757)
			(xy 343.449108 -238.718108) (xy 343.498722 -238.698636) (xy 343.550684 -238.686776) (xy 343.603834 -238.682793)
			(xy 343.656984 -238.686776) (xy 343.708946 -238.698636) (xy 343.75856 -238.718108) (xy 343.804718 -238.744757)
			(xy 343.846389 -238.777988) (xy 343.882641 -238.817059) (xy 343.912665 -238.861096) (xy 343.935791 -238.909117)
			(xy 343.951501 -238.960047) (xy 343.959444 -239.012751) (xy 343.959942 -239.0394) (xy 343.959444 -239.066049)
			(xy 344.188024 -239.066049) (xy 344.188024 -239.012751) (xy 344.195967 -238.960047) (xy 344.211677 -238.909117)
			(xy 344.234803 -238.861096) (xy 344.264827 -238.817059) (xy 344.301079 -238.777988) (xy 344.34275 -238.744757)
			(xy 344.388908 -238.718108) (xy 344.438522 -238.698636) (xy 344.490484 -238.686776) (xy 344.543634 -238.682793)
			(xy 344.596784 -238.686776) (xy 344.648746 -238.698636) (xy 344.69836 -238.718108) (xy 344.744518 -238.744757)
			(xy 344.786189 -238.777988) (xy 344.822441 -238.817059) (xy 344.852465 -238.861096) (xy 344.875591 -238.909117)
			(xy 344.891301 -238.960047) (xy 344.899244 -239.012751) (xy 344.899742 -239.0394) (xy 344.899244 -239.066049)
			(xy 345.127824 -239.066049) (xy 345.127824 -239.012751) (xy 345.135767 -238.960047) (xy 345.151477 -238.909117)
			(xy 345.174603 -238.861096) (xy 345.204627 -238.817059) (xy 345.240879 -238.777988) (xy 345.28255 -238.744757)
			(xy 345.328708 -238.718108) (xy 345.378322 -238.698636) (xy 345.430284 -238.686776) (xy 345.483434 -238.682793)
			(xy 345.536584 -238.686776) (xy 345.588546 -238.698636) (xy 345.63816 -238.718108) (xy 345.684318 -238.744757)
			(xy 345.725989 -238.777988) (xy 345.762241 -238.817059) (xy 345.792265 -238.861096) (xy 345.815391 -238.909117)
			(xy 345.831101 -238.960047) (xy 345.839044 -239.012751) (xy 345.839542 -239.0394) (xy 345.839044 -239.066049)
			(xy 346.067624 -239.066049) (xy 346.067624 -239.012751) (xy 346.075567 -238.960047) (xy 346.091277 -238.909117)
			(xy 346.114403 -238.861096) (xy 346.144427 -238.817059) (xy 346.180679 -238.777988) (xy 346.22235 -238.744757)
			(xy 346.268508 -238.718108) (xy 346.318122 -238.698636) (xy 346.370084 -238.686776) (xy 346.423234 -238.682793)
			(xy 346.476384 -238.686776) (xy 346.528346 -238.698636) (xy 346.57796 -238.718108) (xy 346.624118 -238.744757)
			(xy 346.665789 -238.777988) (xy 346.702041 -238.817059) (xy 346.732065 -238.861096) (xy 346.755191 -238.909117)
			(xy 346.770901 -238.960047) (xy 346.778844 -239.012751) (xy 346.779342 -239.0394) (xy 346.778844 -239.066049)
			(xy 346.770901 -239.118753) (xy 346.755191 -239.169683) (xy 346.732065 -239.217704) (xy 346.702041 -239.261741)
			(xy 346.665789 -239.300812) (xy 346.624118 -239.334043) (xy 346.57796 -239.360692) (xy 346.528346 -239.380164)
			(xy 346.476384 -239.392024) (xy 346.423234 -239.396008) (xy 346.370084 -239.392024) (xy 346.318122 -239.380164)
			(xy 346.268508 -239.360692) (xy 346.22235 -239.334043) (xy 346.180679 -239.300812) (xy 346.144427 -239.261741)
			(xy 346.114403 -239.217704) (xy 346.091277 -239.169683) (xy 346.075567 -239.118753) (xy 346.067624 -239.066049)
			(xy 345.839044 -239.066049) (xy 345.831101 -239.118753) (xy 345.815391 -239.169683) (xy 345.792265 -239.217704)
			(xy 345.762241 -239.261741) (xy 345.725989 -239.300812) (xy 345.684318 -239.334043) (xy 345.63816 -239.360692)
			(xy 345.588546 -239.380164) (xy 345.536584 -239.392024) (xy 345.483434 -239.396008) (xy 345.430284 -239.392024)
			(xy 345.378322 -239.380164) (xy 345.328708 -239.360692) (xy 345.28255 -239.334043) (xy 345.240879 -239.300812)
			(xy 345.204627 -239.261741) (xy 345.174603 -239.217704) (xy 345.151477 -239.169683) (xy 345.135767 -239.118753)
			(xy 345.127824 -239.066049) (xy 344.899244 -239.066049) (xy 344.891301 -239.118753) (xy 344.875591 -239.169683)
			(xy 344.852465 -239.217704) (xy 344.822441 -239.261741) (xy 344.786189 -239.300812) (xy 344.744518 -239.334043)
			(xy 344.69836 -239.360692) (xy 344.648746 -239.380164) (xy 344.596784 -239.392024) (xy 344.543634 -239.396008)
			(xy 344.490484 -239.392024) (xy 344.438522 -239.380164) (xy 344.388908 -239.360692) (xy 344.34275 -239.334043)
			(xy 344.301079 -239.300812) (xy 344.264827 -239.261741) (xy 344.234803 -239.217704) (xy 344.211677 -239.169683)
			(xy 344.195967 -239.118753) (xy 344.188024 -239.066049) (xy 343.959444 -239.066049) (xy 343.951501 -239.118753)
			(xy 343.935791 -239.169683) (xy 343.912665 -239.217704) (xy 343.882641 -239.261741) (xy 343.846389 -239.300812)
			(xy 343.804718 -239.334043) (xy 343.75856 -239.360692) (xy 343.708946 -239.380164) (xy 343.656984 -239.392024)
			(xy 343.603834 -239.396008) (xy 343.550684 -239.392024) (xy 343.498722 -239.380164) (xy 343.449108 -239.360692)
			(xy 343.40295 -239.334043) (xy 343.361279 -239.300812) (xy 343.325027 -239.261741) (xy 343.295003 -239.217704)
			(xy 343.271877 -239.169683) (xy 343.256167 -239.118753) (xy 343.248224 -239.066049) (xy 343.01939 -239.066049)
			(xy 343.011447 -239.118753) (xy 342.995737 -239.169683) (xy 342.972611 -239.217704) (xy 342.942587 -239.261741)
			(xy 342.906335 -239.300812) (xy 342.864664 -239.334043) (xy 342.818506 -239.360692) (xy 342.768892 -239.380164)
			(xy 342.71693 -239.392024) (xy 342.66378 -239.396008) (xy 342.61063 -239.392024) (xy 342.558668 -239.380164)
			(xy 342.509054 -239.360692) (xy 342.462896 -239.334043) (xy 342.421225 -239.300812) (xy 342.384973 -239.261741)
			(xy 342.354949 -239.217704) (xy 342.331823 -239.169683) (xy 342.316113 -239.118753) (xy 342.30817 -239.066049)
			(xy 342.079844 -239.066049) (xy 342.071901 -239.118753) (xy 342.056191 -239.169683) (xy 342.033065 -239.217704)
			(xy 342.003041 -239.261741) (xy 341.966789 -239.300812) (xy 341.925118 -239.334043) (xy 341.87896 -239.360692)
			(xy 341.829346 -239.380164) (xy 341.777384 -239.392024) (xy 341.724234 -239.396008) (xy 341.671084 -239.392024)
			(xy 341.619122 -239.380164) (xy 341.569508 -239.360692) (xy 341.52335 -239.334043) (xy 341.481679 -239.300812)
			(xy 341.445427 -239.261741) (xy 341.415403 -239.217704) (xy 341.392277 -239.169683) (xy 341.376567 -239.118753)
			(xy 341.368624 -239.066049) (xy 341.140044 -239.066049) (xy 341.132101 -239.118753) (xy 341.116391 -239.169683)
			(xy 341.093265 -239.217704) (xy 341.063241 -239.261741) (xy 341.026989 -239.300812) (xy 340.985318 -239.334043)
			(xy 340.93916 -239.360692) (xy 340.889546 -239.380164) (xy 340.837584 -239.392024) (xy 340.784434 -239.396008)
			(xy 340.731284 -239.392024) (xy 340.679322 -239.380164) (xy 340.629708 -239.360692) (xy 340.58355 -239.334043)
			(xy 340.541879 -239.300812) (xy 340.505627 -239.261741) (xy 340.475603 -239.217704) (xy 340.452477 -239.169683)
			(xy 340.436767 -239.118753) (xy 340.428824 -239.066049) (xy 340.200244 -239.066049) (xy 340.192301 -239.118753)
			(xy 340.176591 -239.169683) (xy 340.153465 -239.217704) (xy 340.123441 -239.261741) (xy 340.087189 -239.300812)
			(xy 340.045518 -239.334043) (xy 339.99936 -239.360692) (xy 339.949746 -239.380164) (xy 339.897784 -239.392024)
			(xy 339.844634 -239.396008) (xy 339.791484 -239.392024) (xy 339.739522 -239.380164) (xy 339.689908 -239.360692)
			(xy 339.64375 -239.334043) (xy 339.602079 -239.300812) (xy 339.565827 -239.261741) (xy 339.535803 -239.217704)
			(xy 339.512677 -239.169683) (xy 339.496967 -239.118753) (xy 339.489024 -239.066049) (xy 339.37956 -239.066049)
			(xy 339.37956 -239.494314) (xy 339.423502 -239.50041) (xy 339.450052 -239.504592) (xy 339.501573 -239.519901)
			(xy 339.550208 -239.542777) (xy 339.594854 -239.572701) (xy 339.634497 -239.608993) (xy 339.668237 -239.650829)
			(xy 339.695309 -239.69726) (xy 339.715097 -239.747231) (xy 339.727152 -239.799608) (xy 339.731201 -239.853202)
			(xy 339.729186 -239.879865) (xy 339.95867 -239.879865) (xy 339.95867 -239.826567) (xy 339.966613 -239.773863)
			(xy 339.982323 -239.722933) (xy 340.005449 -239.674912) (xy 340.035473 -239.630875) (xy 340.071725 -239.591804)
			(xy 340.113396 -239.558573) (xy 340.159554 -239.531924) (xy 340.209168 -239.512452) (xy 340.26113 -239.500592)
			(xy 340.31428 -239.496609) (xy 340.36743 -239.500592) (xy 340.419392 -239.512452) (xy 340.469006 -239.531924)
			(xy 340.515164 -239.558573) (xy 340.556835 -239.591804) (xy 340.593087 -239.630875) (xy 340.623111 -239.674912)
			(xy 340.646237 -239.722933) (xy 340.661947 -239.773863) (xy 340.66989 -239.826567) (xy 340.670388 -239.853216)
			(xy 340.66989 -239.879865) (xy 340.89847 -239.879865) (xy 340.89847 -239.826567) (xy 340.906413 -239.773863)
			(xy 340.922123 -239.722933) (xy 340.945249 -239.674912) (xy 340.975273 -239.630875) (xy 341.011525 -239.591804)
			(xy 341.053196 -239.558573) (xy 341.099354 -239.531924) (xy 341.148968 -239.512452) (xy 341.20093 -239.500592)
			(xy 341.25408 -239.496609) (xy 341.30723 -239.500592) (xy 341.359192 -239.512452) (xy 341.408806 -239.531924)
			(xy 341.454964 -239.558573) (xy 341.496635 -239.591804) (xy 341.532887 -239.630875) (xy 341.562911 -239.674912)
			(xy 341.586037 -239.722933) (xy 341.601747 -239.773863) (xy 341.60969 -239.826567) (xy 341.610188 -239.853216)
			(xy 341.60969 -239.879865) (xy 341.83827 -239.879865) (xy 341.83827 -239.826567) (xy 341.846213 -239.773863)
			(xy 341.861923 -239.722933) (xy 341.885049 -239.674912) (xy 341.915073 -239.630875) (xy 341.951325 -239.591804)
			(xy 341.992996 -239.558573) (xy 342.039154 -239.531924) (xy 342.088768 -239.512452) (xy 342.14073 -239.500592)
			(xy 342.19388 -239.496609) (xy 342.24703 -239.500592) (xy 342.298992 -239.512452) (xy 342.348606 -239.531924)
			(xy 342.394764 -239.558573) (xy 342.436435 -239.591804) (xy 342.472687 -239.630875) (xy 342.502711 -239.674912)
			(xy 342.525837 -239.722933) (xy 342.541547 -239.773863) (xy 342.54949 -239.826567) (xy 342.549988 -239.853216)
			(xy 342.54949 -239.879865) (xy 342.77807 -239.879865) (xy 342.77807 -239.826567) (xy 342.786013 -239.773863)
			(xy 342.801723 -239.722933) (xy 342.824849 -239.674912) (xy 342.854873 -239.630875) (xy 342.891125 -239.591804)
			(xy 342.932796 -239.558573) (xy 342.978954 -239.531924) (xy 343.028568 -239.512452) (xy 343.08053 -239.500592)
			(xy 343.13368 -239.496609) (xy 343.18683 -239.500592) (xy 343.238792 -239.512452) (xy 343.288406 -239.531924)
			(xy 343.334564 -239.558573) (xy 343.376235 -239.591804) (xy 343.412487 -239.630875) (xy 343.442511 -239.674912)
			(xy 343.465637 -239.722933) (xy 343.481347 -239.773863) (xy 343.48929 -239.826567) (xy 343.489788 -239.853216)
			(xy 343.48929 -239.879865) (xy 343.71787 -239.879865) (xy 343.71787 -239.826567) (xy 343.725813 -239.773863)
			(xy 343.741523 -239.722933) (xy 343.764649 -239.674912) (xy 343.794673 -239.630875) (xy 343.830925 -239.591804)
			(xy 343.872596 -239.558573) (xy 343.918754 -239.531924) (xy 343.968368 -239.512452) (xy 344.02033 -239.500592)
			(xy 344.07348 -239.496609) (xy 344.12663 -239.500592) (xy 344.178592 -239.512452) (xy 344.228206 -239.531924)
			(xy 344.274364 -239.558573) (xy 344.316035 -239.591804) (xy 344.352287 -239.630875) (xy 344.382311 -239.674912)
			(xy 344.405437 -239.722933) (xy 344.421147 -239.773863) (xy 344.42909 -239.826567) (xy 344.429588 -239.853216)
			(xy 344.42909 -239.879865) (xy 344.657924 -239.879865) (xy 344.657924 -239.826567) (xy 344.665867 -239.773863)
			(xy 344.681577 -239.722933) (xy 344.704703 -239.674912) (xy 344.734727 -239.630875) (xy 344.770979 -239.591804)
			(xy 344.81265 -239.558573) (xy 344.858808 -239.531924) (xy 344.908422 -239.512452) (xy 344.960384 -239.500592)
			(xy 345.013534 -239.496609) (xy 345.066684 -239.500592) (xy 345.118646 -239.512452) (xy 345.16826 -239.531924)
			(xy 345.214418 -239.558573) (xy 345.256089 -239.591804) (xy 345.292341 -239.630875) (xy 345.322365 -239.674912)
			(xy 345.345491 -239.722933) (xy 345.361201 -239.773863) (xy 345.369144 -239.826567) (xy 345.369642 -239.853216)
			(xy 345.369144 -239.879865) (xy 345.59747 -239.879865) (xy 345.59747 -239.826567) (xy 345.605413 -239.773863)
			(xy 345.621123 -239.722933) (xy 345.644249 -239.674912) (xy 345.674273 -239.630875) (xy 345.710525 -239.591804)
			(xy 345.752196 -239.558573) (xy 345.798354 -239.531924) (xy 345.847968 -239.512452) (xy 345.89993 -239.500592)
			(xy 345.95308 -239.496609) (xy 346.00623 -239.500592) (xy 346.058192 -239.512452) (xy 346.107806 -239.531924)
			(xy 346.153964 -239.558573) (xy 346.195635 -239.591804) (xy 346.231887 -239.630875) (xy 346.261911 -239.674912)
			(xy 346.285037 -239.722933) (xy 346.300747 -239.773863) (xy 346.30869 -239.826567) (xy 346.309188 -239.853216)
			(xy 346.30869 -239.879865) (xy 346.53727 -239.879865) (xy 346.53727 -239.826567) (xy 346.545213 -239.773863)
			(xy 346.560923 -239.722933) (xy 346.584049 -239.674912) (xy 346.614073 -239.630875) (xy 346.650325 -239.591804)
			(xy 346.691996 -239.558573) (xy 346.738154 -239.531924) (xy 346.787768 -239.512452) (xy 346.83973 -239.500592)
			(xy 346.89288 -239.496609) (xy 346.94603 -239.500592) (xy 346.997992 -239.512452) (xy 347.047606 -239.531924)
			(xy 347.093764 -239.558573) (xy 347.135435 -239.591804) (xy 347.171687 -239.630875) (xy 347.201711 -239.674912)
			(xy 347.224837 -239.722933) (xy 347.240547 -239.773863) (xy 347.24849 -239.826567) (xy 347.248988 -239.853216)
			(xy 347.24849 -239.879865) (xy 347.240547 -239.932569) (xy 347.224837 -239.983499) (xy 347.201711 -240.03152)
			(xy 347.171687 -240.075557) (xy 347.135435 -240.114628) (xy 347.093764 -240.147859) (xy 347.047606 -240.174508)
			(xy 346.997992 -240.19398) (xy 346.94603 -240.20584) (xy 346.89288 -240.209824) (xy 346.83973 -240.20584)
			(xy 346.787768 -240.19398) (xy 346.738154 -240.174508) (xy 346.691996 -240.147859) (xy 346.650325 -240.114628)
			(xy 346.614073 -240.075557) (xy 346.584049 -240.03152) (xy 346.560923 -239.983499) (xy 346.545213 -239.932569)
			(xy 346.53727 -239.879865) (xy 346.30869 -239.879865) (xy 346.300747 -239.932569) (xy 346.285037 -239.983499)
			(xy 346.261911 -240.03152) (xy 346.231887 -240.075557) (xy 346.195635 -240.114628) (xy 346.153964 -240.147859)
			(xy 346.107806 -240.174508) (xy 346.058192 -240.19398) (xy 346.00623 -240.20584) (xy 345.95308 -240.209824)
			(xy 345.89993 -240.20584) (xy 345.847968 -240.19398) (xy 345.798354 -240.174508) (xy 345.752196 -240.147859)
			(xy 345.710525 -240.114628) (xy 345.674273 -240.075557) (xy 345.644249 -240.03152) (xy 345.621123 -239.983499)
			(xy 345.605413 -239.932569) (xy 345.59747 -239.879865) (xy 345.369144 -239.879865) (xy 345.361201 -239.932569)
			(xy 345.345491 -239.983499) (xy 345.322365 -240.03152) (xy 345.292341 -240.075557) (xy 345.256089 -240.114628)
			(xy 345.214418 -240.147859) (xy 345.16826 -240.174508) (xy 345.118646 -240.19398) (xy 345.066684 -240.20584)
			(xy 345.013534 -240.209824) (xy 344.960384 -240.20584) (xy 344.908422 -240.19398) (xy 344.858808 -240.174508)
			(xy 344.81265 -240.147859) (xy 344.770979 -240.114628) (xy 344.734727 -240.075557) (xy 344.704703 -240.03152)
			(xy 344.681577 -239.983499) (xy 344.665867 -239.932569) (xy 344.657924 -239.879865) (xy 344.42909 -239.879865)
			(xy 344.421147 -239.932569) (xy 344.405437 -239.983499) (xy 344.382311 -240.03152) (xy 344.352287 -240.075557)
			(xy 344.316035 -240.114628) (xy 344.274364 -240.147859) (xy 344.228206 -240.174508) (xy 344.178592 -240.19398)
			(xy 344.12663 -240.20584) (xy 344.07348 -240.209824) (xy 344.02033 -240.20584) (xy 343.968368 -240.19398)
			(xy 343.918754 -240.174508) (xy 343.872596 -240.147859) (xy 343.830925 -240.114628) (xy 343.794673 -240.075557)
			(xy 343.764649 -240.03152) (xy 343.741523 -239.983499) (xy 343.725813 -239.932569) (xy 343.71787 -239.879865)
			(xy 343.48929 -239.879865) (xy 343.481347 -239.932569) (xy 343.465637 -239.983499) (xy 343.442511 -240.03152)
			(xy 343.412487 -240.075557) (xy 343.376235 -240.114628) (xy 343.334564 -240.147859) (xy 343.288406 -240.174508)
			(xy 343.238792 -240.19398) (xy 343.18683 -240.20584) (xy 343.13368 -240.209824) (xy 343.08053 -240.20584)
			(xy 343.028568 -240.19398) (xy 342.978954 -240.174508) (xy 342.932796 -240.147859) (xy 342.891125 -240.114628)
			(xy 342.854873 -240.075557) (xy 342.824849 -240.03152) (xy 342.801723 -239.983499) (xy 342.786013 -239.932569)
			(xy 342.77807 -239.879865) (xy 342.54949 -239.879865) (xy 342.541547 -239.932569) (xy 342.525837 -239.983499)
			(xy 342.502711 -240.03152) (xy 342.472687 -240.075557) (xy 342.436435 -240.114628) (xy 342.394764 -240.147859)
			(xy 342.348606 -240.174508) (xy 342.298992 -240.19398) (xy 342.24703 -240.20584) (xy 342.19388 -240.209824)
			(xy 342.14073 -240.20584) (xy 342.088768 -240.19398) (xy 342.039154 -240.174508) (xy 341.992996 -240.147859)
			(xy 341.951325 -240.114628) (xy 341.915073 -240.075557) (xy 341.885049 -240.03152) (xy 341.861923 -239.983499)
			(xy 341.846213 -239.932569) (xy 341.83827 -239.879865) (xy 341.60969 -239.879865) (xy 341.601747 -239.932569)
			(xy 341.586037 -239.983499) (xy 341.562911 -240.03152) (xy 341.532887 -240.075557) (xy 341.496635 -240.114628)
			(xy 341.454964 -240.147859) (xy 341.408806 -240.174508) (xy 341.359192 -240.19398) (xy 341.30723 -240.20584)
			(xy 341.25408 -240.209824) (xy 341.20093 -240.20584) (xy 341.148968 -240.19398) (xy 341.099354 -240.174508)
			(xy 341.053196 -240.147859) (xy 341.011525 -240.114628) (xy 340.975273 -240.075557) (xy 340.945249 -240.03152)
			(xy 340.922123 -239.983499) (xy 340.906413 -239.932569) (xy 340.89847 -239.879865) (xy 340.66989 -239.879865)
			(xy 340.661947 -239.932569) (xy 340.646237 -239.983499) (xy 340.623111 -240.03152) (xy 340.593087 -240.075557)
			(xy 340.556835 -240.114628) (xy 340.515164 -240.147859) (xy 340.469006 -240.174508) (xy 340.419392 -240.19398)
			(xy 340.36743 -240.20584) (xy 340.31428 -240.209824) (xy 340.26113 -240.20584) (xy 340.209168 -240.19398)
			(xy 340.159554 -240.174508) (xy 340.113396 -240.147859) (xy 340.071725 -240.114628) (xy 340.035473 -240.075557)
			(xy 340.005449 -240.03152) (xy 339.982323 -239.983499) (xy 339.966613 -239.932569) (xy 339.95867 -239.879865)
			(xy 339.729186 -239.879865) (xy 339.727151 -239.906796) (xy 339.715095 -239.959173) (xy 339.695307 -240.009144)
			(xy 339.668235 -240.055574) (xy 339.634494 -240.09741) (xy 339.59485 -240.133702) (xy 339.550204 -240.163625)
			(xy 339.501568 -240.1865) (xy 339.450048 -240.201809) (xy 339.423502 -240.206022) (xy 339.37956 -240.212118)
			(xy 339.37956 -240.693935) (xy 339.489024 -240.693935) (xy 339.489024 -240.640637) (xy 339.496967 -240.587933)
			(xy 339.512677 -240.537003) (xy 339.535803 -240.488982) (xy 339.565827 -240.444945) (xy 339.602079 -240.405874)
			(xy 339.64375 -240.372643) (xy 339.689908 -240.345994) (xy 339.739522 -240.326522) (xy 339.791484 -240.314662)
			(xy 339.844634 -240.310679) (xy 339.897784 -240.314662) (xy 339.949746 -240.326522) (xy 339.99936 -240.345994)
			(xy 340.045518 -240.372643) (xy 340.087189 -240.405874) (xy 340.123441 -240.444945) (xy 340.153465 -240.488982)
			(xy 340.176591 -240.537003) (xy 340.192301 -240.587933) (xy 340.200244 -240.640637) (xy 340.200742 -240.667286)
			(xy 340.200244 -240.693935) (xy 340.428824 -240.693935) (xy 340.428824 -240.640637) (xy 340.436767 -240.587933)
			(xy 340.452477 -240.537003) (xy 340.475603 -240.488982) (xy 340.505627 -240.444945) (xy 340.541879 -240.405874)
			(xy 340.58355 -240.372643) (xy 340.629708 -240.345994) (xy 340.679322 -240.326522) (xy 340.731284 -240.314662)
			(xy 340.784434 -240.310679) (xy 340.837584 -240.314662) (xy 340.889546 -240.326522) (xy 340.93916 -240.345994)
			(xy 340.985318 -240.372643) (xy 341.026989 -240.405874) (xy 341.063241 -240.444945) (xy 341.093265 -240.488982)
			(xy 341.116391 -240.537003) (xy 341.132101 -240.587933) (xy 341.140044 -240.640637) (xy 341.140542 -240.667286)
			(xy 341.140044 -240.693935) (xy 341.368624 -240.693935) (xy 341.368624 -240.640637) (xy 341.376567 -240.587933)
			(xy 341.392277 -240.537003) (xy 341.415403 -240.488982) (xy 341.445427 -240.444945) (xy 341.481679 -240.405874)
			(xy 341.52335 -240.372643) (xy 341.569508 -240.345994) (xy 341.619122 -240.326522) (xy 341.671084 -240.314662)
			(xy 341.724234 -240.310679) (xy 341.777384 -240.314662) (xy 341.829346 -240.326522) (xy 341.87896 -240.345994)
			(xy 341.925118 -240.372643) (xy 341.966789 -240.405874) (xy 342.003041 -240.444945) (xy 342.033065 -240.488982)
			(xy 342.056191 -240.537003) (xy 342.071901 -240.587933) (xy 342.079844 -240.640637) (xy 342.080342 -240.667286)
			(xy 342.079844 -240.693935) (xy 342.308424 -240.693935) (xy 342.308424 -240.640637) (xy 342.316367 -240.587933)
			(xy 342.332077 -240.537003) (xy 342.355203 -240.488982) (xy 342.385227 -240.444945) (xy 342.421479 -240.405874)
			(xy 342.46315 -240.372643) (xy 342.509308 -240.345994) (xy 342.558922 -240.326522) (xy 342.610884 -240.314662)
			(xy 342.664034 -240.310679) (xy 342.717184 -240.314662) (xy 342.769146 -240.326522) (xy 342.81876 -240.345994)
			(xy 342.864918 -240.372643) (xy 342.906589 -240.405874) (xy 342.942841 -240.444945) (xy 342.972865 -240.488982)
			(xy 342.995991 -240.537003) (xy 343.011701 -240.587933) (xy 343.019644 -240.640637) (xy 343.020142 -240.667286)
			(xy 343.019644 -240.693935) (xy 343.248224 -240.693935) (xy 343.248224 -240.640637) (xy 343.256167 -240.587933)
			(xy 343.271877 -240.537003) (xy 343.295003 -240.488982) (xy 343.325027 -240.444945) (xy 343.361279 -240.405874)
			(xy 343.40295 -240.372643) (xy 343.449108 -240.345994) (xy 343.498722 -240.326522) (xy 343.550684 -240.314662)
			(xy 343.603834 -240.310679) (xy 343.656984 -240.314662) (xy 343.708946 -240.326522) (xy 343.75856 -240.345994)
			(xy 343.804718 -240.372643) (xy 343.846389 -240.405874) (xy 343.882641 -240.444945) (xy 343.912665 -240.488982)
			(xy 343.935791 -240.537003) (xy 343.951501 -240.587933) (xy 343.959444 -240.640637) (xy 343.959942 -240.667286)
			(xy 343.959444 -240.693935) (xy 344.188024 -240.693935) (xy 344.188024 -240.640637) (xy 344.195967 -240.587933)
			(xy 344.211677 -240.537003) (xy 344.234803 -240.488982) (xy 344.264827 -240.444945) (xy 344.301079 -240.405874)
			(xy 344.34275 -240.372643) (xy 344.388908 -240.345994) (xy 344.438522 -240.326522) (xy 344.490484 -240.314662)
			(xy 344.543634 -240.310679) (xy 344.596784 -240.314662) (xy 344.648746 -240.326522) (xy 344.69836 -240.345994)
			(xy 344.744518 -240.372643) (xy 344.786189 -240.405874) (xy 344.822441 -240.444945) (xy 344.852465 -240.488982)
			(xy 344.875591 -240.537003) (xy 344.891301 -240.587933) (xy 344.899244 -240.640637) (xy 344.899742 -240.667286)
			(xy 344.899244 -240.693935) (xy 345.12757 -240.693935) (xy 345.12757 -240.640637) (xy 345.135513 -240.587933)
			(xy 345.151223 -240.537003) (xy 345.174349 -240.488982) (xy 345.204373 -240.444945) (xy 345.240625 -240.405874)
			(xy 345.282296 -240.372643) (xy 345.328454 -240.345994) (xy 345.378068 -240.326522) (xy 345.43003 -240.314662)
			(xy 345.48318 -240.310679) (xy 345.53633 -240.314662) (xy 345.588292 -240.326522) (xy 345.637906 -240.345994)
			(xy 345.684064 -240.372643) (xy 345.725735 -240.405874) (xy 345.761987 -240.444945) (xy 345.792011 -240.488982)
			(xy 345.815137 -240.537003) (xy 345.830847 -240.587933) (xy 345.83879 -240.640637) (xy 345.839288 -240.667286)
			(xy 345.83879 -240.693935) (xy 346.067624 -240.693935) (xy 346.067624 -240.640637) (xy 346.075567 -240.587933)
			(xy 346.091277 -240.537003) (xy 346.114403 -240.488982) (xy 346.144427 -240.444945) (xy 346.180679 -240.405874)
			(xy 346.22235 -240.372643) (xy 346.268508 -240.345994) (xy 346.318122 -240.326522) (xy 346.370084 -240.314662)
			(xy 346.423234 -240.310679) (xy 346.476384 -240.314662) (xy 346.528346 -240.326522) (xy 346.57796 -240.345994)
			(xy 346.624118 -240.372643) (xy 346.665789 -240.405874) (xy 346.702041 -240.444945) (xy 346.732065 -240.488982)
			(xy 346.755191 -240.537003) (xy 346.770901 -240.587933) (xy 346.778844 -240.640637) (xy 346.779342 -240.667286)
			(xy 346.778844 -240.693935) (xy 346.770901 -240.746639) (xy 346.755191 -240.797569) (xy 346.732065 -240.84559)
			(xy 346.702041 -240.889627) (xy 346.665789 -240.928698) (xy 346.624118 -240.961929) (xy 346.57796 -240.988578)
			(xy 346.528346 -241.00805) (xy 346.476384 -241.01991) (xy 346.423234 -241.023894) (xy 346.370084 -241.01991)
			(xy 346.318122 -241.00805) (xy 346.268508 -240.988578) (xy 346.22235 -240.961929) (xy 346.180679 -240.928698)
			(xy 346.144427 -240.889627) (xy 346.114403 -240.84559) (xy 346.091277 -240.797569) (xy 346.075567 -240.746639)
			(xy 346.067624 -240.693935) (xy 345.83879 -240.693935) (xy 345.830847 -240.746639) (xy 345.815137 -240.797569)
			(xy 345.792011 -240.84559) (xy 345.761987 -240.889627) (xy 345.725735 -240.928698) (xy 345.684064 -240.961929)
			(xy 345.637906 -240.988578) (xy 345.588292 -241.00805) (xy 345.53633 -241.01991) (xy 345.48318 -241.023894)
			(xy 345.43003 -241.01991) (xy 345.378068 -241.00805) (xy 345.328454 -240.988578) (xy 345.282296 -240.961929)
			(xy 345.240625 -240.928698) (xy 345.204373 -240.889627) (xy 345.174349 -240.84559) (xy 345.151223 -240.797569)
			(xy 345.135513 -240.746639) (xy 345.12757 -240.693935) (xy 344.899244 -240.693935) (xy 344.891301 -240.746639)
			(xy 344.875591 -240.797569) (xy 344.852465 -240.84559) (xy 344.822441 -240.889627) (xy 344.786189 -240.928698)
			(xy 344.744518 -240.961929) (xy 344.69836 -240.988578) (xy 344.648746 -241.00805) (xy 344.596784 -241.01991)
			(xy 344.543634 -241.023894) (xy 344.490484 -241.01991) (xy 344.438522 -241.00805) (xy 344.388908 -240.988578)
			(xy 344.34275 -240.961929) (xy 344.301079 -240.928698) (xy 344.264827 -240.889627) (xy 344.234803 -240.84559)
			(xy 344.211677 -240.797569) (xy 344.195967 -240.746639) (xy 344.188024 -240.693935) (xy 343.959444 -240.693935)
			(xy 343.951501 -240.746639) (xy 343.935791 -240.797569) (xy 343.912665 -240.84559) (xy 343.882641 -240.889627)
			(xy 343.846389 -240.928698) (xy 343.804718 -240.961929) (xy 343.75856 -240.988578) (xy 343.708946 -241.00805)
			(xy 343.656984 -241.01991) (xy 343.603834 -241.023894) (xy 343.550684 -241.01991) (xy 343.498722 -241.00805)
			(xy 343.449108 -240.988578) (xy 343.40295 -240.961929) (xy 343.361279 -240.928698) (xy 343.325027 -240.889627)
			(xy 343.295003 -240.84559) (xy 343.271877 -240.797569) (xy 343.256167 -240.746639) (xy 343.248224 -240.693935)
			(xy 343.019644 -240.693935) (xy 343.011701 -240.746639) (xy 342.995991 -240.797569) (xy 342.972865 -240.84559)
			(xy 342.942841 -240.889627) (xy 342.906589 -240.928698) (xy 342.864918 -240.961929) (xy 342.81876 -240.988578)
			(xy 342.769146 -241.00805) (xy 342.717184 -241.01991) (xy 342.664034 -241.023894) (xy 342.610884 -241.01991)
			(xy 342.558922 -241.00805) (xy 342.509308 -240.988578) (xy 342.46315 -240.961929) (xy 342.421479 -240.928698)
			(xy 342.385227 -240.889627) (xy 342.355203 -240.84559) (xy 342.332077 -240.797569) (xy 342.316367 -240.746639)
			(xy 342.308424 -240.693935) (xy 342.079844 -240.693935) (xy 342.071901 -240.746639) (xy 342.056191 -240.797569)
			(xy 342.033065 -240.84559) (xy 342.003041 -240.889627) (xy 341.966789 -240.928698) (xy 341.925118 -240.961929)
			(xy 341.87896 -240.988578) (xy 341.829346 -241.00805) (xy 341.777384 -241.01991) (xy 341.724234 -241.023894)
			(xy 341.671084 -241.01991) (xy 341.619122 -241.00805) (xy 341.569508 -240.988578) (xy 341.52335 -240.961929)
			(xy 341.481679 -240.928698) (xy 341.445427 -240.889627) (xy 341.415403 -240.84559) (xy 341.392277 -240.797569)
			(xy 341.376567 -240.746639) (xy 341.368624 -240.693935) (xy 341.140044 -240.693935) (xy 341.132101 -240.746639)
			(xy 341.116391 -240.797569) (xy 341.093265 -240.84559) (xy 341.063241 -240.889627) (xy 341.026989 -240.928698)
			(xy 340.985318 -240.961929) (xy 340.93916 -240.988578) (xy 340.889546 -241.00805) (xy 340.837584 -241.01991)
			(xy 340.784434 -241.023894) (xy 340.731284 -241.01991) (xy 340.679322 -241.00805) (xy 340.629708 -240.988578)
			(xy 340.58355 -240.961929) (xy 340.541879 -240.928698) (xy 340.505627 -240.889627) (xy 340.475603 -240.84559)
			(xy 340.452477 -240.797569) (xy 340.436767 -240.746639) (xy 340.428824 -240.693935) (xy 340.200244 -240.693935)
			(xy 340.192301 -240.746639) (xy 340.176591 -240.797569) (xy 340.153465 -240.84559) (xy 340.123441 -240.889627)
			(xy 340.087189 -240.928698) (xy 340.045518 -240.961929) (xy 339.99936 -240.988578) (xy 339.949746 -241.00805)
			(xy 339.897784 -241.01991) (xy 339.844634 -241.023894) (xy 339.791484 -241.01991) (xy 339.739522 -241.00805)
			(xy 339.689908 -240.988578) (xy 339.64375 -240.961929) (xy 339.602079 -240.928698) (xy 339.565827 -240.889627)
			(xy 339.535803 -240.84559) (xy 339.512677 -240.797569) (xy 339.496967 -240.746639) (xy 339.489024 -240.693935)
			(xy 339.37956 -240.693935) (xy 339.37956 -241.1222) (xy 339.423502 -241.128296) (xy 339.450053 -241.132478)
			(xy 339.501576 -241.147788) (xy 339.550213 -241.170664) (xy 339.594861 -241.200589) (xy 339.634506 -241.236882)
			(xy 339.668248 -241.27872) (xy 339.69532 -241.325152) (xy 339.715109 -241.375125) (xy 339.727165 -241.427504)
			(xy 339.731215 -241.4811) (xy 339.729201 -241.507751) (xy 339.95867 -241.507751) (xy 339.95867 -241.454453)
			(xy 339.966613 -241.401749) (xy 339.982323 -241.350819) (xy 340.005449 -241.302798) (xy 340.035473 -241.258761)
			(xy 340.071725 -241.21969) (xy 340.113396 -241.186459) (xy 340.159554 -241.15981) (xy 340.209168 -241.140338)
			(xy 340.26113 -241.128478) (xy 340.31428 -241.124495) (xy 340.36743 -241.128478) (xy 340.419392 -241.140338)
			(xy 340.469006 -241.15981) (xy 340.515164 -241.186459) (xy 340.556835 -241.21969) (xy 340.593087 -241.258761)
			(xy 340.623111 -241.302798) (xy 340.646237 -241.350819) (xy 340.661947 -241.401749) (xy 340.66989 -241.454453)
			(xy 340.670388 -241.481102) (xy 340.66989 -241.507751) (xy 340.89847 -241.507751) (xy 340.89847 -241.454453)
			(xy 340.906413 -241.401749) (xy 340.922123 -241.350819) (xy 340.945249 -241.302798) (xy 340.975273 -241.258761)
			(xy 341.011525 -241.21969) (xy 341.053196 -241.186459) (xy 341.099354 -241.15981) (xy 341.148968 -241.140338)
			(xy 341.20093 -241.128478) (xy 341.25408 -241.124495) (xy 341.30723 -241.128478) (xy 341.359192 -241.140338)
			(xy 341.408806 -241.15981) (xy 341.454964 -241.186459) (xy 341.496635 -241.21969) (xy 341.532887 -241.258761)
			(xy 341.562911 -241.302798) (xy 341.586037 -241.350819) (xy 341.601747 -241.401749) (xy 341.60969 -241.454453)
			(xy 341.610188 -241.481102) (xy 341.60969 -241.507751) (xy 341.838524 -241.507751) (xy 341.838524 -241.454453)
			(xy 341.846467 -241.401749) (xy 341.862177 -241.350819) (xy 341.885303 -241.302798) (xy 341.915327 -241.258761)
			(xy 341.951579 -241.21969) (xy 341.99325 -241.186459) (xy 342.039408 -241.15981) (xy 342.089022 -241.140338)
			(xy 342.140984 -241.128478) (xy 342.194134 -241.124495) (xy 342.247284 -241.128478) (xy 342.299246 -241.140338)
			(xy 342.34886 -241.15981) (xy 342.395018 -241.186459) (xy 342.436689 -241.21969) (xy 342.472941 -241.258761)
			(xy 342.502965 -241.302798) (xy 342.526091 -241.350819) (xy 342.541801 -241.401749) (xy 342.549744 -241.454453)
			(xy 342.550242 -241.481102) (xy 342.549744 -241.507751) (xy 342.77807 -241.507751) (xy 342.77807 -241.454453)
			(xy 342.786013 -241.401749) (xy 342.801723 -241.350819) (xy 342.824849 -241.302798) (xy 342.854873 -241.258761)
			(xy 342.891125 -241.21969) (xy 342.932796 -241.186459) (xy 342.978954 -241.15981) (xy 343.028568 -241.140338)
			(xy 343.08053 -241.128478) (xy 343.13368 -241.124495) (xy 343.18683 -241.128478) (xy 343.238792 -241.140338)
			(xy 343.288406 -241.15981) (xy 343.334564 -241.186459) (xy 343.376235 -241.21969) (xy 343.412487 -241.258761)
			(xy 343.442511 -241.302798) (xy 343.465637 -241.350819) (xy 343.481347 -241.401749) (xy 343.48929 -241.454453)
			(xy 343.489788 -241.481102) (xy 343.48929 -241.507751) (xy 343.71787 -241.507751) (xy 343.71787 -241.454453)
			(xy 343.725813 -241.401749) (xy 343.741523 -241.350819) (xy 343.764649 -241.302798) (xy 343.794673 -241.258761)
			(xy 343.830925 -241.21969) (xy 343.872596 -241.186459) (xy 343.918754 -241.15981) (xy 343.968368 -241.140338)
			(xy 344.02033 -241.128478) (xy 344.07348 -241.124495) (xy 344.12663 -241.128478) (xy 344.178592 -241.140338)
			(xy 344.228206 -241.15981) (xy 344.274364 -241.186459) (xy 344.316035 -241.21969) (xy 344.352287 -241.258761)
			(xy 344.382311 -241.302798) (xy 344.405437 -241.350819) (xy 344.421147 -241.401749) (xy 344.42909 -241.454453)
			(xy 344.429588 -241.481102) (xy 344.42909 -241.507751) (xy 344.65767 -241.507751) (xy 344.65767 -241.454453)
			(xy 344.665613 -241.401749) (xy 344.681323 -241.350819) (xy 344.704449 -241.302798) (xy 344.734473 -241.258761)
			(xy 344.770725 -241.21969) (xy 344.812396 -241.186459) (xy 344.858554 -241.15981) (xy 344.908168 -241.140338)
			(xy 344.96013 -241.128478) (xy 345.01328 -241.124495) (xy 345.06643 -241.128478) (xy 345.118392 -241.140338)
			(xy 345.168006 -241.15981) (xy 345.214164 -241.186459) (xy 345.255835 -241.21969) (xy 345.292087 -241.258761)
			(xy 345.322111 -241.302798) (xy 345.345237 -241.350819) (xy 345.360947 -241.401749) (xy 345.36889 -241.454453)
			(xy 345.369388 -241.481102) (xy 345.36889 -241.507751) (xy 345.59747 -241.507751) (xy 345.59747 -241.454453)
			(xy 345.605413 -241.401749) (xy 345.621123 -241.350819) (xy 345.644249 -241.302798) (xy 345.674273 -241.258761)
			(xy 345.710525 -241.21969) (xy 345.752196 -241.186459) (xy 345.798354 -241.15981) (xy 345.847968 -241.140338)
			(xy 345.89993 -241.128478) (xy 345.95308 -241.124495) (xy 346.00623 -241.128478) (xy 346.058192 -241.140338)
			(xy 346.107806 -241.15981) (xy 346.153964 -241.186459) (xy 346.195635 -241.21969) (xy 346.231887 -241.258761)
			(xy 346.261911 -241.302798) (xy 346.285037 -241.350819) (xy 346.300747 -241.401749) (xy 346.30869 -241.454453)
			(xy 346.309188 -241.481102) (xy 346.30869 -241.507751) (xy 346.53727 -241.507751) (xy 346.53727 -241.454453)
			(xy 346.545213 -241.401749) (xy 346.560923 -241.350819) (xy 346.584049 -241.302798) (xy 346.614073 -241.258761)
			(xy 346.650325 -241.21969) (xy 346.691996 -241.186459) (xy 346.738154 -241.15981) (xy 346.787768 -241.140338)
			(xy 346.83973 -241.128478) (xy 346.89288 -241.124495) (xy 346.94603 -241.128478) (xy 346.997992 -241.140338)
			(xy 347.047606 -241.15981) (xy 347.093764 -241.186459) (xy 347.135435 -241.21969) (xy 347.171687 -241.258761)
			(xy 347.201711 -241.302798) (xy 347.224837 -241.350819) (xy 347.240547 -241.401749) (xy 347.24849 -241.454453)
			(xy 347.248988 -241.481102) (xy 347.24849 -241.507751) (xy 347.240547 -241.560455) (xy 347.224837 -241.611385)
			(xy 347.201711 -241.659406) (xy 347.171687 -241.703443) (xy 347.135435 -241.742514) (xy 347.093764 -241.775745)
			(xy 347.047606 -241.802394) (xy 346.997992 -241.821866) (xy 346.94603 -241.833726) (xy 346.89288 -241.83771)
			(xy 346.83973 -241.833726) (xy 346.787768 -241.821866) (xy 346.738154 -241.802394) (xy 346.691996 -241.775745)
			(xy 346.650325 -241.742514) (xy 346.614073 -241.703443) (xy 346.584049 -241.659406) (xy 346.560923 -241.611385)
			(xy 346.545213 -241.560455) (xy 346.53727 -241.507751) (xy 346.30869 -241.507751) (xy 346.300747 -241.560455)
			(xy 346.285037 -241.611385) (xy 346.261911 -241.659406) (xy 346.231887 -241.703443) (xy 346.195635 -241.742514)
			(xy 346.153964 -241.775745) (xy 346.107806 -241.802394) (xy 346.058192 -241.821866) (xy 346.00623 -241.833726)
			(xy 345.95308 -241.83771) (xy 345.89993 -241.833726) (xy 345.847968 -241.821866) (xy 345.798354 -241.802394)
			(xy 345.752196 -241.775745) (xy 345.710525 -241.742514) (xy 345.674273 -241.703443) (xy 345.644249 -241.659406)
			(xy 345.621123 -241.611385) (xy 345.605413 -241.560455) (xy 345.59747 -241.507751) (xy 345.36889 -241.507751)
			(xy 345.360947 -241.560455) (xy 345.345237 -241.611385) (xy 345.322111 -241.659406) (xy 345.292087 -241.703443)
			(xy 345.255835 -241.742514) (xy 345.214164 -241.775745) (xy 345.168006 -241.802394) (xy 345.118392 -241.821866)
			(xy 345.06643 -241.833726) (xy 345.01328 -241.83771) (xy 344.96013 -241.833726) (xy 344.908168 -241.821866)
			(xy 344.858554 -241.802394) (xy 344.812396 -241.775745) (xy 344.770725 -241.742514) (xy 344.734473 -241.703443)
			(xy 344.704449 -241.659406) (xy 344.681323 -241.611385) (xy 344.665613 -241.560455) (xy 344.65767 -241.507751)
			(xy 344.42909 -241.507751) (xy 344.421147 -241.560455) (xy 344.405437 -241.611385) (xy 344.382311 -241.659406)
			(xy 344.352287 -241.703443) (xy 344.316035 -241.742514) (xy 344.274364 -241.775745) (xy 344.228206 -241.802394)
			(xy 344.178592 -241.821866) (xy 344.12663 -241.833726) (xy 344.07348 -241.83771) (xy 344.02033 -241.833726)
			(xy 343.968368 -241.821866) (xy 343.918754 -241.802394) (xy 343.872596 -241.775745) (xy 343.830925 -241.742514)
			(xy 343.794673 -241.703443) (xy 343.764649 -241.659406) (xy 343.741523 -241.611385) (xy 343.725813 -241.560455)
			(xy 343.71787 -241.507751) (xy 343.48929 -241.507751) (xy 343.481347 -241.560455) (xy 343.465637 -241.611385)
			(xy 343.442511 -241.659406) (xy 343.412487 -241.703443) (xy 343.376235 -241.742514) (xy 343.334564 -241.775745)
			(xy 343.288406 -241.802394) (xy 343.238792 -241.821866) (xy 343.18683 -241.833726) (xy 343.13368 -241.83771)
			(xy 343.08053 -241.833726) (xy 343.028568 -241.821866) (xy 342.978954 -241.802394) (xy 342.932796 -241.775745)
			(xy 342.891125 -241.742514) (xy 342.854873 -241.703443) (xy 342.824849 -241.659406) (xy 342.801723 -241.611385)
			(xy 342.786013 -241.560455) (xy 342.77807 -241.507751) (xy 342.549744 -241.507751) (xy 342.541801 -241.560455)
			(xy 342.526091 -241.611385) (xy 342.502965 -241.659406) (xy 342.472941 -241.703443) (xy 342.436689 -241.742514)
			(xy 342.395018 -241.775745) (xy 342.34886 -241.802394) (xy 342.299246 -241.821866) (xy 342.247284 -241.833726)
			(xy 342.194134 -241.83771) (xy 342.140984 -241.833726) (xy 342.089022 -241.821866) (xy 342.039408 -241.802394)
			(xy 341.99325 -241.775745) (xy 341.951579 -241.742514) (xy 341.915327 -241.703443) (xy 341.885303 -241.659406)
			(xy 341.862177 -241.611385) (xy 341.846467 -241.560455) (xy 341.838524 -241.507751) (xy 341.60969 -241.507751)
			(xy 341.601747 -241.560455) (xy 341.586037 -241.611385) (xy 341.562911 -241.659406) (xy 341.532887 -241.703443)
			(xy 341.496635 -241.742514) (xy 341.454964 -241.775745) (xy 341.408806 -241.802394) (xy 341.359192 -241.821866)
			(xy 341.30723 -241.833726) (xy 341.25408 -241.83771) (xy 341.20093 -241.833726) (xy 341.148968 -241.821866)
			(xy 341.099354 -241.802394) (xy 341.053196 -241.775745) (xy 341.011525 -241.742514) (xy 340.975273 -241.703443)
			(xy 340.945249 -241.659406) (xy 340.922123 -241.611385) (xy 340.906413 -241.560455) (xy 340.89847 -241.507751)
			(xy 340.66989 -241.507751) (xy 340.661947 -241.560455) (xy 340.646237 -241.611385) (xy 340.623111 -241.659406)
			(xy 340.593087 -241.703443) (xy 340.556835 -241.742514) (xy 340.515164 -241.775745) (xy 340.469006 -241.802394)
			(xy 340.419392 -241.821866) (xy 340.36743 -241.833726) (xy 340.31428 -241.83771) (xy 340.26113 -241.833726)
			(xy 340.209168 -241.821866) (xy 340.159554 -241.802394) (xy 340.113396 -241.775745) (xy 340.071725 -241.742514)
			(xy 340.035473 -241.703443) (xy 340.005449 -241.659406) (xy 339.982323 -241.611385) (xy 339.966613 -241.560455)
			(xy 339.95867 -241.507751) (xy 339.729201 -241.507751) (xy 339.727165 -241.534696) (xy 339.715109 -241.587075)
			(xy 339.69532 -241.637048) (xy 339.668247 -241.683481) (xy 339.634505 -241.725318) (xy 339.59486 -241.761612)
			(xy 339.550212 -241.791536) (xy 339.501575 -241.814413) (xy 339.450053 -241.829722) (xy 339.423502 -241.833908)
			(xy 339.37956 -241.840004) (xy 339.37956 -242.321567) (xy 339.489024 -242.321567) (xy 339.489024 -242.268269)
			(xy 339.496967 -242.215565) (xy 339.512677 -242.164635) (xy 339.535803 -242.116614) (xy 339.565827 -242.072577)
			(xy 339.602079 -242.033506) (xy 339.64375 -242.000275) (xy 339.689908 -241.973626) (xy 339.739522 -241.954154)
			(xy 339.791484 -241.942294) (xy 339.844634 -241.938311) (xy 339.897784 -241.942294) (xy 339.949746 -241.954154)
			(xy 339.99936 -241.973626) (xy 340.045518 -242.000275) (xy 340.087189 -242.033506) (xy 340.123441 -242.072577)
			(xy 340.153465 -242.116614) (xy 340.176591 -242.164635) (xy 340.192301 -242.215565) (xy 340.200244 -242.268269)
			(xy 340.200742 -242.294918) (xy 340.200244 -242.321567) (xy 340.428824 -242.321567) (xy 340.428824 -242.268269)
			(xy 340.436767 -242.215565) (xy 340.452477 -242.164635) (xy 340.475603 -242.116614) (xy 340.505627 -242.072577)
			(xy 340.541879 -242.033506) (xy 340.58355 -242.000275) (xy 340.629708 -241.973626) (xy 340.679322 -241.954154)
			(xy 340.731284 -241.942294) (xy 340.784434 -241.938311) (xy 340.837584 -241.942294) (xy 340.889546 -241.954154)
			(xy 340.93916 -241.973626) (xy 340.985318 -242.000275) (xy 341.026989 -242.033506) (xy 341.063241 -242.072577)
			(xy 341.093265 -242.116614) (xy 341.116391 -242.164635) (xy 341.132101 -242.215565) (xy 341.140044 -242.268269)
			(xy 341.140542 -242.294918) (xy 341.140044 -242.321567) (xy 341.368624 -242.321567) (xy 341.368624 -242.268269)
			(xy 341.376567 -242.215565) (xy 341.392277 -242.164635) (xy 341.415403 -242.116614) (xy 341.445427 -242.072577)
			(xy 341.481679 -242.033506) (xy 341.52335 -242.000275) (xy 341.569508 -241.973626) (xy 341.619122 -241.954154)
			(xy 341.671084 -241.942294) (xy 341.724234 -241.938311) (xy 341.777384 -241.942294) (xy 341.829346 -241.954154)
			(xy 341.87896 -241.973626) (xy 341.925118 -242.000275) (xy 341.966789 -242.033506) (xy 342.003041 -242.072577)
			(xy 342.033065 -242.116614) (xy 342.056191 -242.164635) (xy 342.071901 -242.215565) (xy 342.079844 -242.268269)
			(xy 342.080342 -242.294918) (xy 342.079844 -242.321567) (xy 342.308424 -242.321567) (xy 342.308424 -242.268269)
			(xy 342.316367 -242.215565) (xy 342.332077 -242.164635) (xy 342.355203 -242.116614) (xy 342.385227 -242.072577)
			(xy 342.421479 -242.033506) (xy 342.46315 -242.000275) (xy 342.509308 -241.973626) (xy 342.558922 -241.954154)
			(xy 342.610884 -241.942294) (xy 342.664034 -241.938311) (xy 342.717184 -241.942294) (xy 342.769146 -241.954154)
			(xy 342.81876 -241.973626) (xy 342.864918 -242.000275) (xy 342.906589 -242.033506) (xy 342.942841 -242.072577)
			(xy 342.972865 -242.116614) (xy 342.995991 -242.164635) (xy 343.011701 -242.215565) (xy 343.019644 -242.268269)
			(xy 343.020142 -242.294918) (xy 343.019644 -242.321567) (xy 343.248224 -242.321567) (xy 343.248224 -242.268269)
			(xy 343.256167 -242.215565) (xy 343.271877 -242.164635) (xy 343.295003 -242.116614) (xy 343.325027 -242.072577)
			(xy 343.361279 -242.033506) (xy 343.40295 -242.000275) (xy 343.449108 -241.973626) (xy 343.498722 -241.954154)
			(xy 343.550684 -241.942294) (xy 343.603834 -241.938311) (xy 343.656984 -241.942294) (xy 343.708946 -241.954154)
			(xy 343.75856 -241.973626) (xy 343.804718 -242.000275) (xy 343.846389 -242.033506) (xy 343.882641 -242.072577)
			(xy 343.912665 -242.116614) (xy 343.935791 -242.164635) (xy 343.951501 -242.215565) (xy 343.959444 -242.268269)
			(xy 343.959942 -242.294918) (xy 343.959444 -242.321567) (xy 344.188024 -242.321567) (xy 344.188024 -242.268269)
			(xy 344.195967 -242.215565) (xy 344.211677 -242.164635) (xy 344.234803 -242.116614) (xy 344.264827 -242.072577)
			(xy 344.301079 -242.033506) (xy 344.34275 -242.000275) (xy 344.388908 -241.973626) (xy 344.438522 -241.954154)
			(xy 344.490484 -241.942294) (xy 344.543634 -241.938311) (xy 344.596784 -241.942294) (xy 344.648746 -241.954154)
			(xy 344.69836 -241.973626) (xy 344.744518 -242.000275) (xy 344.786189 -242.033506) (xy 344.822441 -242.072577)
			(xy 344.852465 -242.116614) (xy 344.875591 -242.164635) (xy 344.891301 -242.215565) (xy 344.899244 -242.268269)
			(xy 344.899742 -242.294918) (xy 344.899244 -242.321567) (xy 345.127824 -242.321567) (xy 345.127824 -242.268269)
			(xy 345.135767 -242.215565) (xy 345.151477 -242.164635) (xy 345.174603 -242.116614) (xy 345.204627 -242.072577)
			(xy 345.240879 -242.033506) (xy 345.28255 -242.000275) (xy 345.328708 -241.973626) (xy 345.378322 -241.954154)
			(xy 345.430284 -241.942294) (xy 345.483434 -241.938311) (xy 345.536584 -241.942294) (xy 345.588546 -241.954154)
			(xy 345.63816 -241.973626) (xy 345.684318 -242.000275) (xy 345.725989 -242.033506) (xy 345.762241 -242.072577)
			(xy 345.792265 -242.116614) (xy 345.815391 -242.164635) (xy 345.831101 -242.215565) (xy 345.839044 -242.268269)
			(xy 345.839542 -242.294918) (xy 345.839044 -242.321567) (xy 346.067624 -242.321567) (xy 346.067624 -242.268269)
			(xy 346.075567 -242.215565) (xy 346.091277 -242.164635) (xy 346.114403 -242.116614) (xy 346.144427 -242.072577)
			(xy 346.180679 -242.033506) (xy 346.22235 -242.000275) (xy 346.268508 -241.973626) (xy 346.318122 -241.954154)
			(xy 346.370084 -241.942294) (xy 346.423234 -241.938311) (xy 346.476384 -241.942294) (xy 346.528346 -241.954154)
			(xy 346.57796 -241.973626) (xy 346.624118 -242.000275) (xy 346.665789 -242.033506) (xy 346.702041 -242.072577)
			(xy 346.732065 -242.116614) (xy 346.755191 -242.164635) (xy 346.770901 -242.215565) (xy 346.778844 -242.268269)
			(xy 346.779342 -242.294918) (xy 346.778844 -242.321567) (xy 346.770901 -242.374271) (xy 346.755191 -242.425201)
			(xy 346.732065 -242.473222) (xy 346.702041 -242.517259) (xy 346.665789 -242.55633) (xy 346.624118 -242.589561)
			(xy 346.57796 -242.61621) (xy 346.528346 -242.635682) (xy 346.476384 -242.647542) (xy 346.423234 -242.651526)
			(xy 346.370084 -242.647542) (xy 346.318122 -242.635682) (xy 346.268508 -242.61621) (xy 346.22235 -242.589561)
			(xy 346.180679 -242.55633) (xy 346.144427 -242.517259) (xy 346.114403 -242.473222) (xy 346.091277 -242.425201)
			(xy 346.075567 -242.374271) (xy 346.067624 -242.321567) (xy 345.839044 -242.321567) (xy 345.831101 -242.374271)
			(xy 345.815391 -242.425201) (xy 345.792265 -242.473222) (xy 345.762241 -242.517259) (xy 345.725989 -242.55633)
			(xy 345.684318 -242.589561) (xy 345.63816 -242.61621) (xy 345.588546 -242.635682) (xy 345.536584 -242.647542)
			(xy 345.483434 -242.651526) (xy 345.430284 -242.647542) (xy 345.378322 -242.635682) (xy 345.328708 -242.61621)
			(xy 345.28255 -242.589561) (xy 345.240879 -242.55633) (xy 345.204627 -242.517259) (xy 345.174603 -242.473222)
			(xy 345.151477 -242.425201) (xy 345.135767 -242.374271) (xy 345.127824 -242.321567) (xy 344.899244 -242.321567)
			(xy 344.891301 -242.374271) (xy 344.875591 -242.425201) (xy 344.852465 -242.473222) (xy 344.822441 -242.517259)
			(xy 344.786189 -242.55633) (xy 344.744518 -242.589561) (xy 344.69836 -242.61621) (xy 344.648746 -242.635682)
			(xy 344.596784 -242.647542) (xy 344.543634 -242.651526) (xy 344.490484 -242.647542) (xy 344.438522 -242.635682)
			(xy 344.388908 -242.61621) (xy 344.34275 -242.589561) (xy 344.301079 -242.55633) (xy 344.264827 -242.517259)
			(xy 344.234803 -242.473222) (xy 344.211677 -242.425201) (xy 344.195967 -242.374271) (xy 344.188024 -242.321567)
			(xy 343.959444 -242.321567) (xy 343.951501 -242.374271) (xy 343.935791 -242.425201) (xy 343.912665 -242.473222)
			(xy 343.882641 -242.517259) (xy 343.846389 -242.55633) (xy 343.804718 -242.589561) (xy 343.75856 -242.61621)
			(xy 343.708946 -242.635682) (xy 343.656984 -242.647542) (xy 343.603834 -242.651526) (xy 343.550684 -242.647542)
			(xy 343.498722 -242.635682) (xy 343.449108 -242.61621) (xy 343.40295 -242.589561) (xy 343.361279 -242.55633)
			(xy 343.325027 -242.517259) (xy 343.295003 -242.473222) (xy 343.271877 -242.425201) (xy 343.256167 -242.374271)
			(xy 343.248224 -242.321567) (xy 343.019644 -242.321567) (xy 343.011701 -242.374271) (xy 342.995991 -242.425201)
			(xy 342.972865 -242.473222) (xy 342.942841 -242.517259) (xy 342.906589 -242.55633) (xy 342.864918 -242.589561)
			(xy 342.81876 -242.61621) (xy 342.769146 -242.635682) (xy 342.717184 -242.647542) (xy 342.664034 -242.651526)
			(xy 342.610884 -242.647542) (xy 342.558922 -242.635682) (xy 342.509308 -242.61621) (xy 342.46315 -242.589561)
			(xy 342.421479 -242.55633) (xy 342.385227 -242.517259) (xy 342.355203 -242.473222) (xy 342.332077 -242.425201)
			(xy 342.316367 -242.374271) (xy 342.308424 -242.321567) (xy 342.079844 -242.321567) (xy 342.071901 -242.374271)
			(xy 342.056191 -242.425201) (xy 342.033065 -242.473222) (xy 342.003041 -242.517259) (xy 341.966789 -242.55633)
			(xy 341.925118 -242.589561) (xy 341.87896 -242.61621) (xy 341.829346 -242.635682) (xy 341.777384 -242.647542)
			(xy 341.724234 -242.651526) (xy 341.671084 -242.647542) (xy 341.619122 -242.635682) (xy 341.569508 -242.61621)
			(xy 341.52335 -242.589561) (xy 341.481679 -242.55633) (xy 341.445427 -242.517259) (xy 341.415403 -242.473222)
			(xy 341.392277 -242.425201) (xy 341.376567 -242.374271) (xy 341.368624 -242.321567) (xy 341.140044 -242.321567)
			(xy 341.132101 -242.374271) (xy 341.116391 -242.425201) (xy 341.093265 -242.473222) (xy 341.063241 -242.517259)
			(xy 341.026989 -242.55633) (xy 340.985318 -242.589561) (xy 340.93916 -242.61621) (xy 340.889546 -242.635682)
			(xy 340.837584 -242.647542) (xy 340.784434 -242.651526) (xy 340.731284 -242.647542) (xy 340.679322 -242.635682)
			(xy 340.629708 -242.61621) (xy 340.58355 -242.589561) (xy 340.541879 -242.55633) (xy 340.505627 -242.517259)
			(xy 340.475603 -242.473222) (xy 340.452477 -242.425201) (xy 340.436767 -242.374271) (xy 340.428824 -242.321567)
			(xy 340.200244 -242.321567) (xy 340.192301 -242.374271) (xy 340.176591 -242.425201) (xy 340.153465 -242.473222)
			(xy 340.123441 -242.517259) (xy 340.087189 -242.55633) (xy 340.045518 -242.589561) (xy 339.99936 -242.61621)
			(xy 339.949746 -242.635682) (xy 339.897784 -242.647542) (xy 339.844634 -242.651526) (xy 339.791484 -242.647542)
			(xy 339.739522 -242.635682) (xy 339.689908 -242.61621) (xy 339.64375 -242.589561) (xy 339.602079 -242.55633)
			(xy 339.565827 -242.517259) (xy 339.535803 -242.473222) (xy 339.512677 -242.425201) (xy 339.496967 -242.374271)
			(xy 339.489024 -242.321567) (xy 339.37956 -242.321567) (xy 339.37956 -242.750086) (xy 339.423502 -242.756182)
			(xy 339.450065 -242.760351) (xy 339.501613 -242.77564) (xy 339.550277 -242.798503) (xy 339.594952 -242.828421)
			(xy 339.634623 -242.864714) (xy 339.668388 -242.906557) (xy 339.69548 -242.953) (xy 339.715283 -243.002988)
			(xy 339.727349 -243.055384) (xy 339.731401 -243.108998) (xy 339.729388 -243.135637) (xy 339.95867 -243.135637)
			(xy 339.95867 -243.082339) (xy 339.966613 -243.029635) (xy 339.982323 -242.978705) (xy 340.005449 -242.930684)
			(xy 340.035473 -242.886647) (xy 340.071725 -242.847576) (xy 340.113396 -242.814345) (xy 340.159554 -242.787696)
			(xy 340.209168 -242.768224) (xy 340.26113 -242.756364) (xy 340.31428 -242.752381) (xy 340.36743 -242.756364)
			(xy 340.419392 -242.768224) (xy 340.469006 -242.787696) (xy 340.515164 -242.814345) (xy 340.556835 -242.847576)
			(xy 340.593087 -242.886647) (xy 340.623111 -242.930684) (xy 340.646237 -242.978705) (xy 340.661947 -243.029635)
			(xy 340.66989 -243.082339) (xy 340.670388 -243.108988) (xy 340.66989 -243.135637) (xy 340.89847 -243.135637)
			(xy 340.89847 -243.082339) (xy 340.906413 -243.029635) (xy 340.922123 -242.978705) (xy 340.945249 -242.930684)
			(xy 340.975273 -242.886647) (xy 341.011525 -242.847576) (xy 341.053196 -242.814345) (xy 341.099354 -242.787696)
			(xy 341.148968 -242.768224) (xy 341.20093 -242.756364) (xy 341.25408 -242.752381) (xy 341.30723 -242.756364)
			(xy 341.359192 -242.768224) (xy 341.408806 -242.787696) (xy 341.454964 -242.814345) (xy 341.496635 -242.847576)
			(xy 341.532887 -242.886647) (xy 341.562911 -242.930684) (xy 341.586037 -242.978705) (xy 341.601747 -243.029635)
			(xy 341.60969 -243.082339) (xy 341.610188 -243.108988) (xy 341.60969 -243.135637) (xy 341.83827 -243.135637)
			(xy 341.83827 -243.082339) (xy 341.846213 -243.029635) (xy 341.861923 -242.978705) (xy 341.885049 -242.930684)
			(xy 341.915073 -242.886647) (xy 341.951325 -242.847576) (xy 341.992996 -242.814345) (xy 342.039154 -242.787696)
			(xy 342.088768 -242.768224) (xy 342.14073 -242.756364) (xy 342.19388 -242.752381) (xy 342.24703 -242.756364)
			(xy 342.298992 -242.768224) (xy 342.348606 -242.787696) (xy 342.394764 -242.814345) (xy 342.436435 -242.847576)
			(xy 342.472687 -242.886647) (xy 342.502711 -242.930684) (xy 342.525837 -242.978705) (xy 342.541547 -243.029635)
			(xy 342.54949 -243.082339) (xy 342.549988 -243.108988) (xy 342.54949 -243.135637) (xy 342.77807 -243.135637)
			(xy 342.77807 -243.082339) (xy 342.786013 -243.029635) (xy 342.801723 -242.978705) (xy 342.824849 -242.930684)
			(xy 342.854873 -242.886647) (xy 342.891125 -242.847576) (xy 342.932796 -242.814345) (xy 342.978954 -242.787696)
			(xy 343.028568 -242.768224) (xy 343.08053 -242.756364) (xy 343.13368 -242.752381) (xy 343.18683 -242.756364)
			(xy 343.238792 -242.768224) (xy 343.288406 -242.787696) (xy 343.334564 -242.814345) (xy 343.376235 -242.847576)
			(xy 343.412487 -242.886647) (xy 343.442511 -242.930684) (xy 343.465637 -242.978705) (xy 343.481347 -243.029635)
			(xy 343.48929 -243.082339) (xy 343.489788 -243.108988) (xy 343.48929 -243.135637) (xy 343.71787 -243.135637)
			(xy 343.71787 -243.082339) (xy 343.725813 -243.029635) (xy 343.741523 -242.978705) (xy 343.764649 -242.930684)
			(xy 343.794673 -242.886647) (xy 343.830925 -242.847576) (xy 343.872596 -242.814345) (xy 343.918754 -242.787696)
			(xy 343.968368 -242.768224) (xy 344.02033 -242.756364) (xy 344.07348 -242.752381) (xy 344.12663 -242.756364)
			(xy 344.178592 -242.768224) (xy 344.228206 -242.787696) (xy 344.274364 -242.814345) (xy 344.316035 -242.847576)
			(xy 344.352287 -242.886647) (xy 344.382311 -242.930684) (xy 344.405437 -242.978705) (xy 344.421147 -243.029635)
			(xy 344.42909 -243.082339) (xy 344.429588 -243.108988) (xy 344.42909 -243.135637) (xy 344.65767 -243.135637)
			(xy 344.65767 -243.082339) (xy 344.665613 -243.029635) (xy 344.681323 -242.978705) (xy 344.704449 -242.930684)
			(xy 344.734473 -242.886647) (xy 344.770725 -242.847576) (xy 344.812396 -242.814345) (xy 344.858554 -242.787696)
			(xy 344.908168 -242.768224) (xy 344.96013 -242.756364) (xy 345.01328 -242.752381) (xy 345.06643 -242.756364)
			(xy 345.118392 -242.768224) (xy 345.168006 -242.787696) (xy 345.214164 -242.814345) (xy 345.255835 -242.847576)
			(xy 345.292087 -242.886647) (xy 345.322111 -242.930684) (xy 345.345237 -242.978705) (xy 345.360947 -243.029635)
			(xy 345.36889 -243.082339) (xy 345.369388 -243.108988) (xy 345.36889 -243.135637) (xy 345.597724 -243.135637)
			(xy 345.597724 -243.082339) (xy 345.605667 -243.029635) (xy 345.621377 -242.978705) (xy 345.644503 -242.930684)
			(xy 345.674527 -242.886647) (xy 345.710779 -242.847576) (xy 345.75245 -242.814345) (xy 345.798608 -242.787696)
			(xy 345.848222 -242.768224) (xy 345.900184 -242.756364) (xy 345.953334 -242.752381) (xy 346.006484 -242.756364)
			(xy 346.058446 -242.768224) (xy 346.10806 -242.787696) (xy 346.154218 -242.814345) (xy 346.195889 -242.847576)
			(xy 346.232141 -242.886647) (xy 346.262165 -242.930684) (xy 346.285291 -242.978705) (xy 346.301001 -243.029635)
			(xy 346.308944 -243.082339) (xy 346.309442 -243.108988) (xy 346.308944 -243.135637) (xy 346.53727 -243.135637)
			(xy 346.53727 -243.082339) (xy 346.545213 -243.029635) (xy 346.560923 -242.978705) (xy 346.584049 -242.930684)
			(xy 346.614073 -242.886647) (xy 346.650325 -242.847576) (xy 346.691996 -242.814345) (xy 346.738154 -242.787696)
			(xy 346.787768 -242.768224) (xy 346.83973 -242.756364) (xy 346.89288 -242.752381) (xy 346.94603 -242.756364)
			(xy 346.997992 -242.768224) (xy 347.047606 -242.787696) (xy 347.093764 -242.814345) (xy 347.135435 -242.847576)
			(xy 347.171687 -242.886647) (xy 347.201711 -242.930684) (xy 347.224837 -242.978705) (xy 347.240547 -243.029635)
			(xy 347.24849 -243.082339) (xy 347.248988 -243.108988) (xy 347.24849 -243.135637) (xy 347.240547 -243.188341)
			(xy 347.224837 -243.239271) (xy 347.201711 -243.287292) (xy 347.171687 -243.331329) (xy 347.135435 -243.3704)
			(xy 347.093764 -243.403631) (xy 347.047606 -243.43028) (xy 346.997992 -243.449752) (xy 346.94603 -243.461612)
			(xy 346.89288 -243.465596) (xy 346.83973 -243.461612) (xy 346.787768 -243.449752) (xy 346.738154 -243.43028)
			(xy 346.691996 -243.403631) (xy 346.650325 -243.3704) (xy 346.614073 -243.331329) (xy 346.584049 -243.287292)
			(xy 346.560923 -243.239271) (xy 346.545213 -243.188341) (xy 346.53727 -243.135637) (xy 346.308944 -243.135637)
			(xy 346.301001 -243.188341) (xy 346.285291 -243.239271) (xy 346.262165 -243.287292) (xy 346.232141 -243.331329)
			(xy 346.195889 -243.3704) (xy 346.154218 -243.403631) (xy 346.10806 -243.43028) (xy 346.058446 -243.449752)
			(xy 346.006484 -243.461612) (xy 345.953334 -243.465596) (xy 345.900184 -243.461612) (xy 345.848222 -243.449752)
			(xy 345.798608 -243.43028) (xy 345.75245 -243.403631) (xy 345.710779 -243.3704) (xy 345.674527 -243.331329)
			(xy 345.644503 -243.287292) (xy 345.621377 -243.239271) (xy 345.605667 -243.188341) (xy 345.597724 -243.135637)
			(xy 345.36889 -243.135637) (xy 345.360947 -243.188341) (xy 345.345237 -243.239271) (xy 345.322111 -243.287292)
			(xy 345.292087 -243.331329) (xy 345.255835 -243.3704) (xy 345.214164 -243.403631) (xy 345.168006 -243.43028)
			(xy 345.118392 -243.449752) (xy 345.06643 -243.461612) (xy 345.01328 -243.465596) (xy 344.96013 -243.461612)
			(xy 344.908168 -243.449752) (xy 344.858554 -243.43028) (xy 344.812396 -243.403631) (xy 344.770725 -243.3704)
			(xy 344.734473 -243.331329) (xy 344.704449 -243.287292) (xy 344.681323 -243.239271) (xy 344.665613 -243.188341)
			(xy 344.65767 -243.135637) (xy 344.42909 -243.135637) (xy 344.421147 -243.188341) (xy 344.405437 -243.239271)
			(xy 344.382311 -243.287292) (xy 344.352287 -243.331329) (xy 344.316035 -243.3704) (xy 344.274364 -243.403631)
			(xy 344.228206 -243.43028) (xy 344.178592 -243.449752) (xy 344.12663 -243.461612) (xy 344.07348 -243.465596)
			(xy 344.02033 -243.461612) (xy 343.968368 -243.449752) (xy 343.918754 -243.43028) (xy 343.872596 -243.403631)
			(xy 343.830925 -243.3704) (xy 343.794673 -243.331329) (xy 343.764649 -243.287292) (xy 343.741523 -243.239271)
			(xy 343.725813 -243.188341) (xy 343.71787 -243.135637) (xy 343.48929 -243.135637) (xy 343.481347 -243.188341)
			(xy 343.465637 -243.239271) (xy 343.442511 -243.287292) (xy 343.412487 -243.331329) (xy 343.376235 -243.3704)
			(xy 343.334564 -243.403631) (xy 343.288406 -243.43028) (xy 343.238792 -243.449752) (xy 343.18683 -243.461612)
			(xy 343.13368 -243.465596) (xy 343.08053 -243.461612) (xy 343.028568 -243.449752) (xy 342.978954 -243.43028)
			(xy 342.932796 -243.403631) (xy 342.891125 -243.3704) (xy 342.854873 -243.331329) (xy 342.824849 -243.287292)
			(xy 342.801723 -243.239271) (xy 342.786013 -243.188341) (xy 342.77807 -243.135637) (xy 342.54949 -243.135637)
			(xy 342.541547 -243.188341) (xy 342.525837 -243.239271) (xy 342.502711 -243.287292) (xy 342.472687 -243.331329)
			(xy 342.436435 -243.3704) (xy 342.394764 -243.403631) (xy 342.348606 -243.43028) (xy 342.298992 -243.449752)
			(xy 342.24703 -243.461612) (xy 342.19388 -243.465596) (xy 342.14073 -243.461612) (xy 342.088768 -243.449752)
			(xy 342.039154 -243.43028) (xy 341.992996 -243.403631) (xy 341.951325 -243.3704) (xy 341.915073 -243.331329)
			(xy 341.885049 -243.287292) (xy 341.861923 -243.239271) (xy 341.846213 -243.188341) (xy 341.83827 -243.135637)
			(xy 341.60969 -243.135637) (xy 341.601747 -243.188341) (xy 341.586037 -243.239271) (xy 341.562911 -243.287292)
			(xy 341.532887 -243.331329) (xy 341.496635 -243.3704) (xy 341.454964 -243.403631) (xy 341.408806 -243.43028)
			(xy 341.359192 -243.449752) (xy 341.30723 -243.461612) (xy 341.25408 -243.465596) (xy 341.20093 -243.461612)
			(xy 341.148968 -243.449752) (xy 341.099354 -243.43028) (xy 341.053196 -243.403631) (xy 341.011525 -243.3704)
			(xy 340.975273 -243.331329) (xy 340.945249 -243.287292) (xy 340.922123 -243.239271) (xy 340.906413 -243.188341)
			(xy 340.89847 -243.135637) (xy 340.66989 -243.135637) (xy 340.661947 -243.188341) (xy 340.646237 -243.239271)
			(xy 340.623111 -243.287292) (xy 340.593087 -243.331329) (xy 340.556835 -243.3704) (xy 340.515164 -243.403631)
			(xy 340.469006 -243.43028) (xy 340.419392 -243.449752) (xy 340.36743 -243.461612) (xy 340.31428 -243.465596)
			(xy 340.26113 -243.461612) (xy 340.209168 -243.449752) (xy 340.159554 -243.43028) (xy 340.113396 -243.403631)
			(xy 340.071725 -243.3704) (xy 340.035473 -243.331329) (xy 340.005449 -243.287292) (xy 339.982323 -243.239271)
			(xy 339.966613 -243.188341) (xy 339.95867 -243.135637) (xy 339.729388 -243.135637) (xy 339.727349 -243.162613)
			(xy 339.715284 -243.215009) (xy 339.695481 -243.264997) (xy 339.66839 -243.31144) (xy 339.634625 -243.353284)
			(xy 339.594955 -243.389577) (xy 339.55028 -243.419495) (xy 339.501616 -243.442359) (xy 339.450068 -243.457648)
			(xy 339.423502 -243.461794) (xy 339.37956 -243.46789) (xy 339.37956 -243.949453) (xy 339.489024 -243.949453)
			(xy 339.489024 -243.896155) (xy 339.496967 -243.843451) (xy 339.512677 -243.792521) (xy 339.535803 -243.7445)
			(xy 339.565827 -243.700463) (xy 339.602079 -243.661392) (xy 339.64375 -243.628161) (xy 339.689908 -243.601512)
			(xy 339.739522 -243.58204) (xy 339.791484 -243.57018) (xy 339.844634 -243.566197) (xy 339.897784 -243.57018)
			(xy 339.949746 -243.58204) (xy 339.99936 -243.601512) (xy 340.045518 -243.628161) (xy 340.087189 -243.661392)
			(xy 340.123441 -243.700463) (xy 340.153465 -243.7445) (xy 340.176591 -243.792521) (xy 340.192301 -243.843451)
			(xy 340.200244 -243.896155) (xy 340.200742 -243.922804) (xy 340.200244 -243.949453) (xy 340.428824 -243.949453)
			(xy 340.428824 -243.896155) (xy 340.436767 -243.843451) (xy 340.452477 -243.792521) (xy 340.475603 -243.7445)
			(xy 340.505627 -243.700463) (xy 340.541879 -243.661392) (xy 340.58355 -243.628161) (xy 340.629708 -243.601512)
			(xy 340.679322 -243.58204) (xy 340.731284 -243.57018) (xy 340.784434 -243.566197) (xy 340.837584 -243.57018)
			(xy 340.889546 -243.58204) (xy 340.93916 -243.601512) (xy 340.985318 -243.628161) (xy 341.026989 -243.661392)
			(xy 341.063241 -243.700463) (xy 341.093265 -243.7445) (xy 341.116391 -243.792521) (xy 341.132101 -243.843451)
			(xy 341.140044 -243.896155) (xy 341.140542 -243.922804) (xy 341.140044 -243.949453) (xy 341.368624 -243.949453)
			(xy 341.368624 -243.896155) (xy 341.376567 -243.843451) (xy 341.392277 -243.792521) (xy 341.415403 -243.7445)
			(xy 341.445427 -243.700463) (xy 341.481679 -243.661392) (xy 341.52335 -243.628161) (xy 341.569508 -243.601512)
			(xy 341.619122 -243.58204) (xy 341.671084 -243.57018) (xy 341.724234 -243.566197) (xy 341.777384 -243.57018)
			(xy 341.829346 -243.58204) (xy 341.87896 -243.601512) (xy 341.925118 -243.628161) (xy 341.966789 -243.661392)
			(xy 342.003041 -243.700463) (xy 342.033065 -243.7445) (xy 342.056191 -243.792521) (xy 342.071901 -243.843451)
			(xy 342.079844 -243.896155) (xy 342.080342 -243.922804) (xy 342.079844 -243.949453) (xy 342.30817 -243.949453)
			(xy 342.30817 -243.896155) (xy 342.316113 -243.843451) (xy 342.331823 -243.792521) (xy 342.354949 -243.7445)
			(xy 342.384973 -243.700463) (xy 342.421225 -243.661392) (xy 342.462896 -243.628161) (xy 342.509054 -243.601512)
			(xy 342.558668 -243.58204) (xy 342.61063 -243.57018) (xy 342.66378 -243.566197) (xy 342.71693 -243.57018)
			(xy 342.768892 -243.58204) (xy 342.818506 -243.601512) (xy 342.864664 -243.628161) (xy 342.906335 -243.661392)
			(xy 342.942587 -243.700463) (xy 342.972611 -243.7445) (xy 342.995737 -243.792521) (xy 343.011447 -243.843451)
			(xy 343.01939 -243.896155) (xy 343.019888 -243.922804) (xy 343.01939 -243.949453) (xy 343.248224 -243.949453)
			(xy 343.248224 -243.896155) (xy 343.256167 -243.843451) (xy 343.271877 -243.792521) (xy 343.295003 -243.7445)
			(xy 343.325027 -243.700463) (xy 343.361279 -243.661392) (xy 343.40295 -243.628161) (xy 343.449108 -243.601512)
			(xy 343.498722 -243.58204) (xy 343.550684 -243.57018) (xy 343.603834 -243.566197) (xy 343.656984 -243.57018)
			(xy 343.708946 -243.58204) (xy 343.75856 -243.601512) (xy 343.804718 -243.628161) (xy 343.846389 -243.661392)
			(xy 343.882641 -243.700463) (xy 343.912665 -243.7445) (xy 343.935791 -243.792521) (xy 343.951501 -243.843451)
			(xy 343.959444 -243.896155) (xy 343.959942 -243.922804) (xy 343.959444 -243.949453) (xy 344.188024 -243.949453)
			(xy 344.188024 -243.896155) (xy 344.195967 -243.843451) (xy 344.211677 -243.792521) (xy 344.234803 -243.7445)
			(xy 344.264827 -243.700463) (xy 344.301079 -243.661392) (xy 344.34275 -243.628161) (xy 344.388908 -243.601512)
			(xy 344.438522 -243.58204) (xy 344.490484 -243.57018) (xy 344.543634 -243.566197) (xy 344.596784 -243.57018)
			(xy 344.648746 -243.58204) (xy 344.69836 -243.601512) (xy 344.744518 -243.628161) (xy 344.786189 -243.661392)
			(xy 344.822441 -243.700463) (xy 344.852465 -243.7445) (xy 344.875591 -243.792521) (xy 344.891301 -243.843451)
			(xy 344.899244 -243.896155) (xy 344.899742 -243.922804) (xy 344.899244 -243.949453) (xy 345.127824 -243.949453)
			(xy 345.127824 -243.896155) (xy 345.135767 -243.843451) (xy 345.151477 -243.792521) (xy 345.174603 -243.7445)
			(xy 345.204627 -243.700463) (xy 345.240879 -243.661392) (xy 345.28255 -243.628161) (xy 345.328708 -243.601512)
			(xy 345.378322 -243.58204) (xy 345.430284 -243.57018) (xy 345.483434 -243.566197) (xy 345.536584 -243.57018)
			(xy 345.588546 -243.58204) (xy 345.63816 -243.601512) (xy 345.684318 -243.628161) (xy 345.725989 -243.661392)
			(xy 345.762241 -243.700463) (xy 345.792265 -243.7445) (xy 345.815391 -243.792521) (xy 345.831101 -243.843451)
			(xy 345.839044 -243.896155) (xy 345.839542 -243.922804) (xy 345.839044 -243.949453) (xy 346.067624 -243.949453)
			(xy 346.067624 -243.896155) (xy 346.075567 -243.843451) (xy 346.091277 -243.792521) (xy 346.114403 -243.7445)
			(xy 346.144427 -243.700463) (xy 346.180679 -243.661392) (xy 346.22235 -243.628161) (xy 346.268508 -243.601512)
			(xy 346.318122 -243.58204) (xy 346.370084 -243.57018) (xy 346.423234 -243.566197) (xy 346.476384 -243.57018)
			(xy 346.528346 -243.58204) (xy 346.57796 -243.601512) (xy 346.624118 -243.628161) (xy 346.665789 -243.661392)
			(xy 346.702041 -243.700463) (xy 346.732065 -243.7445) (xy 346.755191 -243.792521) (xy 346.770901 -243.843451)
			(xy 346.778844 -243.896155) (xy 346.779342 -243.922804) (xy 346.778844 -243.949453) (xy 346.770901 -244.002157)
			(xy 346.755191 -244.053087) (xy 346.732065 -244.101108) (xy 346.702041 -244.145145) (xy 346.665789 -244.184216)
			(xy 346.624118 -244.217447) (xy 346.57796 -244.244096) (xy 346.528346 -244.263568) (xy 346.476384 -244.275428)
			(xy 346.423234 -244.279412) (xy 346.370084 -244.275428) (xy 346.318122 -244.263568) (xy 346.268508 -244.244096)
			(xy 346.22235 -244.217447) (xy 346.180679 -244.184216) (xy 346.144427 -244.145145) (xy 346.114403 -244.101108)
			(xy 346.091277 -244.053087) (xy 346.075567 -244.002157) (xy 346.067624 -243.949453) (xy 345.839044 -243.949453)
			(xy 345.831101 -244.002157) (xy 345.815391 -244.053087) (xy 345.792265 -244.101108) (xy 345.762241 -244.145145)
			(xy 345.725989 -244.184216) (xy 345.684318 -244.217447) (xy 345.63816 -244.244096) (xy 345.588546 -244.263568)
			(xy 345.536584 -244.275428) (xy 345.483434 -244.279412) (xy 345.430284 -244.275428) (xy 345.378322 -244.263568)
			(xy 345.328708 -244.244096) (xy 345.28255 -244.217447) (xy 345.240879 -244.184216) (xy 345.204627 -244.145145)
			(xy 345.174603 -244.101108) (xy 345.151477 -244.053087) (xy 345.135767 -244.002157) (xy 345.127824 -243.949453)
			(xy 344.899244 -243.949453) (xy 344.891301 -244.002157) (xy 344.875591 -244.053087) (xy 344.852465 -244.101108)
			(xy 344.822441 -244.145145) (xy 344.786189 -244.184216) (xy 344.744518 -244.217447) (xy 344.69836 -244.244096)
			(xy 344.648746 -244.263568) (xy 344.596784 -244.275428) (xy 344.543634 -244.279412) (xy 344.490484 -244.275428)
			(xy 344.438522 -244.263568) (xy 344.388908 -244.244096) (xy 344.34275 -244.217447) (xy 344.301079 -244.184216)
			(xy 344.264827 -244.145145) (xy 344.234803 -244.101108) (xy 344.211677 -244.053087) (xy 344.195967 -244.002157)
			(xy 344.188024 -243.949453) (xy 343.959444 -243.949453) (xy 343.951501 -244.002157) (xy 343.935791 -244.053087)
			(xy 343.912665 -244.101108) (xy 343.882641 -244.145145) (xy 343.846389 -244.184216) (xy 343.804718 -244.217447)
			(xy 343.75856 -244.244096) (xy 343.708946 -244.263568) (xy 343.656984 -244.275428) (xy 343.603834 -244.279412)
			(xy 343.550684 -244.275428) (xy 343.498722 -244.263568) (xy 343.449108 -244.244096) (xy 343.40295 -244.217447)
			(xy 343.361279 -244.184216) (xy 343.325027 -244.145145) (xy 343.295003 -244.101108) (xy 343.271877 -244.053087)
			(xy 343.256167 -244.002157) (xy 343.248224 -243.949453) (xy 343.01939 -243.949453) (xy 343.011447 -244.002157)
			(xy 342.995737 -244.053087) (xy 342.972611 -244.101108) (xy 342.942587 -244.145145) (xy 342.906335 -244.184216)
			(xy 342.864664 -244.217447) (xy 342.818506 -244.244096) (xy 342.768892 -244.263568) (xy 342.71693 -244.275428)
			(xy 342.66378 -244.279412) (xy 342.61063 -244.275428) (xy 342.558668 -244.263568) (xy 342.509054 -244.244096)
			(xy 342.462896 -244.217447) (xy 342.421225 -244.184216) (xy 342.384973 -244.145145) (xy 342.354949 -244.101108)
			(xy 342.331823 -244.053087) (xy 342.316113 -244.002157) (xy 342.30817 -243.949453) (xy 342.079844 -243.949453)
			(xy 342.071901 -244.002157) (xy 342.056191 -244.053087) (xy 342.033065 -244.101108) (xy 342.003041 -244.145145)
			(xy 341.966789 -244.184216) (xy 341.925118 -244.217447) (xy 341.87896 -244.244096) (xy 341.829346 -244.263568)
			(xy 341.777384 -244.275428) (xy 341.724234 -244.279412) (xy 341.671084 -244.275428) (xy 341.619122 -244.263568)
			(xy 341.569508 -244.244096) (xy 341.52335 -244.217447) (xy 341.481679 -244.184216) (xy 341.445427 -244.145145)
			(xy 341.415403 -244.101108) (xy 341.392277 -244.053087) (xy 341.376567 -244.002157) (xy 341.368624 -243.949453)
			(xy 341.140044 -243.949453) (xy 341.132101 -244.002157) (xy 341.116391 -244.053087) (xy 341.093265 -244.101108)
			(xy 341.063241 -244.145145) (xy 341.026989 -244.184216) (xy 340.985318 -244.217447) (xy 340.93916 -244.244096)
			(xy 340.889546 -244.263568) (xy 340.837584 -244.275428) (xy 340.784434 -244.279412) (xy 340.731284 -244.275428)
			(xy 340.679322 -244.263568) (xy 340.629708 -244.244096) (xy 340.58355 -244.217447) (xy 340.541879 -244.184216)
			(xy 340.505627 -244.145145) (xy 340.475603 -244.101108) (xy 340.452477 -244.053087) (xy 340.436767 -244.002157)
			(xy 340.428824 -243.949453) (xy 340.200244 -243.949453) (xy 340.192301 -244.002157) (xy 340.176591 -244.053087)
			(xy 340.153465 -244.101108) (xy 340.123441 -244.145145) (xy 340.087189 -244.184216) (xy 340.045518 -244.217447)
			(xy 339.99936 -244.244096) (xy 339.949746 -244.263568) (xy 339.897784 -244.275428) (xy 339.844634 -244.279412)
			(xy 339.791484 -244.275428) (xy 339.739522 -244.263568) (xy 339.689908 -244.244096) (xy 339.64375 -244.217447)
			(xy 339.602079 -244.184216) (xy 339.565827 -244.145145) (xy 339.535803 -244.101108) (xy 339.512677 -244.053087)
			(xy 339.496967 -244.002157) (xy 339.489024 -243.949453) (xy 339.37956 -243.949453) (xy 339.37956 -244.377718)
			(xy 339.423502 -244.383814) (xy 339.450052 -244.387996) (xy 339.501572 -244.403305) (xy 339.550206 -244.426181)
			(xy 339.594852 -244.456104) (xy 339.634494 -244.492396) (xy 339.668234 -244.534232) (xy 339.695305 -244.580662)
			(xy 339.715093 -244.630633) (xy 339.727148 -244.68301) (xy 339.731197 -244.736603) (xy 339.729182 -244.763269)
			(xy 339.958924 -244.763269) (xy 339.958924 -244.709971) (xy 339.966867 -244.657267) (xy 339.982577 -244.606337)
			(xy 340.005703 -244.558316) (xy 340.035727 -244.514279) (xy 340.071979 -244.475208) (xy 340.11365 -244.441977)
			(xy 340.159808 -244.415328) (xy 340.209422 -244.395856) (xy 340.261384 -244.383996) (xy 340.314534 -244.380013)
			(xy 340.367684 -244.383996) (xy 340.419646 -244.395856) (xy 340.46926 -244.415328) (xy 340.515418 -244.441977)
			(xy 340.557089 -244.475208) (xy 340.593341 -244.514279) (xy 340.623365 -244.558316) (xy 340.646491 -244.606337)
			(xy 340.662201 -244.657267) (xy 340.670144 -244.709971) (xy 340.670642 -244.73662) (xy 340.670144 -244.763269)
			(xy 340.89847 -244.763269) (xy 340.89847 -244.709971) (xy 340.906413 -244.657267) (xy 340.922123 -244.606337)
			(xy 340.945249 -244.558316) (xy 340.975273 -244.514279) (xy 341.011525 -244.475208) (xy 341.053196 -244.441977)
			(xy 341.099354 -244.415328) (xy 341.148968 -244.395856) (xy 341.20093 -244.383996) (xy 341.25408 -244.380013)
			(xy 341.30723 -244.383996) (xy 341.359192 -244.395856) (xy 341.408806 -244.415328) (xy 341.454964 -244.441977)
			(xy 341.496635 -244.475208) (xy 341.532887 -244.514279) (xy 341.562911 -244.558316) (xy 341.586037 -244.606337)
			(xy 341.601747 -244.657267) (xy 341.60969 -244.709971) (xy 341.610188 -244.73662) (xy 341.60969 -244.763269)
			(xy 341.83827 -244.763269) (xy 341.83827 -244.709971) (xy 341.846213 -244.657267) (xy 341.861923 -244.606337)
			(xy 341.885049 -244.558316) (xy 341.915073 -244.514279) (xy 341.951325 -244.475208) (xy 341.992996 -244.441977)
			(xy 342.039154 -244.415328) (xy 342.088768 -244.395856) (xy 342.14073 -244.383996) (xy 342.19388 -244.380013)
			(xy 342.24703 -244.383996) (xy 342.298992 -244.395856) (xy 342.348606 -244.415328) (xy 342.394764 -244.441977)
			(xy 342.436435 -244.475208) (xy 342.472687 -244.514279) (xy 342.502711 -244.558316) (xy 342.525837 -244.606337)
			(xy 342.541547 -244.657267) (xy 342.54949 -244.709971) (xy 342.549988 -244.73662) (xy 342.54949 -244.763269)
			(xy 342.77807 -244.763269) (xy 342.77807 -244.709971) (xy 342.786013 -244.657267) (xy 342.801723 -244.606337)
			(xy 342.824849 -244.558316) (xy 342.854873 -244.514279) (xy 342.891125 -244.475208) (xy 342.932796 -244.441977)
			(xy 342.978954 -244.415328) (xy 343.028568 -244.395856) (xy 343.08053 -244.383996) (xy 343.13368 -244.380013)
			(xy 343.18683 -244.383996) (xy 343.238792 -244.395856) (xy 343.288406 -244.415328) (xy 343.334564 -244.441977)
			(xy 343.376235 -244.475208) (xy 343.412487 -244.514279) (xy 343.442511 -244.558316) (xy 343.465637 -244.606337)
			(xy 343.481347 -244.657267) (xy 343.48929 -244.709971) (xy 343.489788 -244.73662) (xy 343.48929 -244.763269)
			(xy 343.71787 -244.763269) (xy 343.71787 -244.709971) (xy 343.725813 -244.657267) (xy 343.741523 -244.606337)
			(xy 343.764649 -244.558316) (xy 343.794673 -244.514279) (xy 343.830925 -244.475208) (xy 343.872596 -244.441977)
			(xy 343.918754 -244.415328) (xy 343.968368 -244.395856) (xy 344.02033 -244.383996) (xy 344.07348 -244.380013)
			(xy 344.12663 -244.383996) (xy 344.178592 -244.395856) (xy 344.228206 -244.415328) (xy 344.274364 -244.441977)
			(xy 344.316035 -244.475208) (xy 344.352287 -244.514279) (xy 344.382311 -244.558316) (xy 344.405437 -244.606337)
			(xy 344.421147 -244.657267) (xy 344.42909 -244.709971) (xy 344.429588 -244.73662) (xy 344.42909 -244.763269)
			(xy 344.657924 -244.763269) (xy 344.657924 -244.709971) (xy 344.665867 -244.657267) (xy 344.681577 -244.606337)
			(xy 344.704703 -244.558316) (xy 344.734727 -244.514279) (xy 344.770979 -244.475208) (xy 344.81265 -244.441977)
			(xy 344.858808 -244.415328) (xy 344.908422 -244.395856) (xy 344.960384 -244.383996) (xy 345.013534 -244.380013)
			(xy 345.066684 -244.383996) (xy 345.118646 -244.395856) (xy 345.16826 -244.415328) (xy 345.214418 -244.441977)
			(xy 345.256089 -244.475208) (xy 345.292341 -244.514279) (xy 345.322365 -244.558316) (xy 345.345491 -244.606337)
			(xy 345.361201 -244.657267) (xy 345.369144 -244.709971) (xy 345.369642 -244.73662) (xy 345.369144 -244.763269)
			(xy 345.59747 -244.763269) (xy 345.59747 -244.709971) (xy 345.605413 -244.657267) (xy 345.621123 -244.606337)
			(xy 345.644249 -244.558316) (xy 345.674273 -244.514279) (xy 345.710525 -244.475208) (xy 345.752196 -244.441977)
			(xy 345.798354 -244.415328) (xy 345.847968 -244.395856) (xy 345.89993 -244.383996) (xy 345.95308 -244.380013)
			(xy 346.00623 -244.383996) (xy 346.058192 -244.395856) (xy 346.107806 -244.415328) (xy 346.153964 -244.441977)
			(xy 346.195635 -244.475208) (xy 346.231887 -244.514279) (xy 346.261911 -244.558316) (xy 346.285037 -244.606337)
			(xy 346.300747 -244.657267) (xy 346.30869 -244.709971) (xy 346.309188 -244.73662) (xy 346.30869 -244.763269)
			(xy 346.53727 -244.763269) (xy 346.53727 -244.709971) (xy 346.545213 -244.657267) (xy 346.560923 -244.606337)
			(xy 346.584049 -244.558316) (xy 346.614073 -244.514279) (xy 346.650325 -244.475208) (xy 346.691996 -244.441977)
			(xy 346.738154 -244.415328) (xy 346.787768 -244.395856) (xy 346.83973 -244.383996) (xy 346.89288 -244.380013)
			(xy 346.94603 -244.383996) (xy 346.997992 -244.395856) (xy 347.047606 -244.415328) (xy 347.093764 -244.441977)
			(xy 347.135435 -244.475208) (xy 347.171687 -244.514279) (xy 347.201711 -244.558316) (xy 347.224837 -244.606337)
			(xy 347.240547 -244.657267) (xy 347.24849 -244.709971) (xy 347.248988 -244.73662) (xy 347.24849 -244.763269)
			(xy 347.240547 -244.815973) (xy 347.224837 -244.866903) (xy 347.201711 -244.914924) (xy 347.171687 -244.958961)
			(xy 347.135435 -244.998032) (xy 347.093764 -245.031263) (xy 347.047606 -245.057912) (xy 346.997992 -245.077384)
			(xy 346.94603 -245.089244) (xy 346.89288 -245.093228) (xy 346.83973 -245.089244) (xy 346.787768 -245.077384)
			(xy 346.738154 -245.057912) (xy 346.691996 -245.031263) (xy 346.650325 -244.998032) (xy 346.614073 -244.958961)
			(xy 346.584049 -244.914924) (xy 346.560923 -244.866903) (xy 346.545213 -244.815973) (xy 346.53727 -244.763269)
			(xy 346.30869 -244.763269) (xy 346.300747 -244.815973) (xy 346.285037 -244.866903) (xy 346.261911 -244.914924)
			(xy 346.231887 -244.958961) (xy 346.195635 -244.998032) (xy 346.153964 -245.031263) (xy 346.107806 -245.057912)
			(xy 346.058192 -245.077384) (xy 346.00623 -245.089244) (xy 345.95308 -245.093228) (xy 345.89993 -245.089244)
			(xy 345.847968 -245.077384) (xy 345.798354 -245.057912) (xy 345.752196 -245.031263) (xy 345.710525 -244.998032)
			(xy 345.674273 -244.958961) (xy 345.644249 -244.914924) (xy 345.621123 -244.866903) (xy 345.605413 -244.815973)
			(xy 345.59747 -244.763269) (xy 345.369144 -244.763269) (xy 345.361201 -244.815973) (xy 345.345491 -244.866903)
			(xy 345.322365 -244.914924) (xy 345.292341 -244.958961) (xy 345.256089 -244.998032) (xy 345.214418 -245.031263)
			(xy 345.16826 -245.057912) (xy 345.118646 -245.077384) (xy 345.066684 -245.089244) (xy 345.013534 -245.093228)
			(xy 344.960384 -245.089244) (xy 344.908422 -245.077384) (xy 344.858808 -245.057912) (xy 344.81265 -245.031263)
			(xy 344.770979 -244.998032) (xy 344.734727 -244.958961) (xy 344.704703 -244.914924) (xy 344.681577 -244.866903)
			(xy 344.665867 -244.815973) (xy 344.657924 -244.763269) (xy 344.42909 -244.763269) (xy 344.421147 -244.815973)
			(xy 344.405437 -244.866903) (xy 344.382311 -244.914924) (xy 344.352287 -244.958961) (xy 344.316035 -244.998032)
			(xy 344.274364 -245.031263) (xy 344.228206 -245.057912) (xy 344.178592 -245.077384) (xy 344.12663 -245.089244)
			(xy 344.07348 -245.093228) (xy 344.02033 -245.089244) (xy 343.968368 -245.077384) (xy 343.918754 -245.057912)
			(xy 343.872596 -245.031263) (xy 343.830925 -244.998032) (xy 343.794673 -244.958961) (xy 343.764649 -244.914924)
			(xy 343.741523 -244.866903) (xy 343.725813 -244.815973) (xy 343.71787 -244.763269) (xy 343.48929 -244.763269)
			(xy 343.481347 -244.815973) (xy 343.465637 -244.866903) (xy 343.442511 -244.914924) (xy 343.412487 -244.958961)
			(xy 343.376235 -244.998032) (xy 343.334564 -245.031263) (xy 343.288406 -245.057912) (xy 343.238792 -245.077384)
			(xy 343.18683 -245.089244) (xy 343.13368 -245.093228) (xy 343.08053 -245.089244) (xy 343.028568 -245.077384)
			(xy 342.978954 -245.057912) (xy 342.932796 -245.031263) (xy 342.891125 -244.998032) (xy 342.854873 -244.958961)
			(xy 342.824849 -244.914924) (xy 342.801723 -244.866903) (xy 342.786013 -244.815973) (xy 342.77807 -244.763269)
			(xy 342.54949 -244.763269) (xy 342.541547 -244.815973) (xy 342.525837 -244.866903) (xy 342.502711 -244.914924)
			(xy 342.472687 -244.958961) (xy 342.436435 -244.998032) (xy 342.394764 -245.031263) (xy 342.348606 -245.057912)
			(xy 342.298992 -245.077384) (xy 342.24703 -245.089244) (xy 342.19388 -245.093228) (xy 342.14073 -245.089244)
			(xy 342.088768 -245.077384) (xy 342.039154 -245.057912) (xy 341.992996 -245.031263) (xy 341.951325 -244.998032)
			(xy 341.915073 -244.958961) (xy 341.885049 -244.914924) (xy 341.861923 -244.866903) (xy 341.846213 -244.815973)
			(xy 341.83827 -244.763269) (xy 341.60969 -244.763269) (xy 341.601747 -244.815973) (xy 341.586037 -244.866903)
			(xy 341.562911 -244.914924) (xy 341.532887 -244.958961) (xy 341.496635 -244.998032) (xy 341.454964 -245.031263)
			(xy 341.408806 -245.057912) (xy 341.359192 -245.077384) (xy 341.30723 -245.089244) (xy 341.25408 -245.093228)
			(xy 341.20093 -245.089244) (xy 341.148968 -245.077384) (xy 341.099354 -245.057912) (xy 341.053196 -245.031263)
			(xy 341.011525 -244.998032) (xy 340.975273 -244.958961) (xy 340.945249 -244.914924) (xy 340.922123 -244.866903)
			(xy 340.906413 -244.815973) (xy 340.89847 -244.763269) (xy 340.670144 -244.763269) (xy 340.662201 -244.815973)
			(xy 340.646491 -244.866903) (xy 340.623365 -244.914924) (xy 340.593341 -244.958961) (xy 340.557089 -244.998032)
			(xy 340.515418 -245.031263) (xy 340.46926 -245.057912) (xy 340.419646 -245.077384) (xy 340.367684 -245.089244)
			(xy 340.314534 -245.093228) (xy 340.261384 -245.089244) (xy 340.209422 -245.077384) (xy 340.159808 -245.057912)
			(xy 340.11365 -245.031263) (xy 340.071979 -244.998032) (xy 340.035727 -244.958961) (xy 340.005703 -244.914924)
			(xy 339.982577 -244.866903) (xy 339.966867 -244.815973) (xy 339.958924 -244.763269) (xy 339.729182 -244.763269)
			(xy 339.727147 -244.790196) (xy 339.715092 -244.842572) (xy 339.695303 -244.892543) (xy 339.668231 -244.938973)
			(xy 339.634491 -244.980808) (xy 339.594847 -245.017099) (xy 339.550201 -245.047022) (xy 339.501566 -245.069897)
			(xy 339.450047 -245.085205) (xy 339.423502 -245.089426) (xy 339.37956 -245.095522) (xy 339.37956 -245.577339)
			(xy 339.489024 -245.577339) (xy 339.489024 -245.524041) (xy 339.496967 -245.471337) (xy 339.512677 -245.420407)
			(xy 339.535803 -245.372386) (xy 339.565827 -245.328349) (xy 339.602079 -245.289278) (xy 339.64375 -245.256047)
			(xy 339.689908 -245.229398) (xy 339.739522 -245.209926) (xy 339.791484 -245.198066) (xy 339.844634 -245.194083)
			(xy 339.897784 -245.198066) (xy 339.949746 -245.209926) (xy 339.99936 -245.229398) (xy 340.045518 -245.256047)
			(xy 340.087189 -245.289278) (xy 340.123441 -245.328349) (xy 340.153465 -245.372386) (xy 340.176591 -245.420407)
			(xy 340.192301 -245.471337) (xy 340.200244 -245.524041) (xy 340.200742 -245.55069) (xy 340.200244 -245.577339)
			(xy 340.42857 -245.577339) (xy 340.42857 -245.524041) (xy 340.436513 -245.471337) (xy 340.452223 -245.420407)
			(xy 340.475349 -245.372386) (xy 340.505373 -245.328349) (xy 340.541625 -245.289278) (xy 340.583296 -245.256047)
			(xy 340.629454 -245.229398) (xy 340.679068 -245.209926) (xy 340.73103 -245.198066) (xy 340.78418 -245.194083)
			(xy 340.83733 -245.198066) (xy 340.889292 -245.209926) (xy 340.938906 -245.229398) (xy 340.985064 -245.256047)
			(xy 341.026735 -245.289278) (xy 341.062987 -245.328349) (xy 341.093011 -245.372386) (xy 341.116137 -245.420407)
			(xy 341.131847 -245.471337) (xy 341.13979 -245.524041) (xy 341.140288 -245.55069) (xy 341.13979 -245.577339)
			(xy 341.368624 -245.577339) (xy 341.368624 -245.524041) (xy 341.376567 -245.471337) (xy 341.392277 -245.420407)
			(xy 341.415403 -245.372386) (xy 341.445427 -245.328349) (xy 341.481679 -245.289278) (xy 341.52335 -245.256047)
			(xy 341.569508 -245.229398) (xy 341.619122 -245.209926) (xy 341.671084 -245.198066) (xy 341.724234 -245.194083)
			(xy 341.777384 -245.198066) (xy 341.829346 -245.209926) (xy 341.87896 -245.229398) (xy 341.925118 -245.256047)
			(xy 341.966789 -245.289278) (xy 342.003041 -245.328349) (xy 342.033065 -245.372386) (xy 342.056191 -245.420407)
			(xy 342.071901 -245.471337) (xy 342.079844 -245.524041) (xy 342.080342 -245.55069) (xy 342.079844 -245.577339)
			(xy 342.308424 -245.577339) (xy 342.308424 -245.524041) (xy 342.316367 -245.471337) (xy 342.332077 -245.420407)
			(xy 342.355203 -245.372386) (xy 342.385227 -245.328349) (xy 342.421479 -245.289278) (xy 342.46315 -245.256047)
			(xy 342.509308 -245.229398) (xy 342.558922 -245.209926) (xy 342.610884 -245.198066) (xy 342.664034 -245.194083)
			(xy 342.717184 -245.198066) (xy 342.769146 -245.209926) (xy 342.81876 -245.229398) (xy 342.864918 -245.256047)
			(xy 342.906589 -245.289278) (xy 342.942841 -245.328349) (xy 342.972865 -245.372386) (xy 342.995991 -245.420407)
			(xy 343.011701 -245.471337) (xy 343.019644 -245.524041) (xy 343.020142 -245.55069) (xy 343.019644 -245.577339)
			(xy 343.248224 -245.577339) (xy 343.248224 -245.524041) (xy 343.256167 -245.471337) (xy 343.271877 -245.420407)
			(xy 343.295003 -245.372386) (xy 343.325027 -245.328349) (xy 343.361279 -245.289278) (xy 343.40295 -245.256047)
			(xy 343.449108 -245.229398) (xy 343.498722 -245.209926) (xy 343.550684 -245.198066) (xy 343.603834 -245.194083)
			(xy 343.656984 -245.198066) (xy 343.708946 -245.209926) (xy 343.75856 -245.229398) (xy 343.804718 -245.256047)
			(xy 343.846389 -245.289278) (xy 343.882641 -245.328349) (xy 343.912665 -245.372386) (xy 343.935791 -245.420407)
			(xy 343.951501 -245.471337) (xy 343.959444 -245.524041) (xy 343.959942 -245.55069) (xy 343.959444 -245.577339)
			(xy 344.188024 -245.577339) (xy 344.188024 -245.524041) (xy 344.195967 -245.471337) (xy 344.211677 -245.420407)
			(xy 344.234803 -245.372386) (xy 344.264827 -245.328349) (xy 344.301079 -245.289278) (xy 344.34275 -245.256047)
			(xy 344.388908 -245.229398) (xy 344.438522 -245.209926) (xy 344.490484 -245.198066) (xy 344.543634 -245.194083)
			(xy 344.596784 -245.198066) (xy 344.648746 -245.209926) (xy 344.69836 -245.229398) (xy 344.744518 -245.256047)
			(xy 344.786189 -245.289278) (xy 344.822441 -245.328349) (xy 344.852465 -245.372386) (xy 344.875591 -245.420407)
			(xy 344.891301 -245.471337) (xy 344.899244 -245.524041) (xy 344.899742 -245.55069) (xy 344.899244 -245.577339)
			(xy 345.12757 -245.577339) (xy 345.12757 -245.524041) (xy 345.135513 -245.471337) (xy 345.151223 -245.420407)
			(xy 345.174349 -245.372386) (xy 345.204373 -245.328349) (xy 345.240625 -245.289278) (xy 345.282296 -245.256047)
			(xy 345.328454 -245.229398) (xy 345.378068 -245.209926) (xy 345.43003 -245.198066) (xy 345.48318 -245.194083)
			(xy 345.53633 -245.198066) (xy 345.588292 -245.209926) (xy 345.637906 -245.229398) (xy 345.684064 -245.256047)
			(xy 345.725735 -245.289278) (xy 345.761987 -245.328349) (xy 345.792011 -245.372386) (xy 345.815137 -245.420407)
			(xy 345.830847 -245.471337) (xy 345.83879 -245.524041) (xy 345.839288 -245.55069) (xy 345.83879 -245.577339)
			(xy 346.067624 -245.577339) (xy 346.067624 -245.524041) (xy 346.075567 -245.471337) (xy 346.091277 -245.420407)
			(xy 346.114403 -245.372386) (xy 346.144427 -245.328349) (xy 346.180679 -245.289278) (xy 346.22235 -245.256047)
			(xy 346.268508 -245.229398) (xy 346.318122 -245.209926) (xy 346.370084 -245.198066) (xy 346.423234 -245.194083)
			(xy 346.476384 -245.198066) (xy 346.528346 -245.209926) (xy 346.57796 -245.229398) (xy 346.624118 -245.256047)
			(xy 346.665789 -245.289278) (xy 346.702041 -245.328349) (xy 346.732065 -245.372386) (xy 346.755191 -245.420407)
			(xy 346.770901 -245.471337) (xy 346.778844 -245.524041) (xy 346.779342 -245.55069) (xy 346.778844 -245.577339)
			(xy 346.770901 -245.630043) (xy 346.755191 -245.680973) (xy 346.732065 -245.728994) (xy 346.702041 -245.773031)
			(xy 346.665789 -245.812102) (xy 346.624118 -245.845333) (xy 346.57796 -245.871982) (xy 346.528346 -245.891454)
			(xy 346.476384 -245.903314) (xy 346.423234 -245.907298) (xy 346.370084 -245.903314) (xy 346.318122 -245.891454)
			(xy 346.268508 -245.871982) (xy 346.22235 -245.845333) (xy 346.180679 -245.812102) (xy 346.144427 -245.773031)
			(xy 346.114403 -245.728994) (xy 346.091277 -245.680973) (xy 346.075567 -245.630043) (xy 346.067624 -245.577339)
			(xy 345.83879 -245.577339) (xy 345.830847 -245.630043) (xy 345.815137 -245.680973) (xy 345.792011 -245.728994)
			(xy 345.761987 -245.773031) (xy 345.725735 -245.812102) (xy 345.684064 -245.845333) (xy 345.637906 -245.871982)
			(xy 345.588292 -245.891454) (xy 345.53633 -245.903314) (xy 345.48318 -245.907298) (xy 345.43003 -245.903314)
			(xy 345.378068 -245.891454) (xy 345.328454 -245.871982) (xy 345.282296 -245.845333) (xy 345.240625 -245.812102)
			(xy 345.204373 -245.773031) (xy 345.174349 -245.728994) (xy 345.151223 -245.680973) (xy 345.135513 -245.630043)
			(xy 345.12757 -245.577339) (xy 344.899244 -245.577339) (xy 344.891301 -245.630043) (xy 344.875591 -245.680973)
			(xy 344.852465 -245.728994) (xy 344.822441 -245.773031) (xy 344.786189 -245.812102) (xy 344.744518 -245.845333)
			(xy 344.69836 -245.871982) (xy 344.648746 -245.891454) (xy 344.596784 -245.903314) (xy 344.543634 -245.907298)
			(xy 344.490484 -245.903314) (xy 344.438522 -245.891454) (xy 344.388908 -245.871982) (xy 344.34275 -245.845333)
			(xy 344.301079 -245.812102) (xy 344.264827 -245.773031) (xy 344.234803 -245.728994) (xy 344.211677 -245.680973)
			(xy 344.195967 -245.630043) (xy 344.188024 -245.577339) (xy 343.959444 -245.577339) (xy 343.951501 -245.630043)
			(xy 343.935791 -245.680973) (xy 343.912665 -245.728994) (xy 343.882641 -245.773031) (xy 343.846389 -245.812102)
			(xy 343.804718 -245.845333) (xy 343.75856 -245.871982) (xy 343.708946 -245.891454) (xy 343.656984 -245.903314)
			(xy 343.603834 -245.907298) (xy 343.550684 -245.903314) (xy 343.498722 -245.891454) (xy 343.449108 -245.871982)
			(xy 343.40295 -245.845333) (xy 343.361279 -245.812102) (xy 343.325027 -245.773031) (xy 343.295003 -245.728994)
			(xy 343.271877 -245.680973) (xy 343.256167 -245.630043) (xy 343.248224 -245.577339) (xy 343.019644 -245.577339)
			(xy 343.011701 -245.630043) (xy 342.995991 -245.680973) (xy 342.972865 -245.728994) (xy 342.942841 -245.773031)
			(xy 342.906589 -245.812102) (xy 342.864918 -245.845333) (xy 342.81876 -245.871982) (xy 342.769146 -245.891454)
			(xy 342.717184 -245.903314) (xy 342.664034 -245.907298) (xy 342.610884 -245.903314) (xy 342.558922 -245.891454)
			(xy 342.509308 -245.871982) (xy 342.46315 -245.845333) (xy 342.421479 -245.812102) (xy 342.385227 -245.773031)
			(xy 342.355203 -245.728994) (xy 342.332077 -245.680973) (xy 342.316367 -245.630043) (xy 342.308424 -245.577339)
			(xy 342.079844 -245.577339) (xy 342.071901 -245.630043) (xy 342.056191 -245.680973) (xy 342.033065 -245.728994)
			(xy 342.003041 -245.773031) (xy 341.966789 -245.812102) (xy 341.925118 -245.845333) (xy 341.87896 -245.871982)
			(xy 341.829346 -245.891454) (xy 341.777384 -245.903314) (xy 341.724234 -245.907298) (xy 341.671084 -245.903314)
			(xy 341.619122 -245.891454) (xy 341.569508 -245.871982) (xy 341.52335 -245.845333) (xy 341.481679 -245.812102)
			(xy 341.445427 -245.773031) (xy 341.415403 -245.728994) (xy 341.392277 -245.680973) (xy 341.376567 -245.630043)
			(xy 341.368624 -245.577339) (xy 341.13979 -245.577339) (xy 341.131847 -245.630043) (xy 341.116137 -245.680973)
			(xy 341.093011 -245.728994) (xy 341.062987 -245.773031) (xy 341.026735 -245.812102) (xy 340.985064 -245.845333)
			(xy 340.938906 -245.871982) (xy 340.889292 -245.891454) (xy 340.83733 -245.903314) (xy 340.78418 -245.907298)
			(xy 340.73103 -245.903314) (xy 340.679068 -245.891454) (xy 340.629454 -245.871982) (xy 340.583296 -245.845333)
			(xy 340.541625 -245.812102) (xy 340.505373 -245.773031) (xy 340.475349 -245.728994) (xy 340.452223 -245.680973)
			(xy 340.436513 -245.630043) (xy 340.42857 -245.577339) (xy 340.200244 -245.577339) (xy 340.192301 -245.630043)
			(xy 340.176591 -245.680973) (xy 340.153465 -245.728994) (xy 340.123441 -245.773031) (xy 340.087189 -245.812102)
			(xy 340.045518 -245.845333) (xy 339.99936 -245.871982) (xy 339.949746 -245.891454) (xy 339.897784 -245.903314)
			(xy 339.844634 -245.907298) (xy 339.791484 -245.903314) (xy 339.739522 -245.891454) (xy 339.689908 -245.871982)
			(xy 339.64375 -245.845333) (xy 339.602079 -245.812102) (xy 339.565827 -245.773031) (xy 339.535803 -245.728994)
			(xy 339.512677 -245.680973) (xy 339.496967 -245.630043) (xy 339.489024 -245.577339) (xy 339.37956 -245.577339)
			(xy 339.37956 -246.005604) (xy 339.423502 -246.0117) (xy 339.450053 -246.015882) (xy 339.501575 -246.031191)
			(xy 339.550211 -246.054068) (xy 339.594859 -246.083992) (xy 339.634503 -246.120285) (xy 339.668245 -246.162122)
			(xy 339.695317 -246.208554) (xy 339.715106 -246.258527) (xy 339.727162 -246.310906) (xy 339.731211 -246.364501)
			(xy 339.729197 -246.391155) (xy 339.95867 -246.391155) (xy 339.95867 -246.337857) (xy 339.966613 -246.285153)
			(xy 339.982323 -246.234223) (xy 340.005449 -246.186202) (xy 340.035473 -246.142165) (xy 340.071725 -246.103094)
			(xy 340.113396 -246.069863) (xy 340.159554 -246.043214) (xy 340.209168 -246.023742) (xy 340.26113 -246.011882)
			(xy 340.31428 -246.007899) (xy 340.36743 -246.011882) (xy 340.419392 -246.023742) (xy 340.469006 -246.043214)
			(xy 340.515164 -246.069863) (xy 340.556835 -246.103094) (xy 340.593087 -246.142165) (xy 340.623111 -246.186202)
			(xy 340.646237 -246.234223) (xy 340.661947 -246.285153) (xy 340.66989 -246.337857) (xy 340.670388 -246.364506)
			(xy 340.66989 -246.391155) (xy 340.89847 -246.391155) (xy 340.89847 -246.337857) (xy 340.906413 -246.285153)
			(xy 340.922123 -246.234223) (xy 340.945249 -246.186202) (xy 340.975273 -246.142165) (xy 341.011525 -246.103094)
			(xy 341.053196 -246.069863) (xy 341.099354 -246.043214) (xy 341.148968 -246.023742) (xy 341.20093 -246.011882)
			(xy 341.25408 -246.007899) (xy 341.30723 -246.011882) (xy 341.359192 -246.023742) (xy 341.408806 -246.043214)
			(xy 341.454964 -246.069863) (xy 341.496635 -246.103094) (xy 341.532887 -246.142165) (xy 341.562911 -246.186202)
			(xy 341.586037 -246.234223) (xy 341.601747 -246.285153) (xy 341.60969 -246.337857) (xy 341.610188 -246.364506)
			(xy 341.60969 -246.391155) (xy 341.838524 -246.391155) (xy 341.838524 -246.337857) (xy 341.846467 -246.285153)
			(xy 341.862177 -246.234223) (xy 341.885303 -246.186202) (xy 341.915327 -246.142165) (xy 341.951579 -246.103094)
			(xy 341.99325 -246.069863) (xy 342.039408 -246.043214) (xy 342.089022 -246.023742) (xy 342.140984 -246.011882)
			(xy 342.194134 -246.007899) (xy 342.247284 -246.011882) (xy 342.299246 -246.023742) (xy 342.34886 -246.043214)
			(xy 342.395018 -246.069863) (xy 342.436689 -246.103094) (xy 342.472941 -246.142165) (xy 342.502965 -246.186202)
			(xy 342.526091 -246.234223) (xy 342.541801 -246.285153) (xy 342.549744 -246.337857) (xy 342.550242 -246.364506)
			(xy 342.549744 -246.391155) (xy 342.77807 -246.391155) (xy 342.77807 -246.337857) (xy 342.786013 -246.285153)
			(xy 342.801723 -246.234223) (xy 342.824849 -246.186202) (xy 342.854873 -246.142165) (xy 342.891125 -246.103094)
			(xy 342.932796 -246.069863) (xy 342.978954 -246.043214) (xy 343.028568 -246.023742) (xy 343.08053 -246.011882)
			(xy 343.13368 -246.007899) (xy 343.18683 -246.011882) (xy 343.238792 -246.023742) (xy 343.288406 -246.043214)
			(xy 343.334564 -246.069863) (xy 343.376235 -246.103094) (xy 343.412487 -246.142165) (xy 343.442511 -246.186202)
			(xy 343.465637 -246.234223) (xy 343.481347 -246.285153) (xy 343.48929 -246.337857) (xy 343.489788 -246.364506)
			(xy 343.48929 -246.391155) (xy 343.71787 -246.391155) (xy 343.71787 -246.337857) (xy 343.725813 -246.285153)
			(xy 343.741523 -246.234223) (xy 343.764649 -246.186202) (xy 343.794673 -246.142165) (xy 343.830925 -246.103094)
			(xy 343.872596 -246.069863) (xy 343.918754 -246.043214) (xy 343.968368 -246.023742) (xy 344.02033 -246.011882)
			(xy 344.07348 -246.007899) (xy 344.12663 -246.011882) (xy 344.178592 -246.023742) (xy 344.228206 -246.043214)
			(xy 344.274364 -246.069863) (xy 344.316035 -246.103094) (xy 344.352287 -246.142165) (xy 344.382311 -246.186202)
			(xy 344.405437 -246.234223) (xy 344.421147 -246.285153) (xy 344.42909 -246.337857) (xy 344.429588 -246.364506)
			(xy 344.42909 -246.391155) (xy 344.65767 -246.391155) (xy 344.65767 -246.337857) (xy 344.665613 -246.285153)
			(xy 344.681323 -246.234223) (xy 344.704449 -246.186202) (xy 344.734473 -246.142165) (xy 344.770725 -246.103094)
			(xy 344.812396 -246.069863) (xy 344.858554 -246.043214) (xy 344.908168 -246.023742) (xy 344.96013 -246.011882)
			(xy 345.01328 -246.007899) (xy 345.06643 -246.011882) (xy 345.118392 -246.023742) (xy 345.168006 -246.043214)
			(xy 345.214164 -246.069863) (xy 345.255835 -246.103094) (xy 345.292087 -246.142165) (xy 345.322111 -246.186202)
			(xy 345.345237 -246.234223) (xy 345.360947 -246.285153) (xy 345.36889 -246.337857) (xy 345.369388 -246.364506)
			(xy 345.36889 -246.391155) (xy 345.59747 -246.391155) (xy 345.59747 -246.337857) (xy 345.605413 -246.285153)
			(xy 345.621123 -246.234223) (xy 345.644249 -246.186202) (xy 345.674273 -246.142165) (xy 345.710525 -246.103094)
			(xy 345.752196 -246.069863) (xy 345.798354 -246.043214) (xy 345.847968 -246.023742) (xy 345.89993 -246.011882)
			(xy 345.95308 -246.007899) (xy 346.00623 -246.011882) (xy 346.058192 -246.023742) (xy 346.107806 -246.043214)
			(xy 346.153964 -246.069863) (xy 346.195635 -246.103094) (xy 346.231887 -246.142165) (xy 346.261911 -246.186202)
			(xy 346.285037 -246.234223) (xy 346.300747 -246.285153) (xy 346.30869 -246.337857) (xy 346.309188 -246.364506)
			(xy 346.30869 -246.391155) (xy 346.53727 -246.391155) (xy 346.53727 -246.337857) (xy 346.545213 -246.285153)
			(xy 346.560923 -246.234223) (xy 346.584049 -246.186202) (xy 346.614073 -246.142165) (xy 346.650325 -246.103094)
			(xy 346.691996 -246.069863) (xy 346.738154 -246.043214) (xy 346.787768 -246.023742) (xy 346.83973 -246.011882)
			(xy 346.89288 -246.007899) (xy 346.94603 -246.011882) (xy 346.997992 -246.023742) (xy 347.047606 -246.043214)
			(xy 347.093764 -246.069863) (xy 347.135435 -246.103094) (xy 347.171687 -246.142165) (xy 347.201711 -246.186202)
			(xy 347.224837 -246.234223) (xy 347.240547 -246.285153) (xy 347.24849 -246.337857) (xy 347.248988 -246.364506)
			(xy 347.24849 -246.391155) (xy 347.240547 -246.443859) (xy 347.224837 -246.494789) (xy 347.201711 -246.54281)
			(xy 347.171687 -246.586847) (xy 347.135435 -246.625918) (xy 347.093764 -246.659149) (xy 347.047606 -246.685798)
			(xy 346.997992 -246.70527) (xy 346.94603 -246.71713) (xy 346.89288 -246.721114) (xy 346.83973 -246.71713)
			(xy 346.787768 -246.70527) (xy 346.738154 -246.685798) (xy 346.691996 -246.659149) (xy 346.650325 -246.625918)
			(xy 346.614073 -246.586847) (xy 346.584049 -246.54281) (xy 346.560923 -246.494789) (xy 346.545213 -246.443859)
			(xy 346.53727 -246.391155) (xy 346.30869 -246.391155) (xy 346.300747 -246.443859) (xy 346.285037 -246.494789)
			(xy 346.261911 -246.54281) (xy 346.231887 -246.586847) (xy 346.195635 -246.625918) (xy 346.153964 -246.659149)
			(xy 346.107806 -246.685798) (xy 346.058192 -246.70527) (xy 346.00623 -246.71713) (xy 345.95308 -246.721114)
			(xy 345.89993 -246.71713) (xy 345.847968 -246.70527) (xy 345.798354 -246.685798) (xy 345.752196 -246.659149)
			(xy 345.710525 -246.625918) (xy 345.674273 -246.586847) (xy 345.644249 -246.54281) (xy 345.621123 -246.494789)
			(xy 345.605413 -246.443859) (xy 345.59747 -246.391155) (xy 345.36889 -246.391155) (xy 345.360947 -246.443859)
			(xy 345.345237 -246.494789) (xy 345.322111 -246.54281) (xy 345.292087 -246.586847) (xy 345.255835 -246.625918)
			(xy 345.214164 -246.659149) (xy 345.168006 -246.685798) (xy 345.118392 -246.70527) (xy 345.06643 -246.71713)
			(xy 345.01328 -246.721114) (xy 344.96013 -246.71713) (xy 344.908168 -246.70527) (xy 344.858554 -246.685798)
			(xy 344.812396 -246.659149) (xy 344.770725 -246.625918) (xy 344.734473 -246.586847) (xy 344.704449 -246.54281)
			(xy 344.681323 -246.494789) (xy 344.665613 -246.443859) (xy 344.65767 -246.391155) (xy 344.42909 -246.391155)
			(xy 344.421147 -246.443859) (xy 344.405437 -246.494789) (xy 344.382311 -246.54281) (xy 344.352287 -246.586847)
			(xy 344.316035 -246.625918) (xy 344.274364 -246.659149) (xy 344.228206 -246.685798) (xy 344.178592 -246.70527)
			(xy 344.12663 -246.71713) (xy 344.07348 -246.721114) (xy 344.02033 -246.71713) (xy 343.968368 -246.70527)
			(xy 343.918754 -246.685798) (xy 343.872596 -246.659149) (xy 343.830925 -246.625918) (xy 343.794673 -246.586847)
			(xy 343.764649 -246.54281) (xy 343.741523 -246.494789) (xy 343.725813 -246.443859) (xy 343.71787 -246.391155)
			(xy 343.48929 -246.391155) (xy 343.481347 -246.443859) (xy 343.465637 -246.494789) (xy 343.442511 -246.54281)
			(xy 343.412487 -246.586847) (xy 343.376235 -246.625918) (xy 343.334564 -246.659149) (xy 343.288406 -246.685798)
			(xy 343.238792 -246.70527) (xy 343.18683 -246.71713) (xy 343.13368 -246.721114) (xy 343.08053 -246.71713)
			(xy 343.028568 -246.70527) (xy 342.978954 -246.685798) (xy 342.932796 -246.659149) (xy 342.891125 -246.625918)
			(xy 342.854873 -246.586847) (xy 342.824849 -246.54281) (xy 342.801723 -246.494789) (xy 342.786013 -246.443859)
			(xy 342.77807 -246.391155) (xy 342.549744 -246.391155) (xy 342.541801 -246.443859) (xy 342.526091 -246.494789)
			(xy 342.502965 -246.54281) (xy 342.472941 -246.586847) (xy 342.436689 -246.625918) (xy 342.395018 -246.659149)
			(xy 342.34886 -246.685798) (xy 342.299246 -246.70527) (xy 342.247284 -246.71713) (xy 342.194134 -246.721114)
			(xy 342.140984 -246.71713) (xy 342.089022 -246.70527) (xy 342.039408 -246.685798) (xy 341.99325 -246.659149)
			(xy 341.951579 -246.625918) (xy 341.915327 -246.586847) (xy 341.885303 -246.54281) (xy 341.862177 -246.494789)
			(xy 341.846467 -246.443859) (xy 341.838524 -246.391155) (xy 341.60969 -246.391155) (xy 341.601747 -246.443859)
			(xy 341.586037 -246.494789) (xy 341.562911 -246.54281) (xy 341.532887 -246.586847) (xy 341.496635 -246.625918)
			(xy 341.454964 -246.659149) (xy 341.408806 -246.685798) (xy 341.359192 -246.70527) (xy 341.30723 -246.71713)
			(xy 341.25408 -246.721114) (xy 341.20093 -246.71713) (xy 341.148968 -246.70527) (xy 341.099354 -246.685798)
			(xy 341.053196 -246.659149) (xy 341.011525 -246.625918) (xy 340.975273 -246.586847) (xy 340.945249 -246.54281)
			(xy 340.922123 -246.494789) (xy 340.906413 -246.443859) (xy 340.89847 -246.391155) (xy 340.66989 -246.391155)
			(xy 340.661947 -246.443859) (xy 340.646237 -246.494789) (xy 340.623111 -246.54281) (xy 340.593087 -246.586847)
			(xy 340.556835 -246.625918) (xy 340.515164 -246.659149) (xy 340.469006 -246.685798) (xy 340.419392 -246.70527)
			(xy 340.36743 -246.71713) (xy 340.31428 -246.721114) (xy 340.26113 -246.71713) (xy 340.209168 -246.70527)
			(xy 340.159554 -246.685798) (xy 340.113396 -246.659149) (xy 340.071725 -246.625918) (xy 340.035473 -246.586847)
			(xy 340.005449 -246.54281) (xy 339.982323 -246.494789) (xy 339.966613 -246.443859) (xy 339.95867 -246.391155)
			(xy 339.729197 -246.391155) (xy 339.727161 -246.418096) (xy 339.715105 -246.470475) (xy 339.695316 -246.520447)
			(xy 339.668244 -246.566879) (xy 339.634502 -246.608716) (xy 339.594857 -246.645009) (xy 339.55021 -246.674933)
			(xy 339.501573 -246.697809) (xy 339.450051 -246.713118) (xy 339.423502 -246.717312) (xy 339.37956 -246.723408)
			(xy 339.37956 -247.204971) (xy 339.48877 -247.204971) (xy 339.48877 -247.151673) (xy 339.496713 -247.098969)
			(xy 339.512423 -247.048039) (xy 339.535549 -247.000018) (xy 339.565573 -246.955981) (xy 339.601825 -246.91691)
			(xy 339.643496 -246.883679) (xy 339.689654 -246.85703) (xy 339.739268 -246.837558) (xy 339.79123 -246.825698)
			(xy 339.84438 -246.821715) (xy 339.89753 -246.825698) (xy 339.949492 -246.837558) (xy 339.999106 -246.85703)
			(xy 340.045264 -246.883679) (xy 340.086935 -246.91691) (xy 340.123187 -246.955981) (xy 340.153211 -247.000018)
			(xy 340.176337 -247.048039) (xy 340.192047 -247.098969) (xy 340.19999 -247.151673) (xy 340.200488 -247.178322)
			(xy 340.19999 -247.204971) (xy 340.428824 -247.204971) (xy 340.428824 -247.151673) (xy 340.436767 -247.098969)
			(xy 340.452477 -247.048039) (xy 340.475603 -247.000018) (xy 340.505627 -246.955981) (xy 340.541879 -246.91691)
			(xy 340.58355 -246.883679) (xy 340.629708 -246.85703) (xy 340.679322 -246.837558) (xy 340.731284 -246.825698)
			(xy 340.784434 -246.821715) (xy 340.837584 -246.825698) (xy 340.889546 -246.837558) (xy 340.93916 -246.85703)
			(xy 340.985318 -246.883679) (xy 341.026989 -246.91691) (xy 341.063241 -246.955981) (xy 341.093265 -247.000018)
			(xy 341.116391 -247.048039) (xy 341.132101 -247.098969) (xy 341.140044 -247.151673) (xy 341.140542 -247.178322)
			(xy 341.140044 -247.204971) (xy 341.368624 -247.204971) (xy 341.368624 -247.151673) (xy 341.376567 -247.098969)
			(xy 341.392277 -247.048039) (xy 341.415403 -247.000018) (xy 341.445427 -246.955981) (xy 341.481679 -246.91691)
			(xy 341.52335 -246.883679) (xy 341.569508 -246.85703) (xy 341.619122 -246.837558) (xy 341.671084 -246.825698)
			(xy 341.724234 -246.821715) (xy 341.777384 -246.825698) (xy 341.829346 -246.837558) (xy 341.87896 -246.85703)
			(xy 341.925118 -246.883679) (xy 341.966789 -246.91691) (xy 342.003041 -246.955981) (xy 342.033065 -247.000018)
			(xy 342.056191 -247.048039) (xy 342.071901 -247.098969) (xy 342.079844 -247.151673) (xy 342.080342 -247.178322)
			(xy 342.079844 -247.204971) (xy 342.308424 -247.204971) (xy 342.308424 -247.151673) (xy 342.316367 -247.098969)
			(xy 342.332077 -247.048039) (xy 342.355203 -247.000018) (xy 342.385227 -246.955981) (xy 342.421479 -246.91691)
			(xy 342.46315 -246.883679) (xy 342.509308 -246.85703) (xy 342.558922 -246.837558) (xy 342.610884 -246.825698)
			(xy 342.664034 -246.821715) (xy 342.717184 -246.825698) (xy 342.769146 -246.837558) (xy 342.81876 -246.85703)
			(xy 342.864918 -246.883679) (xy 342.906589 -246.91691) (xy 342.942841 -246.955981) (xy 342.972865 -247.000018)
			(xy 342.995991 -247.048039) (xy 343.011701 -247.098969) (xy 343.019644 -247.151673) (xy 343.020142 -247.178322)
			(xy 343.019644 -247.204971) (xy 343.248224 -247.204971) (xy 343.248224 -247.151673) (xy 343.256167 -247.098969)
			(xy 343.271877 -247.048039) (xy 343.295003 -247.000018) (xy 343.325027 -246.955981) (xy 343.361279 -246.91691)
			(xy 343.40295 -246.883679) (xy 343.449108 -246.85703) (xy 343.498722 -246.837558) (xy 343.550684 -246.825698)
			(xy 343.603834 -246.821715) (xy 343.656984 -246.825698) (xy 343.708946 -246.837558) (xy 343.75856 -246.85703)
			(xy 343.804718 -246.883679) (xy 343.846389 -246.91691) (xy 343.882641 -246.955981) (xy 343.912665 -247.000018)
			(xy 343.935791 -247.048039) (xy 343.951501 -247.098969) (xy 343.959444 -247.151673) (xy 343.959942 -247.178322)
			(xy 343.959444 -247.204971) (xy 344.18777 -247.204971) (xy 344.18777 -247.151673) (xy 344.195713 -247.098969)
			(xy 344.211423 -247.048039) (xy 344.234549 -247.000018) (xy 344.264573 -246.955981) (xy 344.300825 -246.91691)
			(xy 344.342496 -246.883679) (xy 344.388654 -246.85703) (xy 344.438268 -246.837558) (xy 344.49023 -246.825698)
			(xy 344.54338 -246.821715) (xy 344.59653 -246.825698) (xy 344.648492 -246.837558) (xy 344.698106 -246.85703)
			(xy 344.744264 -246.883679) (xy 344.785935 -246.91691) (xy 344.822187 -246.955981) (xy 344.852211 -247.000018)
			(xy 344.875337 -247.048039) (xy 344.891047 -247.098969) (xy 344.89899 -247.151673) (xy 344.899488 -247.178322)
			(xy 344.89899 -247.204971) (xy 345.127824 -247.204971) (xy 345.127824 -247.151673) (xy 345.135767 -247.098969)
			(xy 345.151477 -247.048039) (xy 345.174603 -247.000018) (xy 345.204627 -246.955981) (xy 345.240879 -246.91691)
			(xy 345.28255 -246.883679) (xy 345.328708 -246.85703) (xy 345.378322 -246.837558) (xy 345.430284 -246.825698)
			(xy 345.483434 -246.821715) (xy 345.536584 -246.825698) (xy 345.588546 -246.837558) (xy 345.63816 -246.85703)
			(xy 345.684318 -246.883679) (xy 345.725989 -246.91691) (xy 345.762241 -246.955981) (xy 345.792265 -247.000018)
			(xy 345.815391 -247.048039) (xy 345.831101 -247.098969) (xy 345.839044 -247.151673) (xy 345.839542 -247.178322)
			(xy 345.839044 -247.204971) (xy 346.06737 -247.204971) (xy 346.06737 -247.151673) (xy 346.075313 -247.098969)
			(xy 346.091023 -247.048039) (xy 346.114149 -247.000018) (xy 346.144173 -246.955981) (xy 346.180425 -246.91691)
			(xy 346.222096 -246.883679) (xy 346.268254 -246.85703) (xy 346.317868 -246.837558) (xy 346.36983 -246.825698)
			(xy 346.42298 -246.821715) (xy 346.47613 -246.825698) (xy 346.528092 -246.837558) (xy 346.577706 -246.85703)
			(xy 346.623864 -246.883679) (xy 346.665535 -246.91691) (xy 346.701787 -246.955981) (xy 346.731811 -247.000018)
			(xy 346.754937 -247.048039) (xy 346.770647 -247.098969) (xy 346.77859 -247.151673) (xy 346.779088 -247.178322)
			(xy 346.77859 -247.204971) (xy 346.770647 -247.257675) (xy 346.754937 -247.308605) (xy 346.731811 -247.356626)
			(xy 346.701787 -247.400663) (xy 346.665535 -247.439734) (xy 346.623864 -247.472965) (xy 346.577706 -247.499614)
			(xy 346.528092 -247.519086) (xy 346.47613 -247.530946) (xy 346.42298 -247.53493) (xy 346.36983 -247.530946)
			(xy 346.317868 -247.519086) (xy 346.268254 -247.499614) (xy 346.222096 -247.472965) (xy 346.180425 -247.439734)
			(xy 346.144173 -247.400663) (xy 346.114149 -247.356626) (xy 346.091023 -247.308605) (xy 346.075313 -247.257675)
			(xy 346.06737 -247.204971) (xy 345.839044 -247.204971) (xy 345.831101 -247.257675) (xy 345.815391 -247.308605)
			(xy 345.792265 -247.356626) (xy 345.762241 -247.400663) (xy 345.725989 -247.439734) (xy 345.684318 -247.472965)
			(xy 345.63816 -247.499614) (xy 345.588546 -247.519086) (xy 345.536584 -247.530946) (xy 345.483434 -247.53493)
			(xy 345.430284 -247.530946) (xy 345.378322 -247.519086) (xy 345.328708 -247.499614) (xy 345.28255 -247.472965)
			(xy 345.240879 -247.439734) (xy 345.204627 -247.400663) (xy 345.174603 -247.356626) (xy 345.151477 -247.308605)
			(xy 345.135767 -247.257675) (xy 345.127824 -247.204971) (xy 344.89899 -247.204971) (xy 344.891047 -247.257675)
			(xy 344.875337 -247.308605) (xy 344.852211 -247.356626) (xy 344.822187 -247.400663) (xy 344.785935 -247.439734)
			(xy 344.744264 -247.472965) (xy 344.698106 -247.499614) (xy 344.648492 -247.519086) (xy 344.59653 -247.530946)
			(xy 344.54338 -247.53493) (xy 344.49023 -247.530946) (xy 344.438268 -247.519086) (xy 344.388654 -247.499614)
			(xy 344.342496 -247.472965) (xy 344.300825 -247.439734) (xy 344.264573 -247.400663) (xy 344.234549 -247.356626)
			(xy 344.211423 -247.308605) (xy 344.195713 -247.257675) (xy 344.18777 -247.204971) (xy 343.959444 -247.204971)
			(xy 343.951501 -247.257675) (xy 343.935791 -247.308605) (xy 343.912665 -247.356626) (xy 343.882641 -247.400663)
			(xy 343.846389 -247.439734) (xy 343.804718 -247.472965) (xy 343.75856 -247.499614) (xy 343.708946 -247.519086)
			(xy 343.656984 -247.530946) (xy 343.603834 -247.53493) (xy 343.550684 -247.530946) (xy 343.498722 -247.519086)
			(xy 343.449108 -247.499614) (xy 343.40295 -247.472965) (xy 343.361279 -247.439734) (xy 343.325027 -247.400663)
			(xy 343.295003 -247.356626) (xy 343.271877 -247.308605) (xy 343.256167 -247.257675) (xy 343.248224 -247.204971)
			(xy 343.019644 -247.204971) (xy 343.011701 -247.257675) (xy 342.995991 -247.308605) (xy 342.972865 -247.356626)
			(xy 342.942841 -247.400663) (xy 342.906589 -247.439734) (xy 342.864918 -247.472965) (xy 342.81876 -247.499614)
			(xy 342.769146 -247.519086) (xy 342.717184 -247.530946) (xy 342.664034 -247.53493) (xy 342.610884 -247.530946)
			(xy 342.558922 -247.519086) (xy 342.509308 -247.499614) (xy 342.46315 -247.472965) (xy 342.421479 -247.439734)
			(xy 342.385227 -247.400663) (xy 342.355203 -247.356626) (xy 342.332077 -247.308605) (xy 342.316367 -247.257675)
			(xy 342.308424 -247.204971) (xy 342.079844 -247.204971) (xy 342.071901 -247.257675) (xy 342.056191 -247.308605)
			(xy 342.033065 -247.356626) (xy 342.003041 -247.400663) (xy 341.966789 -247.439734) (xy 341.925118 -247.472965)
			(xy 341.87896 -247.499614) (xy 341.829346 -247.519086) (xy 341.777384 -247.530946) (xy 341.724234 -247.53493)
			(xy 341.671084 -247.530946) (xy 341.619122 -247.519086) (xy 341.569508 -247.499614) (xy 341.52335 -247.472965)
			(xy 341.481679 -247.439734) (xy 341.445427 -247.400663) (xy 341.415403 -247.356626) (xy 341.392277 -247.308605)
			(xy 341.376567 -247.257675) (xy 341.368624 -247.204971) (xy 341.140044 -247.204971) (xy 341.132101 -247.257675)
			(xy 341.116391 -247.308605) (xy 341.093265 -247.356626) (xy 341.063241 -247.400663) (xy 341.026989 -247.439734)
			(xy 340.985318 -247.472965) (xy 340.93916 -247.499614) (xy 340.889546 -247.519086) (xy 340.837584 -247.530946)
			(xy 340.784434 -247.53493) (xy 340.731284 -247.530946) (xy 340.679322 -247.519086) (xy 340.629708 -247.499614)
			(xy 340.58355 -247.472965) (xy 340.541879 -247.439734) (xy 340.505627 -247.400663) (xy 340.475603 -247.356626)
			(xy 340.452477 -247.308605) (xy 340.436767 -247.257675) (xy 340.428824 -247.204971) (xy 340.19999 -247.204971)
			(xy 340.192047 -247.257675) (xy 340.176337 -247.308605) (xy 340.153211 -247.356626) (xy 340.123187 -247.400663)
			(xy 340.086935 -247.439734) (xy 340.045264 -247.472965) (xy 339.999106 -247.499614) (xy 339.949492 -247.519086)
			(xy 339.89753 -247.530946) (xy 339.84438 -247.53493) (xy 339.79123 -247.530946) (xy 339.739268 -247.519086)
			(xy 339.689654 -247.499614) (xy 339.643496 -247.472965) (xy 339.601825 -247.439734) (xy 339.565573 -247.400663)
			(xy 339.535549 -247.356626) (xy 339.512423 -247.308605) (xy 339.496713 -247.257675) (xy 339.48877 -247.204971)
			(xy 339.37956 -247.204971) (xy 339.37956 -247.633236) (xy 339.423502 -247.639332) (xy 339.450061 -247.643501)
			(xy 339.501602 -247.658789) (xy 339.550259 -247.68165) (xy 339.594927 -247.711564) (xy 339.634592 -247.747853)
			(xy 339.668351 -247.789691) (xy 339.695438 -247.836128) (xy 339.715238 -247.886109) (xy 339.727301 -247.938498)
			(xy 339.731352 -247.992105) (xy 339.729335 -248.018787) (xy 339.95867 -248.018787) (xy 339.95867 -247.965489)
			(xy 339.966613 -247.912785) (xy 339.982323 -247.861855) (xy 340.005449 -247.813834) (xy 340.035473 -247.769797)
			(xy 340.071725 -247.730726) (xy 340.113396 -247.697495) (xy 340.159554 -247.670846) (xy 340.209168 -247.651374)
			(xy 340.26113 -247.639514) (xy 340.31428 -247.635531) (xy 340.36743 -247.639514) (xy 340.419392 -247.651374)
			(xy 340.469006 -247.670846) (xy 340.515164 -247.697495) (xy 340.556835 -247.730726) (xy 340.593087 -247.769797)
			(xy 340.623111 -247.813834) (xy 340.646237 -247.861855) (xy 340.661947 -247.912785) (xy 340.66989 -247.965489)
			(xy 340.670388 -247.992138) (xy 340.66989 -248.018787) (xy 340.89847 -248.018787) (xy 340.89847 -247.965489)
			(xy 340.906413 -247.912785) (xy 340.922123 -247.861855) (xy 340.945249 -247.813834) (xy 340.975273 -247.769797)
			(xy 341.011525 -247.730726) (xy 341.053196 -247.697495) (xy 341.099354 -247.670846) (xy 341.148968 -247.651374)
			(xy 341.20093 -247.639514) (xy 341.25408 -247.635531) (xy 341.30723 -247.639514) (xy 341.359192 -247.651374)
			(xy 341.408806 -247.670846) (xy 341.454964 -247.697495) (xy 341.496635 -247.730726) (xy 341.532887 -247.769797)
			(xy 341.562911 -247.813834) (xy 341.586037 -247.861855) (xy 341.601747 -247.912785) (xy 341.60969 -247.965489)
			(xy 341.610188 -247.992138) (xy 341.60969 -248.018787) (xy 341.83827 -248.018787) (xy 341.83827 -247.965489)
			(xy 341.846213 -247.912785) (xy 341.861923 -247.861855) (xy 341.885049 -247.813834) (xy 341.915073 -247.769797)
			(xy 341.951325 -247.730726) (xy 341.992996 -247.697495) (xy 342.039154 -247.670846) (xy 342.088768 -247.651374)
			(xy 342.14073 -247.639514) (xy 342.19388 -247.635531) (xy 342.24703 -247.639514) (xy 342.298992 -247.651374)
			(xy 342.348606 -247.670846) (xy 342.394764 -247.697495) (xy 342.436435 -247.730726) (xy 342.472687 -247.769797)
			(xy 342.502711 -247.813834) (xy 342.525837 -247.861855) (xy 342.541547 -247.912785) (xy 342.54949 -247.965489)
			(xy 342.549988 -247.992138) (xy 342.54949 -248.018787) (xy 342.77807 -248.018787) (xy 342.77807 -247.965489)
			(xy 342.786013 -247.912785) (xy 342.801723 -247.861855) (xy 342.824849 -247.813834) (xy 342.854873 -247.769797)
			(xy 342.891125 -247.730726) (xy 342.932796 -247.697495) (xy 342.978954 -247.670846) (xy 343.028568 -247.651374)
			(xy 343.08053 -247.639514) (xy 343.13368 -247.635531) (xy 343.18683 -247.639514) (xy 343.238792 -247.651374)
			(xy 343.288406 -247.670846) (xy 343.334564 -247.697495) (xy 343.376235 -247.730726) (xy 343.412487 -247.769797)
			(xy 343.442511 -247.813834) (xy 343.465637 -247.861855) (xy 343.481347 -247.912785) (xy 343.48929 -247.965489)
			(xy 343.489788 -247.992138) (xy 343.48929 -248.018787) (xy 343.718124 -248.018787) (xy 343.718124 -247.965489)
			(xy 343.726067 -247.912785) (xy 343.741777 -247.861855) (xy 343.764903 -247.813834) (xy 343.794927 -247.769797)
			(xy 343.831179 -247.730726) (xy 343.87285 -247.697495) (xy 343.919008 -247.670846) (xy 343.968622 -247.651374)
			(xy 344.020584 -247.639514) (xy 344.073734 -247.635531) (xy 344.126884 -247.639514) (xy 344.178846 -247.651374)
			(xy 344.22846 -247.670846) (xy 344.274618 -247.697495) (xy 344.316289 -247.730726) (xy 344.352541 -247.769797)
			(xy 344.382565 -247.813834) (xy 344.405691 -247.861855) (xy 344.421401 -247.912785) (xy 344.429344 -247.965489)
			(xy 344.429842 -247.992138) (xy 344.429344 -248.018787) (xy 344.65767 -248.018787) (xy 344.65767 -247.965489)
			(xy 344.665613 -247.912785) (xy 344.681323 -247.861855) (xy 344.704449 -247.813834) (xy 344.734473 -247.769797)
			(xy 344.770725 -247.730726) (xy 344.812396 -247.697495) (xy 344.858554 -247.670846) (xy 344.908168 -247.651374)
			(xy 344.96013 -247.639514) (xy 345.01328 -247.635531) (xy 345.06643 -247.639514) (xy 345.118392 -247.651374)
			(xy 345.168006 -247.670846) (xy 345.214164 -247.697495) (xy 345.255835 -247.730726) (xy 345.292087 -247.769797)
			(xy 345.322111 -247.813834) (xy 345.345237 -247.861855) (xy 345.360947 -247.912785) (xy 345.36889 -247.965489)
			(xy 345.369388 -247.992138) (xy 345.36889 -248.018787) (xy 345.597724 -248.018787) (xy 345.597724 -247.965489)
			(xy 345.605667 -247.912785) (xy 345.621377 -247.861855) (xy 345.644503 -247.813834) (xy 345.674527 -247.769797)
			(xy 345.710779 -247.730726) (xy 345.75245 -247.697495) (xy 345.798608 -247.670846) (xy 345.848222 -247.651374)
			(xy 345.900184 -247.639514) (xy 345.953334 -247.635531) (xy 346.006484 -247.639514) (xy 346.058446 -247.651374)
			(xy 346.10806 -247.670846) (xy 346.154218 -247.697495) (xy 346.195889 -247.730726) (xy 346.232141 -247.769797)
			(xy 346.262165 -247.813834) (xy 346.285291 -247.861855) (xy 346.301001 -247.912785) (xy 346.308944 -247.965489)
			(xy 346.309442 -247.992138) (xy 346.308944 -248.018787) (xy 346.537524 -248.018787) (xy 346.537524 -247.965489)
			(xy 346.545467 -247.912785) (xy 346.561177 -247.861855) (xy 346.584303 -247.813834) (xy 346.614327 -247.769797)
			(xy 346.650579 -247.730726) (xy 346.69225 -247.697495) (xy 346.738408 -247.670846) (xy 346.788022 -247.651374)
			(xy 346.839984 -247.639514) (xy 346.893134 -247.635531) (xy 346.946284 -247.639514) (xy 346.998246 -247.651374)
			(xy 347.04786 -247.670846) (xy 347.094018 -247.697495) (xy 347.135689 -247.730726) (xy 347.171941 -247.769797)
			(xy 347.201965 -247.813834) (xy 347.225091 -247.861855) (xy 347.240801 -247.912785) (xy 347.248744 -247.965489)
			(xy 347.249242 -247.992138) (xy 347.248744 -248.018787) (xy 347.240801 -248.071491) (xy 347.225091 -248.122421)
			(xy 347.201965 -248.170442) (xy 347.171941 -248.214479) (xy 347.135689 -248.25355) (xy 347.094018 -248.286781)
			(xy 347.04786 -248.31343) (xy 346.998246 -248.332902) (xy 346.946284 -248.344762) (xy 346.893134 -248.348746)
			(xy 346.839984 -248.344762) (xy 346.788022 -248.332902) (xy 346.738408 -248.31343) (xy 346.69225 -248.286781)
			(xy 346.650579 -248.25355) (xy 346.614327 -248.214479) (xy 346.584303 -248.170442) (xy 346.561177 -248.122421)
			(xy 346.545467 -248.071491) (xy 346.537524 -248.018787) (xy 346.308944 -248.018787) (xy 346.301001 -248.071491)
			(xy 346.285291 -248.122421) (xy 346.262165 -248.170442) (xy 346.232141 -248.214479) (xy 346.195889 -248.25355)
			(xy 346.154218 -248.286781) (xy 346.10806 -248.31343) (xy 346.058446 -248.332902) (xy 346.006484 -248.344762)
			(xy 345.953334 -248.348746) (xy 345.900184 -248.344762) (xy 345.848222 -248.332902) (xy 345.798608 -248.31343)
			(xy 345.75245 -248.286781) (xy 345.710779 -248.25355) (xy 345.674527 -248.214479) (xy 345.644503 -248.170442)
			(xy 345.621377 -248.122421) (xy 345.605667 -248.071491) (xy 345.597724 -248.018787) (xy 345.36889 -248.018787)
			(xy 345.360947 -248.071491) (xy 345.345237 -248.122421) (xy 345.322111 -248.170442) (xy 345.292087 -248.214479)
			(xy 345.255835 -248.25355) (xy 345.214164 -248.286781) (xy 345.168006 -248.31343) (xy 345.118392 -248.332902)
			(xy 345.06643 -248.344762) (xy 345.01328 -248.348746) (xy 344.96013 -248.344762) (xy 344.908168 -248.332902)
			(xy 344.858554 -248.31343) (xy 344.812396 -248.286781) (xy 344.770725 -248.25355) (xy 344.734473 -248.214479)
			(xy 344.704449 -248.170442) (xy 344.681323 -248.122421) (xy 344.665613 -248.071491) (xy 344.65767 -248.018787)
			(xy 344.429344 -248.018787) (xy 344.421401 -248.071491) (xy 344.405691 -248.122421) (xy 344.382565 -248.170442)
			(xy 344.352541 -248.214479) (xy 344.316289 -248.25355) (xy 344.274618 -248.286781) (xy 344.22846 -248.31343)
			(xy 344.178846 -248.332902) (xy 344.126884 -248.344762) (xy 344.073734 -248.348746) (xy 344.020584 -248.344762)
			(xy 343.968622 -248.332902) (xy 343.919008 -248.31343) (xy 343.87285 -248.286781) (xy 343.831179 -248.25355)
			(xy 343.794927 -248.214479) (xy 343.764903 -248.170442) (xy 343.741777 -248.122421) (xy 343.726067 -248.071491)
			(xy 343.718124 -248.018787) (xy 343.48929 -248.018787) (xy 343.481347 -248.071491) (xy 343.465637 -248.122421)
			(xy 343.442511 -248.170442) (xy 343.412487 -248.214479) (xy 343.376235 -248.25355) (xy 343.334564 -248.286781)
			(xy 343.288406 -248.31343) (xy 343.238792 -248.332902) (xy 343.18683 -248.344762) (xy 343.13368 -248.348746)
			(xy 343.08053 -248.344762) (xy 343.028568 -248.332902) (xy 342.978954 -248.31343) (xy 342.932796 -248.286781)
			(xy 342.891125 -248.25355) (xy 342.854873 -248.214479) (xy 342.824849 -248.170442) (xy 342.801723 -248.122421)
			(xy 342.786013 -248.071491) (xy 342.77807 -248.018787) (xy 342.54949 -248.018787) (xy 342.541547 -248.071491)
			(xy 342.525837 -248.122421) (xy 342.502711 -248.170442) (xy 342.472687 -248.214479) (xy 342.436435 -248.25355)
			(xy 342.394764 -248.286781) (xy 342.348606 -248.31343) (xy 342.298992 -248.332902) (xy 342.24703 -248.344762)
			(xy 342.19388 -248.348746) (xy 342.14073 -248.344762) (xy 342.088768 -248.332902) (xy 342.039154 -248.31343)
			(xy 341.992996 -248.286781) (xy 341.951325 -248.25355) (xy 341.915073 -248.214479) (xy 341.885049 -248.170442)
			(xy 341.861923 -248.122421) (xy 341.846213 -248.071491) (xy 341.83827 -248.018787) (xy 341.60969 -248.018787)
			(xy 341.601747 -248.071491) (xy 341.586037 -248.122421) (xy 341.562911 -248.170442) (xy 341.532887 -248.214479)
			(xy 341.496635 -248.25355) (xy 341.454964 -248.286781) (xy 341.408806 -248.31343) (xy 341.359192 -248.332902)
			(xy 341.30723 -248.344762) (xy 341.25408 -248.348746) (xy 341.20093 -248.344762) (xy 341.148968 -248.332902)
			(xy 341.099354 -248.31343) (xy 341.053196 -248.286781) (xy 341.011525 -248.25355) (xy 340.975273 -248.214479)
			(xy 340.945249 -248.170442) (xy 340.922123 -248.122421) (xy 340.906413 -248.071491) (xy 340.89847 -248.018787)
			(xy 340.66989 -248.018787) (xy 340.661947 -248.071491) (xy 340.646237 -248.122421) (xy 340.623111 -248.170442)
			(xy 340.593087 -248.214479) (xy 340.556835 -248.25355) (xy 340.515164 -248.286781) (xy 340.469006 -248.31343)
			(xy 340.419392 -248.332902) (xy 340.36743 -248.344762) (xy 340.31428 -248.348746) (xy 340.26113 -248.344762)
			(xy 340.209168 -248.332902) (xy 340.159554 -248.31343) (xy 340.113396 -248.286781) (xy 340.071725 -248.25355)
			(xy 340.035473 -248.214479) (xy 340.005449 -248.170442) (xy 339.982323 -248.122421) (xy 339.966613 -248.071491)
			(xy 339.95867 -248.018787) (xy 339.729335 -248.018787) (xy 339.727299 -248.045712) (xy 339.715235 -248.098101)
			(xy 339.695434 -248.148081) (xy 339.668345 -248.194518) (xy 339.634584 -248.236355) (xy 339.594919 -248.272642)
			(xy 339.55025 -248.302556) (xy 339.501592 -248.325415) (xy 339.450051 -248.340701) (xy 339.423502 -248.344944)
			(xy 339.37956 -248.35104) (xy 339.37956 -248.832857) (xy 339.489024 -248.832857) (xy 339.489024 -248.779559)
			(xy 339.496967 -248.726855) (xy 339.512677 -248.675925) (xy 339.535803 -248.627904) (xy 339.565827 -248.583867)
			(xy 339.602079 -248.544796) (xy 339.64375 -248.511565) (xy 339.689908 -248.484916) (xy 339.739522 -248.465444)
			(xy 339.791484 -248.453584) (xy 339.844634 -248.449601) (xy 339.897784 -248.453584) (xy 339.949746 -248.465444)
			(xy 339.99936 -248.484916) (xy 340.045518 -248.511565) (xy 340.087189 -248.544796) (xy 340.123441 -248.583867)
			(xy 340.153465 -248.627904) (xy 340.176591 -248.675925) (xy 340.192301 -248.726855) (xy 340.200244 -248.779559)
			(xy 340.200742 -248.806208) (xy 340.200244 -248.832857) (xy 340.428824 -248.832857) (xy 340.428824 -248.779559)
			(xy 340.436767 -248.726855) (xy 340.452477 -248.675925) (xy 340.475603 -248.627904) (xy 340.505627 -248.583867)
			(xy 340.541879 -248.544796) (xy 340.58355 -248.511565) (xy 340.629708 -248.484916) (xy 340.679322 -248.465444)
			(xy 340.731284 -248.453584) (xy 340.784434 -248.449601) (xy 340.837584 -248.453584) (xy 340.889546 -248.465444)
			(xy 340.93916 -248.484916) (xy 340.985318 -248.511565) (xy 341.026989 -248.544796) (xy 341.063241 -248.583867)
			(xy 341.093265 -248.627904) (xy 341.116391 -248.675925) (xy 341.132101 -248.726855) (xy 341.140044 -248.779559)
			(xy 341.140542 -248.806208) (xy 341.140044 -248.832857) (xy 341.368624 -248.832857) (xy 341.368624 -248.779559)
			(xy 341.376567 -248.726855) (xy 341.392277 -248.675925) (xy 341.415403 -248.627904) (xy 341.445427 -248.583867)
			(xy 341.481679 -248.544796) (xy 341.52335 -248.511565) (xy 341.569508 -248.484916) (xy 341.619122 -248.465444)
			(xy 341.671084 -248.453584) (xy 341.724234 -248.449601) (xy 341.777384 -248.453584) (xy 341.829346 -248.465444)
			(xy 341.87896 -248.484916) (xy 341.925118 -248.511565) (xy 341.966789 -248.544796) (xy 342.003041 -248.583867)
			(xy 342.033065 -248.627904) (xy 342.056191 -248.675925) (xy 342.071901 -248.726855) (xy 342.079844 -248.779559)
			(xy 342.080342 -248.806208) (xy 342.079844 -248.832857) (xy 342.30817 -248.832857) (xy 342.30817 -248.779559)
			(xy 342.316113 -248.726855) (xy 342.331823 -248.675925) (xy 342.354949 -248.627904) (xy 342.384973 -248.583867)
			(xy 342.421225 -248.544796) (xy 342.462896 -248.511565) (xy 342.509054 -248.484916) (xy 342.558668 -248.465444)
			(xy 342.61063 -248.453584) (xy 342.66378 -248.449601) (xy 342.71693 -248.453584) (xy 342.768892 -248.465444)
			(xy 342.818506 -248.484916) (xy 342.864664 -248.511565) (xy 342.906335 -248.544796) (xy 342.942587 -248.583867)
			(xy 342.972611 -248.627904) (xy 342.995737 -248.675925) (xy 343.011447 -248.726855) (xy 343.01939 -248.779559)
			(xy 343.019888 -248.806208) (xy 343.01939 -248.832857) (xy 343.248224 -248.832857) (xy 343.248224 -248.779559)
			(xy 343.256167 -248.726855) (xy 343.271877 -248.675925) (xy 343.295003 -248.627904) (xy 343.325027 -248.583867)
			(xy 343.361279 -248.544796) (xy 343.40295 -248.511565) (xy 343.449108 -248.484916) (xy 343.498722 -248.465444)
			(xy 343.550684 -248.453584) (xy 343.603834 -248.449601) (xy 343.656984 -248.453584) (xy 343.708946 -248.465444)
			(xy 343.75856 -248.484916) (xy 343.804718 -248.511565) (xy 343.846389 -248.544796) (xy 343.882641 -248.583867)
			(xy 343.912665 -248.627904) (xy 343.935791 -248.675925) (xy 343.951501 -248.726855) (xy 343.959444 -248.779559)
			(xy 343.959942 -248.806208) (xy 343.959444 -248.832857) (xy 344.188024 -248.832857) (xy 344.188024 -248.779559)
			(xy 344.195967 -248.726855) (xy 344.211677 -248.675925) (xy 344.234803 -248.627904) (xy 344.264827 -248.583867)
			(xy 344.301079 -248.544796) (xy 344.34275 -248.511565) (xy 344.388908 -248.484916) (xy 344.438522 -248.465444)
			(xy 344.490484 -248.453584) (xy 344.543634 -248.449601) (xy 344.596784 -248.453584) (xy 344.648746 -248.465444)
			(xy 344.69836 -248.484916) (xy 344.744518 -248.511565) (xy 344.786189 -248.544796) (xy 344.822441 -248.583867)
			(xy 344.852465 -248.627904) (xy 344.875591 -248.675925) (xy 344.891301 -248.726855) (xy 344.899244 -248.779559)
			(xy 344.899742 -248.806208) (xy 344.899244 -248.832857) (xy 345.127824 -248.832857) (xy 345.127824 -248.779559)
			(xy 345.135767 -248.726855) (xy 345.151477 -248.675925) (xy 345.174603 -248.627904) (xy 345.204627 -248.583867)
			(xy 345.240879 -248.544796) (xy 345.28255 -248.511565) (xy 345.328708 -248.484916) (xy 345.378322 -248.465444)
			(xy 345.430284 -248.453584) (xy 345.483434 -248.449601) (xy 345.536584 -248.453584) (xy 345.588546 -248.465444)
			(xy 345.63816 -248.484916) (xy 345.684318 -248.511565) (xy 345.725989 -248.544796) (xy 345.762241 -248.583867)
			(xy 345.792265 -248.627904) (xy 345.815391 -248.675925) (xy 345.831101 -248.726855) (xy 345.839044 -248.779559)
			(xy 345.839542 -248.806208) (xy 345.839044 -248.832857) (xy 346.067624 -248.832857) (xy 346.067624 -248.779559)
			(xy 346.075567 -248.726855) (xy 346.091277 -248.675925) (xy 346.114403 -248.627904) (xy 346.144427 -248.583867)
			(xy 346.180679 -248.544796) (xy 346.22235 -248.511565) (xy 346.268508 -248.484916) (xy 346.318122 -248.465444)
			(xy 346.370084 -248.453584) (xy 346.423234 -248.449601) (xy 346.476384 -248.453584) (xy 346.528346 -248.465444)
			(xy 346.57796 -248.484916) (xy 346.624118 -248.511565) (xy 346.665789 -248.544796) (xy 346.702041 -248.583867)
			(xy 346.732065 -248.627904) (xy 346.755191 -248.675925) (xy 346.770901 -248.726855) (xy 346.778844 -248.779559)
			(xy 346.779342 -248.806208) (xy 346.778844 -248.832857) (xy 346.770901 -248.885561) (xy 346.755191 -248.936491)
			(xy 346.732065 -248.984512) (xy 346.702041 -249.028549) (xy 346.665789 -249.06762) (xy 346.624118 -249.100851)
			(xy 346.57796 -249.1275) (xy 346.528346 -249.146972) (xy 346.476384 -249.158832) (xy 346.423234 -249.162816)
			(xy 346.370084 -249.158832) (xy 346.318122 -249.146972) (xy 346.268508 -249.1275) (xy 346.22235 -249.100851)
			(xy 346.180679 -249.06762) (xy 346.144427 -249.028549) (xy 346.114403 -248.984512) (xy 346.091277 -248.936491)
			(xy 346.075567 -248.885561) (xy 346.067624 -248.832857) (xy 345.839044 -248.832857) (xy 345.831101 -248.885561)
			(xy 345.815391 -248.936491) (xy 345.792265 -248.984512) (xy 345.762241 -249.028549) (xy 345.725989 -249.06762)
			(xy 345.684318 -249.100851) (xy 345.63816 -249.1275) (xy 345.588546 -249.146972) (xy 345.536584 -249.158832)
			(xy 345.483434 -249.162816) (xy 345.430284 -249.158832) (xy 345.378322 -249.146972) (xy 345.328708 -249.1275)
			(xy 345.28255 -249.100851) (xy 345.240879 -249.06762) (xy 345.204627 -249.028549) (xy 345.174603 -248.984512)
			(xy 345.151477 -248.936491) (xy 345.135767 -248.885561) (xy 345.127824 -248.832857) (xy 344.899244 -248.832857)
			(xy 344.891301 -248.885561) (xy 344.875591 -248.936491) (xy 344.852465 -248.984512) (xy 344.822441 -249.028549)
			(xy 344.786189 -249.06762) (xy 344.744518 -249.100851) (xy 344.69836 -249.1275) (xy 344.648746 -249.146972)
			(xy 344.596784 -249.158832) (xy 344.543634 -249.162816) (xy 344.490484 -249.158832) (xy 344.438522 -249.146972)
			(xy 344.388908 -249.1275) (xy 344.34275 -249.100851) (xy 344.301079 -249.06762) (xy 344.264827 -249.028549)
			(xy 344.234803 -248.984512) (xy 344.211677 -248.936491) (xy 344.195967 -248.885561) (xy 344.188024 -248.832857)
			(xy 343.959444 -248.832857) (xy 343.951501 -248.885561) (xy 343.935791 -248.936491) (xy 343.912665 -248.984512)
			(xy 343.882641 -249.028549) (xy 343.846389 -249.06762) (xy 343.804718 -249.100851) (xy 343.75856 -249.1275)
			(xy 343.708946 -249.146972) (xy 343.656984 -249.158832) (xy 343.603834 -249.162816) (xy 343.550684 -249.158832)
			(xy 343.498722 -249.146972) (xy 343.449108 -249.1275) (xy 343.40295 -249.100851) (xy 343.361279 -249.06762)
			(xy 343.325027 -249.028549) (xy 343.295003 -248.984512) (xy 343.271877 -248.936491) (xy 343.256167 -248.885561)
			(xy 343.248224 -248.832857) (xy 343.01939 -248.832857) (xy 343.011447 -248.885561) (xy 342.995737 -248.936491)
			(xy 342.972611 -248.984512) (xy 342.942587 -249.028549) (xy 342.906335 -249.06762) (xy 342.864664 -249.100851)
			(xy 342.818506 -249.1275) (xy 342.768892 -249.146972) (xy 342.71693 -249.158832) (xy 342.66378 -249.162816)
			(xy 342.61063 -249.158832) (xy 342.558668 -249.146972) (xy 342.509054 -249.1275) (xy 342.462896 -249.100851)
			(xy 342.421225 -249.06762) (xy 342.384973 -249.028549) (xy 342.354949 -248.984512) (xy 342.331823 -248.936491)
			(xy 342.316113 -248.885561) (xy 342.30817 -248.832857) (xy 342.079844 -248.832857) (xy 342.071901 -248.885561)
			(xy 342.056191 -248.936491) (xy 342.033065 -248.984512) (xy 342.003041 -249.028549) (xy 341.966789 -249.06762)
			(xy 341.925118 -249.100851) (xy 341.87896 -249.1275) (xy 341.829346 -249.146972) (xy 341.777384 -249.158832)
			(xy 341.724234 -249.162816) (xy 341.671084 -249.158832) (xy 341.619122 -249.146972) (xy 341.569508 -249.1275)
			(xy 341.52335 -249.100851) (xy 341.481679 -249.06762) (xy 341.445427 -249.028549) (xy 341.415403 -248.984512)
			(xy 341.392277 -248.936491) (xy 341.376567 -248.885561) (xy 341.368624 -248.832857) (xy 341.140044 -248.832857)
			(xy 341.132101 -248.885561) (xy 341.116391 -248.936491) (xy 341.093265 -248.984512) (xy 341.063241 -249.028549)
			(xy 341.026989 -249.06762) (xy 340.985318 -249.100851) (xy 340.93916 -249.1275) (xy 340.889546 -249.146972)
			(xy 340.837584 -249.158832) (xy 340.784434 -249.162816) (xy 340.731284 -249.158832) (xy 340.679322 -249.146972)
			(xy 340.629708 -249.1275) (xy 340.58355 -249.100851) (xy 340.541879 -249.06762) (xy 340.505627 -249.028549)
			(xy 340.475603 -248.984512) (xy 340.452477 -248.936491) (xy 340.436767 -248.885561) (xy 340.428824 -248.832857)
			(xy 340.200244 -248.832857) (xy 340.192301 -248.885561) (xy 340.176591 -248.936491) (xy 340.153465 -248.984512)
			(xy 340.123441 -249.028549) (xy 340.087189 -249.06762) (xy 340.045518 -249.100851) (xy 339.99936 -249.1275)
			(xy 339.949746 -249.146972) (xy 339.897784 -249.158832) (xy 339.844634 -249.162816) (xy 339.791484 -249.158832)
			(xy 339.739522 -249.146972) (xy 339.689908 -249.1275) (xy 339.64375 -249.100851) (xy 339.602079 -249.06762)
			(xy 339.565827 -249.028549) (xy 339.535803 -248.984512) (xy 339.512677 -248.936491) (xy 339.496967 -248.885561)
			(xy 339.489024 -248.832857) (xy 339.37956 -248.832857) (xy 339.37956 -249.261122) (xy 339.423502 -249.267218)
			(xy 339.450052 -249.2714) (xy 339.501571 -249.286709) (xy 339.550205 -249.309585) (xy 339.59485 -249.339508)
			(xy 339.634492 -249.375799) (xy 339.668231 -249.417635) (xy 339.695302 -249.464064) (xy 339.71509 -249.514035)
			(xy 339.727144 -249.566411) (xy 339.731193 -249.620003) (xy 339.729178 -249.646673) (xy 339.95867 -249.646673)
			(xy 339.95867 -249.593375) (xy 339.966613 -249.540671) (xy 339.982323 -249.489741) (xy 340.005449 -249.44172)
			(xy 340.035473 -249.397683) (xy 340.071725 -249.358612) (xy 340.113396 -249.325381) (xy 340.159554 -249.298732)
			(xy 340.209168 -249.27926) (xy 340.26113 -249.2674) (xy 340.31428 -249.263417) (xy 340.36743 -249.2674)
			(xy 340.419392 -249.27926) (xy 340.469006 -249.298732) (xy 340.515164 -249.325381) (xy 340.556835 -249.358612)
			(xy 340.593087 -249.397683) (xy 340.623111 -249.44172) (xy 340.646237 -249.489741) (xy 340.661947 -249.540671)
			(xy 340.66989 -249.593375) (xy 340.670388 -249.620024) (xy 340.66989 -249.646673) (xy 340.89847 -249.646673)
			(xy 340.89847 -249.593375) (xy 340.906413 -249.540671) (xy 340.922123 -249.489741) (xy 340.945249 -249.44172)
			(xy 340.975273 -249.397683) (xy 341.011525 -249.358612) (xy 341.053196 -249.325381) (xy 341.099354 -249.298732)
			(xy 341.148968 -249.27926) (xy 341.20093 -249.2674) (xy 341.25408 -249.263417) (xy 341.30723 -249.2674)
			(xy 341.359192 -249.27926) (xy 341.408806 -249.298732) (xy 341.454964 -249.325381) (xy 341.496635 -249.358612)
			(xy 341.532887 -249.397683) (xy 341.562911 -249.44172) (xy 341.586037 -249.489741) (xy 341.601747 -249.540671)
			(xy 341.60969 -249.593375) (xy 341.610188 -249.620024) (xy 341.60969 -249.646673) (xy 341.83827 -249.646673)
			(xy 341.83827 -249.593375) (xy 341.846213 -249.540671) (xy 341.861923 -249.489741) (xy 341.885049 -249.44172)
			(xy 341.915073 -249.397683) (xy 341.951325 -249.358612) (xy 341.992996 -249.325381) (xy 342.039154 -249.298732)
			(xy 342.088768 -249.27926) (xy 342.14073 -249.2674) (xy 342.19388 -249.263417) (xy 342.24703 -249.2674)
			(xy 342.298992 -249.27926) (xy 342.348606 -249.298732) (xy 342.394764 -249.325381) (xy 342.436435 -249.358612)
			(xy 342.472687 -249.397683) (xy 342.502711 -249.44172) (xy 342.525837 -249.489741) (xy 342.541547 -249.540671)
			(xy 342.54949 -249.593375) (xy 342.549988 -249.620024) (xy 342.54949 -249.646673) (xy 342.77807 -249.646673)
			(xy 342.77807 -249.593375) (xy 342.786013 -249.540671) (xy 342.801723 -249.489741) (xy 342.824849 -249.44172)
			(xy 342.854873 -249.397683) (xy 342.891125 -249.358612) (xy 342.932796 -249.325381) (xy 342.978954 -249.298732)
			(xy 343.028568 -249.27926) (xy 343.08053 -249.2674) (xy 343.13368 -249.263417) (xy 343.18683 -249.2674)
			(xy 343.238792 -249.27926) (xy 343.288406 -249.298732) (xy 343.334564 -249.325381) (xy 343.376235 -249.358612)
			(xy 343.412487 -249.397683) (xy 343.442511 -249.44172) (xy 343.465637 -249.489741) (xy 343.481347 -249.540671)
			(xy 343.48929 -249.593375) (xy 343.489788 -249.620024) (xy 343.48929 -249.646673) (xy 343.71787 -249.646673)
			(xy 343.71787 -249.593375) (xy 343.725813 -249.540671) (xy 343.741523 -249.489741) (xy 343.764649 -249.44172)
			(xy 343.794673 -249.397683) (xy 343.830925 -249.358612) (xy 343.872596 -249.325381) (xy 343.918754 -249.298732)
			(xy 343.968368 -249.27926) (xy 344.02033 -249.2674) (xy 344.07348 -249.263417) (xy 344.12663 -249.2674)
			(xy 344.178592 -249.27926) (xy 344.228206 -249.298732) (xy 344.274364 -249.325381) (xy 344.316035 -249.358612)
			(xy 344.352287 -249.397683) (xy 344.382311 -249.44172) (xy 344.405437 -249.489741) (xy 344.421147 -249.540671)
			(xy 344.42909 -249.593375) (xy 344.429588 -249.620024) (xy 344.42909 -249.646673) (xy 344.657924 -249.646673)
			(xy 344.657924 -249.593375) (xy 344.665867 -249.540671) (xy 344.681577 -249.489741) (xy 344.704703 -249.44172)
			(xy 344.734727 -249.397683) (xy 344.770979 -249.358612) (xy 344.81265 -249.325381) (xy 344.858808 -249.298732)
			(xy 344.908422 -249.27926) (xy 344.960384 -249.2674) (xy 345.013534 -249.263417) (xy 345.066684 -249.2674)
			(xy 345.118646 -249.27926) (xy 345.16826 -249.298732) (xy 345.214418 -249.325381) (xy 345.256089 -249.358612)
			(xy 345.292341 -249.397683) (xy 345.322365 -249.44172) (xy 345.345491 -249.489741) (xy 345.361201 -249.540671)
			(xy 345.369144 -249.593375) (xy 345.369642 -249.620024) (xy 345.369144 -249.646673) (xy 345.59747 -249.646673)
			(xy 345.59747 -249.593375) (xy 345.605413 -249.540671) (xy 345.621123 -249.489741) (xy 345.644249 -249.44172)
			(xy 345.674273 -249.397683) (xy 345.710525 -249.358612) (xy 345.752196 -249.325381) (xy 345.798354 -249.298732)
			(xy 345.847968 -249.27926) (xy 345.89993 -249.2674) (xy 345.95308 -249.263417) (xy 346.00623 -249.2674)
			(xy 346.058192 -249.27926) (xy 346.107806 -249.298732) (xy 346.153964 -249.325381) (xy 346.195635 -249.358612)
			(xy 346.231887 -249.397683) (xy 346.261911 -249.44172) (xy 346.285037 -249.489741) (xy 346.300747 -249.540671)
			(xy 346.30869 -249.593375) (xy 346.309188 -249.620024) (xy 346.30869 -249.646673) (xy 346.53727 -249.646673)
			(xy 346.53727 -249.593375) (xy 346.545213 -249.540671) (xy 346.560923 -249.489741) (xy 346.584049 -249.44172)
			(xy 346.614073 -249.397683) (xy 346.650325 -249.358612) (xy 346.691996 -249.325381) (xy 346.738154 -249.298732)
			(xy 346.787768 -249.27926) (xy 346.83973 -249.2674) (xy 346.89288 -249.263417) (xy 346.94603 -249.2674)
			(xy 346.997992 -249.27926) (xy 347.047606 -249.298732) (xy 347.093764 -249.325381) (xy 347.135435 -249.358612)
			(xy 347.171687 -249.397683) (xy 347.201711 -249.44172) (xy 347.224837 -249.489741) (xy 347.240547 -249.540671)
			(xy 347.24849 -249.593375) (xy 347.248988 -249.620024) (xy 347.24849 -249.646673) (xy 347.240547 -249.699377)
			(xy 347.224837 -249.750307) (xy 347.201711 -249.798328) (xy 347.171687 -249.842365) (xy 347.135435 -249.881436)
			(xy 347.093764 -249.914667) (xy 347.047606 -249.941316) (xy 346.997992 -249.960788) (xy 346.94603 -249.972648)
			(xy 346.89288 -249.976632) (xy 346.83973 -249.972648) (xy 346.787768 -249.960788) (xy 346.738154 -249.941316)
			(xy 346.691996 -249.914667) (xy 346.650325 -249.881436) (xy 346.614073 -249.842365) (xy 346.584049 -249.798328)
			(xy 346.560923 -249.750307) (xy 346.545213 -249.699377) (xy 346.53727 -249.646673) (xy 346.30869 -249.646673)
			(xy 346.300747 -249.699377) (xy 346.285037 -249.750307) (xy 346.261911 -249.798328) (xy 346.231887 -249.842365)
			(xy 346.195635 -249.881436) (xy 346.153964 -249.914667) (xy 346.107806 -249.941316) (xy 346.058192 -249.960788)
			(xy 346.00623 -249.972648) (xy 345.95308 -249.976632) (xy 345.89993 -249.972648) (xy 345.847968 -249.960788)
			(xy 345.798354 -249.941316) (xy 345.752196 -249.914667) (xy 345.710525 -249.881436) (xy 345.674273 -249.842365)
			(xy 345.644249 -249.798328) (xy 345.621123 -249.750307) (xy 345.605413 -249.699377) (xy 345.59747 -249.646673)
			(xy 345.369144 -249.646673) (xy 345.361201 -249.699377) (xy 345.345491 -249.750307) (xy 345.322365 -249.798328)
			(xy 345.292341 -249.842365) (xy 345.256089 -249.881436) (xy 345.214418 -249.914667) (xy 345.16826 -249.941316)
			(xy 345.118646 -249.960788) (xy 345.066684 -249.972648) (xy 345.013534 -249.976632) (xy 344.960384 -249.972648)
			(xy 344.908422 -249.960788) (xy 344.858808 -249.941316) (xy 344.81265 -249.914667) (xy 344.770979 -249.881436)
			(xy 344.734727 -249.842365) (xy 344.704703 -249.798328) (xy 344.681577 -249.750307) (xy 344.665867 -249.699377)
			(xy 344.657924 -249.646673) (xy 344.42909 -249.646673) (xy 344.421147 -249.699377) (xy 344.405437 -249.750307)
			(xy 344.382311 -249.798328) (xy 344.352287 -249.842365) (xy 344.316035 -249.881436) (xy 344.274364 -249.914667)
			(xy 344.228206 -249.941316) (xy 344.178592 -249.960788) (xy 344.12663 -249.972648) (xy 344.07348 -249.976632)
			(xy 344.02033 -249.972648) (xy 343.968368 -249.960788) (xy 343.918754 -249.941316) (xy 343.872596 -249.914667)
			(xy 343.830925 -249.881436) (xy 343.794673 -249.842365) (xy 343.764649 -249.798328) (xy 343.741523 -249.750307)
			(xy 343.725813 -249.699377) (xy 343.71787 -249.646673) (xy 343.48929 -249.646673) (xy 343.481347 -249.699377)
			(xy 343.465637 -249.750307) (xy 343.442511 -249.798328) (xy 343.412487 -249.842365) (xy 343.376235 -249.881436)
			(xy 343.334564 -249.914667) (xy 343.288406 -249.941316) (xy 343.238792 -249.960788) (xy 343.18683 -249.972648)
			(xy 343.13368 -249.976632) (xy 343.08053 -249.972648) (xy 343.028568 -249.960788) (xy 342.978954 -249.941316)
			(xy 342.932796 -249.914667) (xy 342.891125 -249.881436) (xy 342.854873 -249.842365) (xy 342.824849 -249.798328)
			(xy 342.801723 -249.750307) (xy 342.786013 -249.699377) (xy 342.77807 -249.646673) (xy 342.54949 -249.646673)
			(xy 342.541547 -249.699377) (xy 342.525837 -249.750307) (xy 342.502711 -249.798328) (xy 342.472687 -249.842365)
			(xy 342.436435 -249.881436) (xy 342.394764 -249.914667) (xy 342.348606 -249.941316) (xy 342.298992 -249.960788)
			(xy 342.24703 -249.972648) (xy 342.19388 -249.976632) (xy 342.14073 -249.972648) (xy 342.088768 -249.960788)
			(xy 342.039154 -249.941316) (xy 341.992996 -249.914667) (xy 341.951325 -249.881436) (xy 341.915073 -249.842365)
			(xy 341.885049 -249.798328) (xy 341.861923 -249.750307) (xy 341.846213 -249.699377) (xy 341.83827 -249.646673)
			(xy 341.60969 -249.646673) (xy 341.601747 -249.699377) (xy 341.586037 -249.750307) (xy 341.562911 -249.798328)
			(xy 341.532887 -249.842365) (xy 341.496635 -249.881436) (xy 341.454964 -249.914667) (xy 341.408806 -249.941316)
			(xy 341.359192 -249.960788) (xy 341.30723 -249.972648) (xy 341.25408 -249.976632) (xy 341.20093 -249.972648)
			(xy 341.148968 -249.960788) (xy 341.099354 -249.941316) (xy 341.053196 -249.914667) (xy 341.011525 -249.881436)
			(xy 340.975273 -249.842365) (xy 340.945249 -249.798328) (xy 340.922123 -249.750307) (xy 340.906413 -249.699377)
			(xy 340.89847 -249.646673) (xy 340.66989 -249.646673) (xy 340.661947 -249.699377) (xy 340.646237 -249.750307)
			(xy 340.623111 -249.798328) (xy 340.593087 -249.842365) (xy 340.556835 -249.881436) (xy 340.515164 -249.914667)
			(xy 340.469006 -249.941316) (xy 340.419392 -249.960788) (xy 340.36743 -249.972648) (xy 340.31428 -249.976632)
			(xy 340.26113 -249.972648) (xy 340.209168 -249.960788) (xy 340.159554 -249.941316) (xy 340.113396 -249.914667)
			(xy 340.071725 -249.881436) (xy 340.035473 -249.842365) (xy 340.005449 -249.798328) (xy 339.982323 -249.750307)
			(xy 339.966613 -249.699377) (xy 339.95867 -249.646673) (xy 339.729178 -249.646673) (xy 339.727143 -249.673596)
			(xy 339.715088 -249.725972) (xy 339.695299 -249.775941) (xy 339.668228 -249.822371) (xy 339.634487 -249.864206)
			(xy 339.594844 -249.900496) (xy 339.550199 -249.930419) (xy 339.501565 -249.953293) (xy 339.450045 -249.968601)
			(xy 339.423502 -249.97283) (xy 339.37956 -249.978926) (xy 339.37956 -253.132569) (xy 342.887798 -253.132569)
			(xy 342.887798 -253.079271) (xy 342.895741 -253.026567) (xy 342.911451 -252.975637) (xy 342.934577 -252.927616)
			(xy 342.964601 -252.883579) (xy 343.000853 -252.844508) (xy 343.042524 -252.811277) (xy 343.088682 -252.784628)
			(xy 343.138296 -252.765156) (xy 343.190258 -252.753296) (xy 343.243408 -252.749313) (xy 343.296558 -252.753296)
			(xy 343.34852 -252.765156) (xy 343.398134 -252.784628) (xy 343.444292 -252.811277) (xy 343.485963 -252.844508)
			(xy 343.522215 -252.883579) (xy 343.552239 -252.927616) (xy 343.575365 -252.975637) (xy 343.591075 -253.026567)
			(xy 343.599018 -253.079271) (xy 343.599516 -253.10592) (xy 343.599018 -253.132569) (xy 343.591075 -253.185273)
			(xy 343.575365 -253.236203) (xy 343.552239 -253.284224) (xy 343.522215 -253.328261) (xy 343.485963 -253.367332)
			(xy 343.444292 -253.400563) (xy 343.398134 -253.427212) (xy 343.34852 -253.446684) (xy 343.296558 -253.458544)
			(xy 343.243408 -253.462528) (xy 343.190258 -253.458544) (xy 343.138296 -253.446684) (xy 343.088682 -253.427212)
			(xy 343.042524 -253.400563) (xy 343.000853 -253.367332) (xy 342.964601 -253.328261) (xy 342.934577 -253.284224)
			(xy 342.911451 -253.236203) (xy 342.895741 -253.185273) (xy 342.887798 -253.132569) (xy 339.37956 -253.132569)
			(xy 339.37956 -253.946385) (xy 339.599006 -253.946385) (xy 339.599006 -253.893087) (xy 339.606949 -253.840383)
			(xy 339.622659 -253.789453) (xy 339.645785 -253.741432) (xy 339.675809 -253.697395) (xy 339.712061 -253.658324)
			(xy 339.753732 -253.625093) (xy 339.79989 -253.598444) (xy 339.849504 -253.578972) (xy 339.901466 -253.567112)
			(xy 339.954616 -253.563129) (xy 340.007766 -253.567112) (xy 340.059728 -253.578972) (xy 340.109342 -253.598444)
			(xy 340.1555 -253.625093) (xy 340.197171 -253.658324) (xy 340.233423 -253.697395) (xy 340.263447 -253.741432)
			(xy 340.286573 -253.789453) (xy 340.302283 -253.840383) (xy 340.310226 -253.893087) (xy 340.310724 -253.919736)
			(xy 340.310226 -253.946385) (xy 340.538806 -253.946385) (xy 340.538806 -253.893087) (xy 340.546749 -253.840383)
			(xy 340.562459 -253.789453) (xy 340.585585 -253.741432) (xy 340.615609 -253.697395) (xy 340.651861 -253.658324)
			(xy 340.693532 -253.625093) (xy 340.73969 -253.598444) (xy 340.789304 -253.578972) (xy 340.841266 -253.567112)
			(xy 340.894416 -253.563129) (xy 340.947566 -253.567112) (xy 340.999528 -253.578972) (xy 341.049142 -253.598444)
			(xy 341.0953 -253.625093) (xy 341.136971 -253.658324) (xy 341.173223 -253.697395) (xy 341.203247 -253.741432)
			(xy 341.226373 -253.789453) (xy 341.242083 -253.840383) (xy 341.250026 -253.893087) (xy 341.250524 -253.919736)
			(xy 341.250026 -253.946385) (xy 341.478606 -253.946385) (xy 341.478606 -253.893087) (xy 341.486549 -253.840383)
			(xy 341.502259 -253.789453) (xy 341.525385 -253.741432) (xy 341.555409 -253.697395) (xy 341.591661 -253.658324)
			(xy 341.633332 -253.625093) (xy 341.67949 -253.598444) (xy 341.729104 -253.578972) (xy 341.781066 -253.567112)
			(xy 341.834216 -253.563129) (xy 341.887366 -253.567112) (xy 341.939328 -253.578972) (xy 341.988942 -253.598444)
			(xy 342.0351 -253.625093) (xy 342.076771 -253.658324) (xy 342.113023 -253.697395) (xy 342.143047 -253.741432)
			(xy 342.166173 -253.789453) (xy 342.181883 -253.840383) (xy 342.189826 -253.893087) (xy 342.190324 -253.919736)
			(xy 342.189826 -253.946385) (xy 342.418152 -253.946385) (xy 342.418152 -253.893087) (xy 342.426095 -253.840383)
			(xy 342.441805 -253.789453) (xy 342.464931 -253.741432) (xy 342.494955 -253.697395) (xy 342.531207 -253.658324)
			(xy 342.572878 -253.625093) (xy 342.619036 -253.598444) (xy 342.66865 -253.578972) (xy 342.720612 -253.567112)
			(xy 342.773762 -253.563129) (xy 342.826912 -253.567112) (xy 342.878874 -253.578972) (xy 342.928488 -253.598444)
			(xy 342.974646 -253.625093) (xy 343.016317 -253.658324) (xy 343.052569 -253.697395) (xy 343.082593 -253.741432)
			(xy 343.105719 -253.789453) (xy 343.121429 -253.840383) (xy 343.129372 -253.893087) (xy 343.12987 -253.919736)
			(xy 343.129372 -253.946385) (xy 343.358206 -253.946385) (xy 343.358206 -253.893087) (xy 343.366149 -253.840383)
			(xy 343.381859 -253.789453) (xy 343.404985 -253.741432) (xy 343.435009 -253.697395) (xy 343.471261 -253.658324)
			(xy 343.512932 -253.625093) (xy 343.55909 -253.598444) (xy 343.608704 -253.578972) (xy 343.660666 -253.567112)
			(xy 343.713816 -253.563129) (xy 343.766966 -253.567112) (xy 343.818928 -253.578972) (xy 343.868542 -253.598444)
			(xy 343.9147 -253.625093) (xy 343.956371 -253.658324) (xy 343.992623 -253.697395) (xy 344.022647 -253.741432)
			(xy 344.045773 -253.789453) (xy 344.061483 -253.840383) (xy 344.069426 -253.893087) (xy 344.069924 -253.919736)
			(xy 344.069426 -253.946385) (xy 344.298006 -253.946385) (xy 344.298006 -253.893087) (xy 344.305949 -253.840383)
			(xy 344.321659 -253.789453) (xy 344.344785 -253.741432) (xy 344.374809 -253.697395) (xy 344.411061 -253.658324)
			(xy 344.452732 -253.625093) (xy 344.49889 -253.598444) (xy 344.548504 -253.578972) (xy 344.600466 -253.567112)
			(xy 344.653616 -253.563129) (xy 344.706766 -253.567112) (xy 344.758728 -253.578972) (xy 344.808342 -253.598444)
			(xy 344.8545 -253.625093) (xy 344.896171 -253.658324) (xy 344.932423 -253.697395) (xy 344.962447 -253.741432)
			(xy 344.985573 -253.789453) (xy 345.001283 -253.840383) (xy 345.009226 -253.893087) (xy 345.009724 -253.919736)
			(xy 345.009226 -253.946385) (xy 345.237806 -253.946385) (xy 345.237806 -253.893087) (xy 345.245749 -253.840383)
			(xy 345.261459 -253.789453) (xy 345.284585 -253.741432) (xy 345.314609 -253.697395) (xy 345.350861 -253.658324)
			(xy 345.392532 -253.625093) (xy 345.43869 -253.598444) (xy 345.488304 -253.578972) (xy 345.540266 -253.567112)
			(xy 345.593416 -253.563129) (xy 345.646566 -253.567112) (xy 345.698528 -253.578972) (xy 345.748142 -253.598444)
			(xy 345.7943 -253.625093) (xy 345.835971 -253.658324) (xy 345.872223 -253.697395) (xy 345.902247 -253.741432)
			(xy 345.925373 -253.789453) (xy 345.941083 -253.840383) (xy 345.949026 -253.893087) (xy 345.949524 -253.919736)
			(xy 345.949026 -253.946385) (xy 346.177606 -253.946385) (xy 346.177606 -253.893087) (xy 346.185549 -253.840383)
			(xy 346.201259 -253.789453) (xy 346.224385 -253.741432) (xy 346.254409 -253.697395) (xy 346.290661 -253.658324)
			(xy 346.332332 -253.625093) (xy 346.37849 -253.598444) (xy 346.428104 -253.578972) (xy 346.480066 -253.567112)
			(xy 346.533216 -253.563129) (xy 346.586366 -253.567112) (xy 346.638328 -253.578972) (xy 346.687942 -253.598444)
			(xy 346.7341 -253.625093) (xy 346.775771 -253.658324) (xy 346.812023 -253.697395) (xy 346.842047 -253.741432)
			(xy 346.865173 -253.789453) (xy 346.880883 -253.840383) (xy 346.888826 -253.893087) (xy 346.889324 -253.919736)
			(xy 346.888826 -253.946385) (xy 346.880883 -253.999089) (xy 346.865173 -254.050019) (xy 346.842047 -254.09804)
			(xy 346.812023 -254.142077) (xy 346.775771 -254.181148) (xy 346.7341 -254.214379) (xy 346.687942 -254.241028)
			(xy 346.638328 -254.2605) (xy 346.586366 -254.27236) (xy 346.533216 -254.276344) (xy 346.480066 -254.27236)
			(xy 346.428104 -254.2605) (xy 346.37849 -254.241028) (xy 346.332332 -254.214379) (xy 346.290661 -254.181148)
			(xy 346.254409 -254.142077) (xy 346.224385 -254.09804) (xy 346.201259 -254.050019) (xy 346.185549 -253.999089)
			(xy 346.177606 -253.946385) (xy 345.949026 -253.946385) (xy 345.941083 -253.999089) (xy 345.925373 -254.050019)
			(xy 345.902247 -254.09804) (xy 345.872223 -254.142077) (xy 345.835971 -254.181148) (xy 345.7943 -254.214379)
			(xy 345.748142 -254.241028) (xy 345.698528 -254.2605) (xy 345.646566 -254.27236) (xy 345.593416 -254.276344)
			(xy 345.540266 -254.27236) (xy 345.488304 -254.2605) (xy 345.43869 -254.241028) (xy 345.392532 -254.214379)
			(xy 345.350861 -254.181148) (xy 345.314609 -254.142077) (xy 345.284585 -254.09804) (xy 345.261459 -254.050019)
			(xy 345.245749 -253.999089) (xy 345.237806 -253.946385) (xy 345.009226 -253.946385) (xy 345.001283 -253.999089)
			(xy 344.985573 -254.050019) (xy 344.962447 -254.09804) (xy 344.932423 -254.142077) (xy 344.896171 -254.181148)
			(xy 344.8545 -254.214379) (xy 344.808342 -254.241028) (xy 344.758728 -254.2605) (xy 344.706766 -254.27236)
			(xy 344.653616 -254.276344) (xy 344.600466 -254.27236) (xy 344.548504 -254.2605) (xy 344.49889 -254.241028)
			(xy 344.452732 -254.214379) (xy 344.411061 -254.181148) (xy 344.374809 -254.142077) (xy 344.344785 -254.09804)
			(xy 344.321659 -254.050019) (xy 344.305949 -253.999089) (xy 344.298006 -253.946385) (xy 344.069426 -253.946385)
			(xy 344.061483 -253.999089) (xy 344.045773 -254.050019) (xy 344.022647 -254.09804) (xy 343.992623 -254.142077)
			(xy 343.956371 -254.181148) (xy 343.9147 -254.214379) (xy 343.868542 -254.241028) (xy 343.818928 -254.2605)
			(xy 343.766966 -254.27236) (xy 343.713816 -254.276344) (xy 343.660666 -254.27236) (xy 343.608704 -254.2605)
			(xy 343.55909 -254.241028) (xy 343.512932 -254.214379) (xy 343.471261 -254.181148) (xy 343.435009 -254.142077)
			(xy 343.404985 -254.09804) (xy 343.381859 -254.050019) (xy 343.366149 -253.999089) (xy 343.358206 -253.946385)
			(xy 343.129372 -253.946385) (xy 343.121429 -253.999089) (xy 343.105719 -254.050019) (xy 343.082593 -254.09804)
			(xy 343.052569 -254.142077) (xy 343.016317 -254.181148) (xy 342.974646 -254.214379) (xy 342.928488 -254.241028)
			(xy 342.878874 -254.2605) (xy 342.826912 -254.27236) (xy 342.773762 -254.276344) (xy 342.720612 -254.27236)
			(xy 342.66865 -254.2605) (xy 342.619036 -254.241028) (xy 342.572878 -254.214379) (xy 342.531207 -254.181148)
			(xy 342.494955 -254.142077) (xy 342.464931 -254.09804) (xy 342.441805 -254.050019) (xy 342.426095 -253.999089)
			(xy 342.418152 -253.946385) (xy 342.189826 -253.946385) (xy 342.181883 -253.999089) (xy 342.166173 -254.050019)
			(xy 342.143047 -254.09804) (xy 342.113023 -254.142077) (xy 342.076771 -254.181148) (xy 342.0351 -254.214379)
			(xy 341.988942 -254.241028) (xy 341.939328 -254.2605) (xy 341.887366 -254.27236) (xy 341.834216 -254.276344)
			(xy 341.781066 -254.27236) (xy 341.729104 -254.2605) (xy 341.67949 -254.241028) (xy 341.633332 -254.214379)
			(xy 341.591661 -254.181148) (xy 341.555409 -254.142077) (xy 341.525385 -254.09804) (xy 341.502259 -254.050019)
			(xy 341.486549 -253.999089) (xy 341.478606 -253.946385) (xy 341.250026 -253.946385) (xy 341.242083 -253.999089)
			(xy 341.226373 -254.050019) (xy 341.203247 -254.09804) (xy 341.173223 -254.142077) (xy 341.136971 -254.181148)
			(xy 341.0953 -254.214379) (xy 341.049142 -254.241028) (xy 340.999528 -254.2605) (xy 340.947566 -254.27236)
			(xy 340.894416 -254.276344) (xy 340.841266 -254.27236) (xy 340.789304 -254.2605) (xy 340.73969 -254.241028)
			(xy 340.693532 -254.214379) (xy 340.651861 -254.181148) (xy 340.615609 -254.142077) (xy 340.585585 -254.09804)
			(xy 340.562459 -254.050019) (xy 340.546749 -253.999089) (xy 340.538806 -253.946385) (xy 340.310226 -253.946385)
			(xy 340.302283 -253.999089) (xy 340.286573 -254.050019) (xy 340.263447 -254.09804) (xy 340.233423 -254.142077)
			(xy 340.197171 -254.181148) (xy 340.1555 -254.214379) (xy 340.109342 -254.241028) (xy 340.059728 -254.2605)
			(xy 340.007766 -254.27236) (xy 339.954616 -254.276344) (xy 339.901466 -254.27236) (xy 339.849504 -254.2605)
			(xy 339.79989 -254.241028) (xy 339.753732 -254.214379) (xy 339.712061 -254.181148) (xy 339.675809 -254.142077)
			(xy 339.645785 -254.09804) (xy 339.622659 -254.050019) (xy 339.606949 -253.999089) (xy 339.599006 -253.946385)
			(xy 339.37956 -253.946385) (xy 339.37956 -254.275844) (xy 339.379969 -254.289229) (xy 339.386938 -254.315077)
			(xy 339.400384 -254.338225) (xy 339.419385 -254.357084) (xy 339.442635 -254.370356) (xy 339.468534 -254.377129)
			(xy 339.481922 -254.377444) (xy 339.484716 -254.377444) (xy 339.511368 -254.377943) (xy 339.564077 -254.38589)
			(xy 339.615012 -254.401603) (xy 339.663037 -254.424733) (xy 339.707078 -254.454761) (xy 339.746152 -254.491018)
			(xy 339.779386 -254.532694) (xy 339.806037 -254.578857) (xy 339.825511 -254.628477) (xy 339.837372 -254.680445)
			(xy 339.841356 -254.7336) (xy 339.839362 -254.760201) (xy 340.068652 -254.760201) (xy 340.068652 -254.706903)
			(xy 340.076595 -254.654199) (xy 340.092305 -254.603269) (xy 340.115431 -254.555248) (xy 340.145455 -254.511211)
			(xy 340.181707 -254.47214) (xy 340.223378 -254.438909) (xy 340.269536 -254.41226) (xy 340.31915 -254.392788)
			(xy 340.371112 -254.380928) (xy 340.424262 -254.376945) (xy 340.477412 -254.380928) (xy 340.529374 -254.392788)
			(xy 340.578988 -254.41226) (xy 340.625146 -254.438909) (xy 340.666817 -254.47214) (xy 340.703069 -254.511211)
			(xy 340.733093 -254.555248) (xy 340.756219 -254.603269) (xy 340.771929 -254.654199) (xy 340.779872 -254.706903)
			(xy 340.78037 -254.733552) (xy 341.020149 -254.733552) (xy 341.024179 -254.681054) (xy 341.036176 -254.629786)
			(xy 341.055859 -254.580951) (xy 341.082765 -254.535692) (xy 341.116265 -254.495071) (xy 341.155573 -254.46004)
			(xy 341.199768 -254.43142) (xy 341.247813 -254.409881) (xy 341.298584 -254.395929) (xy 341.350889 -254.389891)
			(xy 341.403503 -254.391908) (xy 341.455193 -254.401932) (xy 341.504746 -254.41973) (xy 341.551002 -254.444883)
			(xy 341.592876 -254.476802) (xy 341.629388 -254.51474) (xy 341.65968 -254.557806) (xy 341.683043 -254.604991)
			(xy 341.698929 -254.65519) (xy 341.706966 -254.707226) (xy 341.70747 -254.733552) (xy 341.959949 -254.733552)
			(xy 341.963979 -254.681054) (xy 341.975976 -254.629786) (xy 341.995659 -254.580951) (xy 342.022565 -254.535692)
			(xy 342.056065 -254.495071) (xy 342.095373 -254.46004) (xy 342.139568 -254.43142) (xy 342.187613 -254.409881)
			(xy 342.238384 -254.395929) (xy 342.290689 -254.389891) (xy 342.343303 -254.391908) (xy 342.394993 -254.401932)
			(xy 342.444546 -254.41973) (xy 342.490802 -254.444883) (xy 342.532676 -254.476802) (xy 342.569188 -254.51474)
			(xy 342.59948 -254.557806) (xy 342.622843 -254.604991) (xy 342.638729 -254.65519) (xy 342.646766 -254.707226)
			(xy 342.64727 -254.733552) (xy 342.646766 -254.759878) (xy 342.646716 -254.760201) (xy 342.888052 -254.760201)
			(xy 342.888052 -254.706903) (xy 342.895995 -254.654199) (xy 342.911705 -254.603269) (xy 342.934831 -254.555248)
			(xy 342.964855 -254.511211) (xy 343.001107 -254.47214) (xy 343.042778 -254.438909) (xy 343.088936 -254.41226)
			(xy 343.13855 -254.392788) (xy 343.190512 -254.380928) (xy 343.243662 -254.376945) (xy 343.296812 -254.380928)
			(xy 343.348774 -254.392788) (xy 343.398388 -254.41226) (xy 343.444546 -254.438909) (xy 343.486217 -254.47214)
			(xy 343.522469 -254.511211) (xy 343.552493 -254.555248) (xy 343.575619 -254.603269) (xy 343.591329 -254.654199)
			(xy 343.599272 -254.706903) (xy 343.59977 -254.733552) (xy 343.599272 -254.760201) (xy 343.827852 -254.760201)
			(xy 343.827852 -254.706903) (xy 343.835795 -254.654199) (xy 343.851505 -254.603269) (xy 343.874631 -254.555248)
			(xy 343.904655 -254.511211) (xy 343.940907 -254.47214) (xy 343.982578 -254.438909) (xy 344.028736 -254.41226)
			(xy 344.07835 -254.392788) (xy 344.130312 -254.380928) (xy 344.183462 -254.376945) (xy 344.236612 -254.380928)
			(xy 344.288574 -254.392788) (xy 344.338188 -254.41226) (xy 344.384346 -254.438909) (xy 344.426017 -254.47214)
			(xy 344.462269 -254.511211) (xy 344.492293 -254.555248) (xy 344.515419 -254.603269) (xy 344.531129 -254.654199)
			(xy 344.539072 -254.706903) (xy 344.53957 -254.733552) (xy 344.539072 -254.760201) (xy 344.767652 -254.760201)
			(xy 344.767652 -254.706903) (xy 344.775595 -254.654199) (xy 344.791305 -254.603269) (xy 344.814431 -254.555248)
			(xy 344.844455 -254.511211) (xy 344.880707 -254.47214) (xy 344.922378 -254.438909) (xy 344.968536 -254.41226)
			(xy 345.01815 -254.392788) (xy 345.070112 -254.380928) (xy 345.123262 -254.376945) (xy 345.176412 -254.380928)
			(xy 345.228374 -254.392788) (xy 345.277988 -254.41226) (xy 345.324146 -254.438909) (xy 345.365817 -254.47214)
			(xy 345.402069 -254.511211) (xy 345.432093 -254.555248) (xy 345.455219 -254.603269) (xy 345.470929 -254.654199)
			(xy 345.478872 -254.706903) (xy 345.47937 -254.733552) (xy 345.478872 -254.760201) (xy 345.707706 -254.760201)
			(xy 345.707706 -254.706903) (xy 345.715649 -254.654199) (xy 345.731359 -254.603269) (xy 345.754485 -254.555248)
			(xy 345.784509 -254.511211) (xy 345.820761 -254.47214) (xy 345.862432 -254.438909) (xy 345.90859 -254.41226)
			(xy 345.958204 -254.392788) (xy 346.010166 -254.380928) (xy 346.063316 -254.376945) (xy 346.116466 -254.380928)
			(xy 346.168428 -254.392788) (xy 346.218042 -254.41226) (xy 346.2642 -254.438909) (xy 346.305871 -254.47214)
			(xy 346.342123 -254.511211) (xy 346.372147 -254.555248) (xy 346.395273 -254.603269) (xy 346.410983 -254.654199)
			(xy 346.418926 -254.706903) (xy 346.419424 -254.733552) (xy 346.418926 -254.760201) (xy 346.410983 -254.812905)
			(xy 346.395273 -254.863835) (xy 346.372147 -254.911856) (xy 346.342123 -254.955893) (xy 346.305871 -254.994964)
			(xy 346.2642 -255.028195) (xy 346.218042 -255.054844) (xy 346.168428 -255.074316) (xy 346.116466 -255.086176)
			(xy 346.063316 -255.09016) (xy 346.010166 -255.086176) (xy 345.958204 -255.074316) (xy 345.90859 -255.054844)
			(xy 345.862432 -255.028195) (xy 345.820761 -254.994964) (xy 345.784509 -254.955893) (xy 345.754485 -254.911856)
			(xy 345.731359 -254.863835) (xy 345.715649 -254.812905) (xy 345.707706 -254.760201) (xy 345.478872 -254.760201)
			(xy 345.470929 -254.812905) (xy 345.455219 -254.863835) (xy 345.432093 -254.911856) (xy 345.402069 -254.955893)
			(xy 345.365817 -254.994964) (xy 345.324146 -255.028195) (xy 345.277988 -255.054844) (xy 345.228374 -255.074316)
			(xy 345.176412 -255.086176) (xy 345.123262 -255.09016) (xy 345.070112 -255.086176) (xy 345.01815 -255.074316)
			(xy 344.968536 -255.054844) (xy 344.922378 -255.028195) (xy 344.880707 -254.994964) (xy 344.844455 -254.955893)
			(xy 344.814431 -254.911856) (xy 344.791305 -254.863835) (xy 344.775595 -254.812905) (xy 344.767652 -254.760201)
			(xy 344.539072 -254.760201) (xy 344.531129 -254.812905) (xy 344.515419 -254.863835) (xy 344.492293 -254.911856)
			(xy 344.462269 -254.955893) (xy 344.426017 -254.994964) (xy 344.384346 -255.028195) (xy 344.338188 -255.054844)
			(xy 344.288574 -255.074316) (xy 344.236612 -255.086176) (xy 344.183462 -255.09016) (xy 344.130312 -255.086176)
			(xy 344.07835 -255.074316) (xy 344.028736 -255.054844) (xy 343.982578 -255.028195) (xy 343.940907 -254.994964)
			(xy 343.904655 -254.955893) (xy 343.874631 -254.911856) (xy 343.851505 -254.863835) (xy 343.835795 -254.812905)
			(xy 343.827852 -254.760201) (xy 343.599272 -254.760201) (xy 343.591329 -254.812905) (xy 343.575619 -254.863835)
			(xy 343.552493 -254.911856) (xy 343.522469 -254.955893) (xy 343.486217 -254.994964) (xy 343.444546 -255.028195)
			(xy 343.398388 -255.054844) (xy 343.348774 -255.074316) (xy 343.296812 -255.086176) (xy 343.243662 -255.09016)
			(xy 343.190512 -255.086176) (xy 343.13855 -255.074316) (xy 343.088936 -255.054844) (xy 343.042778 -255.028195)
			(xy 343.001107 -254.994964) (xy 342.964855 -254.955893) (xy 342.934831 -254.911856) (xy 342.911705 -254.863835)
			(xy 342.895995 -254.812905) (xy 342.888052 -254.760201) (xy 342.646716 -254.760201) (xy 342.638729 -254.811914)
			(xy 342.622843 -254.862113) (xy 342.59948 -254.909298) (xy 342.569188 -254.952364) (xy 342.532676 -254.990302)
			(xy 342.490802 -255.022221) (xy 342.444546 -255.047374) (xy 342.394993 -255.065172) (xy 342.343303 -255.075196)
			(xy 342.290689 -255.077213) (xy 342.238384 -255.071175) (xy 342.187613 -255.057223) (xy 342.139568 -255.035684)
			(xy 342.095373 -255.007064) (xy 342.056065 -254.972033) (xy 342.022565 -254.931412) (xy 341.995659 -254.886153)
			(xy 341.975976 -254.837318) (xy 341.963979 -254.78605) (xy 341.959949 -254.733552) (xy 341.70747 -254.733552)
			(xy 341.706966 -254.759878) (xy 341.698929 -254.811914) (xy 341.683043 -254.862113) (xy 341.65968 -254.909298)
			(xy 341.629388 -254.952364) (xy 341.592876 -254.990302) (xy 341.551002 -255.022221) (xy 341.504746 -255.047374)
			(xy 341.455193 -255.065172) (xy 341.403503 -255.075196) (xy 341.350889 -255.077213) (xy 341.298584 -255.071175)
			(xy 341.247813 -255.057223) (xy 341.199768 -255.035684) (xy 341.155573 -255.007064) (xy 341.116265 -254.972033)
			(xy 341.082765 -254.931412) (xy 341.055859 -254.886153) (xy 341.036176 -254.837318) (xy 341.024179 -254.78605)
			(xy 341.020149 -254.733552) (xy 340.78037 -254.733552) (xy 340.779872 -254.760201) (xy 340.771929 -254.812905)
			(xy 340.756219 -254.863835) (xy 340.733093 -254.911856) (xy 340.703069 -254.955893) (xy 340.666817 -254.994964)
			(xy 340.625146 -255.028195) (xy 340.578988 -255.054844) (xy 340.529374 -255.074316) (xy 340.477412 -255.086176)
			(xy 340.424262 -255.09016) (xy 340.371112 -255.086176) (xy 340.31915 -255.074316) (xy 340.269536 -255.054844)
			(xy 340.223378 -255.028195) (xy 340.181707 -254.994964) (xy 340.145455 -254.955893) (xy 340.115431 -254.911856)
			(xy 340.092305 -254.863835) (xy 340.076595 -254.812905) (xy 340.068652 -254.760201) (xy 339.839362 -254.760201)
			(xy 339.837372 -254.786755) (xy 339.825511 -254.838723) (xy 339.806037 -254.888343) (xy 339.779386 -254.934506)
			(xy 339.746152 -254.976182) (xy 339.707078 -255.012439) (xy 339.663037 -255.042467) (xy 339.615012 -255.065597)
			(xy 339.564077 -255.08131) (xy 339.511368 -255.089257) (xy 339.484716 -255.08966) (xy 339.481922 -255.08966)
			(xy 339.468533 -255.089968) (xy 339.442633 -255.096742) (xy 339.419383 -255.110015) (xy 339.400381 -255.128875)
			(xy 339.386934 -255.152025) (xy 339.379966 -255.177874) (xy 339.37956 -255.19126) (xy 339.37956 -255.574271)
			(xy 339.598752 -255.574271) (xy 339.598752 -255.520973) (xy 339.606695 -255.468269) (xy 339.622405 -255.417339)
			(xy 339.645531 -255.369318) (xy 339.675555 -255.325281) (xy 339.711807 -255.28621) (xy 339.753478 -255.252979)
			(xy 339.799636 -255.22633) (xy 339.84925 -255.206858) (xy 339.901212 -255.194998) (xy 339.954362 -255.191015)
			(xy 340.007512 -255.194998) (xy 340.059474 -255.206858) (xy 340.109088 -255.22633) (xy 340.155246 -255.252979)
			(xy 340.196917 -255.28621) (xy 340.233169 -255.325281) (xy 340.263193 -255.369318) (xy 340.286319 -255.417339)
			(xy 340.302029 -255.468269) (xy 340.309972 -255.520973) (xy 340.31047 -255.547622) (xy 340.309972 -255.574271)
			(xy 340.538806 -255.574271) (xy 340.538806 -255.520973) (xy 340.546749 -255.468269) (xy 340.562459 -255.417339)
			(xy 340.585585 -255.369318) (xy 340.615609 -255.325281) (xy 340.651861 -255.28621) (xy 340.693532 -255.252979)
			(xy 340.73969 -255.22633) (xy 340.789304 -255.206858) (xy 340.841266 -255.194998) (xy 340.894416 -255.191015)
			(xy 340.947566 -255.194998) (xy 340.999528 -255.206858) (xy 341.049142 -255.22633) (xy 341.0953 -255.252979)
			(xy 341.136971 -255.28621) (xy 341.173223 -255.325281) (xy 341.203247 -255.369318) (xy 341.226373 -255.417339)
			(xy 341.242083 -255.468269) (xy 341.250026 -255.520973) (xy 341.250524 -255.547622) (xy 341.250026 -255.574271)
			(xy 341.478606 -255.574271) (xy 341.478606 -255.520973) (xy 341.486549 -255.468269) (xy 341.502259 -255.417339)
			(xy 341.525385 -255.369318) (xy 341.555409 -255.325281) (xy 341.591661 -255.28621) (xy 341.633332 -255.252979)
			(xy 341.67949 -255.22633) (xy 341.729104 -255.206858) (xy 341.781066 -255.194998) (xy 341.834216 -255.191015)
			(xy 341.887366 -255.194998) (xy 341.939328 -255.206858) (xy 341.988942 -255.22633) (xy 342.0351 -255.252979)
			(xy 342.076771 -255.28621) (xy 342.113023 -255.325281) (xy 342.143047 -255.369318) (xy 342.166173 -255.417339)
			(xy 342.181883 -255.468269) (xy 342.189826 -255.520973) (xy 342.190324 -255.547622) (xy 342.189826 -255.574271)
			(xy 342.418406 -255.574271) (xy 342.418406 -255.520973) (xy 342.426349 -255.468269) (xy 342.442059 -255.417339)
			(xy 342.465185 -255.369318) (xy 342.495209 -255.325281) (xy 342.531461 -255.28621) (xy 342.573132 -255.252979)
			(xy 342.61929 -255.22633) (xy 342.668904 -255.206858) (xy 342.720866 -255.194998) (xy 342.774016 -255.191015)
			(xy 342.827166 -255.194998) (xy 342.879128 -255.206858) (xy 342.928742 -255.22633) (xy 342.9749 -255.252979)
			(xy 343.016571 -255.28621) (xy 343.052823 -255.325281) (xy 343.082847 -255.369318) (xy 343.105973 -255.417339)
			(xy 343.121683 -255.468269) (xy 343.129626 -255.520973) (xy 343.130124 -255.547622) (xy 343.129626 -255.574271)
			(xy 343.358206 -255.574271) (xy 343.358206 -255.520973) (xy 343.366149 -255.468269) (xy 343.381859 -255.417339)
			(xy 343.404985 -255.369318) (xy 343.435009 -255.325281) (xy 343.471261 -255.28621) (xy 343.512932 -255.252979)
			(xy 343.55909 -255.22633) (xy 343.608704 -255.206858) (xy 343.660666 -255.194998) (xy 343.713816 -255.191015)
			(xy 343.766966 -255.194998) (xy 343.818928 -255.206858) (xy 343.868542 -255.22633) (xy 343.9147 -255.252979)
			(xy 343.956371 -255.28621) (xy 343.992623 -255.325281) (xy 344.022647 -255.369318) (xy 344.045773 -255.417339)
			(xy 344.061483 -255.468269) (xy 344.069426 -255.520973) (xy 344.069924 -255.547622) (xy 344.069426 -255.574271)
			(xy 344.298006 -255.574271) (xy 344.298006 -255.520973) (xy 344.305949 -255.468269) (xy 344.321659 -255.417339)
			(xy 344.344785 -255.369318) (xy 344.374809 -255.325281) (xy 344.411061 -255.28621) (xy 344.452732 -255.252979)
			(xy 344.49889 -255.22633) (xy 344.548504 -255.206858) (xy 344.600466 -255.194998) (xy 344.653616 -255.191015)
			(xy 344.706766 -255.194998) (xy 344.758728 -255.206858) (xy 344.808342 -255.22633) (xy 344.8545 -255.252979)
			(xy 344.896171 -255.28621) (xy 344.932423 -255.325281) (xy 344.962447 -255.369318) (xy 344.985573 -255.417339)
			(xy 345.001283 -255.468269) (xy 345.009226 -255.520973) (xy 345.009724 -255.547622) (xy 345.009226 -255.574271)
			(xy 345.237806 -255.574271) (xy 345.237806 -255.520973) (xy 345.245749 -255.468269) (xy 345.261459 -255.417339)
			(xy 345.284585 -255.369318) (xy 345.314609 -255.325281) (xy 345.350861 -255.28621) (xy 345.392532 -255.252979)
			(xy 345.43869 -255.22633) (xy 345.488304 -255.206858) (xy 345.540266 -255.194998) (xy 345.593416 -255.191015)
			(xy 345.646566 -255.194998) (xy 345.698528 -255.206858) (xy 345.748142 -255.22633) (xy 345.7943 -255.252979)
			(xy 345.835971 -255.28621) (xy 345.872223 -255.325281) (xy 345.902247 -255.369318) (xy 345.925373 -255.417339)
			(xy 345.941083 -255.468269) (xy 345.949026 -255.520973) (xy 345.949524 -255.547622) (xy 345.949026 -255.574271)
			(xy 346.177352 -255.574271) (xy 346.177352 -255.520973) (xy 346.185295 -255.468269) (xy 346.201005 -255.417339)
			(xy 346.224131 -255.369318) (xy 346.254155 -255.325281) (xy 346.290407 -255.28621) (xy 346.332078 -255.252979)
			(xy 346.378236 -255.22633) (xy 346.42785 -255.206858) (xy 346.479812 -255.194998) (xy 346.532962 -255.191015)
			(xy 346.586112 -255.194998) (xy 346.638074 -255.206858) (xy 346.687688 -255.22633) (xy 346.733846 -255.252979)
			(xy 346.775517 -255.28621) (xy 346.811769 -255.325281) (xy 346.841793 -255.369318) (xy 346.864919 -255.417339)
			(xy 346.880629 -255.468269) (xy 346.888572 -255.520973) (xy 346.88907 -255.547622) (xy 346.888572 -255.574271)
			(xy 346.880629 -255.626975) (xy 346.864919 -255.677905) (xy 346.841793 -255.725926) (xy 346.811769 -255.769963)
			(xy 346.775517 -255.809034) (xy 346.733846 -255.842265) (xy 346.687688 -255.868914) (xy 346.638074 -255.888386)
			(xy 346.586112 -255.900246) (xy 346.532962 -255.90423) (xy 346.479812 -255.900246) (xy 346.42785 -255.888386)
			(xy 346.378236 -255.868914) (xy 346.332078 -255.842265) (xy 346.290407 -255.809034) (xy 346.254155 -255.769963)
			(xy 346.224131 -255.725926) (xy 346.201005 -255.677905) (xy 346.185295 -255.626975) (xy 346.177352 -255.574271)
			(xy 345.949026 -255.574271) (xy 345.941083 -255.626975) (xy 345.925373 -255.677905) (xy 345.902247 -255.725926)
			(xy 345.872223 -255.769963) (xy 345.835971 -255.809034) (xy 345.7943 -255.842265) (xy 345.748142 -255.868914)
			(xy 345.698528 -255.888386) (xy 345.646566 -255.900246) (xy 345.593416 -255.90423) (xy 345.540266 -255.900246)
			(xy 345.488304 -255.888386) (xy 345.43869 -255.868914) (xy 345.392532 -255.842265) (xy 345.350861 -255.809034)
			(xy 345.314609 -255.769963) (xy 345.284585 -255.725926) (xy 345.261459 -255.677905) (xy 345.245749 -255.626975)
			(xy 345.237806 -255.574271) (xy 345.009226 -255.574271) (xy 345.001283 -255.626975) (xy 344.985573 -255.677905)
			(xy 344.962447 -255.725926) (xy 344.932423 -255.769963) (xy 344.896171 -255.809034) (xy 344.8545 -255.842265)
			(xy 344.808342 -255.868914) (xy 344.758728 -255.888386) (xy 344.706766 -255.900246) (xy 344.653616 -255.90423)
			(xy 344.600466 -255.900246) (xy 344.548504 -255.888386) (xy 344.49889 -255.868914) (xy 344.452732 -255.842265)
			(xy 344.411061 -255.809034) (xy 344.374809 -255.769963) (xy 344.344785 -255.725926) (xy 344.321659 -255.677905)
			(xy 344.305949 -255.626975) (xy 344.298006 -255.574271) (xy 344.069426 -255.574271) (xy 344.061483 -255.626975)
			(xy 344.045773 -255.677905) (xy 344.022647 -255.725926) (xy 343.992623 -255.769963) (xy 343.956371 -255.809034)
			(xy 343.9147 -255.842265) (xy 343.868542 -255.868914) (xy 343.818928 -255.888386) (xy 343.766966 -255.900246)
			(xy 343.713816 -255.90423) (xy 343.660666 -255.900246) (xy 343.608704 -255.888386) (xy 343.55909 -255.868914)
			(xy 343.512932 -255.842265) (xy 343.471261 -255.809034) (xy 343.435009 -255.769963) (xy 343.404985 -255.725926)
			(xy 343.381859 -255.677905) (xy 343.366149 -255.626975) (xy 343.358206 -255.574271) (xy 343.129626 -255.574271)
			(xy 343.121683 -255.626975) (xy 343.105973 -255.677905) (xy 343.082847 -255.725926) (xy 343.052823 -255.769963)
			(xy 343.016571 -255.809034) (xy 342.9749 -255.842265) (xy 342.928742 -255.868914) (xy 342.879128 -255.888386)
			(xy 342.827166 -255.900246) (xy 342.774016 -255.90423) (xy 342.720866 -255.900246) (xy 342.668904 -255.888386)
			(xy 342.61929 -255.868914) (xy 342.573132 -255.842265) (xy 342.531461 -255.809034) (xy 342.495209 -255.769963)
			(xy 342.465185 -255.725926) (xy 342.442059 -255.677905) (xy 342.426349 -255.626975) (xy 342.418406 -255.574271)
			(xy 342.189826 -255.574271) (xy 342.181883 -255.626975) (xy 342.166173 -255.677905) (xy 342.143047 -255.725926)
			(xy 342.113023 -255.769963) (xy 342.076771 -255.809034) (xy 342.0351 -255.842265) (xy 341.988942 -255.868914)
			(xy 341.939328 -255.888386) (xy 341.887366 -255.900246) (xy 341.834216 -255.90423) (xy 341.781066 -255.900246)
			(xy 341.729104 -255.888386) (xy 341.67949 -255.868914) (xy 341.633332 -255.842265) (xy 341.591661 -255.809034)
			(xy 341.555409 -255.769963) (xy 341.525385 -255.725926) (xy 341.502259 -255.677905) (xy 341.486549 -255.626975)
			(xy 341.478606 -255.574271) (xy 341.250026 -255.574271) (xy 341.242083 -255.626975) (xy 341.226373 -255.677905)
			(xy 341.203247 -255.725926) (xy 341.173223 -255.769963) (xy 341.136971 -255.809034) (xy 341.0953 -255.842265)
			(xy 341.049142 -255.868914) (xy 340.999528 -255.888386) (xy 340.947566 -255.900246) (xy 340.894416 -255.90423)
			(xy 340.841266 -255.900246) (xy 340.789304 -255.888386) (xy 340.73969 -255.868914) (xy 340.693532 -255.842265)
			(xy 340.651861 -255.809034) (xy 340.615609 -255.769963) (xy 340.585585 -255.725926) (xy 340.562459 -255.677905)
			(xy 340.546749 -255.626975) (xy 340.538806 -255.574271) (xy 340.309972 -255.574271) (xy 340.302029 -255.626975)
			(xy 340.286319 -255.677905) (xy 340.263193 -255.725926) (xy 340.233169 -255.769963) (xy 340.196917 -255.809034)
			(xy 340.155246 -255.842265) (xy 340.109088 -255.868914) (xy 340.059474 -255.888386) (xy 340.007512 -255.900246)
			(xy 339.954362 -255.90423) (xy 339.901212 -255.900246) (xy 339.84925 -255.888386) (xy 339.799636 -255.868914)
			(xy 339.753478 -255.842265) (xy 339.711807 -255.809034) (xy 339.675555 -255.769963) (xy 339.645531 -255.725926)
			(xy 339.622405 -255.677905) (xy 339.606695 -255.626975) (xy 339.598752 -255.574271) (xy 339.37956 -255.574271)
			(xy 339.37956 -255.90373) (xy 339.379967 -255.917116) (xy 339.386934 -255.942967) (xy 339.400379 -255.966119)
			(xy 339.419381 -255.98498) (xy 339.442631 -255.998254) (xy 339.468533 -256.005029) (xy 339.481922 -256.00533)
			(xy 339.484462 -256.00533) (xy 339.511112 -256.0058) (xy 339.563818 -256.013739) (xy 339.614751 -256.029445)
			(xy 339.662775 -256.052568) (xy 339.706816 -256.08259) (xy 339.74589 -256.118841) (xy 339.779124 -256.160511)
			(xy 339.805775 -256.20667) (xy 339.825249 -256.256285) (xy 339.837111 -256.308249) (xy 339.841094 -256.3614)
			(xy 339.839094 -256.388087) (xy 340.068652 -256.388087) (xy 340.068652 -256.334789) (xy 340.076595 -256.282085)
			(xy 340.092305 -256.231155) (xy 340.115431 -256.183134) (xy 340.145455 -256.139097) (xy 340.181707 -256.100026)
			(xy 340.223378 -256.066795) (xy 340.269536 -256.040146) (xy 340.31915 -256.020674) (xy 340.371112 -256.008814)
			(xy 340.424262 -256.004831) (xy 340.477412 -256.008814) (xy 340.529374 -256.020674) (xy 340.578988 -256.040146)
			(xy 340.625146 -256.066795) (xy 340.666817 -256.100026) (xy 340.703069 -256.139097) (xy 340.733093 -256.183134)
			(xy 340.756219 -256.231155) (xy 340.771929 -256.282085) (xy 340.779872 -256.334789) (xy 340.78037 -256.361438)
			(xy 340.779872 -256.388087) (xy 341.008452 -256.388087) (xy 341.008452 -256.334789) (xy 341.016395 -256.282085)
			(xy 341.032105 -256.231155) (xy 341.055231 -256.183134) (xy 341.085255 -256.139097) (xy 341.121507 -256.100026)
			(xy 341.163178 -256.066795) (xy 341.209336 -256.040146) (xy 341.25895 -256.020674) (xy 341.310912 -256.008814)
			(xy 341.364062 -256.004831) (xy 341.417212 -256.008814) (xy 341.469174 -256.020674) (xy 341.518788 -256.040146)
			(xy 341.564946 -256.066795) (xy 341.606617 -256.100026) (xy 341.642869 -256.139097) (xy 341.672893 -256.183134)
			(xy 341.696019 -256.231155) (xy 341.711729 -256.282085) (xy 341.719672 -256.334789) (xy 341.72017 -256.361438)
			(xy 341.719672 -256.388087) (xy 341.948506 -256.388087) (xy 341.948506 -256.334789) (xy 341.956449 -256.282085)
			(xy 341.972159 -256.231155) (xy 341.995285 -256.183134) (xy 342.025309 -256.139097) (xy 342.061561 -256.100026)
			(xy 342.103232 -256.066795) (xy 342.14939 -256.040146) (xy 342.199004 -256.020674) (xy 342.250966 -256.008814)
			(xy 342.304116 -256.004831) (xy 342.357266 -256.008814) (xy 342.409228 -256.020674) (xy 342.458842 -256.040146)
			(xy 342.505 -256.066795) (xy 342.546671 -256.100026) (xy 342.582923 -256.139097) (xy 342.612947 -256.183134)
			(xy 342.636073 -256.231155) (xy 342.651783 -256.282085) (xy 342.659726 -256.334789) (xy 342.660224 -256.361438)
			(xy 342.659726 -256.388087) (xy 342.888052 -256.388087) (xy 342.888052 -256.334789) (xy 342.895995 -256.282085)
			(xy 342.911705 -256.231155) (xy 342.934831 -256.183134) (xy 342.964855 -256.139097) (xy 343.001107 -256.100026)
			(xy 343.042778 -256.066795) (xy 343.088936 -256.040146) (xy 343.13855 -256.020674) (xy 343.190512 -256.008814)
			(xy 343.243662 -256.004831) (xy 343.296812 -256.008814) (xy 343.348774 -256.020674) (xy 343.398388 -256.040146)
			(xy 343.444546 -256.066795) (xy 343.486217 -256.100026) (xy 343.522469 -256.139097) (xy 343.552493 -256.183134)
			(xy 343.575619 -256.231155) (xy 343.591329 -256.282085) (xy 343.599272 -256.334789) (xy 343.59977 -256.361438)
			(xy 343.599272 -256.388087) (xy 343.827852 -256.388087) (xy 343.827852 -256.334789) (xy 343.835795 -256.282085)
			(xy 343.851505 -256.231155) (xy 343.874631 -256.183134) (xy 343.904655 -256.139097) (xy 343.940907 -256.100026)
			(xy 343.982578 -256.066795) (xy 344.028736 -256.040146) (xy 344.07835 -256.020674) (xy 344.130312 -256.008814)
			(xy 344.183462 -256.004831) (xy 344.236612 -256.008814) (xy 344.288574 -256.020674) (xy 344.338188 -256.040146)
			(xy 344.384346 -256.066795) (xy 344.426017 -256.100026) (xy 344.462269 -256.139097) (xy 344.492293 -256.183134)
			(xy 344.515419 -256.231155) (xy 344.531129 -256.282085) (xy 344.539072 -256.334789) (xy 344.53957 -256.361438)
			(xy 344.539072 -256.388087) (xy 344.767652 -256.388087) (xy 344.767652 -256.334789) (xy 344.775595 -256.282085)
			(xy 344.791305 -256.231155) (xy 344.814431 -256.183134) (xy 344.844455 -256.139097) (xy 344.880707 -256.100026)
			(xy 344.922378 -256.066795) (xy 344.968536 -256.040146) (xy 345.01815 -256.020674) (xy 345.070112 -256.008814)
			(xy 345.123262 -256.004831) (xy 345.176412 -256.008814) (xy 345.228374 -256.020674) (xy 345.277988 -256.040146)
			(xy 345.324146 -256.066795) (xy 345.365817 -256.100026) (xy 345.402069 -256.139097) (xy 345.432093 -256.183134)
			(xy 345.455219 -256.231155) (xy 345.470929 -256.282085) (xy 345.478872 -256.334789) (xy 345.47937 -256.361438)
			(xy 345.478872 -256.388087) (xy 345.707452 -256.388087) (xy 345.707452 -256.334789) (xy 345.715395 -256.282085)
			(xy 345.731105 -256.231155) (xy 345.754231 -256.183134) (xy 345.784255 -256.139097) (xy 345.820507 -256.100026)
			(xy 345.862178 -256.066795) (xy 345.908336 -256.040146) (xy 345.95795 -256.020674) (xy 346.009912 -256.008814)
			(xy 346.063062 -256.004831) (xy 346.116212 -256.008814) (xy 346.168174 -256.020674) (xy 346.217788 -256.040146)
			(xy 346.263946 -256.066795) (xy 346.305617 -256.100026) (xy 346.341869 -256.139097) (xy 346.371893 -256.183134)
			(xy 346.395019 -256.231155) (xy 346.410729 -256.282085) (xy 346.418672 -256.334789) (xy 346.41917 -256.361438)
			(xy 346.418672 -256.388087) (xy 346.410729 -256.440791) (xy 346.395019 -256.491721) (xy 346.371893 -256.539742)
			(xy 346.341869 -256.583779) (xy 346.305617 -256.62285) (xy 346.263946 -256.656081) (xy 346.217788 -256.68273)
			(xy 346.168174 -256.702202) (xy 346.116212 -256.714062) (xy 346.063062 -256.718046) (xy 346.009912 -256.714062)
			(xy 345.95795 -256.702202) (xy 345.908336 -256.68273) (xy 345.862178 -256.656081) (xy 345.820507 -256.62285)
			(xy 345.784255 -256.583779) (xy 345.754231 -256.539742) (xy 345.731105 -256.491721) (xy 345.715395 -256.440791)
			(xy 345.707452 -256.388087) (xy 345.478872 -256.388087) (xy 345.470929 -256.440791) (xy 345.455219 -256.491721)
			(xy 345.432093 -256.539742) (xy 345.402069 -256.583779) (xy 345.365817 -256.62285) (xy 345.324146 -256.656081)
			(xy 345.277988 -256.68273) (xy 345.228374 -256.702202) (xy 345.176412 -256.714062) (xy 345.123262 -256.718046)
			(xy 345.070112 -256.714062) (xy 345.01815 -256.702202) (xy 344.968536 -256.68273) (xy 344.922378 -256.656081)
			(xy 344.880707 -256.62285) (xy 344.844455 -256.583779) (xy 344.814431 -256.539742) (xy 344.791305 -256.491721)
			(xy 344.775595 -256.440791) (xy 344.767652 -256.388087) (xy 344.539072 -256.388087) (xy 344.531129 -256.440791)
			(xy 344.515419 -256.491721) (xy 344.492293 -256.539742) (xy 344.462269 -256.583779) (xy 344.426017 -256.62285)
			(xy 344.384346 -256.656081) (xy 344.338188 -256.68273) (xy 344.288574 -256.702202) (xy 344.236612 -256.714062)
			(xy 344.183462 -256.718046) (xy 344.130312 -256.714062) (xy 344.07835 -256.702202) (xy 344.028736 -256.68273)
			(xy 343.982578 -256.656081) (xy 343.940907 -256.62285) (xy 343.904655 -256.583779) (xy 343.874631 -256.539742)
			(xy 343.851505 -256.491721) (xy 343.835795 -256.440791) (xy 343.827852 -256.388087) (xy 343.599272 -256.388087)
			(xy 343.591329 -256.440791) (xy 343.575619 -256.491721) (xy 343.552493 -256.539742) (xy 343.522469 -256.583779)
			(xy 343.486217 -256.62285) (xy 343.444546 -256.656081) (xy 343.398388 -256.68273) (xy 343.348774 -256.702202)
			(xy 343.296812 -256.714062) (xy 343.243662 -256.718046) (xy 343.190512 -256.714062) (xy 343.13855 -256.702202)
			(xy 343.088936 -256.68273) (xy 343.042778 -256.656081) (xy 343.001107 -256.62285) (xy 342.964855 -256.583779)
			(xy 342.934831 -256.539742) (xy 342.911705 -256.491721) (xy 342.895995 -256.440791) (xy 342.888052 -256.388087)
			(xy 342.659726 -256.388087) (xy 342.651783 -256.440791) (xy 342.636073 -256.491721) (xy 342.612947 -256.539742)
			(xy 342.582923 -256.583779) (xy 342.546671 -256.62285) (xy 342.505 -256.656081) (xy 342.458842 -256.68273)
			(xy 342.409228 -256.702202) (xy 342.357266 -256.714062) (xy 342.304116 -256.718046) (xy 342.250966 -256.714062)
			(xy 342.199004 -256.702202) (xy 342.14939 -256.68273) (xy 342.103232 -256.656081) (xy 342.061561 -256.62285)
			(xy 342.025309 -256.583779) (xy 341.995285 -256.539742) (xy 341.972159 -256.491721) (xy 341.956449 -256.440791)
			(xy 341.948506 -256.388087) (xy 341.719672 -256.388087) (xy 341.711729 -256.440791) (xy 341.696019 -256.491721)
			(xy 341.672893 -256.539742) (xy 341.642869 -256.583779) (xy 341.606617 -256.62285) (xy 341.564946 -256.656081)
			(xy 341.518788 -256.68273) (xy 341.469174 -256.702202) (xy 341.417212 -256.714062) (xy 341.364062 -256.718046)
			(xy 341.310912 -256.714062) (xy 341.25895 -256.702202) (xy 341.209336 -256.68273) (xy 341.163178 -256.656081)
			(xy 341.121507 -256.62285) (xy 341.085255 -256.583779) (xy 341.055231 -256.539742) (xy 341.032105 -256.491721)
			(xy 341.016395 -256.440791) (xy 341.008452 -256.388087) (xy 340.779872 -256.388087) (xy 340.771929 -256.440791)
			(xy 340.756219 -256.491721) (xy 340.733093 -256.539742) (xy 340.703069 -256.583779) (xy 340.666817 -256.62285)
			(xy 340.625146 -256.656081) (xy 340.578988 -256.68273) (xy 340.529374 -256.702202) (xy 340.477412 -256.714062)
			(xy 340.424262 -256.718046) (xy 340.371112 -256.714062) (xy 340.31915 -256.702202) (xy 340.269536 -256.68273)
			(xy 340.223378 -256.656081) (xy 340.181707 -256.62285) (xy 340.145455 -256.583779) (xy 340.115431 -256.539742)
			(xy 340.092305 -256.491721) (xy 340.076595 -256.440791) (xy 340.068652 -256.388087) (xy 339.839094 -256.388087)
			(xy 339.837111 -256.414551) (xy 339.825249 -256.466515) (xy 339.805775 -256.51613) (xy 339.779124 -256.562289)
			(xy 339.74589 -256.603959) (xy 339.706816 -256.64021) (xy 339.662775 -256.670232) (xy 339.614751 -256.693355)
			(xy 339.563818 -256.709061) (xy 339.511112 -256.717) (xy 339.484462 -256.717546) (xy 339.481922 -256.717546)
			(xy 339.468538 -256.717855) (xy 339.442646 -256.72463) (xy 339.419407 -256.737906) (xy 339.400419 -256.756767)
			(xy 339.386989 -256.779918) (xy 339.380041 -256.805764) (xy 339.37956 -256.819146) (xy 339.37956 -257.201903)
			(xy 339.599006 -257.201903) (xy 339.599006 -257.148605) (xy 339.606949 -257.095901) (xy 339.622659 -257.044971)
			(xy 339.645785 -256.99695) (xy 339.675809 -256.952913) (xy 339.712061 -256.913842) (xy 339.753732 -256.880611)
			(xy 339.79989 -256.853962) (xy 339.849504 -256.83449) (xy 339.901466 -256.82263) (xy 339.954616 -256.818647)
			(xy 340.007766 -256.82263) (xy 340.059728 -256.83449) (xy 340.109342 -256.853962) (xy 340.1555 -256.880611)
			(xy 340.197171 -256.913842) (xy 340.233423 -256.952913) (xy 340.263447 -256.99695) (xy 340.286573 -257.044971)
			(xy 340.302283 -257.095901) (xy 340.310226 -257.148605) (xy 340.310724 -257.175254) (xy 340.310226 -257.201903)
			(xy 340.538552 -257.201903) (xy 340.538552 -257.148605) (xy 340.546495 -257.095901) (xy 340.562205 -257.044971)
			(xy 340.585331 -256.99695) (xy 340.615355 -256.952913) (xy 340.651607 -256.913842) (xy 340.693278 -256.880611)
			(xy 340.739436 -256.853962) (xy 340.78905 -256.83449) (xy 340.841012 -256.82263) (xy 340.894162 -256.818647)
			(xy 340.947312 -256.82263) (xy 340.999274 -256.83449) (xy 341.048888 -256.853962) (xy 341.095046 -256.880611)
			(xy 341.136717 -256.913842) (xy 341.172969 -256.952913) (xy 341.202993 -256.99695) (xy 341.226119 -257.044971)
			(xy 341.241829 -257.095901) (xy 341.249772 -257.148605) (xy 341.25027 -257.175254) (xy 341.249772 -257.201903)
			(xy 341.478606 -257.201903) (xy 341.478606 -257.148605) (xy 341.486549 -257.095901) (xy 341.502259 -257.044971)
			(xy 341.525385 -256.99695) (xy 341.555409 -256.952913) (xy 341.591661 -256.913842) (xy 341.633332 -256.880611)
			(xy 341.67949 -256.853962) (xy 341.729104 -256.83449) (xy 341.781066 -256.82263) (xy 341.834216 -256.818647)
			(xy 341.887366 -256.82263) (xy 341.939328 -256.83449) (xy 341.988942 -256.853962) (xy 342.0351 -256.880611)
			(xy 342.076771 -256.913842) (xy 342.113023 -256.952913) (xy 342.143047 -256.99695) (xy 342.166173 -257.044971)
			(xy 342.181883 -257.095901) (xy 342.189826 -257.148605) (xy 342.190324 -257.175254) (xy 342.189826 -257.201903)
			(xy 342.418406 -257.201903) (xy 342.418406 -257.148605) (xy 342.426349 -257.095901) (xy 342.442059 -257.044971)
			(xy 342.465185 -256.99695) (xy 342.495209 -256.952913) (xy 342.531461 -256.913842) (xy 342.573132 -256.880611)
			(xy 342.61929 -256.853962) (xy 342.668904 -256.83449) (xy 342.720866 -256.82263) (xy 342.774016 -256.818647)
			(xy 342.827166 -256.82263) (xy 342.879128 -256.83449) (xy 342.928742 -256.853962) (xy 342.9749 -256.880611)
			(xy 343.016571 -256.913842) (xy 343.052823 -256.952913) (xy 343.082847 -256.99695) (xy 343.105973 -257.044971)
			(xy 343.121683 -257.095901) (xy 343.129626 -257.148605) (xy 343.130124 -257.175254) (xy 343.129626 -257.201903)
			(xy 343.358206 -257.201903) (xy 343.358206 -257.148605) (xy 343.366149 -257.095901) (xy 343.381859 -257.044971)
			(xy 343.404985 -256.99695) (xy 343.435009 -256.952913) (xy 343.471261 -256.913842) (xy 343.512932 -256.880611)
			(xy 343.55909 -256.853962) (xy 343.608704 -256.83449) (xy 343.660666 -256.82263) (xy 343.713816 -256.818647)
			(xy 343.766966 -256.82263) (xy 343.818928 -256.83449) (xy 343.868542 -256.853962) (xy 343.9147 -256.880611)
			(xy 343.956371 -256.913842) (xy 343.992623 -256.952913) (xy 344.022647 -256.99695) (xy 344.045773 -257.044971)
			(xy 344.061483 -257.095901) (xy 344.069426 -257.148605) (xy 344.069924 -257.175254) (xy 344.069426 -257.201903)
			(xy 344.298006 -257.201903) (xy 344.298006 -257.148605) (xy 344.305949 -257.095901) (xy 344.321659 -257.044971)
			(xy 344.344785 -256.99695) (xy 344.374809 -256.952913) (xy 344.411061 -256.913842) (xy 344.452732 -256.880611)
			(xy 344.49889 -256.853962) (xy 344.548504 -256.83449) (xy 344.600466 -256.82263) (xy 344.653616 -256.818647)
			(xy 344.706766 -256.82263) (xy 344.758728 -256.83449) (xy 344.808342 -256.853962) (xy 344.8545 -256.880611)
			(xy 344.896171 -256.913842) (xy 344.932423 -256.952913) (xy 344.962447 -256.99695) (xy 344.985573 -257.044971)
			(xy 345.001283 -257.095901) (xy 345.009226 -257.148605) (xy 345.009724 -257.175254) (xy 345.009226 -257.201903)
			(xy 345.237552 -257.201903) (xy 345.237552 -257.148605) (xy 345.245495 -257.095901) (xy 345.261205 -257.044971)
			(xy 345.284331 -256.99695) (xy 345.314355 -256.952913) (xy 345.350607 -256.913842) (xy 345.392278 -256.880611)
			(xy 345.438436 -256.853962) (xy 345.48805 -256.83449) (xy 345.540012 -256.82263) (xy 345.593162 -256.818647)
			(xy 345.646312 -256.82263) (xy 345.698274 -256.83449) (xy 345.747888 -256.853962) (xy 345.794046 -256.880611)
			(xy 345.835717 -256.913842) (xy 345.871969 -256.952913) (xy 345.901993 -256.99695) (xy 345.925119 -257.044971)
			(xy 345.940829 -257.095901) (xy 345.948772 -257.148605) (xy 345.94927 -257.175254) (xy 345.948772 -257.201903)
			(xy 346.177606 -257.201903) (xy 346.177606 -257.148605) (xy 346.185549 -257.095901) (xy 346.201259 -257.044971)
			(xy 346.224385 -256.99695) (xy 346.254409 -256.952913) (xy 346.290661 -256.913842) (xy 346.332332 -256.880611)
			(xy 346.37849 -256.853962) (xy 346.428104 -256.83449) (xy 346.480066 -256.82263) (xy 346.533216 -256.818647)
			(xy 346.586366 -256.82263) (xy 346.638328 -256.83449) (xy 346.687942 -256.853962) (xy 346.7341 -256.880611)
			(xy 346.775771 -256.913842) (xy 346.812023 -256.952913) (xy 346.842047 -256.99695) (xy 346.865173 -257.044971)
			(xy 346.880883 -257.095901) (xy 346.888826 -257.148605) (xy 346.889324 -257.175254) (xy 346.888826 -257.201903)
			(xy 346.880883 -257.254607) (xy 346.865173 -257.305537) (xy 346.842047 -257.353558) (xy 346.812023 -257.397595)
			(xy 346.775771 -257.436666) (xy 346.7341 -257.469897) (xy 346.687942 -257.496546) (xy 346.638328 -257.516018)
			(xy 346.586366 -257.527878) (xy 346.533216 -257.531862) (xy 346.480066 -257.527878) (xy 346.428104 -257.516018)
			(xy 346.37849 -257.496546) (xy 346.332332 -257.469897) (xy 346.290661 -257.436666) (xy 346.254409 -257.397595)
			(xy 346.224385 -257.353558) (xy 346.201259 -257.305537) (xy 346.185549 -257.254607) (xy 346.177606 -257.201903)
			(xy 345.948772 -257.201903) (xy 345.940829 -257.254607) (xy 345.925119 -257.305537) (xy 345.901993 -257.353558)
			(xy 345.871969 -257.397595) (xy 345.835717 -257.436666) (xy 345.794046 -257.469897) (xy 345.747888 -257.496546)
			(xy 345.698274 -257.516018) (xy 345.646312 -257.527878) (xy 345.593162 -257.531862) (xy 345.540012 -257.527878)
			(xy 345.48805 -257.516018) (xy 345.438436 -257.496546) (xy 345.392278 -257.469897) (xy 345.350607 -257.436666)
			(xy 345.314355 -257.397595) (xy 345.284331 -257.353558) (xy 345.261205 -257.305537) (xy 345.245495 -257.254607)
			(xy 345.237552 -257.201903) (xy 345.009226 -257.201903) (xy 345.001283 -257.254607) (xy 344.985573 -257.305537)
			(xy 344.962447 -257.353558) (xy 344.932423 -257.397595) (xy 344.896171 -257.436666) (xy 344.8545 -257.469897)
			(xy 344.808342 -257.496546) (xy 344.758728 -257.516018) (xy 344.706766 -257.527878) (xy 344.653616 -257.531862)
			(xy 344.600466 -257.527878) (xy 344.548504 -257.516018) (xy 344.49889 -257.496546) (xy 344.452732 -257.469897)
			(xy 344.411061 -257.436666) (xy 344.374809 -257.397595) (xy 344.344785 -257.353558) (xy 344.321659 -257.305537)
			(xy 344.305949 -257.254607) (xy 344.298006 -257.201903) (xy 344.069426 -257.201903) (xy 344.061483 -257.254607)
			(xy 344.045773 -257.305537) (xy 344.022647 -257.353558) (xy 343.992623 -257.397595) (xy 343.956371 -257.436666)
			(xy 343.9147 -257.469897) (xy 343.868542 -257.496546) (xy 343.818928 -257.516018) (xy 343.766966 -257.527878)
			(xy 343.713816 -257.531862) (xy 343.660666 -257.527878) (xy 343.608704 -257.516018) (xy 343.55909 -257.496546)
			(xy 343.512932 -257.469897) (xy 343.471261 -257.436666) (xy 343.435009 -257.397595) (xy 343.404985 -257.353558)
			(xy 343.381859 -257.305537) (xy 343.366149 -257.254607) (xy 343.358206 -257.201903) (xy 343.129626 -257.201903)
			(xy 343.121683 -257.254607) (xy 343.105973 -257.305537) (xy 343.082847 -257.353558) (xy 343.052823 -257.397595)
			(xy 343.016571 -257.436666) (xy 342.9749 -257.469897) (xy 342.928742 -257.496546) (xy 342.879128 -257.516018)
			(xy 342.827166 -257.527878) (xy 342.774016 -257.531862) (xy 342.720866 -257.527878) (xy 342.668904 -257.516018)
			(xy 342.61929 -257.496546) (xy 342.573132 -257.469897) (xy 342.531461 -257.436666) (xy 342.495209 -257.397595)
			(xy 342.465185 -257.353558) (xy 342.442059 -257.305537) (xy 342.426349 -257.254607) (xy 342.418406 -257.201903)
			(xy 342.189826 -257.201903) (xy 342.181883 -257.254607) (xy 342.166173 -257.305537) (xy 342.143047 -257.353558)
			(xy 342.113023 -257.397595) (xy 342.076771 -257.436666) (xy 342.0351 -257.469897) (xy 341.988942 -257.496546)
			(xy 341.939328 -257.516018) (xy 341.887366 -257.527878) (xy 341.834216 -257.531862) (xy 341.781066 -257.527878)
			(xy 341.729104 -257.516018) (xy 341.67949 -257.496546) (xy 341.633332 -257.469897) (xy 341.591661 -257.436666)
			(xy 341.555409 -257.397595) (xy 341.525385 -257.353558) (xy 341.502259 -257.305537) (xy 341.486549 -257.254607)
			(xy 341.478606 -257.201903) (xy 341.249772 -257.201903) (xy 341.241829 -257.254607) (xy 341.226119 -257.305537)
			(xy 341.202993 -257.353558) (xy 341.172969 -257.397595) (xy 341.136717 -257.436666) (xy 341.095046 -257.469897)
			(xy 341.048888 -257.496546) (xy 340.999274 -257.516018) (xy 340.947312 -257.527878) (xy 340.894162 -257.531862)
			(xy 340.841012 -257.527878) (xy 340.78905 -257.516018) (xy 340.739436 -257.496546) (xy 340.693278 -257.469897)
			(xy 340.651607 -257.436666) (xy 340.615355 -257.397595) (xy 340.585331 -257.353558) (xy 340.562205 -257.305537)
			(xy 340.546495 -257.254607) (xy 340.538552 -257.201903) (xy 340.310226 -257.201903) (xy 340.302283 -257.254607)
			(xy 340.286573 -257.305537) (xy 340.263447 -257.353558) (xy 340.233423 -257.397595) (xy 340.197171 -257.436666)
			(xy 340.1555 -257.469897) (xy 340.109342 -257.496546) (xy 340.059728 -257.516018) (xy 340.007766 -257.527878)
			(xy 339.954616 -257.531862) (xy 339.901466 -257.527878) (xy 339.849504 -257.516018) (xy 339.79989 -257.496546)
			(xy 339.753732 -257.469897) (xy 339.712061 -257.436666) (xy 339.675809 -257.397595) (xy 339.645785 -257.353558)
			(xy 339.622659 -257.305537) (xy 339.606949 -257.254607) (xy 339.599006 -257.201903) (xy 339.37956 -257.201903)
			(xy 339.37956 -257.531362) (xy 339.379959 -257.544754) (xy 339.386914 -257.57062) (xy 339.400355 -257.593788)
			(xy 339.419358 -257.612663) (xy 339.442616 -257.625948) (xy 339.468528 -257.632729) (xy 339.481922 -257.632962)
			(xy 339.484462 -257.632962) (xy 339.511117 -257.633433) (xy 339.563833 -257.641373) (xy 339.614776 -257.657082)
			(xy 339.662809 -257.680209) (xy 339.706858 -257.710237) (xy 339.745939 -257.746495) (xy 339.77918 -257.788173)
			(xy 339.805837 -257.83434) (xy 339.825314 -257.883965) (xy 339.837178 -257.935939) (xy 339.841162 -257.9891)
			(xy 339.839167 -258.015719) (xy 340.068906 -258.015719) (xy 340.068906 -257.962421) (xy 340.076849 -257.909717)
			(xy 340.092559 -257.858787) (xy 340.115685 -257.810766) (xy 340.145709 -257.766729) (xy 340.181961 -257.727658)
			(xy 340.223632 -257.694427) (xy 340.26979 -257.667778) (xy 340.319404 -257.648306) (xy 340.371366 -257.636446)
			(xy 340.424516 -257.632463) (xy 340.477666 -257.636446) (xy 340.529628 -257.648306) (xy 340.579242 -257.667778)
			(xy 340.6254 -257.694427) (xy 340.667071 -257.727658) (xy 340.703323 -257.766729) (xy 340.733347 -257.810766)
			(xy 340.756473 -257.858787) (xy 340.772183 -257.909717) (xy 340.780126 -257.962421) (xy 340.780624 -257.98907)
			(xy 340.780126 -258.015719) (xy 341.008452 -258.015719) (xy 341.008452 -257.962421) (xy 341.016395 -257.909717)
			(xy 341.032105 -257.858787) (xy 341.055231 -257.810766) (xy 341.085255 -257.766729) (xy 341.121507 -257.727658)
			(xy 341.163178 -257.694427) (xy 341.209336 -257.667778) (xy 341.25895 -257.648306) (xy 341.310912 -257.636446)
			(xy 341.364062 -257.632463) (xy 341.417212 -257.636446) (xy 341.469174 -257.648306) (xy 341.518788 -257.667778)
			(xy 341.564946 -257.694427) (xy 341.606617 -257.727658) (xy 341.642869 -257.766729) (xy 341.672893 -257.810766)
			(xy 341.696019 -257.858787) (xy 341.711729 -257.909717) (xy 341.719672 -257.962421) (xy 341.72017 -257.98907)
			(xy 341.719672 -258.015719) (xy 341.948252 -258.015719) (xy 341.948252 -257.962421) (xy 341.956195 -257.909717)
			(xy 341.971905 -257.858787) (xy 341.995031 -257.810766) (xy 342.025055 -257.766729) (xy 342.061307 -257.727658)
			(xy 342.102978 -257.694427) (xy 342.149136 -257.667778) (xy 342.19875 -257.648306) (xy 342.250712 -257.636446)
			(xy 342.303862 -257.632463) (xy 342.357012 -257.636446) (xy 342.408974 -257.648306) (xy 342.458588 -257.667778)
			(xy 342.504746 -257.694427) (xy 342.546417 -257.727658) (xy 342.582669 -257.766729) (xy 342.612693 -257.810766)
			(xy 342.635819 -257.858787) (xy 342.651529 -257.909717) (xy 342.659472 -257.962421) (xy 342.65997 -257.98907)
			(xy 342.659472 -258.015719) (xy 342.888052 -258.015719) (xy 342.888052 -257.962421) (xy 342.895995 -257.909717)
			(xy 342.911705 -257.858787) (xy 342.934831 -257.810766) (xy 342.964855 -257.766729) (xy 343.001107 -257.727658)
			(xy 343.042778 -257.694427) (xy 343.088936 -257.667778) (xy 343.13855 -257.648306) (xy 343.190512 -257.636446)
			(xy 343.243662 -257.632463) (xy 343.296812 -257.636446) (xy 343.348774 -257.648306) (xy 343.398388 -257.667778)
			(xy 343.444546 -257.694427) (xy 343.486217 -257.727658) (xy 343.522469 -257.766729) (xy 343.552493 -257.810766)
			(xy 343.575619 -257.858787) (xy 343.591329 -257.909717) (xy 343.599272 -257.962421) (xy 343.59977 -257.98907)
			(xy 343.599272 -258.015719) (xy 343.827852 -258.015719) (xy 343.827852 -257.962421) (xy 343.835795 -257.909717)
			(xy 343.851505 -257.858787) (xy 343.874631 -257.810766) (xy 343.904655 -257.766729) (xy 343.940907 -257.727658)
			(xy 343.982578 -257.694427) (xy 344.028736 -257.667778) (xy 344.07835 -257.648306) (xy 344.130312 -257.636446)
			(xy 344.183462 -257.632463) (xy 344.236612 -257.636446) (xy 344.288574 -257.648306) (xy 344.338188 -257.667778)
			(xy 344.384346 -257.694427) (xy 344.426017 -257.727658) (xy 344.462269 -257.766729) (xy 344.492293 -257.810766)
			(xy 344.515419 -257.858787) (xy 344.531129 -257.909717) (xy 344.539072 -257.962421) (xy 344.53957 -257.98907)
			(xy 344.539072 -258.015719) (xy 344.767906 -258.015719) (xy 344.767906 -257.962421) (xy 344.775849 -257.909717)
			(xy 344.791559 -257.858787) (xy 344.814685 -257.810766) (xy 344.844709 -257.766729) (xy 344.880961 -257.727658)
			(xy 344.922632 -257.694427) (xy 344.96879 -257.667778) (xy 345.018404 -257.648306) (xy 345.070366 -257.636446)
			(xy 345.123516 -257.632463) (xy 345.176666 -257.636446) (xy 345.228628 -257.648306) (xy 345.278242 -257.667778)
			(xy 345.3244 -257.694427) (xy 345.366071 -257.727658) (xy 345.402323 -257.766729) (xy 345.432347 -257.810766)
			(xy 345.455473 -257.858787) (xy 345.471183 -257.909717) (xy 345.479126 -257.962421) (xy 345.479624 -257.98907)
			(xy 345.479126 -258.015719) (xy 345.707452 -258.015719) (xy 345.707452 -257.962421) (xy 345.715395 -257.909717)
			(xy 345.731105 -257.858787) (xy 345.754231 -257.810766) (xy 345.784255 -257.766729) (xy 345.820507 -257.727658)
			(xy 345.862178 -257.694427) (xy 345.908336 -257.667778) (xy 345.95795 -257.648306) (xy 346.009912 -257.636446)
			(xy 346.063062 -257.632463) (xy 346.116212 -257.636446) (xy 346.168174 -257.648306) (xy 346.217788 -257.667778)
			(xy 346.263946 -257.694427) (xy 346.305617 -257.727658) (xy 346.341869 -257.766729) (xy 346.371893 -257.810766)
			(xy 346.395019 -257.858787) (xy 346.410729 -257.909717) (xy 346.418672 -257.962421) (xy 346.41917 -257.98907)
			(xy 346.418672 -258.015719) (xy 346.410729 -258.068423) (xy 346.395019 -258.119353) (xy 346.371893 -258.167374)
			(xy 346.341869 -258.211411) (xy 346.305617 -258.250482) (xy 346.263946 -258.283713) (xy 346.217788 -258.310362)
			(xy 346.168174 -258.329834) (xy 346.116212 -258.341694) (xy 346.063062 -258.345678) (xy 346.009912 -258.341694)
			(xy 345.95795 -258.329834) (xy 345.908336 -258.310362) (xy 345.862178 -258.283713) (xy 345.820507 -258.250482)
			(xy 345.784255 -258.211411) (xy 345.754231 -258.167374) (xy 345.731105 -258.119353) (xy 345.715395 -258.068423)
			(xy 345.707452 -258.015719) (xy 345.479126 -258.015719) (xy 345.471183 -258.068423) (xy 345.455473 -258.119353)
			(xy 345.432347 -258.167374) (xy 345.402323 -258.211411) (xy 345.366071 -258.250482) (xy 345.3244 -258.283713)
			(xy 345.278242 -258.310362) (xy 345.228628 -258.329834) (xy 345.176666 -258.341694) (xy 345.123516 -258.345678)
			(xy 345.070366 -258.341694) (xy 345.018404 -258.329834) (xy 344.96879 -258.310362) (xy 344.922632 -258.283713)
			(xy 344.880961 -258.250482) (xy 344.844709 -258.211411) (xy 344.814685 -258.167374) (xy 344.791559 -258.119353)
			(xy 344.775849 -258.068423) (xy 344.767906 -258.015719) (xy 344.539072 -258.015719) (xy 344.531129 -258.068423)
			(xy 344.515419 -258.119353) (xy 344.492293 -258.167374) (xy 344.462269 -258.211411) (xy 344.426017 -258.250482)
			(xy 344.384346 -258.283713) (xy 344.338188 -258.310362) (xy 344.288574 -258.329834) (xy 344.236612 -258.341694)
			(xy 344.183462 -258.345678) (xy 344.130312 -258.341694) (xy 344.07835 -258.329834) (xy 344.028736 -258.310362)
			(xy 343.982578 -258.283713) (xy 343.940907 -258.250482) (xy 343.904655 -258.211411) (xy 343.874631 -258.167374)
			(xy 343.851505 -258.119353) (xy 343.835795 -258.068423) (xy 343.827852 -258.015719) (xy 343.599272 -258.015719)
			(xy 343.591329 -258.068423) (xy 343.575619 -258.119353) (xy 343.552493 -258.167374) (xy 343.522469 -258.211411)
			(xy 343.486217 -258.250482) (xy 343.444546 -258.283713) (xy 343.398388 -258.310362) (xy 343.348774 -258.329834)
			(xy 343.296812 -258.341694) (xy 343.243662 -258.345678) (xy 343.190512 -258.341694) (xy 343.13855 -258.329834)
			(xy 343.088936 -258.310362) (xy 343.042778 -258.283713) (xy 343.001107 -258.250482) (xy 342.964855 -258.211411)
			(xy 342.934831 -258.167374) (xy 342.911705 -258.119353) (xy 342.895995 -258.068423) (xy 342.888052 -258.015719)
			(xy 342.659472 -258.015719) (xy 342.651529 -258.068423) (xy 342.635819 -258.119353) (xy 342.612693 -258.167374)
			(xy 342.582669 -258.211411) (xy 342.546417 -258.250482) (xy 342.504746 -258.283713) (xy 342.458588 -258.310362)
			(xy 342.408974 -258.329834) (xy 342.357012 -258.341694) (xy 342.303862 -258.345678) (xy 342.250712 -258.341694)
			(xy 342.19875 -258.329834) (xy 342.149136 -258.310362) (xy 342.102978 -258.283713) (xy 342.061307 -258.250482)
			(xy 342.025055 -258.211411) (xy 341.995031 -258.167374) (xy 341.971905 -258.119353) (xy 341.956195 -258.068423)
			(xy 341.948252 -258.015719) (xy 341.719672 -258.015719) (xy 341.711729 -258.068423) (xy 341.696019 -258.119353)
			(xy 341.672893 -258.167374) (xy 341.642869 -258.211411) (xy 341.606617 -258.250482) (xy 341.564946 -258.283713)
			(xy 341.518788 -258.310362) (xy 341.469174 -258.329834) (xy 341.417212 -258.341694) (xy 341.364062 -258.345678)
			(xy 341.310912 -258.341694) (xy 341.25895 -258.329834) (xy 341.209336 -258.310362) (xy 341.163178 -258.283713)
			(xy 341.121507 -258.250482) (xy 341.085255 -258.211411) (xy 341.055231 -258.167374) (xy 341.032105 -258.119353)
			(xy 341.016395 -258.068423) (xy 341.008452 -258.015719) (xy 340.780126 -258.015719) (xy 340.772183 -258.068423)
			(xy 340.756473 -258.119353) (xy 340.733347 -258.167374) (xy 340.703323 -258.211411) (xy 340.667071 -258.250482)
			(xy 340.6254 -258.283713) (xy 340.579242 -258.310362) (xy 340.529628 -258.329834) (xy 340.477666 -258.341694)
			(xy 340.424516 -258.345678) (xy 340.371366 -258.341694) (xy 340.319404 -258.329834) (xy 340.26979 -258.310362)
			(xy 340.223632 -258.283713) (xy 340.181961 -258.250482) (xy 340.145709 -258.211411) (xy 340.115685 -258.167374)
			(xy 340.092559 -258.119353) (xy 340.076849 -258.068423) (xy 340.068906 -258.015719) (xy 339.839167 -258.015719)
			(xy 339.837178 -258.042261) (xy 339.825314 -258.094235) (xy 339.805837 -258.14386) (xy 339.77918 -258.190027)
			(xy 339.745939 -258.231705) (xy 339.706858 -258.267963) (xy 339.662809 -258.297991) (xy 339.614776 -258.321118)
			(xy 339.563833 -258.336827) (xy 339.511117 -258.344767) (xy 339.484462 -258.345178) (xy 339.481922 -258.345178)
			(xy 339.468534 -258.345487) (xy 339.442636 -258.352261) (xy 339.419388 -258.365535) (xy 339.400389 -258.384394)
			(xy 339.386946 -258.407544) (xy 339.379982 -258.433393) (xy 339.37956 -258.446778) (xy 339.37956 -258.829789)
			(xy 339.599006 -258.829789) (xy 339.599006 -258.776491) (xy 339.606949 -258.723787) (xy 339.622659 -258.672857)
			(xy 339.645785 -258.624836) (xy 339.675809 -258.580799) (xy 339.712061 -258.541728) (xy 339.753732 -258.508497)
			(xy 339.79989 -258.481848) (xy 339.849504 -258.462376) (xy 339.901466 -258.450516) (xy 339.954616 -258.446533)
			(xy 340.007766 -258.450516) (xy 340.059728 -258.462376) (xy 340.109342 -258.481848) (xy 340.1555 -258.508497)
			(xy 340.197171 -258.541728) (xy 340.233423 -258.580799) (xy 340.263447 -258.624836) (xy 340.286573 -258.672857)
			(xy 340.302283 -258.723787) (xy 340.310226 -258.776491) (xy 340.310724 -258.80314) (xy 340.310226 -258.829789)
			(xy 340.538806 -258.829789) (xy 340.538806 -258.776491) (xy 340.546749 -258.723787) (xy 340.562459 -258.672857)
			(xy 340.585585 -258.624836) (xy 340.615609 -258.580799) (xy 340.651861 -258.541728) (xy 340.693532 -258.508497)
			(xy 340.73969 -258.481848) (xy 340.789304 -258.462376) (xy 340.841266 -258.450516) (xy 340.894416 -258.446533)
			(xy 340.947566 -258.450516) (xy 340.999528 -258.462376) (xy 341.049142 -258.481848) (xy 341.0953 -258.508497)
			(xy 341.136971 -258.541728) (xy 341.173223 -258.580799) (xy 341.203247 -258.624836) (xy 341.226373 -258.672857)
			(xy 341.242083 -258.723787) (xy 341.250026 -258.776491) (xy 341.250524 -258.80314) (xy 341.250026 -258.829789)
			(xy 341.478606 -258.829789) (xy 341.478606 -258.776491) (xy 341.486549 -258.723787) (xy 341.502259 -258.672857)
			(xy 341.525385 -258.624836) (xy 341.555409 -258.580799) (xy 341.591661 -258.541728) (xy 341.633332 -258.508497)
			(xy 341.67949 -258.481848) (xy 341.729104 -258.462376) (xy 341.781066 -258.450516) (xy 341.834216 -258.446533)
			(xy 341.887366 -258.450516) (xy 341.939328 -258.462376) (xy 341.988942 -258.481848) (xy 342.0351 -258.508497)
			(xy 342.076771 -258.541728) (xy 342.113023 -258.580799) (xy 342.143047 -258.624836) (xy 342.166173 -258.672857)
			(xy 342.181883 -258.723787) (xy 342.189826 -258.776491) (xy 342.190324 -258.80314) (xy 342.189826 -258.829789)
			(xy 342.418152 -258.829789) (xy 342.418152 -258.776491) (xy 342.426095 -258.723787) (xy 342.441805 -258.672857)
			(xy 342.464931 -258.624836) (xy 342.494955 -258.580799) (xy 342.531207 -258.541728) (xy 342.572878 -258.508497)
			(xy 342.619036 -258.481848) (xy 342.66865 -258.462376) (xy 342.720612 -258.450516) (xy 342.773762 -258.446533)
			(xy 342.826912 -258.450516) (xy 342.878874 -258.462376) (xy 342.928488 -258.481848) (xy 342.974646 -258.508497)
			(xy 343.016317 -258.541728) (xy 343.052569 -258.580799) (xy 343.082593 -258.624836) (xy 343.105719 -258.672857)
			(xy 343.121429 -258.723787) (xy 343.129372 -258.776491) (xy 343.12987 -258.80314) (xy 343.129372 -258.829789)
			(xy 343.358206 -258.829789) (xy 343.358206 -258.776491) (xy 343.366149 -258.723787) (xy 343.381859 -258.672857)
			(xy 343.404985 -258.624836) (xy 343.435009 -258.580799) (xy 343.471261 -258.541728) (xy 343.512932 -258.508497)
			(xy 343.55909 -258.481848) (xy 343.608704 -258.462376) (xy 343.660666 -258.450516) (xy 343.713816 -258.446533)
			(xy 343.766966 -258.450516) (xy 343.818928 -258.462376) (xy 343.868542 -258.481848) (xy 343.9147 -258.508497)
			(xy 343.956371 -258.541728) (xy 343.992623 -258.580799) (xy 344.022647 -258.624836) (xy 344.045773 -258.672857)
			(xy 344.061483 -258.723787) (xy 344.069426 -258.776491) (xy 344.069924 -258.80314) (xy 344.069426 -258.829789)
			(xy 344.298006 -258.829789) (xy 344.298006 -258.776491) (xy 344.305949 -258.723787) (xy 344.321659 -258.672857)
			(xy 344.344785 -258.624836) (xy 344.374809 -258.580799) (xy 344.411061 -258.541728) (xy 344.452732 -258.508497)
			(xy 344.49889 -258.481848) (xy 344.548504 -258.462376) (xy 344.600466 -258.450516) (xy 344.653616 -258.446533)
			(xy 344.706766 -258.450516) (xy 344.758728 -258.462376) (xy 344.808342 -258.481848) (xy 344.8545 -258.508497)
			(xy 344.896171 -258.541728) (xy 344.932423 -258.580799) (xy 344.962447 -258.624836) (xy 344.985573 -258.672857)
			(xy 345.001283 -258.723787) (xy 345.009226 -258.776491) (xy 345.009724 -258.80314) (xy 345.009226 -258.829789)
			(xy 345.237806 -258.829789) (xy 345.237806 -258.776491) (xy 345.245749 -258.723787) (xy 345.261459 -258.672857)
			(xy 345.284585 -258.624836) (xy 345.314609 -258.580799) (xy 345.350861 -258.541728) (xy 345.392532 -258.508497)
			(xy 345.43869 -258.481848) (xy 345.488304 -258.462376) (xy 345.540266 -258.450516) (xy 345.593416 -258.446533)
			(xy 345.646566 -258.450516) (xy 345.698528 -258.462376) (xy 345.748142 -258.481848) (xy 345.7943 -258.508497)
			(xy 345.835971 -258.541728) (xy 345.872223 -258.580799) (xy 345.902247 -258.624836) (xy 345.925373 -258.672857)
			(xy 345.941083 -258.723787) (xy 345.949026 -258.776491) (xy 345.949524 -258.80314) (xy 345.949026 -258.829789)
			(xy 346.177606 -258.829789) (xy 346.177606 -258.776491) (xy 346.185549 -258.723787) (xy 346.201259 -258.672857)
			(xy 346.224385 -258.624836) (xy 346.254409 -258.580799) (xy 346.290661 -258.541728) (xy 346.332332 -258.508497)
			(xy 346.37849 -258.481848) (xy 346.428104 -258.462376) (xy 346.480066 -258.450516) (xy 346.533216 -258.446533)
			(xy 346.586366 -258.450516) (xy 346.638328 -258.462376) (xy 346.687942 -258.481848) (xy 346.7341 -258.508497)
			(xy 346.775771 -258.541728) (xy 346.812023 -258.580799) (xy 346.842047 -258.624836) (xy 346.865173 -258.672857)
			(xy 346.880883 -258.723787) (xy 346.888826 -258.776491) (xy 346.889324 -258.80314) (xy 346.888826 -258.829789)
			(xy 346.880883 -258.882493) (xy 346.865173 -258.933423) (xy 346.842047 -258.981444) (xy 346.812023 -259.025481)
			(xy 346.775771 -259.064552) (xy 346.7341 -259.097783) (xy 346.687942 -259.124432) (xy 346.638328 -259.143904)
			(xy 346.586366 -259.155764) (xy 346.533216 -259.159748) (xy 346.480066 -259.155764) (xy 346.428104 -259.143904)
			(xy 346.37849 -259.124432) (xy 346.332332 -259.097783) (xy 346.290661 -259.064552) (xy 346.254409 -259.025481)
			(xy 346.224385 -258.981444) (xy 346.201259 -258.933423) (xy 346.185549 -258.882493) (xy 346.177606 -258.829789)
			(xy 345.949026 -258.829789) (xy 345.941083 -258.882493) (xy 345.925373 -258.933423) (xy 345.902247 -258.981444)
			(xy 345.872223 -259.025481) (xy 345.835971 -259.064552) (xy 345.7943 -259.097783) (xy 345.748142 -259.124432)
			(xy 345.698528 -259.143904) (xy 345.646566 -259.155764) (xy 345.593416 -259.159748) (xy 345.540266 -259.155764)
			(xy 345.488304 -259.143904) (xy 345.43869 -259.124432) (xy 345.392532 -259.097783) (xy 345.350861 -259.064552)
			(xy 345.314609 -259.025481) (xy 345.284585 -258.981444) (xy 345.261459 -258.933423) (xy 345.245749 -258.882493)
			(xy 345.237806 -258.829789) (xy 345.009226 -258.829789) (xy 345.001283 -258.882493) (xy 344.985573 -258.933423)
			(xy 344.962447 -258.981444) (xy 344.932423 -259.025481) (xy 344.896171 -259.064552) (xy 344.8545 -259.097783)
			(xy 344.808342 -259.124432) (xy 344.758728 -259.143904) (xy 344.706766 -259.155764) (xy 344.653616 -259.159748)
			(xy 344.600466 -259.155764) (xy 344.548504 -259.143904) (xy 344.49889 -259.124432) (xy 344.452732 -259.097783)
			(xy 344.411061 -259.064552) (xy 344.374809 -259.025481) (xy 344.344785 -258.981444) (xy 344.321659 -258.933423)
			(xy 344.305949 -258.882493) (xy 344.298006 -258.829789) (xy 344.069426 -258.829789) (xy 344.061483 -258.882493)
			(xy 344.045773 -258.933423) (xy 344.022647 -258.981444) (xy 343.992623 -259.025481) (xy 343.956371 -259.064552)
			(xy 343.9147 -259.097783) (xy 343.868542 -259.124432) (xy 343.818928 -259.143904) (xy 343.766966 -259.155764)
			(xy 343.713816 -259.159748) (xy 343.660666 -259.155764) (xy 343.608704 -259.143904) (xy 343.55909 -259.124432)
			(xy 343.512932 -259.097783) (xy 343.471261 -259.064552) (xy 343.435009 -259.025481) (xy 343.404985 -258.981444)
			(xy 343.381859 -258.933423) (xy 343.366149 -258.882493) (xy 343.358206 -258.829789) (xy 343.129372 -258.829789)
			(xy 343.121429 -258.882493) (xy 343.105719 -258.933423) (xy 343.082593 -258.981444) (xy 343.052569 -259.025481)
			(xy 343.016317 -259.064552) (xy 342.974646 -259.097783) (xy 342.928488 -259.124432) (xy 342.878874 -259.143904)
			(xy 342.826912 -259.155764) (xy 342.773762 -259.159748) (xy 342.720612 -259.155764) (xy 342.66865 -259.143904)
			(xy 342.619036 -259.124432) (xy 342.572878 -259.097783) (xy 342.531207 -259.064552) (xy 342.494955 -259.025481)
			(xy 342.464931 -258.981444) (xy 342.441805 -258.933423) (xy 342.426095 -258.882493) (xy 342.418152 -258.829789)
			(xy 342.189826 -258.829789) (xy 342.181883 -258.882493) (xy 342.166173 -258.933423) (xy 342.143047 -258.981444)
			(xy 342.113023 -259.025481) (xy 342.076771 -259.064552) (xy 342.0351 -259.097783) (xy 341.988942 -259.124432)
			(xy 341.939328 -259.143904) (xy 341.887366 -259.155764) (xy 341.834216 -259.159748) (xy 341.781066 -259.155764)
			(xy 341.729104 -259.143904) (xy 341.67949 -259.124432) (xy 341.633332 -259.097783) (xy 341.591661 -259.064552)
			(xy 341.555409 -259.025481) (xy 341.525385 -258.981444) (xy 341.502259 -258.933423) (xy 341.486549 -258.882493)
			(xy 341.478606 -258.829789) (xy 341.250026 -258.829789) (xy 341.242083 -258.882493) (xy 341.226373 -258.933423)
			(xy 341.203247 -258.981444) (xy 341.173223 -259.025481) (xy 341.136971 -259.064552) (xy 341.0953 -259.097783)
			(xy 341.049142 -259.124432) (xy 340.999528 -259.143904) (xy 340.947566 -259.155764) (xy 340.894416 -259.159748)
			(xy 340.841266 -259.155764) (xy 340.789304 -259.143904) (xy 340.73969 -259.124432) (xy 340.693532 -259.097783)
			(xy 340.651861 -259.064552) (xy 340.615609 -259.025481) (xy 340.585585 -258.981444) (xy 340.562459 -258.933423)
			(xy 340.546749 -258.882493) (xy 340.538806 -258.829789) (xy 340.310226 -258.829789) (xy 340.302283 -258.882493)
			(xy 340.286573 -258.933423) (xy 340.263447 -258.981444) (xy 340.233423 -259.025481) (xy 340.197171 -259.064552)
			(xy 340.1555 -259.097783) (xy 340.109342 -259.124432) (xy 340.059728 -259.143904) (xy 340.007766 -259.155764)
			(xy 339.954616 -259.159748) (xy 339.901466 -259.155764) (xy 339.849504 -259.143904) (xy 339.79989 -259.124432)
			(xy 339.753732 -259.097783) (xy 339.712061 -259.064552) (xy 339.675809 -259.025481) (xy 339.645785 -258.981444)
			(xy 339.622659 -258.933423) (xy 339.606949 -258.882493) (xy 339.599006 -258.829789) (xy 339.37956 -258.829789)
			(xy 339.37956 -259.159248) (xy 339.379969 -259.172633) (xy 339.386939 -259.19848) (xy 339.400386 -259.221627)
			(xy 339.419387 -259.240485) (xy 339.442635 -259.253756) (xy 339.468534 -259.26053) (xy 339.481922 -259.260848)
			(xy 339.484716 -259.260848) (xy 339.511368 -259.261347) (xy 339.564076 -259.269294) (xy 339.615011 -259.285007)
			(xy 339.663035 -259.308136) (xy 339.707076 -259.338164) (xy 339.746149 -259.374421) (xy 339.779383 -259.416096)
			(xy 339.806034 -259.462259) (xy 339.825507 -259.511878) (xy 339.837368 -259.563845) (xy 339.841352 -259.617)
			(xy 339.839358 -259.643605) (xy 340.068652 -259.643605) (xy 340.068652 -259.590307) (xy 340.076595 -259.537603)
			(xy 340.092305 -259.486673) (xy 340.115431 -259.438652) (xy 340.145455 -259.394615) (xy 340.181707 -259.355544)
			(xy 340.223378 -259.322313) (xy 340.269536 -259.295664) (xy 340.31915 -259.276192) (xy 340.371112 -259.264332)
			(xy 340.424262 -259.260349) (xy 340.477412 -259.264332) (xy 340.529374 -259.276192) (xy 340.578988 -259.295664)
			(xy 340.625146 -259.322313) (xy 340.666817 -259.355544) (xy 340.703069 -259.394615) (xy 340.733093 -259.438652)
			(xy 340.756219 -259.486673) (xy 340.771929 -259.537603) (xy 340.779872 -259.590307) (xy 340.78037 -259.616956)
			(xy 340.779872 -259.643605) (xy 341.008452 -259.643605) (xy 341.008452 -259.590307) (xy 341.016395 -259.537603)
			(xy 341.032105 -259.486673) (xy 341.055231 -259.438652) (xy 341.085255 -259.394615) (xy 341.121507 -259.355544)
			(xy 341.163178 -259.322313) (xy 341.209336 -259.295664) (xy 341.25895 -259.276192) (xy 341.310912 -259.264332)
			(xy 341.364062 -259.260349) (xy 341.417212 -259.264332) (xy 341.469174 -259.276192) (xy 341.518788 -259.295664)
			(xy 341.564946 -259.322313) (xy 341.606617 -259.355544) (xy 341.642869 -259.394615) (xy 341.672893 -259.438652)
			(xy 341.696019 -259.486673) (xy 341.711729 -259.537603) (xy 341.719672 -259.590307) (xy 341.72017 -259.616956)
			(xy 341.719672 -259.643605) (xy 341.948252 -259.643605) (xy 341.948252 -259.590307) (xy 341.956195 -259.537603)
			(xy 341.971905 -259.486673) (xy 341.995031 -259.438652) (xy 342.025055 -259.394615) (xy 342.061307 -259.355544)
			(xy 342.102978 -259.322313) (xy 342.149136 -259.295664) (xy 342.19875 -259.276192) (xy 342.250712 -259.264332)
			(xy 342.303862 -259.260349) (xy 342.357012 -259.264332) (xy 342.408974 -259.276192) (xy 342.458588 -259.295664)
			(xy 342.504746 -259.322313) (xy 342.546417 -259.355544) (xy 342.582669 -259.394615) (xy 342.612693 -259.438652)
			(xy 342.635819 -259.486673) (xy 342.651529 -259.537603) (xy 342.659472 -259.590307) (xy 342.65997 -259.616956)
			(xy 342.659472 -259.643605) (xy 342.888052 -259.643605) (xy 342.888052 -259.590307) (xy 342.895995 -259.537603)
			(xy 342.911705 -259.486673) (xy 342.934831 -259.438652) (xy 342.964855 -259.394615) (xy 343.001107 -259.355544)
			(xy 343.042778 -259.322313) (xy 343.088936 -259.295664) (xy 343.13855 -259.276192) (xy 343.190512 -259.264332)
			(xy 343.243662 -259.260349) (xy 343.296812 -259.264332) (xy 343.348774 -259.276192) (xy 343.398388 -259.295664)
			(xy 343.444546 -259.322313) (xy 343.486217 -259.355544) (xy 343.522469 -259.394615) (xy 343.552493 -259.438652)
			(xy 343.575619 -259.486673) (xy 343.591329 -259.537603) (xy 343.599272 -259.590307) (xy 343.59977 -259.616956)
			(xy 343.599272 -259.643605) (xy 343.827852 -259.643605) (xy 343.827852 -259.590307) (xy 343.835795 -259.537603)
			(xy 343.851505 -259.486673) (xy 343.874631 -259.438652) (xy 343.904655 -259.394615) (xy 343.940907 -259.355544)
			(xy 343.982578 -259.322313) (xy 344.028736 -259.295664) (xy 344.07835 -259.276192) (xy 344.130312 -259.264332)
			(xy 344.183462 -259.260349) (xy 344.236612 -259.264332) (xy 344.288574 -259.276192) (xy 344.338188 -259.295664)
			(xy 344.384346 -259.322313) (xy 344.426017 -259.355544) (xy 344.462269 -259.394615) (xy 344.492293 -259.438652)
			(xy 344.515419 -259.486673) (xy 344.531129 -259.537603) (xy 344.539072 -259.590307) (xy 344.53957 -259.616956)
			(xy 344.539072 -259.643605) (xy 344.767652 -259.643605) (xy 344.767652 -259.590307) (xy 344.775595 -259.537603)
			(xy 344.791305 -259.486673) (xy 344.814431 -259.438652) (xy 344.844455 -259.394615) (xy 344.880707 -259.355544)
			(xy 344.922378 -259.322313) (xy 344.968536 -259.295664) (xy 345.01815 -259.276192) (xy 345.070112 -259.264332)
			(xy 345.123262 -259.260349) (xy 345.176412 -259.264332) (xy 345.228374 -259.276192) (xy 345.277988 -259.295664)
			(xy 345.324146 -259.322313) (xy 345.365817 -259.355544) (xy 345.402069 -259.394615) (xy 345.432093 -259.438652)
			(xy 345.455219 -259.486673) (xy 345.470929 -259.537603) (xy 345.478872 -259.590307) (xy 345.47937 -259.616956)
			(xy 345.478872 -259.643605) (xy 345.707706 -259.643605) (xy 345.707706 -259.590307) (xy 345.715649 -259.537603)
			(xy 345.731359 -259.486673) (xy 345.754485 -259.438652) (xy 345.784509 -259.394615) (xy 345.820761 -259.355544)
			(xy 345.862432 -259.322313) (xy 345.90859 -259.295664) (xy 345.958204 -259.276192) (xy 346.010166 -259.264332)
			(xy 346.063316 -259.260349) (xy 346.116466 -259.264332) (xy 346.168428 -259.276192) (xy 346.218042 -259.295664)
			(xy 346.2642 -259.322313) (xy 346.305871 -259.355544) (xy 346.342123 -259.394615) (xy 346.372147 -259.438652)
			(xy 346.395273 -259.486673) (xy 346.410983 -259.537603) (xy 346.418926 -259.590307) (xy 346.419424 -259.616956)
			(xy 346.418926 -259.643605) (xy 346.410983 -259.696309) (xy 346.395273 -259.747239) (xy 346.372147 -259.79526)
			(xy 346.342123 -259.839297) (xy 346.305871 -259.878368) (xy 346.2642 -259.911599) (xy 346.218042 -259.938248)
			(xy 346.168428 -259.95772) (xy 346.116466 -259.96958) (xy 346.063316 -259.973564) (xy 346.010166 -259.96958)
			(xy 345.958204 -259.95772) (xy 345.90859 -259.938248) (xy 345.862432 -259.911599) (xy 345.820761 -259.878368)
			(xy 345.784509 -259.839297) (xy 345.754485 -259.79526) (xy 345.731359 -259.747239) (xy 345.715649 -259.696309)
			(xy 345.707706 -259.643605) (xy 345.478872 -259.643605) (xy 345.470929 -259.696309) (xy 345.455219 -259.747239)
			(xy 345.432093 -259.79526) (xy 345.402069 -259.839297) (xy 345.365817 -259.878368) (xy 345.324146 -259.911599)
			(xy 345.277988 -259.938248) (xy 345.228374 -259.95772) (xy 345.176412 -259.96958) (xy 345.123262 -259.973564)
			(xy 345.070112 -259.96958) (xy 345.01815 -259.95772) (xy 344.968536 -259.938248) (xy 344.922378 -259.911599)
			(xy 344.880707 -259.878368) (xy 344.844455 -259.839297) (xy 344.814431 -259.79526) (xy 344.791305 -259.747239)
			(xy 344.775595 -259.696309) (xy 344.767652 -259.643605) (xy 344.539072 -259.643605) (xy 344.531129 -259.696309)
			(xy 344.515419 -259.747239) (xy 344.492293 -259.79526) (xy 344.462269 -259.839297) (xy 344.426017 -259.878368)
			(xy 344.384346 -259.911599) (xy 344.338188 -259.938248) (xy 344.288574 -259.95772) (xy 344.236612 -259.96958)
			(xy 344.183462 -259.973564) (xy 344.130312 -259.96958) (xy 344.07835 -259.95772) (xy 344.028736 -259.938248)
			(xy 343.982578 -259.911599) (xy 343.940907 -259.878368) (xy 343.904655 -259.839297) (xy 343.874631 -259.79526)
			(xy 343.851505 -259.747239) (xy 343.835795 -259.696309) (xy 343.827852 -259.643605) (xy 343.599272 -259.643605)
			(xy 343.591329 -259.696309) (xy 343.575619 -259.747239) (xy 343.552493 -259.79526) (xy 343.522469 -259.839297)
			(xy 343.486217 -259.878368) (xy 343.444546 -259.911599) (xy 343.398388 -259.938248) (xy 343.348774 -259.95772)
			(xy 343.296812 -259.96958) (xy 343.243662 -259.973564) (xy 343.190512 -259.96958) (xy 343.13855 -259.95772)
			(xy 343.088936 -259.938248) (xy 343.042778 -259.911599) (xy 343.001107 -259.878368) (xy 342.964855 -259.839297)
			(xy 342.934831 -259.79526) (xy 342.911705 -259.747239) (xy 342.895995 -259.696309) (xy 342.888052 -259.643605)
			(xy 342.659472 -259.643605) (xy 342.651529 -259.696309) (xy 342.635819 -259.747239) (xy 342.612693 -259.79526)
			(xy 342.582669 -259.839297) (xy 342.546417 -259.878368) (xy 342.504746 -259.911599) (xy 342.458588 -259.938248)
			(xy 342.408974 -259.95772) (xy 342.357012 -259.96958) (xy 342.303862 -259.973564) (xy 342.250712 -259.96958)
			(xy 342.19875 -259.95772) (xy 342.149136 -259.938248) (xy 342.102978 -259.911599) (xy 342.061307 -259.878368)
			(xy 342.025055 -259.839297) (xy 341.995031 -259.79526) (xy 341.971905 -259.747239) (xy 341.956195 -259.696309)
			(xy 341.948252 -259.643605) (xy 341.719672 -259.643605) (xy 341.711729 -259.696309) (xy 341.696019 -259.747239)
			(xy 341.672893 -259.79526) (xy 341.642869 -259.839297) (xy 341.606617 -259.878368) (xy 341.564946 -259.911599)
			(xy 341.518788 -259.938248) (xy 341.469174 -259.95772) (xy 341.417212 -259.96958) (xy 341.364062 -259.973564)
			(xy 341.310912 -259.96958) (xy 341.25895 -259.95772) (xy 341.209336 -259.938248) (xy 341.163178 -259.911599)
			(xy 341.121507 -259.878368) (xy 341.085255 -259.839297) (xy 341.055231 -259.79526) (xy 341.032105 -259.747239)
			(xy 341.016395 -259.696309) (xy 341.008452 -259.643605) (xy 340.779872 -259.643605) (xy 340.771929 -259.696309)
			(xy 340.756219 -259.747239) (xy 340.733093 -259.79526) (xy 340.703069 -259.839297) (xy 340.666817 -259.878368)
			(xy 340.625146 -259.911599) (xy 340.578988 -259.938248) (xy 340.529374 -259.95772) (xy 340.477412 -259.96958)
			(xy 340.424262 -259.973564) (xy 340.371112 -259.96958) (xy 340.31915 -259.95772) (xy 340.269536 -259.938248)
			(xy 340.223378 -259.911599) (xy 340.181707 -259.878368) (xy 340.145455 -259.839297) (xy 340.115431 -259.79526)
			(xy 340.092305 -259.747239) (xy 340.076595 -259.696309) (xy 340.068652 -259.643605) (xy 339.839358 -259.643605)
			(xy 339.837368 -259.670155) (xy 339.825507 -259.722122) (xy 339.806034 -259.771741) (xy 339.779383 -259.817904)
			(xy 339.746149 -259.859579) (xy 339.707076 -259.895836) (xy 339.663035 -259.925864) (xy 339.615011 -259.948993)
			(xy 339.564076 -259.964706) (xy 339.511368 -259.972653) (xy 339.484716 -259.973064) (xy 339.481922 -259.973064)
			(xy 339.468534 -259.973372) (xy 339.442633 -259.980146) (xy 339.419384 -259.993419) (xy 339.400383 -260.012279)
			(xy 339.386937 -260.035429) (xy 339.379969 -260.061278) (xy 339.37956 -260.074664) (xy 339.37956 -260.457421)
			(xy 339.598752 -260.457421) (xy 339.598752 -260.404123) (xy 339.606695 -260.351419) (xy 339.622405 -260.300489)
			(xy 339.645531 -260.252468) (xy 339.675555 -260.208431) (xy 339.711807 -260.16936) (xy 339.753478 -260.136129)
			(xy 339.799636 -260.10948) (xy 339.84925 -260.090008) (xy 339.901212 -260.078148) (xy 339.954362 -260.074165)
			(xy 340.007512 -260.078148) (xy 340.059474 -260.090008) (xy 340.109088 -260.10948) (xy 340.155246 -260.136129)
			(xy 340.196917 -260.16936) (xy 340.233169 -260.208431) (xy 340.263193 -260.252468) (xy 340.286319 -260.300489)
			(xy 340.302029 -260.351419) (xy 340.309972 -260.404123) (xy 340.31047 -260.430772) (xy 340.309972 -260.457421)
			(xy 340.538806 -260.457421) (xy 340.538806 -260.404123) (xy 340.546749 -260.351419) (xy 340.562459 -260.300489)
			(xy 340.585585 -260.252468) (xy 340.615609 -260.208431) (xy 340.651861 -260.16936) (xy 340.693532 -260.136129)
			(xy 340.73969 -260.10948) (xy 340.789304 -260.090008) (xy 340.841266 -260.078148) (xy 340.894416 -260.074165)
			(xy 340.947566 -260.078148) (xy 340.999528 -260.090008) (xy 341.049142 -260.10948) (xy 341.0953 -260.136129)
			(xy 341.136971 -260.16936) (xy 341.173223 -260.208431) (xy 341.203247 -260.252468) (xy 341.226373 -260.300489)
			(xy 341.242083 -260.351419) (xy 341.250026 -260.404123) (xy 341.250524 -260.430772) (xy 341.250026 -260.457421)
			(xy 341.478606 -260.457421) (xy 341.478606 -260.404123) (xy 341.486549 -260.351419) (xy 341.502259 -260.300489)
			(xy 341.525385 -260.252468) (xy 341.555409 -260.208431) (xy 341.591661 -260.16936) (xy 341.633332 -260.136129)
			(xy 341.67949 -260.10948) (xy 341.729104 -260.090008) (xy 341.781066 -260.078148) (xy 341.834216 -260.074165)
			(xy 341.887366 -260.078148) (xy 341.939328 -260.090008) (xy 341.988942 -260.10948) (xy 342.0351 -260.136129)
			(xy 342.076771 -260.16936) (xy 342.113023 -260.208431) (xy 342.143047 -260.252468) (xy 342.166173 -260.300489)
			(xy 342.181883 -260.351419) (xy 342.189826 -260.404123) (xy 342.190324 -260.430772) (xy 342.189826 -260.457421)
			(xy 342.417898 -260.457421) (xy 342.417898 -260.404123) (xy 342.425841 -260.351419) (xy 342.441551 -260.300489)
			(xy 342.464677 -260.252468) (xy 342.494701 -260.208431) (xy 342.530953 -260.16936) (xy 342.572624 -260.136129)
			(xy 342.618782 -260.10948) (xy 342.668396 -260.090008) (xy 342.720358 -260.078148) (xy 342.773508 -260.074165)
			(xy 342.826658 -260.078148) (xy 342.87862 -260.090008) (xy 342.928234 -260.10948) (xy 342.974392 -260.136129)
			(xy 343.016063 -260.16936) (xy 343.052315 -260.208431) (xy 343.082339 -260.252468) (xy 343.105465 -260.300489)
			(xy 343.121175 -260.351419) (xy 343.129118 -260.404123) (xy 343.129616 -260.430772) (xy 343.129118 -260.457421)
			(xy 343.358206 -260.457421) (xy 343.358206 -260.404123) (xy 343.366149 -260.351419) (xy 343.381859 -260.300489)
			(xy 343.404985 -260.252468) (xy 343.435009 -260.208431) (xy 343.471261 -260.16936) (xy 343.512932 -260.136129)
			(xy 343.55909 -260.10948) (xy 343.608704 -260.090008) (xy 343.660666 -260.078148) (xy 343.713816 -260.074165)
			(xy 343.766966 -260.078148) (xy 343.818928 -260.090008) (xy 343.868542 -260.10948) (xy 343.9147 -260.136129)
			(xy 343.956371 -260.16936) (xy 343.992623 -260.208431) (xy 344.022647 -260.252468) (xy 344.045773 -260.300489)
			(xy 344.061483 -260.351419) (xy 344.069426 -260.404123) (xy 344.069924 -260.430772) (xy 344.069426 -260.457421)
			(xy 344.297498 -260.457421) (xy 344.297498 -260.404123) (xy 344.305441 -260.351419) (xy 344.321151 -260.300489)
			(xy 344.344277 -260.252468) (xy 344.374301 -260.208431) (xy 344.410553 -260.16936) (xy 344.452224 -260.136129)
			(xy 344.498382 -260.10948) (xy 344.547996 -260.090008) (xy 344.599958 -260.078148) (xy 344.653108 -260.074165)
			(xy 344.706258 -260.078148) (xy 344.75822 -260.090008) (xy 344.807834 -260.10948) (xy 344.853992 -260.136129)
			(xy 344.895663 -260.16936) (xy 344.931915 -260.208431) (xy 344.961939 -260.252468) (xy 344.985065 -260.300489)
			(xy 345.000775 -260.351419) (xy 345.008718 -260.404123) (xy 345.009216 -260.430772) (xy 345.008718 -260.457421)
			(xy 345.237806 -260.457421) (xy 345.237806 -260.404123) (xy 345.245749 -260.351419) (xy 345.261459 -260.300489)
			(xy 345.284585 -260.252468) (xy 345.314609 -260.208431) (xy 345.350861 -260.16936) (xy 345.392532 -260.136129)
			(xy 345.43869 -260.10948) (xy 345.488304 -260.090008) (xy 345.540266 -260.078148) (xy 345.593416 -260.074165)
			(xy 345.646566 -260.078148) (xy 345.698528 -260.090008) (xy 345.748142 -260.10948) (xy 345.7943 -260.136129)
			(xy 345.835971 -260.16936) (xy 345.872223 -260.208431) (xy 345.902247 -260.252468) (xy 345.925373 -260.300489)
			(xy 345.941083 -260.351419) (xy 345.949026 -260.404123) (xy 345.949524 -260.430772) (xy 345.949026 -260.457421)
			(xy 346.177352 -260.457421) (xy 346.177352 -260.404123) (xy 346.185295 -260.351419) (xy 346.201005 -260.300489)
			(xy 346.224131 -260.252468) (xy 346.254155 -260.208431) (xy 346.290407 -260.16936) (xy 346.332078 -260.136129)
			(xy 346.378236 -260.10948) (xy 346.42785 -260.090008) (xy 346.479812 -260.078148) (xy 346.532962 -260.074165)
			(xy 346.586112 -260.078148) (xy 346.638074 -260.090008) (xy 346.687688 -260.10948) (xy 346.733846 -260.136129)
			(xy 346.775517 -260.16936) (xy 346.811769 -260.208431) (xy 346.841793 -260.252468) (xy 346.864919 -260.300489)
			(xy 346.880629 -260.351419) (xy 346.888572 -260.404123) (xy 346.88907 -260.430772) (xy 346.888572 -260.457421)
			(xy 346.880629 -260.510125) (xy 346.864919 -260.561055) (xy 346.841793 -260.609076) (xy 346.811769 -260.653113)
			(xy 346.775517 -260.692184) (xy 346.733846 -260.725415) (xy 346.687688 -260.752064) (xy 346.638074 -260.771536)
			(xy 346.586112 -260.783396) (xy 346.532962 -260.78738) (xy 346.479812 -260.783396) (xy 346.42785 -260.771536)
			(xy 346.378236 -260.752064) (xy 346.332078 -260.725415) (xy 346.290407 -260.692184) (xy 346.254155 -260.653113)
			(xy 346.224131 -260.609076) (xy 346.201005 -260.561055) (xy 346.185295 -260.510125) (xy 346.177352 -260.457421)
			(xy 345.949026 -260.457421) (xy 345.941083 -260.510125) (xy 345.925373 -260.561055) (xy 345.902247 -260.609076)
			(xy 345.872223 -260.653113) (xy 345.835971 -260.692184) (xy 345.7943 -260.725415) (xy 345.748142 -260.752064)
			(xy 345.698528 -260.771536) (xy 345.646566 -260.783396) (xy 345.593416 -260.78738) (xy 345.540266 -260.783396)
			(xy 345.488304 -260.771536) (xy 345.43869 -260.752064) (xy 345.392532 -260.725415) (xy 345.350861 -260.692184)
			(xy 345.314609 -260.653113) (xy 345.284585 -260.609076) (xy 345.261459 -260.561055) (xy 345.245749 -260.510125)
			(xy 345.237806 -260.457421) (xy 345.008718 -260.457421) (xy 345.000775 -260.510125) (xy 344.985065 -260.561055)
			(xy 344.961939 -260.609076) (xy 344.931915 -260.653113) (xy 344.895663 -260.692184) (xy 344.853992 -260.725415)
			(xy 344.807834 -260.752064) (xy 344.75822 -260.771536) (xy 344.706258 -260.783396) (xy 344.653108 -260.78738)
			(xy 344.599958 -260.783396) (xy 344.547996 -260.771536) (xy 344.498382 -260.752064) (xy 344.452224 -260.725415)
			(xy 344.410553 -260.692184) (xy 344.374301 -260.653113) (xy 344.344277 -260.609076) (xy 344.321151 -260.561055)
			(xy 344.305441 -260.510125) (xy 344.297498 -260.457421) (xy 344.069426 -260.457421) (xy 344.061483 -260.510125)
			(xy 344.045773 -260.561055) (xy 344.022647 -260.609076) (xy 343.992623 -260.653113) (xy 343.956371 -260.692184)
			(xy 343.9147 -260.725415) (xy 343.868542 -260.752064) (xy 343.818928 -260.771536) (xy 343.766966 -260.783396)
			(xy 343.713816 -260.78738) (xy 343.660666 -260.783396) (xy 343.608704 -260.771536) (xy 343.55909 -260.752064)
			(xy 343.512932 -260.725415) (xy 343.471261 -260.692184) (xy 343.435009 -260.653113) (xy 343.404985 -260.609076)
			(xy 343.381859 -260.561055) (xy 343.366149 -260.510125) (xy 343.358206 -260.457421) (xy 343.129118 -260.457421)
			(xy 343.121175 -260.510125) (xy 343.105465 -260.561055) (xy 343.082339 -260.609076) (xy 343.052315 -260.653113)
			(xy 343.016063 -260.692184) (xy 342.974392 -260.725415) (xy 342.928234 -260.752064) (xy 342.87862 -260.771536)
			(xy 342.826658 -260.783396) (xy 342.773508 -260.78738) (xy 342.720358 -260.783396) (xy 342.668396 -260.771536)
			(xy 342.618782 -260.752064) (xy 342.572624 -260.725415) (xy 342.530953 -260.692184) (xy 342.494701 -260.653113)
			(xy 342.464677 -260.609076) (xy 342.441551 -260.561055) (xy 342.425841 -260.510125) (xy 342.417898 -260.457421)
			(xy 342.189826 -260.457421) (xy 342.181883 -260.510125) (xy 342.166173 -260.561055) (xy 342.143047 -260.609076)
			(xy 342.113023 -260.653113) (xy 342.076771 -260.692184) (xy 342.0351 -260.725415) (xy 341.988942 -260.752064)
			(xy 341.939328 -260.771536) (xy 341.887366 -260.783396) (xy 341.834216 -260.78738) (xy 341.781066 -260.783396)
			(xy 341.729104 -260.771536) (xy 341.67949 -260.752064) (xy 341.633332 -260.725415) (xy 341.591661 -260.692184)
			(xy 341.555409 -260.653113) (xy 341.525385 -260.609076) (xy 341.502259 -260.561055) (xy 341.486549 -260.510125)
			(xy 341.478606 -260.457421) (xy 341.250026 -260.457421) (xy 341.242083 -260.510125) (xy 341.226373 -260.561055)
			(xy 341.203247 -260.609076) (xy 341.173223 -260.653113) (xy 341.136971 -260.692184) (xy 341.0953 -260.725415)
			(xy 341.049142 -260.752064) (xy 340.999528 -260.771536) (xy 340.947566 -260.783396) (xy 340.894416 -260.78738)
			(xy 340.841266 -260.783396) (xy 340.789304 -260.771536) (xy 340.73969 -260.752064) (xy 340.693532 -260.725415)
			(xy 340.651861 -260.692184) (xy 340.615609 -260.653113) (xy 340.585585 -260.609076) (xy 340.562459 -260.561055)
			(xy 340.546749 -260.510125) (xy 340.538806 -260.457421) (xy 340.309972 -260.457421) (xy 340.302029 -260.510125)
			(xy 340.286319 -260.561055) (xy 340.263193 -260.609076) (xy 340.233169 -260.653113) (xy 340.196917 -260.692184)
			(xy 340.155246 -260.725415) (xy 340.109088 -260.752064) (xy 340.059474 -260.771536) (xy 340.007512 -260.783396)
			(xy 339.954362 -260.78738) (xy 339.901212 -260.783396) (xy 339.84925 -260.771536) (xy 339.799636 -260.752064)
			(xy 339.753478 -260.725415) (xy 339.711807 -260.692184) (xy 339.675555 -260.653113) (xy 339.645531 -260.609076)
			(xy 339.622405 -260.561055) (xy 339.606695 -260.510125) (xy 339.598752 -260.457421) (xy 339.37956 -260.457421)
			(xy 339.37956 -260.787134) (xy 339.379968 -260.80052) (xy 339.386935 -260.82637) (xy 339.400381 -260.849521)
			(xy 339.419382 -260.868381) (xy 339.442632 -260.881655) (xy 339.468533 -260.888429) (xy 339.481922 -260.888734)
			(xy 339.484462 -260.888734) (xy 339.511112 -260.889204) (xy 339.563817 -260.897143) (xy 339.61475 -260.912849)
			(xy 339.662773 -260.935971) (xy 339.706813 -260.965993) (xy 339.745887 -261.002244) (xy 339.77912 -261.043914)
			(xy 339.805772 -261.090072) (xy 339.825246 -261.139686) (xy 339.837107 -261.191649) (xy 339.84109 -261.2448)
			(xy 339.83909 -261.271491) (xy 340.068652 -261.271491) (xy 340.068652 -261.218193) (xy 340.076595 -261.165489)
			(xy 340.092305 -261.114559) (xy 340.115431 -261.066538) (xy 340.145455 -261.022501) (xy 340.181707 -260.98343)
			(xy 340.223378 -260.950199) (xy 340.269536 -260.92355) (xy 340.31915 -260.904078) (xy 340.371112 -260.892218)
			(xy 340.424262 -260.888235) (xy 340.477412 -260.892218) (xy 340.529374 -260.904078) (xy 340.578988 -260.92355)
			(xy 340.625146 -260.950199) (xy 340.666817 -260.98343) (xy 340.703069 -261.022501) (xy 340.733093 -261.066538)
			(xy 340.756219 -261.114559) (xy 340.771929 -261.165489) (xy 340.779872 -261.218193) (xy 340.78037 -261.244842)
			(xy 340.779872 -261.271491) (xy 341.008452 -261.271491) (xy 341.008452 -261.218193) (xy 341.016395 -261.165489)
			(xy 341.032105 -261.114559) (xy 341.055231 -261.066538) (xy 341.085255 -261.022501) (xy 341.121507 -260.98343)
			(xy 341.163178 -260.950199) (xy 341.209336 -260.92355) (xy 341.25895 -260.904078) (xy 341.310912 -260.892218)
			(xy 341.364062 -260.888235) (xy 341.417212 -260.892218) (xy 341.469174 -260.904078) (xy 341.518788 -260.92355)
			(xy 341.564946 -260.950199) (xy 341.606617 -260.98343) (xy 341.642869 -261.022501) (xy 341.672893 -261.066538)
			(xy 341.696019 -261.114559) (xy 341.711729 -261.165489) (xy 341.719672 -261.218193) (xy 341.72017 -261.244842)
			(xy 341.719672 -261.271491) (xy 341.948252 -261.271491) (xy 341.948252 -261.218193) (xy 341.956195 -261.165489)
			(xy 341.971905 -261.114559) (xy 341.995031 -261.066538) (xy 342.025055 -261.022501) (xy 342.061307 -260.98343)
			(xy 342.102978 -260.950199) (xy 342.149136 -260.92355) (xy 342.19875 -260.904078) (xy 342.250712 -260.892218)
			(xy 342.303862 -260.888235) (xy 342.357012 -260.892218) (xy 342.408974 -260.904078) (xy 342.458588 -260.92355)
			(xy 342.504746 -260.950199) (xy 342.546417 -260.98343) (xy 342.582669 -261.022501) (xy 342.612693 -261.066538)
			(xy 342.635819 -261.114559) (xy 342.651529 -261.165489) (xy 342.659472 -261.218193) (xy 342.65997 -261.244842)
			(xy 342.659472 -261.271491) (xy 342.888052 -261.271491) (xy 342.888052 -261.218193) (xy 342.895995 -261.165489)
			(xy 342.911705 -261.114559) (xy 342.934831 -261.066538) (xy 342.964855 -261.022501) (xy 343.001107 -260.98343)
			(xy 343.042778 -260.950199) (xy 343.088936 -260.92355) (xy 343.13855 -260.904078) (xy 343.190512 -260.892218)
			(xy 343.243662 -260.888235) (xy 343.296812 -260.892218) (xy 343.348774 -260.904078) (xy 343.398388 -260.92355)
			(xy 343.444546 -260.950199) (xy 343.486217 -260.98343) (xy 343.522469 -261.022501) (xy 343.552493 -261.066538)
			(xy 343.575619 -261.114559) (xy 343.591329 -261.165489) (xy 343.599272 -261.218193) (xy 343.59977 -261.244842)
			(xy 343.599272 -261.271491) (xy 343.827852 -261.271491) (xy 343.827852 -261.218193) (xy 343.835795 -261.165489)
			(xy 343.851505 -261.114559) (xy 343.874631 -261.066538) (xy 343.904655 -261.022501) (xy 343.940907 -260.98343)
			(xy 343.982578 -260.950199) (xy 344.028736 -260.92355) (xy 344.07835 -260.904078) (xy 344.130312 -260.892218)
			(xy 344.183462 -260.888235) (xy 344.236612 -260.892218) (xy 344.288574 -260.904078) (xy 344.338188 -260.92355)
			(xy 344.384346 -260.950199) (xy 344.426017 -260.98343) (xy 344.462269 -261.022501) (xy 344.492293 -261.066538)
			(xy 344.515419 -261.114559) (xy 344.531129 -261.165489) (xy 344.539072 -261.218193) (xy 344.53957 -261.244842)
			(xy 344.539072 -261.271491) (xy 344.767652 -261.271491) (xy 344.767652 -261.218193) (xy 344.775595 -261.165489)
			(xy 344.791305 -261.114559) (xy 344.814431 -261.066538) (xy 344.844455 -261.022501) (xy 344.880707 -260.98343)
			(xy 344.922378 -260.950199) (xy 344.968536 -260.92355) (xy 345.01815 -260.904078) (xy 345.070112 -260.892218)
			(xy 345.123262 -260.888235) (xy 345.176412 -260.892218) (xy 345.228374 -260.904078) (xy 345.277988 -260.92355)
			(xy 345.324146 -260.950199) (xy 345.365817 -260.98343) (xy 345.402069 -261.022501) (xy 345.432093 -261.066538)
			(xy 345.455219 -261.114559) (xy 345.470929 -261.165489) (xy 345.478872 -261.218193) (xy 345.47937 -261.244842)
			(xy 345.478872 -261.271491) (xy 345.707452 -261.271491) (xy 345.707452 -261.218193) (xy 345.715395 -261.165489)
			(xy 345.731105 -261.114559) (xy 345.754231 -261.066538) (xy 345.784255 -261.022501) (xy 345.820507 -260.98343)
			(xy 345.862178 -260.950199) (xy 345.908336 -260.92355) (xy 345.95795 -260.904078) (xy 346.009912 -260.892218)
			(xy 346.063062 -260.888235) (xy 346.116212 -260.892218) (xy 346.168174 -260.904078) (xy 346.217788 -260.92355)
			(xy 346.263946 -260.950199) (xy 346.305617 -260.98343) (xy 346.341869 -261.022501) (xy 346.371893 -261.066538)
			(xy 346.395019 -261.114559) (xy 346.410729 -261.165489) (xy 346.418672 -261.218193) (xy 346.41917 -261.244842)
			(xy 346.418672 -261.271491) (xy 346.647252 -261.271491) (xy 346.647252 -261.218193) (xy 346.655195 -261.165489)
			(xy 346.670905 -261.114559) (xy 346.694031 -261.066538) (xy 346.724055 -261.022501) (xy 346.760307 -260.98343)
			(xy 346.801978 -260.950199) (xy 346.848136 -260.92355) (xy 346.89775 -260.904078) (xy 346.949712 -260.892218)
			(xy 347.002862 -260.888235) (xy 347.056012 -260.892218) (xy 347.107974 -260.904078) (xy 347.157588 -260.92355)
			(xy 347.203746 -260.950199) (xy 347.245417 -260.98343) (xy 347.281669 -261.022501) (xy 347.311693 -261.066538)
			(xy 347.334819 -261.114559) (xy 347.350529 -261.165489) (xy 347.358472 -261.218193) (xy 347.35897 -261.244842)
			(xy 347.358472 -261.271491) (xy 347.350529 -261.324195) (xy 347.334819 -261.375125) (xy 347.311693 -261.423146)
			(xy 347.281669 -261.467183) (xy 347.245417 -261.506254) (xy 347.203746 -261.539485) (xy 347.157588 -261.566134)
			(xy 347.107974 -261.585606) (xy 347.056012 -261.597466) (xy 347.002862 -261.60145) (xy 346.949712 -261.597466)
			(xy 346.89775 -261.585606) (xy 346.848136 -261.566134) (xy 346.801978 -261.539485) (xy 346.760307 -261.506254)
			(xy 346.724055 -261.467183) (xy 346.694031 -261.423146) (xy 346.670905 -261.375125) (xy 346.655195 -261.324195)
			(xy 346.647252 -261.271491) (xy 346.418672 -261.271491) (xy 346.410729 -261.324195) (xy 346.395019 -261.375125)
			(xy 346.371893 -261.423146) (xy 346.341869 -261.467183) (xy 346.305617 -261.506254) (xy 346.263946 -261.539485)
			(xy 346.217788 -261.566134) (xy 346.168174 -261.585606) (xy 346.116212 -261.597466) (xy 346.063062 -261.60145)
			(xy 346.009912 -261.597466) (xy 345.95795 -261.585606) (xy 345.908336 -261.566134) (xy 345.862178 -261.539485)
			(xy 345.820507 -261.506254) (xy 345.784255 -261.467183) (xy 345.754231 -261.423146) (xy 345.731105 -261.375125)
			(xy 345.715395 -261.324195) (xy 345.707452 -261.271491) (xy 345.478872 -261.271491) (xy 345.470929 -261.324195)
			(xy 345.455219 -261.375125) (xy 345.432093 -261.423146) (xy 345.402069 -261.467183) (xy 345.365817 -261.506254)
			(xy 345.324146 -261.539485) (xy 345.277988 -261.566134) (xy 345.228374 -261.585606) (xy 345.176412 -261.597466)
			(xy 345.123262 -261.60145) (xy 345.070112 -261.597466) (xy 345.01815 -261.585606) (xy 344.968536 -261.566134)
			(xy 344.922378 -261.539485) (xy 344.880707 -261.506254) (xy 344.844455 -261.467183) (xy 344.814431 -261.423146)
			(xy 344.791305 -261.375125) (xy 344.775595 -261.324195) (xy 344.767652 -261.271491) (xy 344.539072 -261.271491)
			(xy 344.531129 -261.324195) (xy 344.515419 -261.375125) (xy 344.492293 -261.423146) (xy 344.462269 -261.467183)
			(xy 344.426017 -261.506254) (xy 344.384346 -261.539485) (xy 344.338188 -261.566134) (xy 344.288574 -261.585606)
			(xy 344.236612 -261.597466) (xy 344.183462 -261.60145) (xy 344.130312 -261.597466) (xy 344.07835 -261.585606)
			(xy 344.028736 -261.566134) (xy 343.982578 -261.539485) (xy 343.940907 -261.506254) (xy 343.904655 -261.467183)
			(xy 343.874631 -261.423146) (xy 343.851505 -261.375125) (xy 343.835795 -261.324195) (xy 343.827852 -261.271491)
			(xy 343.599272 -261.271491) (xy 343.591329 -261.324195) (xy 343.575619 -261.375125) (xy 343.552493 -261.423146)
			(xy 343.522469 -261.467183) (xy 343.486217 -261.506254) (xy 343.444546 -261.539485) (xy 343.398388 -261.566134)
			(xy 343.348774 -261.585606) (xy 343.296812 -261.597466) (xy 343.243662 -261.60145) (xy 343.190512 -261.597466)
			(xy 343.13855 -261.585606) (xy 343.088936 -261.566134) (xy 343.042778 -261.539485) (xy 343.001107 -261.506254)
			(xy 342.964855 -261.467183) (xy 342.934831 -261.423146) (xy 342.911705 -261.375125) (xy 342.895995 -261.324195)
			(xy 342.888052 -261.271491) (xy 342.659472 -261.271491) (xy 342.651529 -261.324195) (xy 342.635819 -261.375125)
			(xy 342.612693 -261.423146) (xy 342.582669 -261.467183) (xy 342.546417 -261.506254) (xy 342.504746 -261.539485)
			(xy 342.458588 -261.566134) (xy 342.408974 -261.585606) (xy 342.357012 -261.597466) (xy 342.303862 -261.60145)
			(xy 342.250712 -261.597466) (xy 342.19875 -261.585606) (xy 342.149136 -261.566134) (xy 342.102978 -261.539485)
			(xy 342.061307 -261.506254) (xy 342.025055 -261.467183) (xy 341.995031 -261.423146) (xy 341.971905 -261.375125)
			(xy 341.956195 -261.324195) (xy 341.948252 -261.271491) (xy 341.719672 -261.271491) (xy 341.711729 -261.324195)
			(xy 341.696019 -261.375125) (xy 341.672893 -261.423146) (xy 341.642869 -261.467183) (xy 341.606617 -261.506254)
			(xy 341.564946 -261.539485) (xy 341.518788 -261.566134) (xy 341.469174 -261.585606) (xy 341.417212 -261.597466)
			(xy 341.364062 -261.60145) (xy 341.310912 -261.597466) (xy 341.25895 -261.585606) (xy 341.209336 -261.566134)
			(xy 341.163178 -261.539485) (xy 341.121507 -261.506254) (xy 341.085255 -261.467183) (xy 341.055231 -261.423146)
			(xy 341.032105 -261.375125) (xy 341.016395 -261.324195) (xy 341.008452 -261.271491) (xy 340.779872 -261.271491)
			(xy 340.771929 -261.324195) (xy 340.756219 -261.375125) (xy 340.733093 -261.423146) (xy 340.703069 -261.467183)
			(xy 340.666817 -261.506254) (xy 340.625146 -261.539485) (xy 340.578988 -261.566134) (xy 340.529374 -261.585606)
			(xy 340.477412 -261.597466) (xy 340.424262 -261.60145) (xy 340.371112 -261.597466) (xy 340.31915 -261.585606)
			(xy 340.269536 -261.566134) (xy 340.223378 -261.539485) (xy 340.181707 -261.506254) (xy 340.145455 -261.467183)
			(xy 340.115431 -261.423146) (xy 340.092305 -261.375125) (xy 340.076595 -261.324195) (xy 340.068652 -261.271491)
			(xy 339.83909 -261.271491) (xy 339.837107 -261.297951) (xy 339.825246 -261.349914) (xy 339.805772 -261.399528)
			(xy 339.77912 -261.445686) (xy 339.745887 -261.487356) (xy 339.706813 -261.523607) (xy 339.662773 -261.553629)
			(xy 339.61475 -261.576751) (xy 339.563817 -261.592457) (xy 339.511112 -261.600396) (xy 339.484462 -261.60095)
			(xy 339.481922 -261.60095) (xy 339.468538 -261.601259) (xy 339.442646 -261.608034) (xy 339.419408 -261.62131)
			(xy 339.400421 -261.640172) (xy 339.386992 -261.663322) (xy 339.380045 -261.689168) (xy 339.37956 -261.70255)
			(xy 339.37956 -262.085307) (xy 339.599006 -262.085307) (xy 339.599006 -262.032009) (xy 339.606949 -261.979305)
			(xy 339.622659 -261.928375) (xy 339.645785 -261.880354) (xy 339.675809 -261.836317) (xy 339.712061 -261.797246)
			(xy 339.753732 -261.764015) (xy 339.79989 -261.737366) (xy 339.849504 -261.717894) (xy 339.901466 -261.706034)
			(xy 339.954616 -261.702051) (xy 340.007766 -261.706034) (xy 340.059728 -261.717894) (xy 340.109342 -261.737366)
			(xy 340.1555 -261.764015) (xy 340.197171 -261.797246) (xy 340.233423 -261.836317) (xy 340.263447 -261.880354)
			(xy 340.286573 -261.928375) (xy 340.302283 -261.979305) (xy 340.310226 -262.032009) (xy 340.310724 -262.058658)
			(xy 340.310226 -262.085307) (xy 340.538806 -262.085307) (xy 340.538806 -262.032009) (xy 340.546749 -261.979305)
			(xy 340.562459 -261.928375) (xy 340.585585 -261.880354) (xy 340.615609 -261.836317) (xy 340.651861 -261.797246)
			(xy 340.693532 -261.764015) (xy 340.73969 -261.737366) (xy 340.789304 -261.717894) (xy 340.841266 -261.706034)
			(xy 340.894416 -261.702051) (xy 340.947566 -261.706034) (xy 340.999528 -261.717894) (xy 341.049142 -261.737366)
			(xy 341.0953 -261.764015) (xy 341.136971 -261.797246) (xy 341.173223 -261.836317) (xy 341.203247 -261.880354)
			(xy 341.226373 -261.928375) (xy 341.242083 -261.979305) (xy 341.250026 -262.032009) (xy 341.250524 -262.058658)
			(xy 341.250026 -262.085307) (xy 341.478606 -262.085307) (xy 341.478606 -262.032009) (xy 341.486549 -261.979305)
			(xy 341.502259 -261.928375) (xy 341.525385 -261.880354) (xy 341.555409 -261.836317) (xy 341.591661 -261.797246)
			(xy 341.633332 -261.764015) (xy 341.67949 -261.737366) (xy 341.729104 -261.717894) (xy 341.781066 -261.706034)
			(xy 341.834216 -261.702051) (xy 341.887366 -261.706034) (xy 341.939328 -261.717894) (xy 341.988942 -261.737366)
			(xy 342.0351 -261.764015) (xy 342.076771 -261.797246) (xy 342.113023 -261.836317) (xy 342.143047 -261.880354)
			(xy 342.166173 -261.928375) (xy 342.181883 -261.979305) (xy 342.189826 -262.032009) (xy 342.190324 -262.058658)
			(xy 342.189826 -262.085307) (xy 342.418406 -262.085307) (xy 342.418406 -262.032009) (xy 342.426349 -261.979305)
			(xy 342.442059 -261.928375) (xy 342.465185 -261.880354) (xy 342.495209 -261.836317) (xy 342.531461 -261.797246)
			(xy 342.573132 -261.764015) (xy 342.61929 -261.737366) (xy 342.668904 -261.717894) (xy 342.720866 -261.706034)
			(xy 342.774016 -261.702051) (xy 342.827166 -261.706034) (xy 342.879128 -261.717894) (xy 342.928742 -261.737366)
			(xy 342.9749 -261.764015) (xy 343.016571 -261.797246) (xy 343.052823 -261.836317) (xy 343.082847 -261.880354)
			(xy 343.105973 -261.928375) (xy 343.121683 -261.979305) (xy 343.129626 -262.032009) (xy 343.130124 -262.058658)
			(xy 343.129626 -262.085307) (xy 343.358206 -262.085307) (xy 343.358206 -262.032009) (xy 343.366149 -261.979305)
			(xy 343.381859 -261.928375) (xy 343.404985 -261.880354) (xy 343.435009 -261.836317) (xy 343.471261 -261.797246)
			(xy 343.512932 -261.764015) (xy 343.55909 -261.737366) (xy 343.608704 -261.717894) (xy 343.660666 -261.706034)
			(xy 343.713816 -261.702051) (xy 343.766966 -261.706034) (xy 343.818928 -261.717894) (xy 343.868542 -261.737366)
			(xy 343.9147 -261.764015) (xy 343.956371 -261.797246) (xy 343.992623 -261.836317) (xy 344.022647 -261.880354)
			(xy 344.045773 -261.928375) (xy 344.061483 -261.979305) (xy 344.069426 -262.032009) (xy 344.069924 -262.058658)
			(xy 344.069426 -262.085307) (xy 344.298006 -262.085307) (xy 344.298006 -262.032009) (xy 344.305949 -261.979305)
			(xy 344.321659 -261.928375) (xy 344.344785 -261.880354) (xy 344.374809 -261.836317) (xy 344.411061 -261.797246)
			(xy 344.452732 -261.764015) (xy 344.49889 -261.737366) (xy 344.548504 -261.717894) (xy 344.600466 -261.706034)
			(xy 344.653616 -261.702051) (xy 344.706766 -261.706034) (xy 344.758728 -261.717894) (xy 344.808342 -261.737366)
			(xy 344.8545 -261.764015) (xy 344.896171 -261.797246) (xy 344.932423 -261.836317) (xy 344.962447 -261.880354)
			(xy 344.985573 -261.928375) (xy 345.001283 -261.979305) (xy 345.009226 -262.032009) (xy 345.009724 -262.058658)
			(xy 345.009226 -262.085307) (xy 345.237552 -262.085307) (xy 345.237552 -262.032009) (xy 345.245495 -261.979305)
			(xy 345.261205 -261.928375) (xy 345.284331 -261.880354) (xy 345.314355 -261.836317) (xy 345.350607 -261.797246)
			(xy 345.392278 -261.764015) (xy 345.438436 -261.737366) (xy 345.48805 -261.717894) (xy 345.540012 -261.706034)
			(xy 345.593162 -261.702051) (xy 345.646312 -261.706034) (xy 345.698274 -261.717894) (xy 345.747888 -261.737366)
			(xy 345.794046 -261.764015) (xy 345.835717 -261.797246) (xy 345.871969 -261.836317) (xy 345.901993 -261.880354)
			(xy 345.925119 -261.928375) (xy 345.940829 -261.979305) (xy 345.948772 -262.032009) (xy 345.94927 -262.058658)
			(xy 345.948772 -262.085307) (xy 346.177606 -262.085307) (xy 346.177606 -262.032009) (xy 346.185549 -261.979305)
			(xy 346.201259 -261.928375) (xy 346.224385 -261.880354) (xy 346.254409 -261.836317) (xy 346.290661 -261.797246)
			(xy 346.332332 -261.764015) (xy 346.37849 -261.737366) (xy 346.428104 -261.717894) (xy 346.480066 -261.706034)
			(xy 346.533216 -261.702051) (xy 346.586366 -261.706034) (xy 346.638328 -261.717894) (xy 346.687942 -261.737366)
			(xy 346.7341 -261.764015) (xy 346.775771 -261.797246) (xy 346.812023 -261.836317) (xy 346.842047 -261.880354)
			(xy 346.865173 -261.928375) (xy 346.880883 -261.979305) (xy 346.888826 -262.032009) (xy 346.889324 -262.058658)
			(xy 346.888826 -262.085307) (xy 347.117406 -262.085307) (xy 347.117406 -262.032009) (xy 347.125349 -261.979305)
			(xy 347.141059 -261.928375) (xy 347.164185 -261.880354) (xy 347.194209 -261.836317) (xy 347.230461 -261.797246)
			(xy 347.272132 -261.764015) (xy 347.31829 -261.737366) (xy 347.367904 -261.717894) (xy 347.419866 -261.706034)
			(xy 347.473016 -261.702051) (xy 347.526166 -261.706034) (xy 347.578128 -261.717894) (xy 347.627742 -261.737366)
			(xy 347.6739 -261.764015) (xy 347.715571 -261.797246) (xy 347.751823 -261.836317) (xy 347.781847 -261.880354)
			(xy 347.804973 -261.928375) (xy 347.820683 -261.979305) (xy 347.828626 -262.032009) (xy 347.829124 -262.058658)
			(xy 347.828626 -262.085307) (xy 347.820683 -262.138011) (xy 347.804973 -262.188941) (xy 347.781847 -262.236962)
			(xy 347.751823 -262.280999) (xy 347.715571 -262.32007) (xy 347.6739 -262.353301) (xy 347.627742 -262.37995)
			(xy 347.578128 -262.399422) (xy 347.526166 -262.411282) (xy 347.473016 -262.415266) (xy 347.419866 -262.411282)
			(xy 347.367904 -262.399422) (xy 347.31829 -262.37995) (xy 347.272132 -262.353301) (xy 347.230461 -262.32007)
			(xy 347.194209 -262.280999) (xy 347.164185 -262.236962) (xy 347.141059 -262.188941) (xy 347.125349 -262.138011)
			(xy 347.117406 -262.085307) (xy 346.888826 -262.085307) (xy 346.880883 -262.138011) (xy 346.865173 -262.188941)
			(xy 346.842047 -262.236962) (xy 346.812023 -262.280999) (xy 346.775771 -262.32007) (xy 346.7341 -262.353301)
			(xy 346.687942 -262.37995) (xy 346.638328 -262.399422) (xy 346.586366 -262.411282) (xy 346.533216 -262.415266)
			(xy 346.480066 -262.411282) (xy 346.428104 -262.399422) (xy 346.37849 -262.37995) (xy 346.332332 -262.353301)
			(xy 346.290661 -262.32007) (xy 346.254409 -262.280999) (xy 346.224385 -262.236962) (xy 346.201259 -262.188941)
			(xy 346.185549 -262.138011) (xy 346.177606 -262.085307) (xy 345.948772 -262.085307) (xy 345.940829 -262.138011)
			(xy 345.925119 -262.188941) (xy 345.901993 -262.236962) (xy 345.871969 -262.280999) (xy 345.835717 -262.32007)
			(xy 345.794046 -262.353301) (xy 345.747888 -262.37995) (xy 345.698274 -262.399422) (xy 345.646312 -262.411282)
			(xy 345.593162 -262.415266) (xy 345.540012 -262.411282) (xy 345.48805 -262.399422) (xy 345.438436 -262.37995)
			(xy 345.392278 -262.353301) (xy 345.350607 -262.32007) (xy 345.314355 -262.280999) (xy 345.284331 -262.236962)
			(xy 345.261205 -262.188941) (xy 345.245495 -262.138011) (xy 345.237552 -262.085307) (xy 345.009226 -262.085307)
			(xy 345.001283 -262.138011) (xy 344.985573 -262.188941) (xy 344.962447 -262.236962) (xy 344.932423 -262.280999)
			(xy 344.896171 -262.32007) (xy 344.8545 -262.353301) (xy 344.808342 -262.37995) (xy 344.758728 -262.399422)
			(xy 344.706766 -262.411282) (xy 344.653616 -262.415266) (xy 344.600466 -262.411282) (xy 344.548504 -262.399422)
			(xy 344.49889 -262.37995) (xy 344.452732 -262.353301) (xy 344.411061 -262.32007) (xy 344.374809 -262.280999)
			(xy 344.344785 -262.236962) (xy 344.321659 -262.188941) (xy 344.305949 -262.138011) (xy 344.298006 -262.085307)
			(xy 344.069426 -262.085307) (xy 344.061483 -262.138011) (xy 344.045773 -262.188941) (xy 344.022647 -262.236962)
			(xy 343.992623 -262.280999) (xy 343.956371 -262.32007) (xy 343.9147 -262.353301) (xy 343.868542 -262.37995)
			(xy 343.818928 -262.399422) (xy 343.766966 -262.411282) (xy 343.713816 -262.415266) (xy 343.660666 -262.411282)
			(xy 343.608704 -262.399422) (xy 343.55909 -262.37995) (xy 343.512932 -262.353301) (xy 343.471261 -262.32007)
			(xy 343.435009 -262.280999) (xy 343.404985 -262.236962) (xy 343.381859 -262.188941) (xy 343.366149 -262.138011)
			(xy 343.358206 -262.085307) (xy 343.129626 -262.085307) (xy 343.121683 -262.138011) (xy 343.105973 -262.188941)
			(xy 343.082847 -262.236962) (xy 343.052823 -262.280999) (xy 343.016571 -262.32007) (xy 342.9749 -262.353301)
			(xy 342.928742 -262.37995) (xy 342.879128 -262.399422) (xy 342.827166 -262.411282) (xy 342.774016 -262.415266)
			(xy 342.720866 -262.411282) (xy 342.668904 -262.399422) (xy 342.61929 -262.37995) (xy 342.573132 -262.353301)
			(xy 342.531461 -262.32007) (xy 342.495209 -262.280999) (xy 342.465185 -262.236962) (xy 342.442059 -262.188941)
			(xy 342.426349 -262.138011) (xy 342.418406 -262.085307) (xy 342.189826 -262.085307) (xy 342.181883 -262.138011)
			(xy 342.166173 -262.188941) (xy 342.143047 -262.236962) (xy 342.113023 -262.280999) (xy 342.076771 -262.32007)
			(xy 342.0351 -262.353301) (xy 341.988942 -262.37995) (xy 341.939328 -262.399422) (xy 341.887366 -262.411282)
			(xy 341.834216 -262.415266) (xy 341.781066 -262.411282) (xy 341.729104 -262.399422) (xy 341.67949 -262.37995)
			(xy 341.633332 -262.353301) (xy 341.591661 -262.32007) (xy 341.555409 -262.280999) (xy 341.525385 -262.236962)
			(xy 341.502259 -262.188941) (xy 341.486549 -262.138011) (xy 341.478606 -262.085307) (xy 341.250026 -262.085307)
			(xy 341.242083 -262.138011) (xy 341.226373 -262.188941) (xy 341.203247 -262.236962) (xy 341.173223 -262.280999)
			(xy 341.136971 -262.32007) (xy 341.0953 -262.353301) (xy 341.049142 -262.37995) (xy 340.999528 -262.399422)
			(xy 340.947566 -262.411282) (xy 340.894416 -262.415266) (xy 340.841266 -262.411282) (xy 340.789304 -262.399422)
			(xy 340.73969 -262.37995) (xy 340.693532 -262.353301) (xy 340.651861 -262.32007) (xy 340.615609 -262.280999)
			(xy 340.585585 -262.236962) (xy 340.562459 -262.188941) (xy 340.546749 -262.138011) (xy 340.538806 -262.085307)
			(xy 340.310226 -262.085307) (xy 340.302283 -262.138011) (xy 340.286573 -262.188941) (xy 340.263447 -262.236962)
			(xy 340.233423 -262.280999) (xy 340.197171 -262.32007) (xy 340.1555 -262.353301) (xy 340.109342 -262.37995)
			(xy 340.059728 -262.399422) (xy 340.007766 -262.411282) (xy 339.954616 -262.415266) (xy 339.901466 -262.411282)
			(xy 339.849504 -262.399422) (xy 339.79989 -262.37995) (xy 339.753732 -262.353301) (xy 339.712061 -262.32007)
			(xy 339.675809 -262.280999) (xy 339.645785 -262.236962) (xy 339.622659 -262.188941) (xy 339.606949 -262.138011)
			(xy 339.599006 -262.085307) (xy 339.37956 -262.085307) (xy 339.37956 -262.414766) (xy 339.379959 -262.428158)
			(xy 339.386915 -262.454023) (xy 339.400357 -262.477189) (xy 339.41936 -262.496064) (xy 339.442617 -262.509349)
			(xy 339.468528 -262.516129) (xy 339.481922 -262.516366) (xy 339.484462 -262.516366) (xy 339.511117 -262.516837)
			(xy 339.563832 -262.524777) (xy 339.614775 -262.540486) (xy 339.662807 -262.563612) (xy 339.706856 -262.59364)
			(xy 339.745936 -262.629898) (xy 339.779177 -262.671575) (xy 339.805833 -262.717742) (xy 339.825311 -262.767366)
			(xy 339.837174 -262.819339) (xy 339.841158 -262.8725) (xy 339.839163 -262.899123) (xy 340.068652 -262.899123)
			(xy 340.068652 -262.845825) (xy 340.076595 -262.793121) (xy 340.092305 -262.742191) (xy 340.115431 -262.69417)
			(xy 340.145455 -262.650133) (xy 340.181707 -262.611062) (xy 340.223378 -262.577831) (xy 340.269536 -262.551182)
			(xy 340.31915 -262.53171) (xy 340.371112 -262.51985) (xy 340.424262 -262.515867) (xy 340.477412 -262.51985)
			(xy 340.529374 -262.53171) (xy 340.578988 -262.551182) (xy 340.625146 -262.577831) (xy 340.666817 -262.611062)
			(xy 340.703069 -262.650133) (xy 340.733093 -262.69417) (xy 340.756219 -262.742191) (xy 340.771929 -262.793121)
			(xy 340.779872 -262.845825) (xy 340.78037 -262.872474) (xy 340.779872 -262.899123) (xy 341.008452 -262.899123)
			(xy 341.008452 -262.845825) (xy 341.016395 -262.793121) (xy 341.032105 -262.742191) (xy 341.055231 -262.69417)
			(xy 341.085255 -262.650133) (xy 341.121507 -262.611062) (xy 341.163178 -262.577831) (xy 341.209336 -262.551182)
			(xy 341.25895 -262.53171) (xy 341.310912 -262.51985) (xy 341.364062 -262.515867) (xy 341.417212 -262.51985)
			(xy 341.469174 -262.53171) (xy 341.518788 -262.551182) (xy 341.564946 -262.577831) (xy 341.606617 -262.611062)
			(xy 341.642869 -262.650133) (xy 341.672893 -262.69417) (xy 341.696019 -262.742191) (xy 341.711729 -262.793121)
			(xy 341.719672 -262.845825) (xy 341.72017 -262.872474) (xy 341.719672 -262.899123) (xy 341.948252 -262.899123)
			(xy 341.948252 -262.845825) (xy 341.956195 -262.793121) (xy 341.971905 -262.742191) (xy 341.995031 -262.69417)
			(xy 342.025055 -262.650133) (xy 342.061307 -262.611062) (xy 342.102978 -262.577831) (xy 342.149136 -262.551182)
			(xy 342.19875 -262.53171) (xy 342.250712 -262.51985) (xy 342.303862 -262.515867) (xy 342.357012 -262.51985)
			(xy 342.408974 -262.53171) (xy 342.458588 -262.551182) (xy 342.504746 -262.577831) (xy 342.546417 -262.611062)
			(xy 342.582669 -262.650133) (xy 342.612693 -262.69417) (xy 342.635819 -262.742191) (xy 342.651529 -262.793121)
			(xy 342.659472 -262.845825) (xy 342.65997 -262.872474) (xy 342.659472 -262.899123) (xy 342.888052 -262.899123)
			(xy 342.888052 -262.845825) (xy 342.895995 -262.793121) (xy 342.911705 -262.742191) (xy 342.934831 -262.69417)
			(xy 342.964855 -262.650133) (xy 343.001107 -262.611062) (xy 343.042778 -262.577831) (xy 343.088936 -262.551182)
			(xy 343.13855 -262.53171) (xy 343.190512 -262.51985) (xy 343.243662 -262.515867) (xy 343.296812 -262.51985)
			(xy 343.348774 -262.53171) (xy 343.398388 -262.551182) (xy 343.444546 -262.577831) (xy 343.486217 -262.611062)
			(xy 343.522469 -262.650133) (xy 343.552493 -262.69417) (xy 343.575619 -262.742191) (xy 343.591329 -262.793121)
			(xy 343.599272 -262.845825) (xy 343.59977 -262.872474) (xy 343.599272 -262.899123) (xy 343.827852 -262.899123)
			(xy 343.827852 -262.845825) (xy 343.835795 -262.793121) (xy 343.851505 -262.742191) (xy 343.874631 -262.69417)
			(xy 343.904655 -262.650133) (xy 343.940907 -262.611062) (xy 343.982578 -262.577831) (xy 344.028736 -262.551182)
			(xy 344.07835 -262.53171) (xy 344.130312 -262.51985) (xy 344.183462 -262.515867) (xy 344.236612 -262.51985)
			(xy 344.288574 -262.53171) (xy 344.338188 -262.551182) (xy 344.384346 -262.577831) (xy 344.426017 -262.611062)
			(xy 344.462269 -262.650133) (xy 344.492293 -262.69417) (xy 344.515419 -262.742191) (xy 344.531129 -262.793121)
			(xy 344.539072 -262.845825) (xy 344.53957 -262.872474) (xy 344.539072 -262.899123) (xy 344.767906 -262.899123)
			(xy 344.767906 -262.845825) (xy 344.775849 -262.793121) (xy 344.791559 -262.742191) (xy 344.814685 -262.69417)
			(xy 344.844709 -262.650133) (xy 344.880961 -262.611062) (xy 344.922632 -262.577831) (xy 344.96879 -262.551182)
			(xy 345.018404 -262.53171) (xy 345.070366 -262.51985) (xy 345.123516 -262.515867) (xy 345.176666 -262.51985)
			(xy 345.228628 -262.53171) (xy 345.278242 -262.551182) (xy 345.3244 -262.577831) (xy 345.366071 -262.611062)
			(xy 345.402323 -262.650133) (xy 345.432347 -262.69417) (xy 345.455473 -262.742191) (xy 345.471183 -262.793121)
			(xy 345.479126 -262.845825) (xy 345.479624 -262.872474) (xy 345.479126 -262.899123) (xy 345.707452 -262.899123)
			(xy 345.707452 -262.845825) (xy 345.715395 -262.793121) (xy 345.731105 -262.742191) (xy 345.754231 -262.69417)
			(xy 345.784255 -262.650133) (xy 345.820507 -262.611062) (xy 345.862178 -262.577831) (xy 345.908336 -262.551182)
			(xy 345.95795 -262.53171) (xy 346.009912 -262.51985) (xy 346.063062 -262.515867) (xy 346.116212 -262.51985)
			(xy 346.168174 -262.53171) (xy 346.217788 -262.551182) (xy 346.263946 -262.577831) (xy 346.305617 -262.611062)
			(xy 346.341869 -262.650133) (xy 346.371893 -262.69417) (xy 346.395019 -262.742191) (xy 346.410729 -262.793121)
			(xy 346.418672 -262.845825) (xy 346.41917 -262.872474) (xy 346.418672 -262.899123) (xy 346.647252 -262.899123)
			(xy 346.647252 -262.845825) (xy 346.655195 -262.793121) (xy 346.670905 -262.742191) (xy 346.694031 -262.69417)
			(xy 346.724055 -262.650133) (xy 346.760307 -262.611062) (xy 346.801978 -262.577831) (xy 346.848136 -262.551182)
			(xy 346.89775 -262.53171) (xy 346.949712 -262.51985) (xy 347.002862 -262.515867) (xy 347.056012 -262.51985)
			(xy 347.107974 -262.53171) (xy 347.157588 -262.551182) (xy 347.203746 -262.577831) (xy 347.245417 -262.611062)
			(xy 347.281669 -262.650133) (xy 347.311693 -262.69417) (xy 347.334819 -262.742191) (xy 347.350529 -262.793121)
			(xy 347.358472 -262.845825) (xy 347.35897 -262.872474) (xy 347.358472 -262.899123) (xy 347.587052 -262.899123)
			(xy 347.587052 -262.845825) (xy 347.594995 -262.793121) (xy 347.610705 -262.742191) (xy 347.633831 -262.69417)
			(xy 347.663855 -262.650133) (xy 347.700107 -262.611062) (xy 347.741778 -262.577831) (xy 347.787936 -262.551182)
			(xy 347.83755 -262.53171) (xy 347.889512 -262.51985) (xy 347.942662 -262.515867) (xy 347.995812 -262.51985)
			(xy 348.047774 -262.53171) (xy 348.097388 -262.551182) (xy 348.143546 -262.577831) (xy 348.185217 -262.611062)
			(xy 348.221469 -262.650133) (xy 348.251493 -262.69417) (xy 348.274619 -262.742191) (xy 348.290329 -262.793121)
			(xy 348.298272 -262.845825) (xy 348.29877 -262.872474) (xy 348.298272 -262.899123) (xy 348.290329 -262.951827)
			(xy 348.274619 -263.002757) (xy 348.251493 -263.050778) (xy 348.221469 -263.094815) (xy 348.185217 -263.133886)
			(xy 348.143546 -263.167117) (xy 348.097388 -263.193766) (xy 348.047774 -263.213238) (xy 347.995812 -263.225098)
			(xy 347.942662 -263.229082) (xy 347.889512 -263.225098) (xy 347.83755 -263.213238) (xy 347.787936 -263.193766)
			(xy 347.741778 -263.167117) (xy 347.700107 -263.133886) (xy 347.663855 -263.094815) (xy 347.633831 -263.050778)
			(xy 347.610705 -263.002757) (xy 347.594995 -262.951827) (xy 347.587052 -262.899123) (xy 347.358472 -262.899123)
			(xy 347.350529 -262.951827) (xy 347.334819 -263.002757) (xy 347.311693 -263.050778) (xy 347.281669 -263.094815)
			(xy 347.245417 -263.133886) (xy 347.203746 -263.167117) (xy 347.157588 -263.193766) (xy 347.107974 -263.213238)
			(xy 347.056012 -263.225098) (xy 347.002862 -263.229082) (xy 346.949712 -263.225098) (xy 346.89775 -263.213238)
			(xy 346.848136 -263.193766) (xy 346.801978 -263.167117) (xy 346.760307 -263.133886) (xy 346.724055 -263.094815)
			(xy 346.694031 -263.050778) (xy 346.670905 -263.002757) (xy 346.655195 -262.951827) (xy 346.647252 -262.899123)
			(xy 346.418672 -262.899123) (xy 346.410729 -262.951827) (xy 346.395019 -263.002757) (xy 346.371893 -263.050778)
			(xy 346.341869 -263.094815) (xy 346.305617 -263.133886) (xy 346.263946 -263.167117) (xy 346.217788 -263.193766)
			(xy 346.168174 -263.213238) (xy 346.116212 -263.225098) (xy 346.063062 -263.229082) (xy 346.009912 -263.225098)
			(xy 345.95795 -263.213238) (xy 345.908336 -263.193766) (xy 345.862178 -263.167117) (xy 345.820507 -263.133886)
			(xy 345.784255 -263.094815) (xy 345.754231 -263.050778) (xy 345.731105 -263.002757) (xy 345.715395 -262.951827)
			(xy 345.707452 -262.899123) (xy 345.479126 -262.899123) (xy 345.471183 -262.951827) (xy 345.455473 -263.002757)
			(xy 345.432347 -263.050778) (xy 345.402323 -263.094815) (xy 345.366071 -263.133886) (xy 345.3244 -263.167117)
			(xy 345.278242 -263.193766) (xy 345.228628 -263.213238) (xy 345.176666 -263.225098) (xy 345.123516 -263.229082)
			(xy 345.070366 -263.225098) (xy 345.018404 -263.213238) (xy 344.96879 -263.193766) (xy 344.922632 -263.167117)
			(xy 344.880961 -263.133886) (xy 344.844709 -263.094815) (xy 344.814685 -263.050778) (xy 344.791559 -263.002757)
			(xy 344.775849 -262.951827) (xy 344.767906 -262.899123) (xy 344.539072 -262.899123) (xy 344.531129 -262.951827)
			(xy 344.515419 -263.002757) (xy 344.492293 -263.050778) (xy 344.462269 -263.094815) (xy 344.426017 -263.133886)
			(xy 344.384346 -263.167117) (xy 344.338188 -263.193766) (xy 344.288574 -263.213238) (xy 344.236612 -263.225098)
			(xy 344.183462 -263.229082) (xy 344.130312 -263.225098) (xy 344.07835 -263.213238) (xy 344.028736 -263.193766)
			(xy 343.982578 -263.167117) (xy 343.940907 -263.133886) (xy 343.904655 -263.094815) (xy 343.874631 -263.050778)
			(xy 343.851505 -263.002757) (xy 343.835795 -262.951827) (xy 343.827852 -262.899123) (xy 343.599272 -262.899123)
			(xy 343.591329 -262.951827) (xy 343.575619 -263.002757) (xy 343.552493 -263.050778) (xy 343.522469 -263.094815)
			(xy 343.486217 -263.133886) (xy 343.444546 -263.167117) (xy 343.398388 -263.193766) (xy 343.348774 -263.213238)
			(xy 343.296812 -263.225098) (xy 343.243662 -263.229082) (xy 343.190512 -263.225098) (xy 343.13855 -263.213238)
			(xy 343.088936 -263.193766) (xy 343.042778 -263.167117) (xy 343.001107 -263.133886) (xy 342.964855 -263.094815)
			(xy 342.934831 -263.050778) (xy 342.911705 -263.002757) (xy 342.895995 -262.951827) (xy 342.888052 -262.899123)
			(xy 342.659472 -262.899123) (xy 342.651529 -262.951827) (xy 342.635819 -263.002757) (xy 342.612693 -263.050778)
			(xy 342.582669 -263.094815) (xy 342.546417 -263.133886) (xy 342.504746 -263.167117) (xy 342.458588 -263.193766)
			(xy 342.408974 -263.213238) (xy 342.357012 -263.225098) (xy 342.303862 -263.229082) (xy 342.250712 -263.225098)
			(xy 342.19875 -263.213238) (xy 342.149136 -263.193766) (xy 342.102978 -263.167117) (xy 342.061307 -263.133886)
			(xy 342.025055 -263.094815) (xy 341.995031 -263.050778) (xy 341.971905 -263.002757) (xy 341.956195 -262.951827)
			(xy 341.948252 -262.899123) (xy 341.719672 -262.899123) (xy 341.711729 -262.951827) (xy 341.696019 -263.002757)
			(xy 341.672893 -263.050778) (xy 341.642869 -263.094815) (xy 341.606617 -263.133886) (xy 341.564946 -263.167117)
			(xy 341.518788 -263.193766) (xy 341.469174 -263.213238) (xy 341.417212 -263.225098) (xy 341.364062 -263.229082)
			(xy 341.310912 -263.225098) (xy 341.25895 -263.213238) (xy 341.209336 -263.193766) (xy 341.163178 -263.167117)
			(xy 341.121507 -263.133886) (xy 341.085255 -263.094815) (xy 341.055231 -263.050778) (xy 341.032105 -263.002757)
			(xy 341.016395 -262.951827) (xy 341.008452 -262.899123) (xy 340.779872 -262.899123) (xy 340.771929 -262.951827)
			(xy 340.756219 -263.002757) (xy 340.733093 -263.050778) (xy 340.703069 -263.094815) (xy 340.666817 -263.133886)
			(xy 340.625146 -263.167117) (xy 340.578988 -263.193766) (xy 340.529374 -263.213238) (xy 340.477412 -263.225098)
			(xy 340.424262 -263.229082) (xy 340.371112 -263.225098) (xy 340.31915 -263.213238) (xy 340.269536 -263.193766)
			(xy 340.223378 -263.167117) (xy 340.181707 -263.133886) (xy 340.145455 -263.094815) (xy 340.115431 -263.050778)
			(xy 340.092305 -263.002757) (xy 340.076595 -262.951827) (xy 340.068652 -262.899123) (xy 339.839163 -262.899123)
			(xy 339.837174 -262.925661) (xy 339.825311 -262.977634) (xy 339.805833 -263.027258) (xy 339.779177 -263.073425)
			(xy 339.745936 -263.115102) (xy 339.706856 -263.15136) (xy 339.662807 -263.181388) (xy 339.614775 -263.204514)
			(xy 339.563832 -263.220223) (xy 339.511117 -263.228163) (xy 339.484462 -263.228582) (xy 339.481922 -263.228582)
			(xy 339.468535 -263.228891) (xy 339.442636 -263.235665) (xy 339.419389 -263.248939) (xy 339.400391 -263.267799)
			(xy 339.386948 -263.290949) (xy 339.379985 -263.316797) (xy 339.37956 -263.330182) (xy 339.37956 -263.713193)
			(xy 339.599006 -263.713193) (xy 339.599006 -263.659895) (xy 339.606949 -263.607191) (xy 339.622659 -263.556261)
			(xy 339.645785 -263.50824) (xy 339.675809 -263.464203) (xy 339.712061 -263.425132) (xy 339.753732 -263.391901)
			(xy 339.79989 -263.365252) (xy 339.849504 -263.34578) (xy 339.901466 -263.33392) (xy 339.954616 -263.329937)
			(xy 340.007766 -263.33392) (xy 340.059728 -263.34578) (xy 340.109342 -263.365252) (xy 340.1555 -263.391901)
			(xy 340.197171 -263.425132) (xy 340.233423 -263.464203) (xy 340.263447 -263.50824) (xy 340.286573 -263.556261)
			(xy 340.302283 -263.607191) (xy 340.310226 -263.659895) (xy 340.310724 -263.686544) (xy 340.310226 -263.713193)
			(xy 340.538806 -263.713193) (xy 340.538806 -263.659895) (xy 340.546749 -263.607191) (xy 340.562459 -263.556261)
			(xy 340.585585 -263.50824) (xy 340.615609 -263.464203) (xy 340.651861 -263.425132) (xy 340.693532 -263.391901)
			(xy 340.73969 -263.365252) (xy 340.789304 -263.34578) (xy 340.841266 -263.33392) (xy 340.894416 -263.329937)
			(xy 340.947566 -263.33392) (xy 340.999528 -263.34578) (xy 341.049142 -263.365252) (xy 341.0953 -263.391901)
			(xy 341.136971 -263.425132) (xy 341.173223 -263.464203) (xy 341.203247 -263.50824) (xy 341.226373 -263.556261)
			(xy 341.242083 -263.607191) (xy 341.250026 -263.659895) (xy 341.250524 -263.686544) (xy 341.250026 -263.713193)
			(xy 341.478606 -263.713193) (xy 341.478606 -263.659895) (xy 341.486549 -263.607191) (xy 341.502259 -263.556261)
			(xy 341.525385 -263.50824) (xy 341.555409 -263.464203) (xy 341.591661 -263.425132) (xy 341.633332 -263.391901)
			(xy 341.67949 -263.365252) (xy 341.729104 -263.34578) (xy 341.781066 -263.33392) (xy 341.834216 -263.329937)
			(xy 341.887366 -263.33392) (xy 341.939328 -263.34578) (xy 341.988942 -263.365252) (xy 342.0351 -263.391901)
			(xy 342.076771 -263.425132) (xy 342.113023 -263.464203) (xy 342.143047 -263.50824) (xy 342.166173 -263.556261)
			(xy 342.181883 -263.607191) (xy 342.189826 -263.659895) (xy 342.190324 -263.686544) (xy 342.189826 -263.713193)
			(xy 342.418152 -263.713193) (xy 342.418152 -263.659895) (xy 342.426095 -263.607191) (xy 342.441805 -263.556261)
			(xy 342.464931 -263.50824) (xy 342.494955 -263.464203) (xy 342.531207 -263.425132) (xy 342.572878 -263.391901)
			(xy 342.619036 -263.365252) (xy 342.66865 -263.34578) (xy 342.720612 -263.33392) (xy 342.773762 -263.329937)
			(xy 342.826912 -263.33392) (xy 342.878874 -263.34578) (xy 342.928488 -263.365252) (xy 342.974646 -263.391901)
			(xy 343.016317 -263.425132) (xy 343.052569 -263.464203) (xy 343.082593 -263.50824) (xy 343.105719 -263.556261)
			(xy 343.121429 -263.607191) (xy 343.129372 -263.659895) (xy 343.12987 -263.686544) (xy 343.129372 -263.713193)
			(xy 343.358206 -263.713193) (xy 343.358206 -263.659895) (xy 343.366149 -263.607191) (xy 343.381859 -263.556261)
			(xy 343.404985 -263.50824) (xy 343.435009 -263.464203) (xy 343.471261 -263.425132) (xy 343.512932 -263.391901)
			(xy 343.55909 -263.365252) (xy 343.608704 -263.34578) (xy 343.660666 -263.33392) (xy 343.713816 -263.329937)
			(xy 343.766966 -263.33392) (xy 343.818928 -263.34578) (xy 343.868542 -263.365252) (xy 343.9147 -263.391901)
			(xy 343.956371 -263.425132) (xy 343.992623 -263.464203) (xy 344.022647 -263.50824) (xy 344.045773 -263.556261)
			(xy 344.061483 -263.607191) (xy 344.069426 -263.659895) (xy 344.069924 -263.686544) (xy 344.069426 -263.713193)
			(xy 344.298006 -263.713193) (xy 344.298006 -263.659895) (xy 344.305949 -263.607191) (xy 344.321659 -263.556261)
			(xy 344.344785 -263.50824) (xy 344.374809 -263.464203) (xy 344.411061 -263.425132) (xy 344.452732 -263.391901)
			(xy 344.49889 -263.365252) (xy 344.548504 -263.34578) (xy 344.600466 -263.33392) (xy 344.653616 -263.329937)
			(xy 344.706766 -263.33392) (xy 344.758728 -263.34578) (xy 344.808342 -263.365252) (xy 344.8545 -263.391901)
			(xy 344.896171 -263.425132) (xy 344.932423 -263.464203) (xy 344.962447 -263.50824) (xy 344.985573 -263.556261)
			(xy 345.001283 -263.607191) (xy 345.009226 -263.659895) (xy 345.009724 -263.686544) (xy 345.009226 -263.713193)
			(xy 345.237806 -263.713193) (xy 345.237806 -263.659895) (xy 345.245749 -263.607191) (xy 345.261459 -263.556261)
			(xy 345.284585 -263.50824) (xy 345.314609 -263.464203) (xy 345.350861 -263.425132) (xy 345.392532 -263.391901)
			(xy 345.43869 -263.365252) (xy 345.488304 -263.34578) (xy 345.540266 -263.33392) (xy 345.593416 -263.329937)
			(xy 345.646566 -263.33392) (xy 345.698528 -263.34578) (xy 345.748142 -263.365252) (xy 345.7943 -263.391901)
			(xy 345.835971 -263.425132) (xy 345.872223 -263.464203) (xy 345.902247 -263.50824) (xy 345.925373 -263.556261)
			(xy 345.941083 -263.607191) (xy 345.949026 -263.659895) (xy 345.949524 -263.686544) (xy 345.949026 -263.713193)
			(xy 346.177606 -263.713193) (xy 346.177606 -263.659895) (xy 346.185549 -263.607191) (xy 346.201259 -263.556261)
			(xy 346.224385 -263.50824) (xy 346.254409 -263.464203) (xy 346.290661 -263.425132) (xy 346.332332 -263.391901)
			(xy 346.37849 -263.365252) (xy 346.428104 -263.34578) (xy 346.480066 -263.33392) (xy 346.533216 -263.329937)
			(xy 346.586366 -263.33392) (xy 346.638328 -263.34578) (xy 346.687942 -263.365252) (xy 346.7341 -263.391901)
			(xy 346.775771 -263.425132) (xy 346.812023 -263.464203) (xy 346.842047 -263.50824) (xy 346.865173 -263.556261)
			(xy 346.880883 -263.607191) (xy 346.888826 -263.659895) (xy 346.889324 -263.686544) (xy 346.888826 -263.713193)
			(xy 347.117406 -263.713193) (xy 347.117406 -263.659895) (xy 347.125349 -263.607191) (xy 347.141059 -263.556261)
			(xy 347.164185 -263.50824) (xy 347.194209 -263.464203) (xy 347.230461 -263.425132) (xy 347.272132 -263.391901)
			(xy 347.31829 -263.365252) (xy 347.367904 -263.34578) (xy 347.419866 -263.33392) (xy 347.473016 -263.329937)
			(xy 347.526166 -263.33392) (xy 347.578128 -263.34578) (xy 347.627742 -263.365252) (xy 347.6739 -263.391901)
			(xy 347.715571 -263.425132) (xy 347.751823 -263.464203) (xy 347.781847 -263.50824) (xy 347.804973 -263.556261)
			(xy 347.820683 -263.607191) (xy 347.828626 -263.659895) (xy 347.829124 -263.686544) (xy 347.828626 -263.713193)
			(xy 348.057206 -263.713193) (xy 348.057206 -263.659895) (xy 348.065149 -263.607191) (xy 348.080859 -263.556261)
			(xy 348.103985 -263.50824) (xy 348.134009 -263.464203) (xy 348.170261 -263.425132) (xy 348.211932 -263.391901)
			(xy 348.25809 -263.365252) (xy 348.307704 -263.34578) (xy 348.359666 -263.33392) (xy 348.412816 -263.329937)
			(xy 348.465966 -263.33392) (xy 348.517928 -263.34578) (xy 348.567542 -263.365252) (xy 348.6137 -263.391901)
			(xy 348.655371 -263.425132) (xy 348.691623 -263.464203) (xy 348.721647 -263.50824) (xy 348.744773 -263.556261)
			(xy 348.760483 -263.607191) (xy 348.768426 -263.659895) (xy 348.768924 -263.686544) (xy 348.768426 -263.713193)
			(xy 348.996752 -263.713193) (xy 348.996752 -263.659895) (xy 349.004695 -263.607191) (xy 349.020405 -263.556261)
			(xy 349.043531 -263.50824) (xy 349.073555 -263.464203) (xy 349.109807 -263.425132) (xy 349.151478 -263.391901)
			(xy 349.197636 -263.365252) (xy 349.24725 -263.34578) (xy 349.299212 -263.33392) (xy 349.352362 -263.329937)
			(xy 349.405512 -263.33392) (xy 349.457474 -263.34578) (xy 349.507088 -263.365252) (xy 349.553246 -263.391901)
			(xy 349.594917 -263.425132) (xy 349.631169 -263.464203) (xy 349.661193 -263.50824) (xy 349.684319 -263.556261)
			(xy 349.700029 -263.607191) (xy 349.707972 -263.659895) (xy 349.70847 -263.686544) (xy 349.707972 -263.713193)
			(xy 349.700029 -263.765897) (xy 349.684319 -263.816827) (xy 349.661193 -263.864848) (xy 349.631169 -263.908885)
			(xy 349.594917 -263.947956) (xy 349.553246 -263.981187) (xy 349.507088 -264.007836) (xy 349.457474 -264.027308)
			(xy 349.405512 -264.039168) (xy 349.352362 -264.043152) (xy 349.299212 -264.039168) (xy 349.24725 -264.027308)
			(xy 349.197636 -264.007836) (xy 349.151478 -263.981187) (xy 349.109807 -263.947956) (xy 349.073555 -263.908885)
			(xy 349.043531 -263.864848) (xy 349.020405 -263.816827) (xy 349.004695 -263.765897) (xy 348.996752 -263.713193)
			(xy 348.768426 -263.713193) (xy 348.760483 -263.765897) (xy 348.744773 -263.816827) (xy 348.721647 -263.864848)
			(xy 348.691623 -263.908885) (xy 348.655371 -263.947956) (xy 348.6137 -263.981187) (xy 348.567542 -264.007836)
			(xy 348.517928 -264.027308) (xy 348.465966 -264.039168) (xy 348.412816 -264.043152) (xy 348.359666 -264.039168)
			(xy 348.307704 -264.027308) (xy 348.25809 -264.007836) (xy 348.211932 -263.981187) (xy 348.170261 -263.947956)
			(xy 348.134009 -263.908885) (xy 348.103985 -263.864848) (xy 348.080859 -263.816827) (xy 348.065149 -263.765897)
			(xy 348.057206 -263.713193) (xy 347.828626 -263.713193) (xy 347.820683 -263.765897) (xy 347.804973 -263.816827)
			(xy 347.781847 -263.864848) (xy 347.751823 -263.908885) (xy 347.715571 -263.947956) (xy 347.6739 -263.981187)
			(xy 347.627742 -264.007836) (xy 347.578128 -264.027308) (xy 347.526166 -264.039168) (xy 347.473016 -264.043152)
			(xy 347.419866 -264.039168) (xy 347.367904 -264.027308) (xy 347.31829 -264.007836) (xy 347.272132 -263.981187)
			(xy 347.230461 -263.947956) (xy 347.194209 -263.908885) (xy 347.164185 -263.864848) (xy 347.141059 -263.816827)
			(xy 347.125349 -263.765897) (xy 347.117406 -263.713193) (xy 346.888826 -263.713193) (xy 346.880883 -263.765897)
			(xy 346.865173 -263.816827) (xy 346.842047 -263.864848) (xy 346.812023 -263.908885) (xy 346.775771 -263.947956)
			(xy 346.7341 -263.981187) (xy 346.687942 -264.007836) (xy 346.638328 -264.027308) (xy 346.586366 -264.039168)
			(xy 346.533216 -264.043152) (xy 346.480066 -264.039168) (xy 346.428104 -264.027308) (xy 346.37849 -264.007836)
			(xy 346.332332 -263.981187) (xy 346.290661 -263.947956) (xy 346.254409 -263.908885) (xy 346.224385 -263.864848)
			(xy 346.201259 -263.816827) (xy 346.185549 -263.765897) (xy 346.177606 -263.713193) (xy 345.949026 -263.713193)
			(xy 345.941083 -263.765897) (xy 345.925373 -263.816827) (xy 345.902247 -263.864848) (xy 345.872223 -263.908885)
			(xy 345.835971 -263.947956) (xy 345.7943 -263.981187) (xy 345.748142 -264.007836) (xy 345.698528 -264.027308)
			(xy 345.646566 -264.039168) (xy 345.593416 -264.043152) (xy 345.540266 -264.039168) (xy 345.488304 -264.027308)
			(xy 345.43869 -264.007836) (xy 345.392532 -263.981187) (xy 345.350861 -263.947956) (xy 345.314609 -263.908885)
			(xy 345.284585 -263.864848) (xy 345.261459 -263.816827) (xy 345.245749 -263.765897) (xy 345.237806 -263.713193)
			(xy 345.009226 -263.713193) (xy 345.001283 -263.765897) (xy 344.985573 -263.816827) (xy 344.962447 -263.864848)
			(xy 344.932423 -263.908885) (xy 344.896171 -263.947956) (xy 344.8545 -263.981187) (xy 344.808342 -264.007836)
			(xy 344.758728 -264.027308) (xy 344.706766 -264.039168) (xy 344.653616 -264.043152) (xy 344.600466 -264.039168)
			(xy 344.548504 -264.027308) (xy 344.49889 -264.007836) (xy 344.452732 -263.981187) (xy 344.411061 -263.947956)
			(xy 344.374809 -263.908885) (xy 344.344785 -263.864848) (xy 344.321659 -263.816827) (xy 344.305949 -263.765897)
			(xy 344.298006 -263.713193) (xy 344.069426 -263.713193) (xy 344.061483 -263.765897) (xy 344.045773 -263.816827)
			(xy 344.022647 -263.864848) (xy 343.992623 -263.908885) (xy 343.956371 -263.947956) (xy 343.9147 -263.981187)
			(xy 343.868542 -264.007836) (xy 343.818928 -264.027308) (xy 343.766966 -264.039168) (xy 343.713816 -264.043152)
			(xy 343.660666 -264.039168) (xy 343.608704 -264.027308) (xy 343.55909 -264.007836) (xy 343.512932 -263.981187)
			(xy 343.471261 -263.947956) (xy 343.435009 -263.908885) (xy 343.404985 -263.864848) (xy 343.381859 -263.816827)
			(xy 343.366149 -263.765897) (xy 343.358206 -263.713193) (xy 343.129372 -263.713193) (xy 343.121429 -263.765897)
			(xy 343.105719 -263.816827) (xy 343.082593 -263.864848) (xy 343.052569 -263.908885) (xy 343.016317 -263.947956)
			(xy 342.974646 -263.981187) (xy 342.928488 -264.007836) (xy 342.878874 -264.027308) (xy 342.826912 -264.039168)
			(xy 342.773762 -264.043152) (xy 342.720612 -264.039168) (xy 342.66865 -264.027308) (xy 342.619036 -264.007836)
			(xy 342.572878 -263.981187) (xy 342.531207 -263.947956) (xy 342.494955 -263.908885) (xy 342.464931 -263.864848)
			(xy 342.441805 -263.816827) (xy 342.426095 -263.765897) (xy 342.418152 -263.713193) (xy 342.189826 -263.713193)
			(xy 342.181883 -263.765897) (xy 342.166173 -263.816827) (xy 342.143047 -263.864848) (xy 342.113023 -263.908885)
			(xy 342.076771 -263.947956) (xy 342.0351 -263.981187) (xy 341.988942 -264.007836) (xy 341.939328 -264.027308)
			(xy 341.887366 -264.039168) (xy 341.834216 -264.043152) (xy 341.781066 -264.039168) (xy 341.729104 -264.027308)
			(xy 341.67949 -264.007836) (xy 341.633332 -263.981187) (xy 341.591661 -263.947956) (xy 341.555409 -263.908885)
			(xy 341.525385 -263.864848) (xy 341.502259 -263.816827) (xy 341.486549 -263.765897) (xy 341.478606 -263.713193)
			(xy 341.250026 -263.713193) (xy 341.242083 -263.765897) (xy 341.226373 -263.816827) (xy 341.203247 -263.864848)
			(xy 341.173223 -263.908885) (xy 341.136971 -263.947956) (xy 341.0953 -263.981187) (xy 341.049142 -264.007836)
			(xy 340.999528 -264.027308) (xy 340.947566 -264.039168) (xy 340.894416 -264.043152) (xy 340.841266 -264.039168)
			(xy 340.789304 -264.027308) (xy 340.73969 -264.007836) (xy 340.693532 -263.981187) (xy 340.651861 -263.947956)
			(xy 340.615609 -263.908885) (xy 340.585585 -263.864848) (xy 340.562459 -263.816827) (xy 340.546749 -263.765897)
			(xy 340.538806 -263.713193) (xy 340.310226 -263.713193) (xy 340.302283 -263.765897) (xy 340.286573 -263.816827)
			(xy 340.263447 -263.864848) (xy 340.233423 -263.908885) (xy 340.197171 -263.947956) (xy 340.1555 -263.981187)
			(xy 340.109342 -264.007836) (xy 340.059728 -264.027308) (xy 340.007766 -264.039168) (xy 339.954616 -264.043152)
			(xy 339.901466 -264.039168) (xy 339.849504 -264.027308) (xy 339.79989 -264.007836) (xy 339.753732 -263.981187)
			(xy 339.712061 -263.947956) (xy 339.675809 -263.908885) (xy 339.645785 -263.864848) (xy 339.622659 -263.816827)
			(xy 339.606949 -263.765897) (xy 339.599006 -263.713193) (xy 339.37956 -263.713193) (xy 339.37956 -264.042652)
			(xy 339.37997 -264.056036) (xy 339.38694 -264.081883) (xy 339.400387 -264.105029) (xy 339.419388 -264.123886)
			(xy 339.442636 -264.137157) (xy 339.468535 -264.14393) (xy 339.481922 -264.144252) (xy 339.484716 -264.144252)
			(xy 339.511368 -264.144751) (xy 339.564075 -264.152697) (xy 339.615009 -264.168411) (xy 339.663033 -264.19154)
			(xy 339.707073 -264.221567) (xy 339.746146 -264.257824) (xy 339.779379 -264.299498) (xy 339.80603 -264.345661)
			(xy 339.825504 -264.395279) (xy 339.837364 -264.447246) (xy 339.841348 -264.5004) (xy 339.839354 -264.527009)
			(xy 340.068652 -264.527009) (xy 340.068652 -264.473711) (xy 340.076595 -264.421007) (xy 340.092305 -264.370077)
			(xy 340.115431 -264.322056) (xy 340.145455 -264.278019) (xy 340.181707 -264.238948) (xy 340.223378 -264.205717)
			(xy 340.269536 -264.179068) (xy 340.31915 -264.159596) (xy 340.371112 -264.147736) (xy 340.424262 -264.143753)
			(xy 340.477412 -264.147736) (xy 340.529374 -264.159596) (xy 340.578988 -264.179068) (xy 340.625146 -264.205717)
			(xy 340.666817 -264.238948) (xy 340.703069 -264.278019) (xy 340.733093 -264.322056) (xy 340.756219 -264.370077)
			(xy 340.771929 -264.421007) (xy 340.779872 -264.473711) (xy 340.78037 -264.50036) (xy 340.779872 -264.527009)
			(xy 341.008452 -264.527009) (xy 341.008452 -264.473711) (xy 341.016395 -264.421007) (xy 341.032105 -264.370077)
			(xy 341.055231 -264.322056) (xy 341.085255 -264.278019) (xy 341.121507 -264.238948) (xy 341.163178 -264.205717)
			(xy 341.209336 -264.179068) (xy 341.25895 -264.159596) (xy 341.310912 -264.147736) (xy 341.364062 -264.143753)
			(xy 341.417212 -264.147736) (xy 341.469174 -264.159596) (xy 341.518788 -264.179068) (xy 341.564946 -264.205717)
			(xy 341.606617 -264.238948) (xy 341.642869 -264.278019) (xy 341.672893 -264.322056) (xy 341.696019 -264.370077)
			(xy 341.711729 -264.421007) (xy 341.719672 -264.473711) (xy 341.72017 -264.50036) (xy 341.719672 -264.527009)
			(xy 341.948252 -264.527009) (xy 341.948252 -264.473711) (xy 341.956195 -264.421007) (xy 341.971905 -264.370077)
			(xy 341.995031 -264.322056) (xy 342.025055 -264.278019) (xy 342.061307 -264.238948) (xy 342.102978 -264.205717)
			(xy 342.149136 -264.179068) (xy 342.19875 -264.159596) (xy 342.250712 -264.147736) (xy 342.303862 -264.143753)
			(xy 342.357012 -264.147736) (xy 342.408974 -264.159596) (xy 342.458588 -264.179068) (xy 342.504746 -264.205717)
			(xy 342.546417 -264.238948) (xy 342.582669 -264.278019) (xy 342.612693 -264.322056) (xy 342.635819 -264.370077)
			(xy 342.651529 -264.421007) (xy 342.659472 -264.473711) (xy 342.65997 -264.50036) (xy 342.659472 -264.527009)
			(xy 342.888052 -264.527009) (xy 342.888052 -264.473711) (xy 342.895995 -264.421007) (xy 342.911705 -264.370077)
			(xy 342.934831 -264.322056) (xy 342.964855 -264.278019) (xy 343.001107 -264.238948) (xy 343.042778 -264.205717)
			(xy 343.088936 -264.179068) (xy 343.13855 -264.159596) (xy 343.190512 -264.147736) (xy 343.243662 -264.143753)
			(xy 343.296812 -264.147736) (xy 343.348774 -264.159596) (xy 343.398388 -264.179068) (xy 343.444546 -264.205717)
			(xy 343.486217 -264.238948) (xy 343.522469 -264.278019) (xy 343.552493 -264.322056) (xy 343.575619 -264.370077)
			(xy 343.591329 -264.421007) (xy 343.599272 -264.473711) (xy 343.59977 -264.50036) (xy 343.599272 -264.527009)
			(xy 343.827852 -264.527009) (xy 343.827852 -264.473711) (xy 343.835795 -264.421007) (xy 343.851505 -264.370077)
			(xy 343.874631 -264.322056) (xy 343.904655 -264.278019) (xy 343.940907 -264.238948) (xy 343.982578 -264.205717)
			(xy 344.028736 -264.179068) (xy 344.07835 -264.159596) (xy 344.130312 -264.147736) (xy 344.183462 -264.143753)
			(xy 344.236612 -264.147736) (xy 344.288574 -264.159596) (xy 344.338188 -264.179068) (xy 344.384346 -264.205717)
			(xy 344.426017 -264.238948) (xy 344.462269 -264.278019) (xy 344.492293 -264.322056) (xy 344.515419 -264.370077)
			(xy 344.531129 -264.421007) (xy 344.539072 -264.473711) (xy 344.53957 -264.50036) (xy 344.539072 -264.527009)
			(xy 344.767652 -264.527009) (xy 344.767652 -264.473711) (xy 344.775595 -264.421007) (xy 344.791305 -264.370077)
			(xy 344.814431 -264.322056) (xy 344.844455 -264.278019) (xy 344.880707 -264.238948) (xy 344.922378 -264.205717)
			(xy 344.968536 -264.179068) (xy 345.01815 -264.159596) (xy 345.070112 -264.147736) (xy 345.123262 -264.143753)
			(xy 345.176412 -264.147736) (xy 345.228374 -264.159596) (xy 345.277988 -264.179068) (xy 345.324146 -264.205717)
			(xy 345.365817 -264.238948) (xy 345.402069 -264.278019) (xy 345.432093 -264.322056) (xy 345.455219 -264.370077)
			(xy 345.470929 -264.421007) (xy 345.478872 -264.473711) (xy 345.47937 -264.50036) (xy 345.478872 -264.527009)
			(xy 345.707706 -264.527009) (xy 345.707706 -264.473711) (xy 345.715649 -264.421007) (xy 345.731359 -264.370077)
			(xy 345.754485 -264.322056) (xy 345.784509 -264.278019) (xy 345.820761 -264.238948) (xy 345.862432 -264.205717)
			(xy 345.90859 -264.179068) (xy 345.958204 -264.159596) (xy 346.010166 -264.147736) (xy 346.063316 -264.143753)
			(xy 346.116466 -264.147736) (xy 346.168428 -264.159596) (xy 346.218042 -264.179068) (xy 346.2642 -264.205717)
			(xy 346.305871 -264.238948) (xy 346.342123 -264.278019) (xy 346.372147 -264.322056) (xy 346.395273 -264.370077)
			(xy 346.410983 -264.421007) (xy 346.418926 -264.473711) (xy 346.419424 -264.50036) (xy 346.418926 -264.527009)
			(xy 346.647252 -264.527009) (xy 346.647252 -264.473711) (xy 346.655195 -264.421007) (xy 346.670905 -264.370077)
			(xy 346.694031 -264.322056) (xy 346.724055 -264.278019) (xy 346.760307 -264.238948) (xy 346.801978 -264.205717)
			(xy 346.848136 -264.179068) (xy 346.89775 -264.159596) (xy 346.949712 -264.147736) (xy 347.002862 -264.143753)
			(xy 347.056012 -264.147736) (xy 347.107974 -264.159596) (xy 347.157588 -264.179068) (xy 347.203746 -264.205717)
			(xy 347.245417 -264.238948) (xy 347.281669 -264.278019) (xy 347.311693 -264.322056) (xy 347.334819 -264.370077)
			(xy 347.350529 -264.421007) (xy 347.358472 -264.473711) (xy 347.35897 -264.50036) (xy 347.358472 -264.527009)
			(xy 347.587052 -264.527009) (xy 347.587052 -264.473711) (xy 347.594995 -264.421007) (xy 347.610705 -264.370077)
			(xy 347.633831 -264.322056) (xy 347.663855 -264.278019) (xy 347.700107 -264.238948) (xy 347.741778 -264.205717)
			(xy 347.787936 -264.179068) (xy 347.83755 -264.159596) (xy 347.889512 -264.147736) (xy 347.942662 -264.143753)
			(xy 347.995812 -264.147736) (xy 348.047774 -264.159596) (xy 348.097388 -264.179068) (xy 348.143546 -264.205717)
			(xy 348.185217 -264.238948) (xy 348.221469 -264.278019) (xy 348.251493 -264.322056) (xy 348.274619 -264.370077)
			(xy 348.290329 -264.421007) (xy 348.298272 -264.473711) (xy 348.29877 -264.50036) (xy 348.298272 -264.527009)
			(xy 348.526852 -264.527009) (xy 348.526852 -264.473711) (xy 348.534795 -264.421007) (xy 348.550505 -264.370077)
			(xy 348.573631 -264.322056) (xy 348.603655 -264.278019) (xy 348.639907 -264.238948) (xy 348.681578 -264.205717)
			(xy 348.727736 -264.179068) (xy 348.77735 -264.159596) (xy 348.829312 -264.147736) (xy 348.882462 -264.143753)
			(xy 348.935612 -264.147736) (xy 348.987574 -264.159596) (xy 349.037188 -264.179068) (xy 349.083346 -264.205717)
			(xy 349.125017 -264.238948) (xy 349.161269 -264.278019) (xy 349.191293 -264.322056) (xy 349.214419 -264.370077)
			(xy 349.230129 -264.421007) (xy 349.238072 -264.473711) (xy 349.23857 -264.50036) (xy 349.238072 -264.527009)
			(xy 349.466652 -264.527009) (xy 349.466652 -264.473711) (xy 349.474595 -264.421007) (xy 349.490305 -264.370077)
			(xy 349.513431 -264.322056) (xy 349.543455 -264.278019) (xy 349.579707 -264.238948) (xy 349.621378 -264.205717)
			(xy 349.667536 -264.179068) (xy 349.71715 -264.159596) (xy 349.769112 -264.147736) (xy 349.822262 -264.143753)
			(xy 349.875412 -264.147736) (xy 349.927374 -264.159596) (xy 349.976988 -264.179068) (xy 350.023146 -264.205717)
			(xy 350.064817 -264.238948) (xy 350.101069 -264.278019) (xy 350.131093 -264.322056) (xy 350.154219 -264.370077)
			(xy 350.169929 -264.421007) (xy 350.177872 -264.473711) (xy 350.17837 -264.50036) (xy 350.177872 -264.527009)
			(xy 350.169929 -264.579713) (xy 350.154219 -264.630643) (xy 350.131093 -264.678664) (xy 350.101069 -264.722701)
			(xy 350.064817 -264.761772) (xy 350.023146 -264.795003) (xy 349.976988 -264.821652) (xy 349.927374 -264.841124)
			(xy 349.875412 -264.852984) (xy 349.822262 -264.856968) (xy 349.769112 -264.852984) (xy 349.71715 -264.841124)
			(xy 349.667536 -264.821652) (xy 349.621378 -264.795003) (xy 349.579707 -264.761772) (xy 349.543455 -264.722701)
			(xy 349.513431 -264.678664) (xy 349.490305 -264.630643) (xy 349.474595 -264.579713) (xy 349.466652 -264.527009)
			(xy 349.238072 -264.527009) (xy 349.230129 -264.579713) (xy 349.214419 -264.630643) (xy 349.191293 -264.678664)
			(xy 349.161269 -264.722701) (xy 349.125017 -264.761772) (xy 349.083346 -264.795003) (xy 349.037188 -264.821652)
			(xy 348.987574 -264.841124) (xy 348.935612 -264.852984) (xy 348.882462 -264.856968) (xy 348.829312 -264.852984)
			(xy 348.77735 -264.841124) (xy 348.727736 -264.821652) (xy 348.681578 -264.795003) (xy 348.639907 -264.761772)
			(xy 348.603655 -264.722701) (xy 348.573631 -264.678664) (xy 348.550505 -264.630643) (xy 348.534795 -264.579713)
			(xy 348.526852 -264.527009) (xy 348.298272 -264.527009) (xy 348.290329 -264.579713) (xy 348.274619 -264.630643)
			(xy 348.251493 -264.678664) (xy 348.221469 -264.722701) (xy 348.185217 -264.761772) (xy 348.143546 -264.795003)
			(xy 348.097388 -264.821652) (xy 348.047774 -264.841124) (xy 347.995812 -264.852984) (xy 347.942662 -264.856968)
			(xy 347.889512 -264.852984) (xy 347.83755 -264.841124) (xy 347.787936 -264.821652) (xy 347.741778 -264.795003)
			(xy 347.700107 -264.761772) (xy 347.663855 -264.722701) (xy 347.633831 -264.678664) (xy 347.610705 -264.630643)
			(xy 347.594995 -264.579713) (xy 347.587052 -264.527009) (xy 347.358472 -264.527009) (xy 347.350529 -264.579713)
			(xy 347.334819 -264.630643) (xy 347.311693 -264.678664) (xy 347.281669 -264.722701) (xy 347.245417 -264.761772)
			(xy 347.203746 -264.795003) (xy 347.157588 -264.821652) (xy 347.107974 -264.841124) (xy 347.056012 -264.852984)
			(xy 347.002862 -264.856968) (xy 346.949712 -264.852984) (xy 346.89775 -264.841124) (xy 346.848136 -264.821652)
			(xy 346.801978 -264.795003) (xy 346.760307 -264.761772) (xy 346.724055 -264.722701) (xy 346.694031 -264.678664)
			(xy 346.670905 -264.630643) (xy 346.655195 -264.579713) (xy 346.647252 -264.527009) (xy 346.418926 -264.527009)
			(xy 346.410983 -264.579713) (xy 346.395273 -264.630643) (xy 346.372147 -264.678664) (xy 346.342123 -264.722701)
			(xy 346.305871 -264.761772) (xy 346.2642 -264.795003) (xy 346.218042 -264.821652) (xy 346.168428 -264.841124)
			(xy 346.116466 -264.852984) (xy 346.063316 -264.856968) (xy 346.010166 -264.852984) (xy 345.958204 -264.841124)
			(xy 345.90859 -264.821652) (xy 345.862432 -264.795003) (xy 345.820761 -264.761772) (xy 345.784509 -264.722701)
			(xy 345.754485 -264.678664) (xy 345.731359 -264.630643) (xy 345.715649 -264.579713) (xy 345.707706 -264.527009)
			(xy 345.478872 -264.527009) (xy 345.470929 -264.579713) (xy 345.455219 -264.630643) (xy 345.432093 -264.678664)
			(xy 345.402069 -264.722701) (xy 345.365817 -264.761772) (xy 345.324146 -264.795003) (xy 345.277988 -264.821652)
			(xy 345.228374 -264.841124) (xy 345.176412 -264.852984) (xy 345.123262 -264.856968) (xy 345.070112 -264.852984)
			(xy 345.01815 -264.841124) (xy 344.968536 -264.821652) (xy 344.922378 -264.795003) (xy 344.880707 -264.761772)
			(xy 344.844455 -264.722701) (xy 344.814431 -264.678664) (xy 344.791305 -264.630643) (xy 344.775595 -264.579713)
			(xy 344.767652 -264.527009) (xy 344.539072 -264.527009) (xy 344.531129 -264.579713) (xy 344.515419 -264.630643)
			(xy 344.492293 -264.678664) (xy 344.462269 -264.722701) (xy 344.426017 -264.761772) (xy 344.384346 -264.795003)
			(xy 344.338188 -264.821652) (xy 344.288574 -264.841124) (xy 344.236612 -264.852984) (xy 344.183462 -264.856968)
			(xy 344.130312 -264.852984) (xy 344.07835 -264.841124) (xy 344.028736 -264.821652) (xy 343.982578 -264.795003)
			(xy 343.940907 -264.761772) (xy 343.904655 -264.722701) (xy 343.874631 -264.678664) (xy 343.851505 -264.630643)
			(xy 343.835795 -264.579713) (xy 343.827852 -264.527009) (xy 343.599272 -264.527009) (xy 343.591329 -264.579713)
			(xy 343.575619 -264.630643) (xy 343.552493 -264.678664) (xy 343.522469 -264.722701) (xy 343.486217 -264.761772)
			(xy 343.444546 -264.795003) (xy 343.398388 -264.821652) (xy 343.348774 -264.841124) (xy 343.296812 -264.852984)
			(xy 343.243662 -264.856968) (xy 343.190512 -264.852984) (xy 343.13855 -264.841124) (xy 343.088936 -264.821652)
			(xy 343.042778 -264.795003) (xy 343.001107 -264.761772) (xy 342.964855 -264.722701) (xy 342.934831 -264.678664)
			(xy 342.911705 -264.630643) (xy 342.895995 -264.579713) (xy 342.888052 -264.527009) (xy 342.659472 -264.527009)
			(xy 342.651529 -264.579713) (xy 342.635819 -264.630643) (xy 342.612693 -264.678664) (xy 342.582669 -264.722701)
			(xy 342.546417 -264.761772) (xy 342.504746 -264.795003) (xy 342.458588 -264.821652) (xy 342.408974 -264.841124)
			(xy 342.357012 -264.852984) (xy 342.303862 -264.856968) (xy 342.250712 -264.852984) (xy 342.19875 -264.841124)
			(xy 342.149136 -264.821652) (xy 342.102978 -264.795003) (xy 342.061307 -264.761772) (xy 342.025055 -264.722701)
			(xy 341.995031 -264.678664) (xy 341.971905 -264.630643) (xy 341.956195 -264.579713) (xy 341.948252 -264.527009)
			(xy 341.719672 -264.527009) (xy 341.711729 -264.579713) (xy 341.696019 -264.630643) (xy 341.672893 -264.678664)
			(xy 341.642869 -264.722701) (xy 341.606617 -264.761772) (xy 341.564946 -264.795003) (xy 341.518788 -264.821652)
			(xy 341.469174 -264.841124) (xy 341.417212 -264.852984) (xy 341.364062 -264.856968) (xy 341.310912 -264.852984)
			(xy 341.25895 -264.841124) (xy 341.209336 -264.821652) (xy 341.163178 -264.795003) (xy 341.121507 -264.761772)
			(xy 341.085255 -264.722701) (xy 341.055231 -264.678664) (xy 341.032105 -264.630643) (xy 341.016395 -264.579713)
			(xy 341.008452 -264.527009) (xy 340.779872 -264.527009) (xy 340.771929 -264.579713) (xy 340.756219 -264.630643)
			(xy 340.733093 -264.678664) (xy 340.703069 -264.722701) (xy 340.666817 -264.761772) (xy 340.625146 -264.795003)
			(xy 340.578988 -264.821652) (xy 340.529374 -264.841124) (xy 340.477412 -264.852984) (xy 340.424262 -264.856968)
			(xy 340.371112 -264.852984) (xy 340.31915 -264.841124) (xy 340.269536 -264.821652) (xy 340.223378 -264.795003)
			(xy 340.181707 -264.761772) (xy 340.145455 -264.722701) (xy 340.115431 -264.678664) (xy 340.092305 -264.630643)
			(xy 340.076595 -264.579713) (xy 340.068652 -264.527009) (xy 339.839354 -264.527009) (xy 339.837364 -264.553554)
			(xy 339.825504 -264.605521) (xy 339.80603 -264.655139) (xy 339.779379 -264.701302) (xy 339.746146 -264.742976)
			(xy 339.707073 -264.779233) (xy 339.663033 -264.80926) (xy 339.615009 -264.832389) (xy 339.564075 -264.848103)
			(xy 339.511368 -264.856049) (xy 339.484716 -264.856468) (xy 339.481922 -264.856468) (xy 339.468534 -264.856776)
			(xy 339.442634 -264.86355) (xy 339.419385 -264.876824) (xy 339.400384 -264.895683) (xy 339.386939 -264.918833)
			(xy 339.379973 -264.944682) (xy 339.37956 -264.958068) (xy 339.37956 -265.340825) (xy 339.598752 -265.340825)
			(xy 339.598752 -265.287527) (xy 339.606695 -265.234823) (xy 339.622405 -265.183893) (xy 339.645531 -265.135872)
			(xy 339.675555 -265.091835) (xy 339.711807 -265.052764) (xy 339.753478 -265.019533) (xy 339.799636 -264.992884)
			(xy 339.84925 -264.973412) (xy 339.901212 -264.961552) (xy 339.954362 -264.957569) (xy 340.007512 -264.961552)
			(xy 340.059474 -264.973412) (xy 340.109088 -264.992884) (xy 340.155246 -265.019533) (xy 340.196917 -265.052764)
			(xy 340.233169 -265.091835) (xy 340.263193 -265.135872) (xy 340.286319 -265.183893) (xy 340.302029 -265.234823)
			(xy 340.309972 -265.287527) (xy 340.31047 -265.314176) (xy 340.309972 -265.340825) (xy 340.538806 -265.340825)
			(xy 340.538806 -265.287527) (xy 340.546749 -265.234823) (xy 340.562459 -265.183893) (xy 340.585585 -265.135872)
			(xy 340.615609 -265.091835) (xy 340.651861 -265.052764) (xy 340.693532 -265.019533) (xy 340.73969 -264.992884)
			(xy 340.789304 -264.973412) (xy 340.841266 -264.961552) (xy 340.894416 -264.957569) (xy 340.947566 -264.961552)
			(xy 340.999528 -264.973412) (xy 341.049142 -264.992884) (xy 341.0953 -265.019533) (xy 341.136971 -265.052764)
			(xy 341.173223 -265.091835) (xy 341.203247 -265.135872) (xy 341.226373 -265.183893) (xy 341.242083 -265.234823)
			(xy 341.250026 -265.287527) (xy 341.250524 -265.314176) (xy 341.250026 -265.340825) (xy 341.478606 -265.340825)
			(xy 341.478606 -265.287527) (xy 341.486549 -265.234823) (xy 341.502259 -265.183893) (xy 341.525385 -265.135872)
			(xy 341.555409 -265.091835) (xy 341.591661 -265.052764) (xy 341.633332 -265.019533) (xy 341.67949 -264.992884)
			(xy 341.729104 -264.973412) (xy 341.781066 -264.961552) (xy 341.834216 -264.957569) (xy 341.887366 -264.961552)
			(xy 341.939328 -264.973412) (xy 341.988942 -264.992884) (xy 342.0351 -265.019533) (xy 342.076771 -265.052764)
			(xy 342.113023 -265.091835) (xy 342.143047 -265.135872) (xy 342.166173 -265.183893) (xy 342.181883 -265.234823)
			(xy 342.189826 -265.287527) (xy 342.190324 -265.314176) (xy 342.189826 -265.340825) (xy 342.418406 -265.340825)
			(xy 342.418406 -265.287527) (xy 342.426349 -265.234823) (xy 342.442059 -265.183893) (xy 342.465185 -265.135872)
			(xy 342.495209 -265.091835) (xy 342.531461 -265.052764) (xy 342.573132 -265.019533) (xy 342.61929 -264.992884)
			(xy 342.668904 -264.973412) (xy 342.720866 -264.961552) (xy 342.774016 -264.957569) (xy 342.827166 -264.961552)
			(xy 342.879128 -264.973412) (xy 342.928742 -264.992884) (xy 342.9749 -265.019533) (xy 343.016571 -265.052764)
			(xy 343.052823 -265.091835) (xy 343.082847 -265.135872) (xy 343.105973 -265.183893) (xy 343.121683 -265.234823)
			(xy 343.129626 -265.287527) (xy 343.130124 -265.314176) (xy 343.129626 -265.340825) (xy 343.358206 -265.340825)
			(xy 343.358206 -265.287527) (xy 343.366149 -265.234823) (xy 343.381859 -265.183893) (xy 343.404985 -265.135872)
			(xy 343.435009 -265.091835) (xy 343.471261 -265.052764) (xy 343.512932 -265.019533) (xy 343.55909 -264.992884)
			(xy 343.608704 -264.973412) (xy 343.660666 -264.961552) (xy 343.713816 -264.957569) (xy 343.766966 -264.961552)
			(xy 343.818928 -264.973412) (xy 343.868542 -264.992884) (xy 343.9147 -265.019533) (xy 343.956371 -265.052764)
			(xy 343.992623 -265.091835) (xy 344.022647 -265.135872) (xy 344.045773 -265.183893) (xy 344.061483 -265.234823)
			(xy 344.069426 -265.287527) (xy 344.069924 -265.314176) (xy 344.069426 -265.340825) (xy 344.298006 -265.340825)
			(xy 344.298006 -265.287527) (xy 344.305949 -265.234823) (xy 344.321659 -265.183893) (xy 344.344785 -265.135872)
			(xy 344.374809 -265.091835) (xy 344.411061 -265.052764) (xy 344.452732 -265.019533) (xy 344.49889 -264.992884)
			(xy 344.548504 -264.973412) (xy 344.600466 -264.961552) (xy 344.653616 -264.957569) (xy 344.706766 -264.961552)
			(xy 344.758728 -264.973412) (xy 344.808342 -264.992884) (xy 344.8545 -265.019533) (xy 344.896171 -265.052764)
			(xy 344.932423 -265.091835) (xy 344.962447 -265.135872) (xy 344.985573 -265.183893) (xy 345.001283 -265.234823)
			(xy 345.009226 -265.287527) (xy 345.009724 -265.314176) (xy 345.009226 -265.340825) (xy 345.237806 -265.340825)
			(xy 345.237806 -265.287527) (xy 345.245749 -265.234823) (xy 345.261459 -265.183893) (xy 345.284585 -265.135872)
			(xy 345.314609 -265.091835) (xy 345.350861 -265.052764) (xy 345.392532 -265.019533) (xy 345.43869 -264.992884)
			(xy 345.488304 -264.973412) (xy 345.540266 -264.961552) (xy 345.593416 -264.957569) (xy 345.646566 -264.961552)
			(xy 345.698528 -264.973412) (xy 345.748142 -264.992884) (xy 345.7943 -265.019533) (xy 345.835971 -265.052764)
			(xy 345.872223 -265.091835) (xy 345.902247 -265.135872) (xy 345.925373 -265.183893) (xy 345.941083 -265.234823)
			(xy 345.949026 -265.287527) (xy 345.949524 -265.314176) (xy 345.949026 -265.340825) (xy 346.177352 -265.340825)
			(xy 346.177352 -265.287527) (xy 346.185295 -265.234823) (xy 346.201005 -265.183893) (xy 346.224131 -265.135872)
			(xy 346.254155 -265.091835) (xy 346.290407 -265.052764) (xy 346.332078 -265.019533) (xy 346.378236 -264.992884)
			(xy 346.42785 -264.973412) (xy 346.479812 -264.961552) (xy 346.532962 -264.957569) (xy 346.586112 -264.961552)
			(xy 346.638074 -264.973412) (xy 346.687688 -264.992884) (xy 346.733846 -265.019533) (xy 346.775517 -265.052764)
			(xy 346.811769 -265.091835) (xy 346.841793 -265.135872) (xy 346.864919 -265.183893) (xy 346.880629 -265.234823)
			(xy 346.888572 -265.287527) (xy 346.88907 -265.314176) (xy 346.888572 -265.340825) (xy 347.117406 -265.340825)
			(xy 347.117406 -265.287527) (xy 347.125349 -265.234823) (xy 347.141059 -265.183893) (xy 347.164185 -265.135872)
			(xy 347.194209 -265.091835) (xy 347.230461 -265.052764) (xy 347.272132 -265.019533) (xy 347.31829 -264.992884)
			(xy 347.367904 -264.973412) (xy 347.419866 -264.961552) (xy 347.473016 -264.957569) (xy 347.526166 -264.961552)
			(xy 347.578128 -264.973412) (xy 347.627742 -264.992884) (xy 347.6739 -265.019533) (xy 347.715571 -265.052764)
			(xy 347.751823 -265.091835) (xy 347.781847 -265.135872) (xy 347.804973 -265.183893) (xy 347.820683 -265.234823)
			(xy 347.828626 -265.287527) (xy 347.829124 -265.314176) (xy 347.828626 -265.340825) (xy 348.057206 -265.340825)
			(xy 348.057206 -265.287527) (xy 348.065149 -265.234823) (xy 348.080859 -265.183893) (xy 348.103985 -265.135872)
			(xy 348.134009 -265.091835) (xy 348.170261 -265.052764) (xy 348.211932 -265.019533) (xy 348.25809 -264.992884)
			(xy 348.307704 -264.973412) (xy 348.359666 -264.961552) (xy 348.412816 -264.957569) (xy 348.465966 -264.961552)
			(xy 348.517928 -264.973412) (xy 348.567542 -264.992884) (xy 348.6137 -265.019533) (xy 348.655371 -265.052764)
			(xy 348.691623 -265.091835) (xy 348.721647 -265.135872) (xy 348.744773 -265.183893) (xy 348.760483 -265.234823)
			(xy 348.768426 -265.287527) (xy 348.768924 -265.314176) (xy 348.768426 -265.340825) (xy 348.997006 -265.340825)
			(xy 348.997006 -265.287527) (xy 349.004949 -265.234823) (xy 349.020659 -265.183893) (xy 349.043785 -265.135872)
			(xy 349.073809 -265.091835) (xy 349.110061 -265.052764) (xy 349.151732 -265.019533) (xy 349.19789 -264.992884)
			(xy 349.247504 -264.973412) (xy 349.299466 -264.961552) (xy 349.352616 -264.957569) (xy 349.405766 -264.961552)
			(xy 349.457728 -264.973412) (xy 349.507342 -264.992884) (xy 349.5535 -265.019533) (xy 349.595171 -265.052764)
			(xy 349.631423 -265.091835) (xy 349.661447 -265.135872) (xy 349.684573 -265.183893) (xy 349.700283 -265.234823)
			(xy 349.708226 -265.287527) (xy 349.708724 -265.314176) (xy 349.708226 -265.340825) (xy 349.936806 -265.340825)
			(xy 349.936806 -265.287527) (xy 349.944749 -265.234823) (xy 349.960459 -265.183893) (xy 349.983585 -265.135872)
			(xy 350.013609 -265.091835) (xy 350.049861 -265.052764) (xy 350.091532 -265.019533) (xy 350.13769 -264.992884)
			(xy 350.187304 -264.973412) (xy 350.239266 -264.961552) (xy 350.292416 -264.957569) (xy 350.345566 -264.961552)
			(xy 350.397528 -264.973412) (xy 350.447142 -264.992884) (xy 350.4933 -265.019533) (xy 350.534971 -265.052764)
			(xy 350.571223 -265.091835) (xy 350.601247 -265.135872) (xy 350.624373 -265.183893) (xy 350.640083 -265.234823)
			(xy 350.648026 -265.287527) (xy 350.648524 -265.314176) (xy 350.648026 -265.340825) (xy 350.876606 -265.340825)
			(xy 350.876606 -265.287527) (xy 350.884549 -265.234823) (xy 350.900259 -265.183893) (xy 350.923385 -265.135872)
			(xy 350.953409 -265.091835) (xy 350.989661 -265.052764) (xy 351.031332 -265.019533) (xy 351.07749 -264.992884)
			(xy 351.127104 -264.973412) (xy 351.179066 -264.961552) (xy 351.232216 -264.957569) (xy 351.285366 -264.961552)
			(xy 351.337328 -264.973412) (xy 351.386942 -264.992884) (xy 351.4331 -265.019533) (xy 351.474771 -265.052764)
			(xy 351.511023 -265.091835) (xy 351.541047 -265.135872) (xy 351.564173 -265.183893) (xy 351.579883 -265.234823)
			(xy 351.587826 -265.287527) (xy 351.588324 -265.314176) (xy 351.587826 -265.340825) (xy 351.816406 -265.340825)
			(xy 351.816406 -265.287527) (xy 351.824349 -265.234823) (xy 351.840059 -265.183893) (xy 351.863185 -265.135872)
			(xy 351.893209 -265.091835) (xy 351.929461 -265.052764) (xy 351.971132 -265.019533) (xy 352.01729 -264.992884)
			(xy 352.066904 -264.973412) (xy 352.118866 -264.961552) (xy 352.172016 -264.957569) (xy 352.225166 -264.961552)
			(xy 352.277128 -264.973412) (xy 352.326742 -264.992884) (xy 352.3729 -265.019533) (xy 352.414571 -265.052764)
			(xy 352.450823 -265.091835) (xy 352.480847 -265.135872) (xy 352.503973 -265.183893) (xy 352.519683 -265.234823)
			(xy 352.527626 -265.287527) (xy 352.528124 -265.314176) (xy 352.527626 -265.340825) (xy 352.756206 -265.340825)
			(xy 352.756206 -265.287527) (xy 352.764149 -265.234823) (xy 352.779859 -265.183893) (xy 352.802985 -265.135872)
			(xy 352.833009 -265.091835) (xy 352.869261 -265.052764) (xy 352.910932 -265.019533) (xy 352.95709 -264.992884)
			(xy 353.006704 -264.973412) (xy 353.058666 -264.961552) (xy 353.111816 -264.957569) (xy 353.164966 -264.961552)
			(xy 353.216928 -264.973412) (xy 353.266542 -264.992884) (xy 353.3127 -265.019533) (xy 353.354371 -265.052764)
			(xy 353.390623 -265.091835) (xy 353.420647 -265.135872) (xy 353.443773 -265.183893) (xy 353.459483 -265.234823)
			(xy 353.467426 -265.287527) (xy 353.467924 -265.314176) (xy 353.467426 -265.340825) (xy 353.696006 -265.340825)
			(xy 353.696006 -265.287527) (xy 353.703949 -265.234823) (xy 353.719659 -265.183893) (xy 353.742785 -265.135872)
			(xy 353.772809 -265.091835) (xy 353.809061 -265.052764) (xy 353.850732 -265.019533) (xy 353.89689 -264.992884)
			(xy 353.946504 -264.973412) (xy 353.998466 -264.961552) (xy 354.051616 -264.957569) (xy 354.104766 -264.961552)
			(xy 354.156728 -264.973412) (xy 354.206342 -264.992884) (xy 354.2525 -265.019533) (xy 354.294171 -265.052764)
			(xy 354.330423 -265.091835) (xy 354.360447 -265.135872) (xy 354.383573 -265.183893) (xy 354.399283 -265.234823)
			(xy 354.407226 -265.287527) (xy 354.407724 -265.314176) (xy 354.407226 -265.340825) (xy 354.635806 -265.340825)
			(xy 354.635806 -265.287527) (xy 354.643749 -265.234823) (xy 354.659459 -265.183893) (xy 354.682585 -265.135872)
			(xy 354.712609 -265.091835) (xy 354.748861 -265.052764) (xy 354.790532 -265.019533) (xy 354.83669 -264.992884)
			(xy 354.886304 -264.973412) (xy 354.938266 -264.961552) (xy 354.991416 -264.957569) (xy 355.044566 -264.961552)
			(xy 355.096528 -264.973412) (xy 355.146142 -264.992884) (xy 355.1923 -265.019533) (xy 355.233971 -265.052764)
			(xy 355.270223 -265.091835) (xy 355.300247 -265.135872) (xy 355.323373 -265.183893) (xy 355.339083 -265.234823)
			(xy 355.347026 -265.287527) (xy 355.347524 -265.314176) (xy 355.347026 -265.340825) (xy 355.339083 -265.393529)
			(xy 355.323373 -265.444459) (xy 355.300247 -265.49248) (xy 355.270223 -265.536517) (xy 355.233971 -265.575588)
			(xy 355.1923 -265.608819) (xy 355.146142 -265.635468) (xy 355.096528 -265.65494) (xy 355.044566 -265.6668)
			(xy 354.991416 -265.670784) (xy 354.938266 -265.6668) (xy 354.886304 -265.65494) (xy 354.83669 -265.635468)
			(xy 354.790532 -265.608819) (xy 354.748861 -265.575588) (xy 354.712609 -265.536517) (xy 354.682585 -265.49248)
			(xy 354.659459 -265.444459) (xy 354.643749 -265.393529) (xy 354.635806 -265.340825) (xy 354.407226 -265.340825)
			(xy 354.399283 -265.393529) (xy 354.383573 -265.444459) (xy 354.360447 -265.49248) (xy 354.330423 -265.536517)
			(xy 354.294171 -265.575588) (xy 354.2525 -265.608819) (xy 354.206342 -265.635468) (xy 354.156728 -265.65494)
			(xy 354.104766 -265.6668) (xy 354.051616 -265.670784) (xy 353.998466 -265.6668) (xy 353.946504 -265.65494)
			(xy 353.89689 -265.635468) (xy 353.850732 -265.608819) (xy 353.809061 -265.575588) (xy 353.772809 -265.536517)
			(xy 353.742785 -265.49248) (xy 353.719659 -265.444459) (xy 353.703949 -265.393529) (xy 353.696006 -265.340825)
			(xy 353.467426 -265.340825) (xy 353.459483 -265.393529) (xy 353.443773 -265.444459) (xy 353.420647 -265.49248)
			(xy 353.390623 -265.536517) (xy 353.354371 -265.575588) (xy 353.3127 -265.608819) (xy 353.266542 -265.635468)
			(xy 353.216928 -265.65494) (xy 353.164966 -265.6668) (xy 353.111816 -265.670784) (xy 353.058666 -265.6668)
			(xy 353.006704 -265.65494) (xy 352.95709 -265.635468) (xy 352.910932 -265.608819) (xy 352.869261 -265.575588)
			(xy 352.833009 -265.536517) (xy 352.802985 -265.49248) (xy 352.779859 -265.444459) (xy 352.764149 -265.393529)
			(xy 352.756206 -265.340825) (xy 352.527626 -265.340825) (xy 352.519683 -265.393529) (xy 352.503973 -265.444459)
			(xy 352.480847 -265.49248) (xy 352.450823 -265.536517) (xy 352.414571 -265.575588) (xy 352.3729 -265.608819)
			(xy 352.326742 -265.635468) (xy 352.277128 -265.65494) (xy 352.225166 -265.6668) (xy 352.172016 -265.670784)
			(xy 352.118866 -265.6668) (xy 352.066904 -265.65494) (xy 352.01729 -265.635468) (xy 351.971132 -265.608819)
			(xy 351.929461 -265.575588) (xy 351.893209 -265.536517) (xy 351.863185 -265.49248) (xy 351.840059 -265.444459)
			(xy 351.824349 -265.393529) (xy 351.816406 -265.340825) (xy 351.587826 -265.340825) (xy 351.579883 -265.393529)
			(xy 351.564173 -265.444459) (xy 351.541047 -265.49248) (xy 351.511023 -265.536517) (xy 351.474771 -265.575588)
			(xy 351.4331 -265.608819) (xy 351.386942 -265.635468) (xy 351.337328 -265.65494) (xy 351.285366 -265.6668)
			(xy 351.232216 -265.670784) (xy 351.179066 -265.6668) (xy 351.127104 -265.65494) (xy 351.07749 -265.635468)
			(xy 351.031332 -265.608819) (xy 350.989661 -265.575588) (xy 350.953409 -265.536517) (xy 350.923385 -265.49248)
			(xy 350.900259 -265.444459) (xy 350.884549 -265.393529) (xy 350.876606 -265.340825) (xy 350.648026 -265.340825)
			(xy 350.640083 -265.393529) (xy 350.624373 -265.444459) (xy 350.601247 -265.49248) (xy 350.571223 -265.536517)
			(xy 350.534971 -265.575588) (xy 350.4933 -265.608819) (xy 350.447142 -265.635468) (xy 350.397528 -265.65494)
			(xy 350.345566 -265.6668) (xy 350.292416 -265.670784) (xy 350.239266 -265.6668) (xy 350.187304 -265.65494)
			(xy 350.13769 -265.635468) (xy 350.091532 -265.608819) (xy 350.049861 -265.575588) (xy 350.013609 -265.536517)
			(xy 349.983585 -265.49248) (xy 349.960459 -265.444459) (xy 349.944749 -265.393529) (xy 349.936806 -265.340825)
			(xy 349.708226 -265.340825) (xy 349.700283 -265.393529) (xy 349.684573 -265.444459) (xy 349.661447 -265.49248)
			(xy 349.631423 -265.536517) (xy 349.595171 -265.575588) (xy 349.5535 -265.608819) (xy 349.507342 -265.635468)
			(xy 349.457728 -265.65494) (xy 349.405766 -265.6668) (xy 349.352616 -265.670784) (xy 349.299466 -265.6668)
			(xy 349.247504 -265.65494) (xy 349.19789 -265.635468) (xy 349.151732 -265.608819) (xy 349.110061 -265.575588)
			(xy 349.073809 -265.536517) (xy 349.043785 -265.49248) (xy 349.020659 -265.444459) (xy 349.004949 -265.393529)
			(xy 348.997006 -265.340825) (xy 348.768426 -265.340825) (xy 348.760483 -265.393529) (xy 348.744773 -265.444459)
			(xy 348.721647 -265.49248) (xy 348.691623 -265.536517) (xy 348.655371 -265.575588) (xy 348.6137 -265.608819)
			(xy 348.567542 -265.635468) (xy 348.517928 -265.65494) (xy 348.465966 -265.6668) (xy 348.412816 -265.670784)
			(xy 348.359666 -265.6668) (xy 348.307704 -265.65494) (xy 348.25809 -265.635468) (xy 348.211932 -265.608819)
			(xy 348.170261 -265.575588) (xy 348.134009 -265.536517) (xy 348.103985 -265.49248) (xy 348.080859 -265.444459)
			(xy 348.065149 -265.393529) (xy 348.057206 -265.340825) (xy 347.828626 -265.340825) (xy 347.820683 -265.393529)
			(xy 347.804973 -265.444459) (xy 347.781847 -265.49248) (xy 347.751823 -265.536517) (xy 347.715571 -265.575588)
			(xy 347.6739 -265.608819) (xy 347.627742 -265.635468) (xy 347.578128 -265.65494) (xy 347.526166 -265.6668)
			(xy 347.473016 -265.670784) (xy 347.419866 -265.6668) (xy 347.367904 -265.65494) (xy 347.31829 -265.635468)
			(xy 347.272132 -265.608819) (xy 347.230461 -265.575588) (xy 347.194209 -265.536517) (xy 347.164185 -265.49248)
			(xy 347.141059 -265.444459) (xy 347.125349 -265.393529) (xy 347.117406 -265.340825) (xy 346.888572 -265.340825)
			(xy 346.880629 -265.393529) (xy 346.864919 -265.444459) (xy 346.841793 -265.49248) (xy 346.811769 -265.536517)
			(xy 346.775517 -265.575588) (xy 346.733846 -265.608819) (xy 346.687688 -265.635468) (xy 346.638074 -265.65494)
			(xy 346.586112 -265.6668) (xy 346.532962 -265.670784) (xy 346.479812 -265.6668) (xy 346.42785 -265.65494)
			(xy 346.378236 -265.635468) (xy 346.332078 -265.608819) (xy 346.290407 -265.575588) (xy 346.254155 -265.536517)
			(xy 346.224131 -265.49248) (xy 346.201005 -265.444459) (xy 346.185295 -265.393529) (xy 346.177352 -265.340825)
			(xy 345.949026 -265.340825) (xy 345.941083 -265.393529) (xy 345.925373 -265.444459) (xy 345.902247 -265.49248)
			(xy 345.872223 -265.536517) (xy 345.835971 -265.575588) (xy 345.7943 -265.608819) (xy 345.748142 -265.635468)
			(xy 345.698528 -265.65494) (xy 345.646566 -265.6668) (xy 345.593416 -265.670784) (xy 345.540266 -265.6668)
			(xy 345.488304 -265.65494) (xy 345.43869 -265.635468) (xy 345.392532 -265.608819) (xy 345.350861 -265.575588)
			(xy 345.314609 -265.536517) (xy 345.284585 -265.49248) (xy 345.261459 -265.444459) (xy 345.245749 -265.393529)
			(xy 345.237806 -265.340825) (xy 345.009226 -265.340825) (xy 345.001283 -265.393529) (xy 344.985573 -265.444459)
			(xy 344.962447 -265.49248) (xy 344.932423 -265.536517) (xy 344.896171 -265.575588) (xy 344.8545 -265.608819)
			(xy 344.808342 -265.635468) (xy 344.758728 -265.65494) (xy 344.706766 -265.6668) (xy 344.653616 -265.670784)
			(xy 344.600466 -265.6668) (xy 344.548504 -265.65494) (xy 344.49889 -265.635468) (xy 344.452732 -265.608819)
			(xy 344.411061 -265.575588) (xy 344.374809 -265.536517) (xy 344.344785 -265.49248) (xy 344.321659 -265.444459)
			(xy 344.305949 -265.393529) (xy 344.298006 -265.340825) (xy 344.069426 -265.340825) (xy 344.061483 -265.393529)
			(xy 344.045773 -265.444459) (xy 344.022647 -265.49248) (xy 343.992623 -265.536517) (xy 343.956371 -265.575588)
			(xy 343.9147 -265.608819) (xy 343.868542 -265.635468) (xy 343.818928 -265.65494) (xy 343.766966 -265.6668)
			(xy 343.713816 -265.670784) (xy 343.660666 -265.6668) (xy 343.608704 -265.65494) (xy 343.55909 -265.635468)
			(xy 343.512932 -265.608819) (xy 343.471261 -265.575588) (xy 343.435009 -265.536517) (xy 343.404985 -265.49248)
			(xy 343.381859 -265.444459) (xy 343.366149 -265.393529) (xy 343.358206 -265.340825) (xy 343.129626 -265.340825)
			(xy 343.121683 -265.393529) (xy 343.105973 -265.444459) (xy 343.082847 -265.49248) (xy 343.052823 -265.536517)
			(xy 343.016571 -265.575588) (xy 342.9749 -265.608819) (xy 342.928742 -265.635468) (xy 342.879128 -265.65494)
			(xy 342.827166 -265.6668) (xy 342.774016 -265.670784) (xy 342.720866 -265.6668) (xy 342.668904 -265.65494)
			(xy 342.61929 -265.635468) (xy 342.573132 -265.608819) (xy 342.531461 -265.575588) (xy 342.495209 -265.536517)
			(xy 342.465185 -265.49248) (xy 342.442059 -265.444459) (xy 342.426349 -265.393529) (xy 342.418406 -265.340825)
			(xy 342.189826 -265.340825) (xy 342.181883 -265.393529) (xy 342.166173 -265.444459) (xy 342.143047 -265.49248)
			(xy 342.113023 -265.536517) (xy 342.076771 -265.575588) (xy 342.0351 -265.608819) (xy 341.988942 -265.635468)
			(xy 341.939328 -265.65494) (xy 341.887366 -265.6668) (xy 341.834216 -265.670784) (xy 341.781066 -265.6668)
			(xy 341.729104 -265.65494) (xy 341.67949 -265.635468) (xy 341.633332 -265.608819) (xy 341.591661 -265.575588)
			(xy 341.555409 -265.536517) (xy 341.525385 -265.49248) (xy 341.502259 -265.444459) (xy 341.486549 -265.393529)
			(xy 341.478606 -265.340825) (xy 341.250026 -265.340825) (xy 341.242083 -265.393529) (xy 341.226373 -265.444459)
			(xy 341.203247 -265.49248) (xy 341.173223 -265.536517) (xy 341.136971 -265.575588) (xy 341.0953 -265.608819)
			(xy 341.049142 -265.635468) (xy 340.999528 -265.65494) (xy 340.947566 -265.6668) (xy 340.894416 -265.670784)
			(xy 340.841266 -265.6668) (xy 340.789304 -265.65494) (xy 340.73969 -265.635468) (xy 340.693532 -265.608819)
			(xy 340.651861 -265.575588) (xy 340.615609 -265.536517) (xy 340.585585 -265.49248) (xy 340.562459 -265.444459)
			(xy 340.546749 -265.393529) (xy 340.538806 -265.340825) (xy 340.309972 -265.340825) (xy 340.302029 -265.393529)
			(xy 340.286319 -265.444459) (xy 340.263193 -265.49248) (xy 340.233169 -265.536517) (xy 340.196917 -265.575588)
			(xy 340.155246 -265.608819) (xy 340.109088 -265.635468) (xy 340.059474 -265.65494) (xy 340.007512 -265.6668)
			(xy 339.954362 -265.670784) (xy 339.901212 -265.6668) (xy 339.84925 -265.65494) (xy 339.799636 -265.635468)
			(xy 339.753478 -265.608819) (xy 339.711807 -265.575588) (xy 339.675555 -265.536517) (xy 339.645531 -265.49248)
			(xy 339.622405 -265.444459) (xy 339.606695 -265.393529) (xy 339.598752 -265.340825) (xy 339.37956 -265.340825)
			(xy 339.37956 -265.670538) (xy 339.379968 -265.683924) (xy 339.386936 -265.709773) (xy 339.400382 -265.732923)
			(xy 339.419383 -265.751782) (xy 339.442633 -265.765055) (xy 339.468534 -265.771829) (xy 339.481922 -265.772138)
			(xy 339.484462 -265.772138) (xy 339.511112 -265.772608) (xy 339.563816 -265.780547) (xy 339.614749 -265.796253)
			(xy 339.662771 -265.819375) (xy 339.706811 -265.849396) (xy 339.745884 -265.885647) (xy 339.779117 -265.927316)
			(xy 339.805768 -265.973473) (xy 339.825242 -266.023088) (xy 339.837103 -266.07505) (xy 339.841086 -266.1282)
			(xy 339.839086 -266.154895) (xy 340.068652 -266.154895) (xy 340.068652 -266.101597) (xy 340.076595 -266.048893)
			(xy 340.092305 -265.997963) (xy 340.115431 -265.949942) (xy 340.145455 -265.905905) (xy 340.181707 -265.866834)
			(xy 340.223378 -265.833603) (xy 340.269536 -265.806954) (xy 340.31915 -265.787482) (xy 340.371112 -265.775622)
			(xy 340.424262 -265.771639) (xy 340.477412 -265.775622) (xy 340.529374 -265.787482) (xy 340.578988 -265.806954)
			(xy 340.625146 -265.833603) (xy 340.666817 -265.866834) (xy 340.703069 -265.905905) (xy 340.733093 -265.949942)
			(xy 340.756219 -265.997963) (xy 340.771929 -266.048893) (xy 340.779872 -266.101597) (xy 340.78037 -266.128246)
			(xy 340.779872 -266.154895) (xy 341.008452 -266.154895) (xy 341.008452 -266.101597) (xy 341.016395 -266.048893)
			(xy 341.032105 -265.997963) (xy 341.055231 -265.949942) (xy 341.085255 -265.905905) (xy 341.121507 -265.866834)
			(xy 341.163178 -265.833603) (xy 341.209336 -265.806954) (xy 341.25895 -265.787482) (xy 341.310912 -265.775622)
			(xy 341.364062 -265.771639) (xy 341.417212 -265.775622) (xy 341.469174 -265.787482) (xy 341.518788 -265.806954)
			(xy 341.564946 -265.833603) (xy 341.606617 -265.866834) (xy 341.642869 -265.905905) (xy 341.672893 -265.949942)
			(xy 341.696019 -265.997963) (xy 341.711729 -266.048893) (xy 341.719672 -266.101597) (xy 341.72017 -266.128246)
			(xy 341.719672 -266.154895) (xy 341.948252 -266.154895) (xy 341.948252 -266.101597) (xy 341.956195 -266.048893)
			(xy 341.971905 -265.997963) (xy 341.995031 -265.949942) (xy 342.025055 -265.905905) (xy 342.061307 -265.866834)
			(xy 342.102978 -265.833603) (xy 342.149136 -265.806954) (xy 342.19875 -265.787482) (xy 342.250712 -265.775622)
			(xy 342.303862 -265.771639) (xy 342.357012 -265.775622) (xy 342.408974 -265.787482) (xy 342.458588 -265.806954)
			(xy 342.504746 -265.833603) (xy 342.546417 -265.866834) (xy 342.582669 -265.905905) (xy 342.612693 -265.949942)
			(xy 342.635819 -265.997963) (xy 342.651529 -266.048893) (xy 342.659472 -266.101597) (xy 342.65997 -266.128246)
			(xy 342.659472 -266.154895) (xy 342.888052 -266.154895) (xy 342.888052 -266.101597) (xy 342.895995 -266.048893)
			(xy 342.911705 -265.997963) (xy 342.934831 -265.949942) (xy 342.964855 -265.905905) (xy 343.001107 -265.866834)
			(xy 343.042778 -265.833603) (xy 343.088936 -265.806954) (xy 343.13855 -265.787482) (xy 343.190512 -265.775622)
			(xy 343.243662 -265.771639) (xy 343.296812 -265.775622) (xy 343.348774 -265.787482) (xy 343.398388 -265.806954)
			(xy 343.444546 -265.833603) (xy 343.486217 -265.866834) (xy 343.522469 -265.905905) (xy 343.552493 -265.949942)
			(xy 343.575619 -265.997963) (xy 343.591329 -266.048893) (xy 343.599272 -266.101597) (xy 343.59977 -266.128246)
			(xy 343.599272 -266.154895) (xy 343.827852 -266.154895) (xy 343.827852 -266.101597) (xy 343.835795 -266.048893)
			(xy 343.851505 -265.997963) (xy 343.874631 -265.949942) (xy 343.904655 -265.905905) (xy 343.940907 -265.866834)
			(xy 343.982578 -265.833603) (xy 344.028736 -265.806954) (xy 344.07835 -265.787482) (xy 344.130312 -265.775622)
			(xy 344.183462 -265.771639) (xy 344.236612 -265.775622) (xy 344.288574 -265.787482) (xy 344.338188 -265.806954)
			(xy 344.384346 -265.833603) (xy 344.426017 -265.866834) (xy 344.462269 -265.905905) (xy 344.492293 -265.949942)
			(xy 344.515419 -265.997963) (xy 344.531129 -266.048893) (xy 344.539072 -266.101597) (xy 344.53957 -266.128246)
			(xy 344.539072 -266.154895) (xy 344.767652 -266.154895) (xy 344.767652 -266.101597) (xy 344.775595 -266.048893)
			(xy 344.791305 -265.997963) (xy 344.814431 -265.949942) (xy 344.844455 -265.905905) (xy 344.880707 -265.866834)
			(xy 344.922378 -265.833603) (xy 344.968536 -265.806954) (xy 345.01815 -265.787482) (xy 345.070112 -265.775622)
			(xy 345.123262 -265.771639) (xy 345.176412 -265.775622) (xy 345.228374 -265.787482) (xy 345.277988 -265.806954)
			(xy 345.324146 -265.833603) (xy 345.365817 -265.866834) (xy 345.402069 -265.905905) (xy 345.432093 -265.949942)
			(xy 345.455219 -265.997963) (xy 345.470929 -266.048893) (xy 345.478872 -266.101597) (xy 345.47937 -266.128246)
			(xy 345.478872 -266.154895) (xy 345.707452 -266.154895) (xy 345.707452 -266.101597) (xy 345.715395 -266.048893)
			(xy 345.731105 -265.997963) (xy 345.754231 -265.949942) (xy 345.784255 -265.905905) (xy 345.820507 -265.866834)
			(xy 345.862178 -265.833603) (xy 345.908336 -265.806954) (xy 345.95795 -265.787482) (xy 346.009912 -265.775622)
			(xy 346.063062 -265.771639) (xy 346.116212 -265.775622) (xy 346.168174 -265.787482) (xy 346.217788 -265.806954)
			(xy 346.263946 -265.833603) (xy 346.305617 -265.866834) (xy 346.341869 -265.905905) (xy 346.371893 -265.949942)
			(xy 346.395019 -265.997963) (xy 346.410729 -266.048893) (xy 346.418672 -266.101597) (xy 346.41917 -266.128246)
			(xy 346.418672 -266.154895) (xy 346.647252 -266.154895) (xy 346.647252 -266.101597) (xy 346.655195 -266.048893)
			(xy 346.670905 -265.997963) (xy 346.694031 -265.949942) (xy 346.724055 -265.905905) (xy 346.760307 -265.866834)
			(xy 346.801978 -265.833603) (xy 346.848136 -265.806954) (xy 346.89775 -265.787482) (xy 346.949712 -265.775622)
			(xy 347.002862 -265.771639) (xy 347.056012 -265.775622) (xy 347.107974 -265.787482) (xy 347.157588 -265.806954)
			(xy 347.203746 -265.833603) (xy 347.245417 -265.866834) (xy 347.281669 -265.905905) (xy 347.311693 -265.949942)
			(xy 347.334819 -265.997963) (xy 347.350529 -266.048893) (xy 347.358472 -266.101597) (xy 347.35897 -266.128246)
			(xy 347.358472 -266.154895) (xy 347.587052 -266.154895) (xy 347.587052 -266.101597) (xy 347.594995 -266.048893)
			(xy 347.610705 -265.997963) (xy 347.633831 -265.949942) (xy 347.663855 -265.905905) (xy 347.700107 -265.866834)
			(xy 347.741778 -265.833603) (xy 347.787936 -265.806954) (xy 347.83755 -265.787482) (xy 347.889512 -265.775622)
			(xy 347.942662 -265.771639) (xy 347.995812 -265.775622) (xy 348.047774 -265.787482) (xy 348.097388 -265.806954)
			(xy 348.143546 -265.833603) (xy 348.185217 -265.866834) (xy 348.221469 -265.905905) (xy 348.251493 -265.949942)
			(xy 348.274619 -265.997963) (xy 348.290329 -266.048893) (xy 348.298272 -266.101597) (xy 348.29877 -266.128246)
			(xy 348.298272 -266.154895) (xy 348.526852 -266.154895) (xy 348.526852 -266.101597) (xy 348.534795 -266.048893)
			(xy 348.550505 -265.997963) (xy 348.573631 -265.949942) (xy 348.603655 -265.905905) (xy 348.639907 -265.866834)
			(xy 348.681578 -265.833603) (xy 348.727736 -265.806954) (xy 348.77735 -265.787482) (xy 348.829312 -265.775622)
			(xy 348.882462 -265.771639) (xy 348.935612 -265.775622) (xy 348.987574 -265.787482) (xy 349.037188 -265.806954)
			(xy 349.083346 -265.833603) (xy 349.125017 -265.866834) (xy 349.161269 -265.905905) (xy 349.191293 -265.949942)
			(xy 349.214419 -265.997963) (xy 349.230129 -266.048893) (xy 349.238072 -266.101597) (xy 349.23857 -266.128246)
			(xy 349.238072 -266.154895) (xy 349.466652 -266.154895) (xy 349.466652 -266.101597) (xy 349.474595 -266.048893)
			(xy 349.490305 -265.997963) (xy 349.513431 -265.949942) (xy 349.543455 -265.905905) (xy 349.579707 -265.866834)
			(xy 349.621378 -265.833603) (xy 349.667536 -265.806954) (xy 349.71715 -265.787482) (xy 349.769112 -265.775622)
			(xy 349.822262 -265.771639) (xy 349.875412 -265.775622) (xy 349.927374 -265.787482) (xy 349.976988 -265.806954)
			(xy 350.023146 -265.833603) (xy 350.064817 -265.866834) (xy 350.101069 -265.905905) (xy 350.131093 -265.949942)
			(xy 350.154219 -265.997963) (xy 350.169929 -266.048893) (xy 350.177872 -266.101597) (xy 350.17837 -266.128246)
			(xy 350.177872 -266.154895) (xy 350.406452 -266.154895) (xy 350.406452 -266.101597) (xy 350.414395 -266.048893)
			(xy 350.430105 -265.997963) (xy 350.453231 -265.949942) (xy 350.483255 -265.905905) (xy 350.519507 -265.866834)
			(xy 350.561178 -265.833603) (xy 350.607336 -265.806954) (xy 350.65695 -265.787482) (xy 350.708912 -265.775622)
			(xy 350.762062 -265.771639) (xy 350.815212 -265.775622) (xy 350.867174 -265.787482) (xy 350.916788 -265.806954)
			(xy 350.962946 -265.833603) (xy 351.004617 -265.866834) (xy 351.040869 -265.905905) (xy 351.070893 -265.949942)
			(xy 351.094019 -265.997963) (xy 351.109729 -266.048893) (xy 351.117672 -266.101597) (xy 351.11817 -266.128246)
			(xy 351.117672 -266.154895) (xy 351.346252 -266.154895) (xy 351.346252 -266.101597) (xy 351.354195 -266.048893)
			(xy 351.369905 -265.997963) (xy 351.393031 -265.949942) (xy 351.423055 -265.905905) (xy 351.459307 -265.866834)
			(xy 351.500978 -265.833603) (xy 351.547136 -265.806954) (xy 351.59675 -265.787482) (xy 351.648712 -265.775622)
			(xy 351.701862 -265.771639) (xy 351.755012 -265.775622) (xy 351.806974 -265.787482) (xy 351.856588 -265.806954)
			(xy 351.902746 -265.833603) (xy 351.944417 -265.866834) (xy 351.980669 -265.905905) (xy 352.010693 -265.949942)
			(xy 352.033819 -265.997963) (xy 352.049529 -266.048893) (xy 352.057472 -266.101597) (xy 352.05797 -266.128246)
			(xy 352.057472 -266.154895) (xy 352.286052 -266.154895) (xy 352.286052 -266.101597) (xy 352.293995 -266.048893)
			(xy 352.309705 -265.997963) (xy 352.332831 -265.949942) (xy 352.362855 -265.905905) (xy 352.399107 -265.866834)
			(xy 352.440778 -265.833603) (xy 352.486936 -265.806954) (xy 352.53655 -265.787482) (xy 352.588512 -265.775622)
			(xy 352.641662 -265.771639) (xy 352.694812 -265.775622) (xy 352.746774 -265.787482) (xy 352.796388 -265.806954)
			(xy 352.842546 -265.833603) (xy 352.884217 -265.866834) (xy 352.920469 -265.905905) (xy 352.950493 -265.949942)
			(xy 352.973619 -265.997963) (xy 352.989329 -266.048893) (xy 352.997272 -266.101597) (xy 352.99777 -266.128246)
			(xy 352.997272 -266.154895) (xy 353.225852 -266.154895) (xy 353.225852 -266.101597) (xy 353.233795 -266.048893)
			(xy 353.249505 -265.997963) (xy 353.272631 -265.949942) (xy 353.302655 -265.905905) (xy 353.338907 -265.866834)
			(xy 353.380578 -265.833603) (xy 353.426736 -265.806954) (xy 353.47635 -265.787482) (xy 353.528312 -265.775622)
			(xy 353.581462 -265.771639) (xy 353.634612 -265.775622) (xy 353.686574 -265.787482) (xy 353.736188 -265.806954)
			(xy 353.782346 -265.833603) (xy 353.824017 -265.866834) (xy 353.860269 -265.905905) (xy 353.890293 -265.949942)
			(xy 353.913419 -265.997963) (xy 353.929129 -266.048893) (xy 353.937072 -266.101597) (xy 353.93757 -266.128246)
			(xy 353.937072 -266.154895) (xy 354.165652 -266.154895) (xy 354.165652 -266.101597) (xy 354.173595 -266.048893)
			(xy 354.189305 -265.997963) (xy 354.212431 -265.949942) (xy 354.242455 -265.905905) (xy 354.278707 -265.866834)
			(xy 354.320378 -265.833603) (xy 354.366536 -265.806954) (xy 354.41615 -265.787482) (xy 354.468112 -265.775622)
			(xy 354.521262 -265.771639) (xy 354.574412 -265.775622) (xy 354.626374 -265.787482) (xy 354.675988 -265.806954)
			(xy 354.722146 -265.833603) (xy 354.763817 -265.866834) (xy 354.800069 -265.905905) (xy 354.830093 -265.949942)
			(xy 354.853219 -265.997963) (xy 354.868929 -266.048893) (xy 354.876872 -266.101597) (xy 354.87737 -266.128246)
			(xy 354.876872 -266.154895) (xy 355.105452 -266.154895) (xy 355.105452 -266.101597) (xy 355.113395 -266.048893)
			(xy 355.129105 -265.997963) (xy 355.152231 -265.949942) (xy 355.182255 -265.905905) (xy 355.218507 -265.866834)
			(xy 355.260178 -265.833603) (xy 355.306336 -265.806954) (xy 355.35595 -265.787482) (xy 355.407912 -265.775622)
			(xy 355.461062 -265.771639) (xy 355.514212 -265.775622) (xy 355.566174 -265.787482) (xy 355.615788 -265.806954)
			(xy 355.661946 -265.833603) (xy 355.703617 -265.866834) (xy 355.739869 -265.905905) (xy 355.769893 -265.949942)
			(xy 355.793019 -265.997963) (xy 355.808729 -266.048893) (xy 355.816672 -266.101597) (xy 355.81717 -266.128246)
			(xy 355.816672 -266.154895) (xy 355.808729 -266.207599) (xy 355.793019 -266.258529) (xy 355.769893 -266.30655)
			(xy 355.739869 -266.350587) (xy 355.703617 -266.389658) (xy 355.661946 -266.422889) (xy 355.615788 -266.449538)
			(xy 355.566174 -266.46901) (xy 355.514212 -266.48087) (xy 355.461062 -266.484854) (xy 355.407912 -266.48087)
			(xy 355.35595 -266.46901) (xy 355.306336 -266.449538) (xy 355.260178 -266.422889) (xy 355.218507 -266.389658)
			(xy 355.182255 -266.350587) (xy 355.152231 -266.30655) (xy 355.129105 -266.258529) (xy 355.113395 -266.207599)
			(xy 355.105452 -266.154895) (xy 354.876872 -266.154895) (xy 354.868929 -266.207599) (xy 354.853219 -266.258529)
			(xy 354.830093 -266.30655) (xy 354.800069 -266.350587) (xy 354.763817 -266.389658) (xy 354.722146 -266.422889)
			(xy 354.675988 -266.449538) (xy 354.626374 -266.46901) (xy 354.574412 -266.48087) (xy 354.521262 -266.484854)
			(xy 354.468112 -266.48087) (xy 354.41615 -266.46901) (xy 354.366536 -266.449538) (xy 354.320378 -266.422889)
			(xy 354.278707 -266.389658) (xy 354.242455 -266.350587) (xy 354.212431 -266.30655) (xy 354.189305 -266.258529)
			(xy 354.173595 -266.207599) (xy 354.165652 -266.154895) (xy 353.937072 -266.154895) (xy 353.929129 -266.207599)
			(xy 353.913419 -266.258529) (xy 353.890293 -266.30655) (xy 353.860269 -266.350587) (xy 353.824017 -266.389658)
			(xy 353.782346 -266.422889) (xy 353.736188 -266.449538) (xy 353.686574 -266.46901) (xy 353.634612 -266.48087)
			(xy 353.581462 -266.484854) (xy 353.528312 -266.48087) (xy 353.47635 -266.46901) (xy 353.426736 -266.449538)
			(xy 353.380578 -266.422889) (xy 353.338907 -266.389658) (xy 353.302655 -266.350587) (xy 353.272631 -266.30655)
			(xy 353.249505 -266.258529) (xy 353.233795 -266.207599) (xy 353.225852 -266.154895) (xy 352.997272 -266.154895)
			(xy 352.989329 -266.207599) (xy 352.973619 -266.258529) (xy 352.950493 -266.30655) (xy 352.920469 -266.350587)
			(xy 352.884217 -266.389658) (xy 352.842546 -266.422889) (xy 352.796388 -266.449538) (xy 352.746774 -266.46901)
			(xy 352.694812 -266.48087) (xy 352.641662 -266.484854) (xy 352.588512 -266.48087) (xy 352.53655 -266.46901)
			(xy 352.486936 -266.449538) (xy 352.440778 -266.422889) (xy 352.399107 -266.389658) (xy 352.362855 -266.350587)
			(xy 352.332831 -266.30655) (xy 352.309705 -266.258529) (xy 352.293995 -266.207599) (xy 352.286052 -266.154895)
			(xy 352.057472 -266.154895) (xy 352.049529 -266.207599) (xy 352.033819 -266.258529) (xy 352.010693 -266.30655)
			(xy 351.980669 -266.350587) (xy 351.944417 -266.389658) (xy 351.902746 -266.422889) (xy 351.856588 -266.449538)
			(xy 351.806974 -266.46901) (xy 351.755012 -266.48087) (xy 351.701862 -266.484854) (xy 351.648712 -266.48087)
			(xy 351.59675 -266.46901) (xy 351.547136 -266.449538) (xy 351.500978 -266.422889) (xy 351.459307 -266.389658)
			(xy 351.423055 -266.350587) (xy 351.393031 -266.30655) (xy 351.369905 -266.258529) (xy 351.354195 -266.207599)
			(xy 351.346252 -266.154895) (xy 351.117672 -266.154895) (xy 351.109729 -266.207599) (xy 351.094019 -266.258529)
			(xy 351.070893 -266.30655) (xy 351.040869 -266.350587) (xy 351.004617 -266.389658) (xy 350.962946 -266.422889)
			(xy 350.916788 -266.449538) (xy 350.867174 -266.46901) (xy 350.815212 -266.48087) (xy 350.762062 -266.484854)
			(xy 350.708912 -266.48087) (xy 350.65695 -266.46901) (xy 350.607336 -266.449538) (xy 350.561178 -266.422889)
			(xy 350.519507 -266.389658) (xy 350.483255 -266.350587) (xy 350.453231 -266.30655) (xy 350.430105 -266.258529)
			(xy 350.414395 -266.207599) (xy 350.406452 -266.154895) (xy 350.177872 -266.154895) (xy 350.169929 -266.207599)
			(xy 350.154219 -266.258529) (xy 350.131093 -266.30655) (xy 350.101069 -266.350587) (xy 350.064817 -266.389658)
			(xy 350.023146 -266.422889) (xy 349.976988 -266.449538) (xy 349.927374 -266.46901) (xy 349.875412 -266.48087)
			(xy 349.822262 -266.484854) (xy 349.769112 -266.48087) (xy 349.71715 -266.46901) (xy 349.667536 -266.449538)
			(xy 349.621378 -266.422889) (xy 349.579707 -266.389658) (xy 349.543455 -266.350587) (xy 349.513431 -266.30655)
			(xy 349.490305 -266.258529) (xy 349.474595 -266.207599) (xy 349.466652 -266.154895) (xy 349.238072 -266.154895)
			(xy 349.230129 -266.207599) (xy 349.214419 -266.258529) (xy 349.191293 -266.30655) (xy 349.161269 -266.350587)
			(xy 349.125017 -266.389658) (xy 349.083346 -266.422889) (xy 349.037188 -266.449538) (xy 348.987574 -266.46901)
			(xy 348.935612 -266.48087) (xy 348.882462 -266.484854) (xy 348.829312 -266.48087) (xy 348.77735 -266.46901)
			(xy 348.727736 -266.449538) (xy 348.681578 -266.422889) (xy 348.639907 -266.389658) (xy 348.603655 -266.350587)
			(xy 348.573631 -266.30655) (xy 348.550505 -266.258529) (xy 348.534795 -266.207599) (xy 348.526852 -266.154895)
			(xy 348.298272 -266.154895) (xy 348.290329 -266.207599) (xy 348.274619 -266.258529) (xy 348.251493 -266.30655)
			(xy 348.221469 -266.350587) (xy 348.185217 -266.389658) (xy 348.143546 -266.422889) (xy 348.097388 -266.449538)
			(xy 348.047774 -266.46901) (xy 347.995812 -266.48087) (xy 347.942662 -266.484854) (xy 347.889512 -266.48087)
			(xy 347.83755 -266.46901) (xy 347.787936 -266.449538) (xy 347.741778 -266.422889) (xy 347.700107 -266.389658)
			(xy 347.663855 -266.350587) (xy 347.633831 -266.30655) (xy 347.610705 -266.258529) (xy 347.594995 -266.207599)
			(xy 347.587052 -266.154895) (xy 347.358472 -266.154895) (xy 347.350529 -266.207599) (xy 347.334819 -266.258529)
			(xy 347.311693 -266.30655) (xy 347.281669 -266.350587) (xy 347.245417 -266.389658) (xy 347.203746 -266.422889)
			(xy 347.157588 -266.449538) (xy 347.107974 -266.46901) (xy 347.056012 -266.48087) (xy 347.002862 -266.484854)
			(xy 346.949712 -266.48087) (xy 346.89775 -266.46901) (xy 346.848136 -266.449538) (xy 346.801978 -266.422889)
			(xy 346.760307 -266.389658) (xy 346.724055 -266.350587) (xy 346.694031 -266.30655) (xy 346.670905 -266.258529)
			(xy 346.655195 -266.207599) (xy 346.647252 -266.154895) (xy 346.418672 -266.154895) (xy 346.410729 -266.207599)
			(xy 346.395019 -266.258529) (xy 346.371893 -266.30655) (xy 346.341869 -266.350587) (xy 346.305617 -266.389658)
			(xy 346.263946 -266.422889) (xy 346.217788 -266.449538) (xy 346.168174 -266.46901) (xy 346.116212 -266.48087)
			(xy 346.063062 -266.484854) (xy 346.009912 -266.48087) (xy 345.95795 -266.46901) (xy 345.908336 -266.449538)
			(xy 345.862178 -266.422889) (xy 345.820507 -266.389658) (xy 345.784255 -266.350587) (xy 345.754231 -266.30655)
			(xy 345.731105 -266.258529) (xy 345.715395 -266.207599) (xy 345.707452 -266.154895) (xy 345.478872 -266.154895)
			(xy 345.470929 -266.207599) (xy 345.455219 -266.258529) (xy 345.432093 -266.30655) (xy 345.402069 -266.350587)
			(xy 345.365817 -266.389658) (xy 345.324146 -266.422889) (xy 345.277988 -266.449538) (xy 345.228374 -266.46901)
			(xy 345.176412 -266.48087) (xy 345.123262 -266.484854) (xy 345.070112 -266.48087) (xy 345.01815 -266.46901)
			(xy 344.968536 -266.449538) (xy 344.922378 -266.422889) (xy 344.880707 -266.389658) (xy 344.844455 -266.350587)
			(xy 344.814431 -266.30655) (xy 344.791305 -266.258529) (xy 344.775595 -266.207599) (xy 344.767652 -266.154895)
			(xy 344.539072 -266.154895) (xy 344.531129 -266.207599) (xy 344.515419 -266.258529) (xy 344.492293 -266.30655)
			(xy 344.462269 -266.350587) (xy 344.426017 -266.389658) (xy 344.384346 -266.422889) (xy 344.338188 -266.449538)
			(xy 344.288574 -266.46901) (xy 344.236612 -266.48087) (xy 344.183462 -266.484854) (xy 344.130312 -266.48087)
			(xy 344.07835 -266.46901) (xy 344.028736 -266.449538) (xy 343.982578 -266.422889) (xy 343.940907 -266.389658)
			(xy 343.904655 -266.350587) (xy 343.874631 -266.30655) (xy 343.851505 -266.258529) (xy 343.835795 -266.207599)
			(xy 343.827852 -266.154895) (xy 343.599272 -266.154895) (xy 343.591329 -266.207599) (xy 343.575619 -266.258529)
			(xy 343.552493 -266.30655) (xy 343.522469 -266.350587) (xy 343.486217 -266.389658) (xy 343.444546 -266.422889)
			(xy 343.398388 -266.449538) (xy 343.348774 -266.46901) (xy 343.296812 -266.48087) (xy 343.243662 -266.484854)
			(xy 343.190512 -266.48087) (xy 343.13855 -266.46901) (xy 343.088936 -266.449538) (xy 343.042778 -266.422889)
			(xy 343.001107 -266.389658) (xy 342.964855 -266.350587) (xy 342.934831 -266.30655) (xy 342.911705 -266.258529)
			(xy 342.895995 -266.207599) (xy 342.888052 -266.154895) (xy 342.659472 -266.154895) (xy 342.651529 -266.207599)
			(xy 342.635819 -266.258529) (xy 342.612693 -266.30655) (xy 342.582669 -266.350587) (xy 342.546417 -266.389658)
			(xy 342.504746 -266.422889) (xy 342.458588 -266.449538) (xy 342.408974 -266.46901) (xy 342.357012 -266.48087)
			(xy 342.303862 -266.484854) (xy 342.250712 -266.48087) (xy 342.19875 -266.46901) (xy 342.149136 -266.449538)
			(xy 342.102978 -266.422889) (xy 342.061307 -266.389658) (xy 342.025055 -266.350587) (xy 341.995031 -266.30655)
			(xy 341.971905 -266.258529) (xy 341.956195 -266.207599) (xy 341.948252 -266.154895) (xy 341.719672 -266.154895)
			(xy 341.711729 -266.207599) (xy 341.696019 -266.258529) (xy 341.672893 -266.30655) (xy 341.642869 -266.350587)
			(xy 341.606617 -266.389658) (xy 341.564946 -266.422889) (xy 341.518788 -266.449538) (xy 341.469174 -266.46901)
			(xy 341.417212 -266.48087) (xy 341.364062 -266.484854) (xy 341.310912 -266.48087) (xy 341.25895 -266.46901)
			(xy 341.209336 -266.449538) (xy 341.163178 -266.422889) (xy 341.121507 -266.389658) (xy 341.085255 -266.350587)
			(xy 341.055231 -266.30655) (xy 341.032105 -266.258529) (xy 341.016395 -266.207599) (xy 341.008452 -266.154895)
			(xy 340.779872 -266.154895) (xy 340.771929 -266.207599) (xy 340.756219 -266.258529) (xy 340.733093 -266.30655)
			(xy 340.703069 -266.350587) (xy 340.666817 -266.389658) (xy 340.625146 -266.422889) (xy 340.578988 -266.449538)
			(xy 340.529374 -266.46901) (xy 340.477412 -266.48087) (xy 340.424262 -266.484854) (xy 340.371112 -266.48087)
			(xy 340.31915 -266.46901) (xy 340.269536 -266.449538) (xy 340.223378 -266.422889) (xy 340.181707 -266.389658)
			(xy 340.145455 -266.350587) (xy 340.115431 -266.30655) (xy 340.092305 -266.258529) (xy 340.076595 -266.207599)
			(xy 340.068652 -266.154895) (xy 339.839086 -266.154895) (xy 339.837103 -266.18135) (xy 339.825242 -266.233312)
			(xy 339.805768 -266.282927) (xy 339.779117 -266.329084) (xy 339.745884 -266.370753) (xy 339.706811 -266.407004)
			(xy 339.662771 -266.437025) (xy 339.614749 -266.460147) (xy 339.563816 -266.475853) (xy 339.511112 -266.483792)
			(xy 339.484462 -266.484354) (xy 339.481922 -266.484354) (xy 339.468538 -266.484663) (xy 339.442647 -266.491438)
			(xy 339.419409 -266.504714) (xy 339.400422 -266.523576) (xy 339.386994 -266.546726) (xy 339.380048 -266.572572)
			(xy 339.37956 -266.585954) (xy 339.37956 -266.968457) (xy 339.599006 -266.968457) (xy 339.599006 -266.915159)
			(xy 339.606949 -266.862455) (xy 339.622659 -266.811525) (xy 339.645785 -266.763504) (xy 339.675809 -266.719467)
			(xy 339.712061 -266.680396) (xy 339.753732 -266.647165) (xy 339.79989 -266.620516) (xy 339.849504 -266.601044)
			(xy 339.901466 -266.589184) (xy 339.954616 -266.585201) (xy 340.007766 -266.589184) (xy 340.059728 -266.601044)
			(xy 340.109342 -266.620516) (xy 340.1555 -266.647165) (xy 340.197171 -266.680396) (xy 340.233423 -266.719467)
			(xy 340.263447 -266.763504) (xy 340.286573 -266.811525) (xy 340.302283 -266.862455) (xy 340.310226 -266.915159)
			(xy 340.310724 -266.941808) (xy 340.310226 -266.968457) (xy 340.538806 -266.968457) (xy 340.538806 -266.915159)
			(xy 340.546749 -266.862455) (xy 340.562459 -266.811525) (xy 340.585585 -266.763504) (xy 340.615609 -266.719467)
			(xy 340.651861 -266.680396) (xy 340.693532 -266.647165) (xy 340.73969 -266.620516) (xy 340.789304 -266.601044)
			(xy 340.841266 -266.589184) (xy 340.894416 -266.585201) (xy 340.947566 -266.589184) (xy 340.999528 -266.601044)
			(xy 341.049142 -266.620516) (xy 341.0953 -266.647165) (xy 341.136971 -266.680396) (xy 341.173223 -266.719467)
			(xy 341.203247 -266.763504) (xy 341.226373 -266.811525) (xy 341.242083 -266.862455) (xy 341.250026 -266.915159)
			(xy 341.250524 -266.941808) (xy 341.250026 -266.968457) (xy 341.478606 -266.968457) (xy 341.478606 -266.915159)
			(xy 341.486549 -266.862455) (xy 341.502259 -266.811525) (xy 341.525385 -266.763504) (xy 341.555409 -266.719467)
			(xy 341.591661 -266.680396) (xy 341.633332 -266.647165) (xy 341.67949 -266.620516) (xy 341.729104 -266.601044)
			(xy 341.781066 -266.589184) (xy 341.834216 -266.585201) (xy 341.887366 -266.589184) (xy 341.939328 -266.601044)
			(xy 341.988942 -266.620516) (xy 342.0351 -266.647165) (xy 342.076771 -266.680396) (xy 342.113023 -266.719467)
			(xy 342.143047 -266.763504) (xy 342.166173 -266.811525) (xy 342.181883 -266.862455) (xy 342.189826 -266.915159)
			(xy 342.190324 -266.941808) (xy 342.189826 -266.968457) (xy 342.418406 -266.968457) (xy 342.418406 -266.915159)
			(xy 342.426349 -266.862455) (xy 342.442059 -266.811525) (xy 342.465185 -266.763504) (xy 342.495209 -266.719467)
			(xy 342.531461 -266.680396) (xy 342.573132 -266.647165) (xy 342.61929 -266.620516) (xy 342.668904 -266.601044)
			(xy 342.720866 -266.589184) (xy 342.774016 -266.585201) (xy 342.827166 -266.589184) (xy 342.879128 -266.601044)
			(xy 342.928742 -266.620516) (xy 342.9749 -266.647165) (xy 343.016571 -266.680396) (xy 343.052823 -266.719467)
			(xy 343.082847 -266.763504) (xy 343.105973 -266.811525) (xy 343.121683 -266.862455) (xy 343.129626 -266.915159)
			(xy 343.130124 -266.941808) (xy 343.129626 -266.968457) (xy 343.358206 -266.968457) (xy 343.358206 -266.915159)
			(xy 343.366149 -266.862455) (xy 343.381859 -266.811525) (xy 343.404985 -266.763504) (xy 343.435009 -266.719467)
			(xy 343.471261 -266.680396) (xy 343.512932 -266.647165) (xy 343.55909 -266.620516) (xy 343.608704 -266.601044)
			(xy 343.660666 -266.589184) (xy 343.713816 -266.585201) (xy 343.766966 -266.589184) (xy 343.818928 -266.601044)
			(xy 343.868542 -266.620516) (xy 343.9147 -266.647165) (xy 343.956371 -266.680396) (xy 343.992623 -266.719467)
			(xy 344.022647 -266.763504) (xy 344.045773 -266.811525) (xy 344.061483 -266.862455) (xy 344.069426 -266.915159)
			(xy 344.069924 -266.941808) (xy 344.069426 -266.968457) (xy 344.298006 -266.968457) (xy 344.298006 -266.915159)
			(xy 344.305949 -266.862455) (xy 344.321659 -266.811525) (xy 344.344785 -266.763504) (xy 344.374809 -266.719467)
			(xy 344.411061 -266.680396) (xy 344.452732 -266.647165) (xy 344.49889 -266.620516) (xy 344.548504 -266.601044)
			(xy 344.600466 -266.589184) (xy 344.653616 -266.585201) (xy 344.706766 -266.589184) (xy 344.758728 -266.601044)
			(xy 344.808342 -266.620516) (xy 344.8545 -266.647165) (xy 344.896171 -266.680396) (xy 344.932423 -266.719467)
			(xy 344.962447 -266.763504) (xy 344.985573 -266.811525) (xy 345.001283 -266.862455) (xy 345.009226 -266.915159)
			(xy 345.009724 -266.941808) (xy 345.009226 -266.968457) (xy 345.237552 -266.968457) (xy 345.237552 -266.915159)
			(xy 345.245495 -266.862455) (xy 345.261205 -266.811525) (xy 345.284331 -266.763504) (xy 345.314355 -266.719467)
			(xy 345.350607 -266.680396) (xy 345.392278 -266.647165) (xy 345.438436 -266.620516) (xy 345.48805 -266.601044)
			(xy 345.540012 -266.589184) (xy 345.593162 -266.585201) (xy 345.646312 -266.589184) (xy 345.698274 -266.601044)
			(xy 345.747888 -266.620516) (xy 345.794046 -266.647165) (xy 345.835717 -266.680396) (xy 345.871969 -266.719467)
			(xy 345.901993 -266.763504) (xy 345.925119 -266.811525) (xy 345.940829 -266.862455) (xy 345.948772 -266.915159)
			(xy 345.94927 -266.941808) (xy 345.948772 -266.968457) (xy 346.177606 -266.968457) (xy 346.177606 -266.915159)
			(xy 346.185549 -266.862455) (xy 346.201259 -266.811525) (xy 346.224385 -266.763504) (xy 346.254409 -266.719467)
			(xy 346.290661 -266.680396) (xy 346.332332 -266.647165) (xy 346.37849 -266.620516) (xy 346.428104 -266.601044)
			(xy 346.480066 -266.589184) (xy 346.533216 -266.585201) (xy 346.586366 -266.589184) (xy 346.638328 -266.601044)
			(xy 346.687942 -266.620516) (xy 346.7341 -266.647165) (xy 346.775771 -266.680396) (xy 346.812023 -266.719467)
			(xy 346.842047 -266.763504) (xy 346.865173 -266.811525) (xy 346.880883 -266.862455) (xy 346.888826 -266.915159)
			(xy 346.889324 -266.941808) (xy 346.888826 -266.968457) (xy 347.117406 -266.968457) (xy 347.117406 -266.915159)
			(xy 347.125349 -266.862455) (xy 347.141059 -266.811525) (xy 347.164185 -266.763504) (xy 347.194209 -266.719467)
			(xy 347.230461 -266.680396) (xy 347.272132 -266.647165) (xy 347.31829 -266.620516) (xy 347.367904 -266.601044)
			(xy 347.419866 -266.589184) (xy 347.473016 -266.585201) (xy 347.526166 -266.589184) (xy 347.578128 -266.601044)
			(xy 347.627742 -266.620516) (xy 347.6739 -266.647165) (xy 347.715571 -266.680396) (xy 347.751823 -266.719467)
			(xy 347.781847 -266.763504) (xy 347.804973 -266.811525) (xy 347.820683 -266.862455) (xy 347.828626 -266.915159)
			(xy 347.829124 -266.941808) (xy 347.828626 -266.968457) (xy 348.057206 -266.968457) (xy 348.057206 -266.915159)
			(xy 348.065149 -266.862455) (xy 348.080859 -266.811525) (xy 348.103985 -266.763504) (xy 348.134009 -266.719467)
			(xy 348.170261 -266.680396) (xy 348.211932 -266.647165) (xy 348.25809 -266.620516) (xy 348.307704 -266.601044)
			(xy 348.359666 -266.589184) (xy 348.412816 -266.585201) (xy 348.465966 -266.589184) (xy 348.517928 -266.601044)
			(xy 348.567542 -266.620516) (xy 348.6137 -266.647165) (xy 348.655371 -266.680396) (xy 348.691623 -266.719467)
			(xy 348.721647 -266.763504) (xy 348.744773 -266.811525) (xy 348.760483 -266.862455) (xy 348.768426 -266.915159)
			(xy 348.768924 -266.941808) (xy 348.768426 -266.968457) (xy 348.997006 -266.968457) (xy 348.997006 -266.915159)
			(xy 349.004949 -266.862455) (xy 349.020659 -266.811525) (xy 349.043785 -266.763504) (xy 349.073809 -266.719467)
			(xy 349.110061 -266.680396) (xy 349.151732 -266.647165) (xy 349.19789 -266.620516) (xy 349.247504 -266.601044)
			(xy 349.299466 -266.589184) (xy 349.352616 -266.585201) (xy 349.405766 -266.589184) (xy 349.457728 -266.601044)
			(xy 349.507342 -266.620516) (xy 349.5535 -266.647165) (xy 349.595171 -266.680396) (xy 349.631423 -266.719467)
			(xy 349.661447 -266.763504) (xy 349.684573 -266.811525) (xy 349.700283 -266.862455) (xy 349.708226 -266.915159)
			(xy 349.708724 -266.941808) (xy 349.708226 -266.968457) (xy 349.936806 -266.968457) (xy 349.936806 -266.915159)
			(xy 349.944749 -266.862455) (xy 349.960459 -266.811525) (xy 349.983585 -266.763504) (xy 350.013609 -266.719467)
			(xy 350.049861 -266.680396) (xy 350.091532 -266.647165) (xy 350.13769 -266.620516) (xy 350.187304 -266.601044)
			(xy 350.239266 -266.589184) (xy 350.292416 -266.585201) (xy 350.345566 -266.589184) (xy 350.397528 -266.601044)
			(xy 350.447142 -266.620516) (xy 350.4933 -266.647165) (xy 350.534971 -266.680396) (xy 350.571223 -266.719467)
			(xy 350.601247 -266.763504) (xy 350.624373 -266.811525) (xy 350.640083 -266.862455) (xy 350.648026 -266.915159)
			(xy 350.648524 -266.941808) (xy 350.648026 -266.968457) (xy 350.876606 -266.968457) (xy 350.876606 -266.915159)
			(xy 350.884549 -266.862455) (xy 350.900259 -266.811525) (xy 350.923385 -266.763504) (xy 350.953409 -266.719467)
			(xy 350.989661 -266.680396) (xy 351.031332 -266.647165) (xy 351.07749 -266.620516) (xy 351.127104 -266.601044)
			(xy 351.179066 -266.589184) (xy 351.232216 -266.585201) (xy 351.285366 -266.589184) (xy 351.337328 -266.601044)
			(xy 351.386942 -266.620516) (xy 351.4331 -266.647165) (xy 351.474771 -266.680396) (xy 351.511023 -266.719467)
			(xy 351.541047 -266.763504) (xy 351.564173 -266.811525) (xy 351.579883 -266.862455) (xy 351.587826 -266.915159)
			(xy 351.588324 -266.941808) (xy 351.587826 -266.968457) (xy 351.816406 -266.968457) (xy 351.816406 -266.915159)
			(xy 351.824349 -266.862455) (xy 351.840059 -266.811525) (xy 351.863185 -266.763504) (xy 351.893209 -266.719467)
			(xy 351.929461 -266.680396) (xy 351.971132 -266.647165) (xy 352.01729 -266.620516) (xy 352.066904 -266.601044)
			(xy 352.118866 -266.589184) (xy 352.172016 -266.585201) (xy 352.225166 -266.589184) (xy 352.277128 -266.601044)
			(xy 352.326742 -266.620516) (xy 352.3729 -266.647165) (xy 352.414571 -266.680396) (xy 352.450823 -266.719467)
			(xy 352.480847 -266.763504) (xy 352.503973 -266.811525) (xy 352.519683 -266.862455) (xy 352.527626 -266.915159)
			(xy 352.528124 -266.941808) (xy 352.527626 -266.968457) (xy 352.756206 -266.968457) (xy 352.756206 -266.915159)
			(xy 352.764149 -266.862455) (xy 352.779859 -266.811525) (xy 352.802985 -266.763504) (xy 352.833009 -266.719467)
			(xy 352.869261 -266.680396) (xy 352.910932 -266.647165) (xy 352.95709 -266.620516) (xy 353.006704 -266.601044)
			(xy 353.058666 -266.589184) (xy 353.111816 -266.585201) (xy 353.164966 -266.589184) (xy 353.216928 -266.601044)
			(xy 353.266542 -266.620516) (xy 353.3127 -266.647165) (xy 353.354371 -266.680396) (xy 353.390623 -266.719467)
			(xy 353.420647 -266.763504) (xy 353.443773 -266.811525) (xy 353.459483 -266.862455) (xy 353.467426 -266.915159)
			(xy 353.467924 -266.941808) (xy 353.467426 -266.968457) (xy 353.696006 -266.968457) (xy 353.696006 -266.915159)
			(xy 353.703949 -266.862455) (xy 353.719659 -266.811525) (xy 353.742785 -266.763504) (xy 353.772809 -266.719467)
			(xy 353.809061 -266.680396) (xy 353.850732 -266.647165) (xy 353.89689 -266.620516) (xy 353.946504 -266.601044)
			(xy 353.998466 -266.589184) (xy 354.051616 -266.585201) (xy 354.104766 -266.589184) (xy 354.156728 -266.601044)
			(xy 354.206342 -266.620516) (xy 354.2525 -266.647165) (xy 354.294171 -266.680396) (xy 354.330423 -266.719467)
			(xy 354.360447 -266.763504) (xy 354.383573 -266.811525) (xy 354.399283 -266.862455) (xy 354.407226 -266.915159)
			(xy 354.407724 -266.941808) (xy 354.407226 -266.968457) (xy 354.635806 -266.968457) (xy 354.635806 -266.915159)
			(xy 354.643749 -266.862455) (xy 354.659459 -266.811525) (xy 354.682585 -266.763504) (xy 354.712609 -266.719467)
			(xy 354.748861 -266.680396) (xy 354.790532 -266.647165) (xy 354.83669 -266.620516) (xy 354.886304 -266.601044)
			(xy 354.938266 -266.589184) (xy 354.991416 -266.585201) (xy 355.044566 -266.589184) (xy 355.096528 -266.601044)
			(xy 355.146142 -266.620516) (xy 355.1923 -266.647165) (xy 355.233971 -266.680396) (xy 355.270223 -266.719467)
			(xy 355.300247 -266.763504) (xy 355.323373 -266.811525) (xy 355.339083 -266.862455) (xy 355.347026 -266.915159)
			(xy 355.347524 -266.941808) (xy 355.347026 -266.968457) (xy 355.339083 -267.021161) (xy 355.323373 -267.072091)
			(xy 355.300247 -267.120112) (xy 355.270223 -267.164149) (xy 355.233971 -267.20322) (xy 355.1923 -267.236451)
			(xy 355.146142 -267.2631) (xy 355.096528 -267.282572) (xy 355.044566 -267.294432) (xy 354.991416 -267.298416)
			(xy 354.938266 -267.294432) (xy 354.886304 -267.282572) (xy 354.83669 -267.2631) (xy 354.790532 -267.236451)
			(xy 354.748861 -267.20322) (xy 354.712609 -267.164149) (xy 354.682585 -267.120112) (xy 354.659459 -267.072091)
			(xy 354.643749 -267.021161) (xy 354.635806 -266.968457) (xy 354.407226 -266.968457) (xy 354.399283 -267.021161)
			(xy 354.383573 -267.072091) (xy 354.360447 -267.120112) (xy 354.330423 -267.164149) (xy 354.294171 -267.20322)
			(xy 354.2525 -267.236451) (xy 354.206342 -267.2631) (xy 354.156728 -267.282572) (xy 354.104766 -267.294432)
			(xy 354.051616 -267.298416) (xy 353.998466 -267.294432) (xy 353.946504 -267.282572) (xy 353.89689 -267.2631)
			(xy 353.850732 -267.236451) (xy 353.809061 -267.20322) (xy 353.772809 -267.164149) (xy 353.742785 -267.120112)
			(xy 353.719659 -267.072091) (xy 353.703949 -267.021161) (xy 353.696006 -266.968457) (xy 353.467426 -266.968457)
			(xy 353.459483 -267.021161) (xy 353.443773 -267.072091) (xy 353.420647 -267.120112) (xy 353.390623 -267.164149)
			(xy 353.354371 -267.20322) (xy 353.3127 -267.236451) (xy 353.266542 -267.2631) (xy 353.216928 -267.282572)
			(xy 353.164966 -267.294432) (xy 353.111816 -267.298416) (xy 353.058666 -267.294432) (xy 353.006704 -267.282572)
			(xy 352.95709 -267.2631) (xy 352.910932 -267.236451) (xy 352.869261 -267.20322) (xy 352.833009 -267.164149)
			(xy 352.802985 -267.120112) (xy 352.779859 -267.072091) (xy 352.764149 -267.021161) (xy 352.756206 -266.968457)
			(xy 352.527626 -266.968457) (xy 352.519683 -267.021161) (xy 352.503973 -267.072091) (xy 352.480847 -267.120112)
			(xy 352.450823 -267.164149) (xy 352.414571 -267.20322) (xy 352.3729 -267.236451) (xy 352.326742 -267.2631)
			(xy 352.277128 -267.282572) (xy 352.225166 -267.294432) (xy 352.172016 -267.298416) (xy 352.118866 -267.294432)
			(xy 352.066904 -267.282572) (xy 352.01729 -267.2631) (xy 351.971132 -267.236451) (xy 351.929461 -267.20322)
			(xy 351.893209 -267.164149) (xy 351.863185 -267.120112) (xy 351.840059 -267.072091) (xy 351.824349 -267.021161)
			(xy 351.816406 -266.968457) (xy 351.587826 -266.968457) (xy 351.579883 -267.021161) (xy 351.564173 -267.072091)
			(xy 351.541047 -267.120112) (xy 351.511023 -267.164149) (xy 351.474771 -267.20322) (xy 351.4331 -267.236451)
			(xy 351.386942 -267.2631) (xy 351.337328 -267.282572) (xy 351.285366 -267.294432) (xy 351.232216 -267.298416)
			(xy 351.179066 -267.294432) (xy 351.127104 -267.282572) (xy 351.07749 -267.2631) (xy 351.031332 -267.236451)
			(xy 350.989661 -267.20322) (xy 350.953409 -267.164149) (xy 350.923385 -267.120112) (xy 350.900259 -267.072091)
			(xy 350.884549 -267.021161) (xy 350.876606 -266.968457) (xy 350.648026 -266.968457) (xy 350.640083 -267.021161)
			(xy 350.624373 -267.072091) (xy 350.601247 -267.120112) (xy 350.571223 -267.164149) (xy 350.534971 -267.20322)
			(xy 350.4933 -267.236451) (xy 350.447142 -267.2631) (xy 350.397528 -267.282572) (xy 350.345566 -267.294432)
			(xy 350.292416 -267.298416) (xy 350.239266 -267.294432) (xy 350.187304 -267.282572) (xy 350.13769 -267.2631)
			(xy 350.091532 -267.236451) (xy 350.049861 -267.20322) (xy 350.013609 -267.164149) (xy 349.983585 -267.120112)
			(xy 349.960459 -267.072091) (xy 349.944749 -267.021161) (xy 349.936806 -266.968457) (xy 349.708226 -266.968457)
			(xy 349.700283 -267.021161) (xy 349.684573 -267.072091) (xy 349.661447 -267.120112) (xy 349.631423 -267.164149)
			(xy 349.595171 -267.20322) (xy 349.5535 -267.236451) (xy 349.507342 -267.2631) (xy 349.457728 -267.282572)
			(xy 349.405766 -267.294432) (xy 349.352616 -267.298416) (xy 349.299466 -267.294432) (xy 349.247504 -267.282572)
			(xy 349.19789 -267.2631) (xy 349.151732 -267.236451) (xy 349.110061 -267.20322) (xy 349.073809 -267.164149)
			(xy 349.043785 -267.120112) (xy 349.020659 -267.072091) (xy 349.004949 -267.021161) (xy 348.997006 -266.968457)
			(xy 348.768426 -266.968457) (xy 348.760483 -267.021161) (xy 348.744773 -267.072091) (xy 348.721647 -267.120112)
			(xy 348.691623 -267.164149) (xy 348.655371 -267.20322) (xy 348.6137 -267.236451) (xy 348.567542 -267.2631)
			(xy 348.517928 -267.282572) (xy 348.465966 -267.294432) (xy 348.412816 -267.298416) (xy 348.359666 -267.294432)
			(xy 348.307704 -267.282572) (xy 348.25809 -267.2631) (xy 348.211932 -267.236451) (xy 348.170261 -267.20322)
			(xy 348.134009 -267.164149) (xy 348.103985 -267.120112) (xy 348.080859 -267.072091) (xy 348.065149 -267.021161)
			(xy 348.057206 -266.968457) (xy 347.828626 -266.968457) (xy 347.820683 -267.021161) (xy 347.804973 -267.072091)
			(xy 347.781847 -267.120112) (xy 347.751823 -267.164149) (xy 347.715571 -267.20322) (xy 347.6739 -267.236451)
			(xy 347.627742 -267.2631) (xy 347.578128 -267.282572) (xy 347.526166 -267.294432) (xy 347.473016 -267.298416)
			(xy 347.419866 -267.294432) (xy 347.367904 -267.282572) (xy 347.31829 -267.2631) (xy 347.272132 -267.236451)
			(xy 347.230461 -267.20322) (xy 347.194209 -267.164149) (xy 347.164185 -267.120112) (xy 347.141059 -267.072091)
			(xy 347.125349 -267.021161) (xy 347.117406 -266.968457) (xy 346.888826 -266.968457) (xy 346.880883 -267.021161)
			(xy 346.865173 -267.072091) (xy 346.842047 -267.120112) (xy 346.812023 -267.164149) (xy 346.775771 -267.20322)
			(xy 346.7341 -267.236451) (xy 346.687942 -267.2631) (xy 346.638328 -267.282572) (xy 346.586366 -267.294432)
			(xy 346.533216 -267.298416) (xy 346.480066 -267.294432) (xy 346.428104 -267.282572) (xy 346.37849 -267.2631)
			(xy 346.332332 -267.236451) (xy 346.290661 -267.20322) (xy 346.254409 -267.164149) (xy 346.224385 -267.120112)
			(xy 346.201259 -267.072091) (xy 346.185549 -267.021161) (xy 346.177606 -266.968457) (xy 345.948772 -266.968457)
			(xy 345.940829 -267.021161) (xy 345.925119 -267.072091) (xy 345.901993 -267.120112) (xy 345.871969 -267.164149)
			(xy 345.835717 -267.20322) (xy 345.794046 -267.236451) (xy 345.747888 -267.2631) (xy 345.698274 -267.282572)
			(xy 345.646312 -267.294432) (xy 345.593162 -267.298416) (xy 345.540012 -267.294432) (xy 345.48805 -267.282572)
			(xy 345.438436 -267.2631) (xy 345.392278 -267.236451) (xy 345.350607 -267.20322) (xy 345.314355 -267.164149)
			(xy 345.284331 -267.120112) (xy 345.261205 -267.072091) (xy 345.245495 -267.021161) (xy 345.237552 -266.968457)
			(xy 345.009226 -266.968457) (xy 345.001283 -267.021161) (xy 344.985573 -267.072091) (xy 344.962447 -267.120112)
			(xy 344.932423 -267.164149) (xy 344.896171 -267.20322) (xy 344.8545 -267.236451) (xy 344.808342 -267.2631)
			(xy 344.758728 -267.282572) (xy 344.706766 -267.294432) (xy 344.653616 -267.298416) (xy 344.600466 -267.294432)
			(xy 344.548504 -267.282572) (xy 344.49889 -267.2631) (xy 344.452732 -267.236451) (xy 344.411061 -267.20322)
			(xy 344.374809 -267.164149) (xy 344.344785 -267.120112) (xy 344.321659 -267.072091) (xy 344.305949 -267.021161)
			(xy 344.298006 -266.968457) (xy 344.069426 -266.968457) (xy 344.061483 -267.021161) (xy 344.045773 -267.072091)
			(xy 344.022647 -267.120112) (xy 343.992623 -267.164149) (xy 343.956371 -267.20322) (xy 343.9147 -267.236451)
			(xy 343.868542 -267.2631) (xy 343.818928 -267.282572) (xy 343.766966 -267.294432) (xy 343.713816 -267.298416)
			(xy 343.660666 -267.294432) (xy 343.608704 -267.282572) (xy 343.55909 -267.2631) (xy 343.512932 -267.236451)
			(xy 343.471261 -267.20322) (xy 343.435009 -267.164149) (xy 343.404985 -267.120112) (xy 343.381859 -267.072091)
			(xy 343.366149 -267.021161) (xy 343.358206 -266.968457) (xy 343.129626 -266.968457) (xy 343.121683 -267.021161)
			(xy 343.105973 -267.072091) (xy 343.082847 -267.120112) (xy 343.052823 -267.164149) (xy 343.016571 -267.20322)
			(xy 342.9749 -267.236451) (xy 342.928742 -267.2631) (xy 342.879128 -267.282572) (xy 342.827166 -267.294432)
			(xy 342.774016 -267.298416) (xy 342.720866 -267.294432) (xy 342.668904 -267.282572) (xy 342.61929 -267.2631)
			(xy 342.573132 -267.236451) (xy 342.531461 -267.20322) (xy 342.495209 -267.164149) (xy 342.465185 -267.120112)
			(xy 342.442059 -267.072091) (xy 342.426349 -267.021161) (xy 342.418406 -266.968457) (xy 342.189826 -266.968457)
			(xy 342.181883 -267.021161) (xy 342.166173 -267.072091) (xy 342.143047 -267.120112) (xy 342.113023 -267.164149)
			(xy 342.076771 -267.20322) (xy 342.0351 -267.236451) (xy 341.988942 -267.2631) (xy 341.939328 -267.282572)
			(xy 341.887366 -267.294432) (xy 341.834216 -267.298416) (xy 341.781066 -267.294432) (xy 341.729104 -267.282572)
			(xy 341.67949 -267.2631) (xy 341.633332 -267.236451) (xy 341.591661 -267.20322) (xy 341.555409 -267.164149)
			(xy 341.525385 -267.120112) (xy 341.502259 -267.072091) (xy 341.486549 -267.021161) (xy 341.478606 -266.968457)
			(xy 341.250026 -266.968457) (xy 341.242083 -267.021161) (xy 341.226373 -267.072091) (xy 341.203247 -267.120112)
			(xy 341.173223 -267.164149) (xy 341.136971 -267.20322) (xy 341.0953 -267.236451) (xy 341.049142 -267.2631)
			(xy 340.999528 -267.282572) (xy 340.947566 -267.294432) (xy 340.894416 -267.298416) (xy 340.841266 -267.294432)
			(xy 340.789304 -267.282572) (xy 340.73969 -267.2631) (xy 340.693532 -267.236451) (xy 340.651861 -267.20322)
			(xy 340.615609 -267.164149) (xy 340.585585 -267.120112) (xy 340.562459 -267.072091) (xy 340.546749 -267.021161)
			(xy 340.538806 -266.968457) (xy 340.310226 -266.968457) (xy 340.302283 -267.021161) (xy 340.286573 -267.072091)
			(xy 340.263447 -267.120112) (xy 340.233423 -267.164149) (xy 340.197171 -267.20322) (xy 340.1555 -267.236451)
			(xy 340.109342 -267.2631) (xy 340.059728 -267.282572) (xy 340.007766 -267.294432) (xy 339.954616 -267.298416)
			(xy 339.901466 -267.294432) (xy 339.849504 -267.282572) (xy 339.79989 -267.2631) (xy 339.753732 -267.236451)
			(xy 339.712061 -267.20322) (xy 339.675809 -267.164149) (xy 339.645785 -267.120112) (xy 339.622659 -267.072091)
			(xy 339.606949 -267.021161) (xy 339.599006 -266.968457) (xy 339.37956 -266.968457) (xy 339.37956 -267.29817)
			(xy 339.37996 -267.311562) (xy 339.386916 -267.337426) (xy 339.400358 -267.360591) (xy 339.419361 -267.379465)
			(xy 339.442618 -267.392749) (xy 339.468528 -267.399529) (xy 339.481922 -267.39977) (xy 339.484462 -267.39977)
			(xy 339.511117 -267.400241) (xy 339.563831 -267.408181) (xy 339.614773 -267.42389) (xy 339.662805 -267.447016)
			(xy 339.706853 -267.477043) (xy 339.745934 -267.5133) (xy 339.779173 -267.554978) (xy 339.805829 -267.601144)
			(xy 339.825307 -267.650767) (xy 339.83717 -267.70274) (xy 339.841154 -267.7559) (xy 339.839158 -267.782527)
			(xy 340.068652 -267.782527) (xy 340.068652 -267.729229) (xy 340.076595 -267.676525) (xy 340.092305 -267.625595)
			(xy 340.115431 -267.577574) (xy 340.145455 -267.533537) (xy 340.181707 -267.494466) (xy 340.223378 -267.461235)
			(xy 340.269536 -267.434586) (xy 340.31915 -267.415114) (xy 340.371112 -267.403254) (xy 340.424262 -267.399271)
			(xy 340.477412 -267.403254) (xy 340.529374 -267.415114) (xy 340.578988 -267.434586) (xy 340.625146 -267.461235)
			(xy 340.666817 -267.494466) (xy 340.703069 -267.533537) (xy 340.733093 -267.577574) (xy 340.756219 -267.625595)
			(xy 340.771929 -267.676525) (xy 340.779872 -267.729229) (xy 340.78037 -267.755878) (xy 340.779872 -267.782527)
			(xy 341.008452 -267.782527) (xy 341.008452 -267.729229) (xy 341.016395 -267.676525) (xy 341.032105 -267.625595)
			(xy 341.055231 -267.577574) (xy 341.085255 -267.533537) (xy 341.121507 -267.494466) (xy 341.163178 -267.461235)
			(xy 341.209336 -267.434586) (xy 341.25895 -267.415114) (xy 341.310912 -267.403254) (xy 341.364062 -267.399271)
			(xy 341.417212 -267.403254) (xy 341.469174 -267.415114) (xy 341.518788 -267.434586) (xy 341.564946 -267.461235)
			(xy 341.606617 -267.494466) (xy 341.642869 -267.533537) (xy 341.672893 -267.577574) (xy 341.696019 -267.625595)
			(xy 341.711729 -267.676525) (xy 341.719672 -267.729229) (xy 341.72017 -267.755878) (xy 341.719672 -267.782527)
			(xy 341.948252 -267.782527) (xy 341.948252 -267.729229) (xy 341.956195 -267.676525) (xy 341.971905 -267.625595)
			(xy 341.995031 -267.577574) (xy 342.025055 -267.533537) (xy 342.061307 -267.494466) (xy 342.102978 -267.461235)
			(xy 342.149136 -267.434586) (xy 342.19875 -267.415114) (xy 342.250712 -267.403254) (xy 342.303862 -267.399271)
			(xy 342.357012 -267.403254) (xy 342.408974 -267.415114) (xy 342.458588 -267.434586) (xy 342.504746 -267.461235)
			(xy 342.546417 -267.494466) (xy 342.582669 -267.533537) (xy 342.612693 -267.577574) (xy 342.635819 -267.625595)
			(xy 342.651529 -267.676525) (xy 342.659472 -267.729229) (xy 342.65997 -267.755878) (xy 342.659472 -267.782527)
			(xy 342.888052 -267.782527) (xy 342.888052 -267.729229) (xy 342.895995 -267.676525) (xy 342.911705 -267.625595)
			(xy 342.934831 -267.577574) (xy 342.964855 -267.533537) (xy 343.001107 -267.494466) (xy 343.042778 -267.461235)
			(xy 343.088936 -267.434586) (xy 343.13855 -267.415114) (xy 343.190512 -267.403254) (xy 343.243662 -267.399271)
			(xy 343.296812 -267.403254) (xy 343.348774 -267.415114) (xy 343.398388 -267.434586) (xy 343.444546 -267.461235)
			(xy 343.486217 -267.494466) (xy 343.522469 -267.533537) (xy 343.552493 -267.577574) (xy 343.575619 -267.625595)
			(xy 343.591329 -267.676525) (xy 343.599272 -267.729229) (xy 343.59977 -267.755878) (xy 343.599272 -267.782527)
			(xy 343.827852 -267.782527) (xy 343.827852 -267.729229) (xy 343.835795 -267.676525) (xy 343.851505 -267.625595)
			(xy 343.874631 -267.577574) (xy 343.904655 -267.533537) (xy 343.940907 -267.494466) (xy 343.982578 -267.461235)
			(xy 344.028736 -267.434586) (xy 344.07835 -267.415114) (xy 344.130312 -267.403254) (xy 344.183462 -267.399271)
			(xy 344.236612 -267.403254) (xy 344.288574 -267.415114) (xy 344.338188 -267.434586) (xy 344.384346 -267.461235)
			(xy 344.426017 -267.494466) (xy 344.462269 -267.533537) (xy 344.492293 -267.577574) (xy 344.515419 -267.625595)
			(xy 344.531129 -267.676525) (xy 344.539072 -267.729229) (xy 344.53957 -267.755878) (xy 344.539072 -267.782527)
			(xy 344.767906 -267.782527) (xy 344.767906 -267.729229) (xy 344.775849 -267.676525) (xy 344.791559 -267.625595)
			(xy 344.814685 -267.577574) (xy 344.844709 -267.533537) (xy 344.880961 -267.494466) (xy 344.922632 -267.461235)
			(xy 344.96879 -267.434586) (xy 345.018404 -267.415114) (xy 345.070366 -267.403254) (xy 345.123516 -267.399271)
			(xy 345.176666 -267.403254) (xy 345.228628 -267.415114) (xy 345.278242 -267.434586) (xy 345.3244 -267.461235)
			(xy 345.366071 -267.494466) (xy 345.402323 -267.533537) (xy 345.432347 -267.577574) (xy 345.455473 -267.625595)
			(xy 345.471183 -267.676525) (xy 345.479126 -267.729229) (xy 345.479624 -267.755878) (xy 345.479126 -267.782527)
			(xy 345.707452 -267.782527) (xy 345.707452 -267.729229) (xy 345.715395 -267.676525) (xy 345.731105 -267.625595)
			(xy 345.754231 -267.577574) (xy 345.784255 -267.533537) (xy 345.820507 -267.494466) (xy 345.862178 -267.461235)
			(xy 345.908336 -267.434586) (xy 345.95795 -267.415114) (xy 346.009912 -267.403254) (xy 346.063062 -267.399271)
			(xy 346.116212 -267.403254) (xy 346.168174 -267.415114) (xy 346.217788 -267.434586) (xy 346.263946 -267.461235)
			(xy 346.305617 -267.494466) (xy 346.341869 -267.533537) (xy 346.371893 -267.577574) (xy 346.395019 -267.625595)
			(xy 346.410729 -267.676525) (xy 346.418672 -267.729229) (xy 346.41917 -267.755878) (xy 346.418672 -267.782527)
			(xy 346.647252 -267.782527) (xy 346.647252 -267.729229) (xy 346.655195 -267.676525) (xy 346.670905 -267.625595)
			(xy 346.694031 -267.577574) (xy 346.724055 -267.533537) (xy 346.760307 -267.494466) (xy 346.801978 -267.461235)
			(xy 346.848136 -267.434586) (xy 346.89775 -267.415114) (xy 346.949712 -267.403254) (xy 347.002862 -267.399271)
			(xy 347.056012 -267.403254) (xy 347.107974 -267.415114) (xy 347.157588 -267.434586) (xy 347.203746 -267.461235)
			(xy 347.245417 -267.494466) (xy 347.281669 -267.533537) (xy 347.311693 -267.577574) (xy 347.334819 -267.625595)
			(xy 347.350529 -267.676525) (xy 347.358472 -267.729229) (xy 347.35897 -267.755878) (xy 347.358472 -267.782527)
			(xy 347.587052 -267.782527) (xy 347.587052 -267.729229) (xy 347.594995 -267.676525) (xy 347.610705 -267.625595)
			(xy 347.633831 -267.577574) (xy 347.663855 -267.533537) (xy 347.700107 -267.494466) (xy 347.741778 -267.461235)
			(xy 347.787936 -267.434586) (xy 347.83755 -267.415114) (xy 347.889512 -267.403254) (xy 347.942662 -267.399271)
			(xy 347.995812 -267.403254) (xy 348.047774 -267.415114) (xy 348.097388 -267.434586) (xy 348.143546 -267.461235)
			(xy 348.185217 -267.494466) (xy 348.221469 -267.533537) (xy 348.251493 -267.577574) (xy 348.274619 -267.625595)
			(xy 348.290329 -267.676525) (xy 348.298272 -267.729229) (xy 348.29877 -267.755878) (xy 348.298272 -267.782527)
			(xy 348.526852 -267.782527) (xy 348.526852 -267.729229) (xy 348.534795 -267.676525) (xy 348.550505 -267.625595)
			(xy 348.573631 -267.577574) (xy 348.603655 -267.533537) (xy 348.639907 -267.494466) (xy 348.681578 -267.461235)
			(xy 348.727736 -267.434586) (xy 348.77735 -267.415114) (xy 348.829312 -267.403254) (xy 348.882462 -267.399271)
			(xy 348.935612 -267.403254) (xy 348.987574 -267.415114) (xy 349.037188 -267.434586) (xy 349.083346 -267.461235)
			(xy 349.125017 -267.494466) (xy 349.161269 -267.533537) (xy 349.191293 -267.577574) (xy 349.214419 -267.625595)
			(xy 349.230129 -267.676525) (xy 349.238072 -267.729229) (xy 349.23857 -267.755878) (xy 349.238072 -267.782527)
			(xy 349.466652 -267.782527) (xy 349.466652 -267.729229) (xy 349.474595 -267.676525) (xy 349.490305 -267.625595)
			(xy 349.513431 -267.577574) (xy 349.543455 -267.533537) (xy 349.579707 -267.494466) (xy 349.621378 -267.461235)
			(xy 349.667536 -267.434586) (xy 349.71715 -267.415114) (xy 349.769112 -267.403254) (xy 349.822262 -267.399271)
			(xy 349.875412 -267.403254) (xy 349.927374 -267.415114) (xy 349.976988 -267.434586) (xy 350.023146 -267.461235)
			(xy 350.064817 -267.494466) (xy 350.101069 -267.533537) (xy 350.131093 -267.577574) (xy 350.154219 -267.625595)
			(xy 350.169929 -267.676525) (xy 350.177872 -267.729229) (xy 350.17837 -267.755878) (xy 350.177872 -267.782527)
			(xy 350.406452 -267.782527) (xy 350.406452 -267.729229) (xy 350.414395 -267.676525) (xy 350.430105 -267.625595)
			(xy 350.453231 -267.577574) (xy 350.483255 -267.533537) (xy 350.519507 -267.494466) (xy 350.561178 -267.461235)
			(xy 350.607336 -267.434586) (xy 350.65695 -267.415114) (xy 350.708912 -267.403254) (xy 350.762062 -267.399271)
			(xy 350.815212 -267.403254) (xy 350.867174 -267.415114) (xy 350.916788 -267.434586) (xy 350.962946 -267.461235)
			(xy 351.004617 -267.494466) (xy 351.040869 -267.533537) (xy 351.070893 -267.577574) (xy 351.094019 -267.625595)
			(xy 351.109729 -267.676525) (xy 351.117672 -267.729229) (xy 351.11817 -267.755878) (xy 351.117672 -267.782527)
			(xy 351.346252 -267.782527) (xy 351.346252 -267.729229) (xy 351.354195 -267.676525) (xy 351.369905 -267.625595)
			(xy 351.393031 -267.577574) (xy 351.423055 -267.533537) (xy 351.459307 -267.494466) (xy 351.500978 -267.461235)
			(xy 351.547136 -267.434586) (xy 351.59675 -267.415114) (xy 351.648712 -267.403254) (xy 351.701862 -267.399271)
			(xy 351.755012 -267.403254) (xy 351.806974 -267.415114) (xy 351.856588 -267.434586) (xy 351.902746 -267.461235)
			(xy 351.944417 -267.494466) (xy 351.980669 -267.533537) (xy 352.010693 -267.577574) (xy 352.033819 -267.625595)
			(xy 352.049529 -267.676525) (xy 352.057472 -267.729229) (xy 352.05797 -267.755878) (xy 352.057472 -267.782527)
			(xy 352.286052 -267.782527) (xy 352.286052 -267.729229) (xy 352.293995 -267.676525) (xy 352.309705 -267.625595)
			(xy 352.332831 -267.577574) (xy 352.362855 -267.533537) (xy 352.399107 -267.494466) (xy 352.440778 -267.461235)
			(xy 352.486936 -267.434586) (xy 352.53655 -267.415114) (xy 352.588512 -267.403254) (xy 352.641662 -267.399271)
			(xy 352.694812 -267.403254) (xy 352.746774 -267.415114) (xy 352.796388 -267.434586) (xy 352.842546 -267.461235)
			(xy 352.884217 -267.494466) (xy 352.920469 -267.533537) (xy 352.950493 -267.577574) (xy 352.973619 -267.625595)
			(xy 352.989329 -267.676525) (xy 352.997272 -267.729229) (xy 352.99777 -267.755878) (xy 352.997272 -267.782527)
			(xy 353.225852 -267.782527) (xy 353.225852 -267.729229) (xy 353.233795 -267.676525) (xy 353.249505 -267.625595)
			(xy 353.272631 -267.577574) (xy 353.302655 -267.533537) (xy 353.338907 -267.494466) (xy 353.380578 -267.461235)
			(xy 353.426736 -267.434586) (xy 353.47635 -267.415114) (xy 353.528312 -267.403254) (xy 353.581462 -267.399271)
			(xy 353.634612 -267.403254) (xy 353.686574 -267.415114) (xy 353.736188 -267.434586) (xy 353.782346 -267.461235)
			(xy 353.824017 -267.494466) (xy 353.860269 -267.533537) (xy 353.890293 -267.577574) (xy 353.913419 -267.625595)
			(xy 353.929129 -267.676525) (xy 353.937072 -267.729229) (xy 353.93757 -267.755878) (xy 353.937072 -267.782527)
			(xy 354.165652 -267.782527) (xy 354.165652 -267.729229) (xy 354.173595 -267.676525) (xy 354.189305 -267.625595)
			(xy 354.212431 -267.577574) (xy 354.242455 -267.533537) (xy 354.278707 -267.494466) (xy 354.320378 -267.461235)
			(xy 354.366536 -267.434586) (xy 354.41615 -267.415114) (xy 354.468112 -267.403254) (xy 354.521262 -267.399271)
			(xy 354.574412 -267.403254) (xy 354.626374 -267.415114) (xy 354.675988 -267.434586) (xy 354.722146 -267.461235)
			(xy 354.763817 -267.494466) (xy 354.800069 -267.533537) (xy 354.830093 -267.577574) (xy 354.853219 -267.625595)
			(xy 354.868929 -267.676525) (xy 354.876872 -267.729229) (xy 354.87737 -267.755878) (xy 354.876872 -267.782527)
			(xy 355.105452 -267.782527) (xy 355.105452 -267.729229) (xy 355.113395 -267.676525) (xy 355.129105 -267.625595)
			(xy 355.152231 -267.577574) (xy 355.182255 -267.533537) (xy 355.218507 -267.494466) (xy 355.260178 -267.461235)
			(xy 355.306336 -267.434586) (xy 355.35595 -267.415114) (xy 355.407912 -267.403254) (xy 355.461062 -267.399271)
			(xy 355.514212 -267.403254) (xy 355.566174 -267.415114) (xy 355.615788 -267.434586) (xy 355.661946 -267.461235)
			(xy 355.703617 -267.494466) (xy 355.739869 -267.533537) (xy 355.769893 -267.577574) (xy 355.793019 -267.625595)
			(xy 355.808729 -267.676525) (xy 355.816672 -267.729229) (xy 355.81717 -267.755878) (xy 355.816672 -267.782527)
			(xy 355.808729 -267.835231) (xy 355.793019 -267.886161) (xy 355.769893 -267.934182) (xy 355.739869 -267.978219)
			(xy 355.703617 -268.01729) (xy 355.661946 -268.050521) (xy 355.615788 -268.07717) (xy 355.566174 -268.096642)
			(xy 355.514212 -268.108502) (xy 355.461062 -268.112486) (xy 355.407912 -268.108502) (xy 355.35595 -268.096642)
			(xy 355.306336 -268.07717) (xy 355.260178 -268.050521) (xy 355.218507 -268.01729) (xy 355.182255 -267.978219)
			(xy 355.152231 -267.934182) (xy 355.129105 -267.886161) (xy 355.113395 -267.835231) (xy 355.105452 -267.782527)
			(xy 354.876872 -267.782527) (xy 354.868929 -267.835231) (xy 354.853219 -267.886161) (xy 354.830093 -267.934182)
			(xy 354.800069 -267.978219) (xy 354.763817 -268.01729) (xy 354.722146 -268.050521) (xy 354.675988 -268.07717)
			(xy 354.626374 -268.096642) (xy 354.574412 -268.108502) (xy 354.521262 -268.112486) (xy 354.468112 -268.108502)
			(xy 354.41615 -268.096642) (xy 354.366536 -268.07717) (xy 354.320378 -268.050521) (xy 354.278707 -268.01729)
			(xy 354.242455 -267.978219) (xy 354.212431 -267.934182) (xy 354.189305 -267.886161) (xy 354.173595 -267.835231)
			(xy 354.165652 -267.782527) (xy 353.937072 -267.782527) (xy 353.929129 -267.835231) (xy 353.913419 -267.886161)
			(xy 353.890293 -267.934182) (xy 353.860269 -267.978219) (xy 353.824017 -268.01729) (xy 353.782346 -268.050521)
			(xy 353.736188 -268.07717) (xy 353.686574 -268.096642) (xy 353.634612 -268.108502) (xy 353.581462 -268.112486)
			(xy 353.528312 -268.108502) (xy 353.47635 -268.096642) (xy 353.426736 -268.07717) (xy 353.380578 -268.050521)
			(xy 353.338907 -268.01729) (xy 353.302655 -267.978219) (xy 353.272631 -267.934182) (xy 353.249505 -267.886161)
			(xy 353.233795 -267.835231) (xy 353.225852 -267.782527) (xy 352.997272 -267.782527) (xy 352.989329 -267.835231)
			(xy 352.973619 -267.886161) (xy 352.950493 -267.934182) (xy 352.920469 -267.978219) (xy 352.884217 -268.01729)
			(xy 352.842546 -268.050521) (xy 352.796388 -268.07717) (xy 352.746774 -268.096642) (xy 352.694812 -268.108502)
			(xy 352.641662 -268.112486) (xy 352.588512 -268.108502) (xy 352.53655 -268.096642) (xy 352.486936 -268.07717)
			(xy 352.440778 -268.050521) (xy 352.399107 -268.01729) (xy 352.362855 -267.978219) (xy 352.332831 -267.934182)
			(xy 352.309705 -267.886161) (xy 352.293995 -267.835231) (xy 352.286052 -267.782527) (xy 352.057472 -267.782527)
			(xy 352.049529 -267.835231) (xy 352.033819 -267.886161) (xy 352.010693 -267.934182) (xy 351.980669 -267.978219)
			(xy 351.944417 -268.01729) (xy 351.902746 -268.050521) (xy 351.856588 -268.07717) (xy 351.806974 -268.096642)
			(xy 351.755012 -268.108502) (xy 351.701862 -268.112486) (xy 351.648712 -268.108502) (xy 351.59675 -268.096642)
			(xy 351.547136 -268.07717) (xy 351.500978 -268.050521) (xy 351.459307 -268.01729) (xy 351.423055 -267.978219)
			(xy 351.393031 -267.934182) (xy 351.369905 -267.886161) (xy 351.354195 -267.835231) (xy 351.346252 -267.782527)
			(xy 351.117672 -267.782527) (xy 351.109729 -267.835231) (xy 351.094019 -267.886161) (xy 351.070893 -267.934182)
			(xy 351.040869 -267.978219) (xy 351.004617 -268.01729) (xy 350.962946 -268.050521) (xy 350.916788 -268.07717)
			(xy 350.867174 -268.096642) (xy 350.815212 -268.108502) (xy 350.762062 -268.112486) (xy 350.708912 -268.108502)
			(xy 350.65695 -268.096642) (xy 350.607336 -268.07717) (xy 350.561178 -268.050521) (xy 350.519507 -268.01729)
			(xy 350.483255 -267.978219) (xy 350.453231 -267.934182) (xy 350.430105 -267.886161) (xy 350.414395 -267.835231)
			(xy 350.406452 -267.782527) (xy 350.177872 -267.782527) (xy 350.169929 -267.835231) (xy 350.154219 -267.886161)
			(xy 350.131093 -267.934182) (xy 350.101069 -267.978219) (xy 350.064817 -268.01729) (xy 350.023146 -268.050521)
			(xy 349.976988 -268.07717) (xy 349.927374 -268.096642) (xy 349.875412 -268.108502) (xy 349.822262 -268.112486)
			(xy 349.769112 -268.108502) (xy 349.71715 -268.096642) (xy 349.667536 -268.07717) (xy 349.621378 -268.050521)
			(xy 349.579707 -268.01729) (xy 349.543455 -267.978219) (xy 349.513431 -267.934182) (xy 349.490305 -267.886161)
			(xy 349.474595 -267.835231) (xy 349.466652 -267.782527) (xy 349.238072 -267.782527) (xy 349.230129 -267.835231)
			(xy 349.214419 -267.886161) (xy 349.191293 -267.934182) (xy 349.161269 -267.978219) (xy 349.125017 -268.01729)
			(xy 349.083346 -268.050521) (xy 349.037188 -268.07717) (xy 348.987574 -268.096642) (xy 348.935612 -268.108502)
			(xy 348.882462 -268.112486) (xy 348.829312 -268.108502) (xy 348.77735 -268.096642) (xy 348.727736 -268.07717)
			(xy 348.681578 -268.050521) (xy 348.639907 -268.01729) (xy 348.603655 -267.978219) (xy 348.573631 -267.934182)
			(xy 348.550505 -267.886161) (xy 348.534795 -267.835231) (xy 348.526852 -267.782527) (xy 348.298272 -267.782527)
			(xy 348.290329 -267.835231) (xy 348.274619 -267.886161) (xy 348.251493 -267.934182) (xy 348.221469 -267.978219)
			(xy 348.185217 -268.01729) (xy 348.143546 -268.050521) (xy 348.097388 -268.07717) (xy 348.047774 -268.096642)
			(xy 347.995812 -268.108502) (xy 347.942662 -268.112486) (xy 347.889512 -268.108502) (xy 347.83755 -268.096642)
			(xy 347.787936 -268.07717) (xy 347.741778 -268.050521) (xy 347.700107 -268.01729) (xy 347.663855 -267.978219)
			(xy 347.633831 -267.934182) (xy 347.610705 -267.886161) (xy 347.594995 -267.835231) (xy 347.587052 -267.782527)
			(xy 347.358472 -267.782527) (xy 347.350529 -267.835231) (xy 347.334819 -267.886161) (xy 347.311693 -267.934182)
			(xy 347.281669 -267.978219) (xy 347.245417 -268.01729) (xy 347.203746 -268.050521) (xy 347.157588 -268.07717)
			(xy 347.107974 -268.096642) (xy 347.056012 -268.108502) (xy 347.002862 -268.112486) (xy 346.949712 -268.108502)
			(xy 346.89775 -268.096642) (xy 346.848136 -268.07717) (xy 346.801978 -268.050521) (xy 346.760307 -268.01729)
			(xy 346.724055 -267.978219) (xy 346.694031 -267.934182) (xy 346.670905 -267.886161) (xy 346.655195 -267.835231)
			(xy 346.647252 -267.782527) (xy 346.418672 -267.782527) (xy 346.410729 -267.835231) (xy 346.395019 -267.886161)
			(xy 346.371893 -267.934182) (xy 346.341869 -267.978219) (xy 346.305617 -268.01729) (xy 346.263946 -268.050521)
			(xy 346.217788 -268.07717) (xy 346.168174 -268.096642) (xy 346.116212 -268.108502) (xy 346.063062 -268.112486)
			(xy 346.009912 -268.108502) (xy 345.95795 -268.096642) (xy 345.908336 -268.07717) (xy 345.862178 -268.050521)
			(xy 345.820507 -268.01729) (xy 345.784255 -267.978219) (xy 345.754231 -267.934182) (xy 345.731105 -267.886161)
			(xy 345.715395 -267.835231) (xy 345.707452 -267.782527) (xy 345.479126 -267.782527) (xy 345.471183 -267.835231)
			(xy 345.455473 -267.886161) (xy 345.432347 -267.934182) (xy 345.402323 -267.978219) (xy 345.366071 -268.01729)
			(xy 345.3244 -268.050521) (xy 345.278242 -268.07717) (xy 345.228628 -268.096642) (xy 345.176666 -268.108502)
			(xy 345.123516 -268.112486) (xy 345.070366 -268.108502) (xy 345.018404 -268.096642) (xy 344.96879 -268.07717)
			(xy 344.922632 -268.050521) (xy 344.880961 -268.01729) (xy 344.844709 -267.978219) (xy 344.814685 -267.934182)
			(xy 344.791559 -267.886161) (xy 344.775849 -267.835231) (xy 344.767906 -267.782527) (xy 344.539072 -267.782527)
			(xy 344.531129 -267.835231) (xy 344.515419 -267.886161) (xy 344.492293 -267.934182) (xy 344.462269 -267.978219)
			(xy 344.426017 -268.01729) (xy 344.384346 -268.050521) (xy 344.338188 -268.07717) (xy 344.288574 -268.096642)
			(xy 344.236612 -268.108502) (xy 344.183462 -268.112486) (xy 344.130312 -268.108502) (xy 344.07835 -268.096642)
			(xy 344.028736 -268.07717) (xy 343.982578 -268.050521) (xy 343.940907 -268.01729) (xy 343.904655 -267.978219)
			(xy 343.874631 -267.934182) (xy 343.851505 -267.886161) (xy 343.835795 -267.835231) (xy 343.827852 -267.782527)
			(xy 343.599272 -267.782527) (xy 343.591329 -267.835231) (xy 343.575619 -267.886161) (xy 343.552493 -267.934182)
			(xy 343.522469 -267.978219) (xy 343.486217 -268.01729) (xy 343.444546 -268.050521) (xy 343.398388 -268.07717)
			(xy 343.348774 -268.096642) (xy 343.296812 -268.108502) (xy 343.243662 -268.112486) (xy 343.190512 -268.108502)
			(xy 343.13855 -268.096642) (xy 343.088936 -268.07717) (xy 343.042778 -268.050521) (xy 343.001107 -268.01729)
			(xy 342.964855 -267.978219) (xy 342.934831 -267.934182) (xy 342.911705 -267.886161) (xy 342.895995 -267.835231)
			(xy 342.888052 -267.782527) (xy 342.659472 -267.782527) (xy 342.651529 -267.835231) (xy 342.635819 -267.886161)
			(xy 342.612693 -267.934182) (xy 342.582669 -267.978219) (xy 342.546417 -268.01729) (xy 342.504746 -268.050521)
			(xy 342.458588 -268.07717) (xy 342.408974 -268.096642) (xy 342.357012 -268.108502) (xy 342.303862 -268.112486)
			(xy 342.250712 -268.108502) (xy 342.19875 -268.096642) (xy 342.149136 -268.07717) (xy 342.102978 -268.050521)
			(xy 342.061307 -268.01729) (xy 342.025055 -267.978219) (xy 341.995031 -267.934182) (xy 341.971905 -267.886161)
			(xy 341.956195 -267.835231) (xy 341.948252 -267.782527) (xy 341.719672 -267.782527) (xy 341.711729 -267.835231)
			(xy 341.696019 -267.886161) (xy 341.672893 -267.934182) (xy 341.642869 -267.978219) (xy 341.606617 -268.01729)
			(xy 341.564946 -268.050521) (xy 341.518788 -268.07717) (xy 341.469174 -268.096642) (xy 341.417212 -268.108502)
			(xy 341.364062 -268.112486) (xy 341.310912 -268.108502) (xy 341.25895 -268.096642) (xy 341.209336 -268.07717)
			(xy 341.163178 -268.050521) (xy 341.121507 -268.01729) (xy 341.085255 -267.978219) (xy 341.055231 -267.934182)
			(xy 341.032105 -267.886161) (xy 341.016395 -267.835231) (xy 341.008452 -267.782527) (xy 340.779872 -267.782527)
			(xy 340.771929 -267.835231) (xy 340.756219 -267.886161) (xy 340.733093 -267.934182) (xy 340.703069 -267.978219)
			(xy 340.666817 -268.01729) (xy 340.625146 -268.050521) (xy 340.578988 -268.07717) (xy 340.529374 -268.096642)
			(xy 340.477412 -268.108502) (xy 340.424262 -268.112486) (xy 340.371112 -268.108502) (xy 340.31915 -268.096642)
			(xy 340.269536 -268.07717) (xy 340.223378 -268.050521) (xy 340.181707 -268.01729) (xy 340.145455 -267.978219)
			(xy 340.115431 -267.934182) (xy 340.092305 -267.886161) (xy 340.076595 -267.835231) (xy 340.068652 -267.782527)
			(xy 339.839158 -267.782527) (xy 339.83717 -267.80906) (xy 339.825307 -267.861033) (xy 339.805829 -267.910656)
			(xy 339.779173 -267.956822) (xy 339.745934 -267.9985) (xy 339.706853 -268.034757) (xy 339.662805 -268.064784)
			(xy 339.614773 -268.08791) (xy 339.563831 -268.103619) (xy 339.511117 -268.111559) (xy 339.484462 -268.111986)
			(xy 339.481922 -268.111986) (xy 339.468535 -268.112295) (xy 339.442637 -268.119069) (xy 339.41939 -268.132343)
			(xy 339.400393 -268.151203) (xy 339.386951 -268.174353) (xy 339.379989 -268.200201) (xy 339.37956 -268.213586)
			(xy 339.37956 -268.596343) (xy 339.599006 -268.596343) (xy 339.599006 -268.543045) (xy 339.606949 -268.490341)
			(xy 339.622659 -268.439411) (xy 339.645785 -268.39139) (xy 339.675809 -268.347353) (xy 339.712061 -268.308282)
			(xy 339.753732 -268.275051) (xy 339.79989 -268.248402) (xy 339.849504 -268.22893) (xy 339.901466 -268.21707)
			(xy 339.954616 -268.213087) (xy 340.007766 -268.21707) (xy 340.059728 -268.22893) (xy 340.109342 -268.248402)
			(xy 340.1555 -268.275051) (xy 340.197171 -268.308282) (xy 340.233423 -268.347353) (xy 340.263447 -268.39139)
			(xy 340.286573 -268.439411) (xy 340.302283 -268.490341) (xy 340.310226 -268.543045) (xy 340.310724 -268.569694)
			(xy 340.310226 -268.596343) (xy 340.538806 -268.596343) (xy 340.538806 -268.543045) (xy 340.546749 -268.490341)
			(xy 340.562459 -268.439411) (xy 340.585585 -268.39139) (xy 340.615609 -268.347353) (xy 340.651861 -268.308282)
			(xy 340.693532 -268.275051) (xy 340.73969 -268.248402) (xy 340.789304 -268.22893) (xy 340.841266 -268.21707)
			(xy 340.894416 -268.213087) (xy 340.947566 -268.21707) (xy 340.999528 -268.22893) (xy 341.049142 -268.248402)
			(xy 341.0953 -268.275051) (xy 341.136971 -268.308282) (xy 341.173223 -268.347353) (xy 341.203247 -268.39139)
			(xy 341.226373 -268.439411) (xy 341.242083 -268.490341) (xy 341.250026 -268.543045) (xy 341.250524 -268.569694)
			(xy 341.250026 -268.596343) (xy 341.478606 -268.596343) (xy 341.478606 -268.543045) (xy 341.486549 -268.490341)
			(xy 341.502259 -268.439411) (xy 341.525385 -268.39139) (xy 341.555409 -268.347353) (xy 341.591661 -268.308282)
			(xy 341.633332 -268.275051) (xy 341.67949 -268.248402) (xy 341.729104 -268.22893) (xy 341.781066 -268.21707)
			(xy 341.834216 -268.213087) (xy 341.887366 -268.21707) (xy 341.939328 -268.22893) (xy 341.988942 -268.248402)
			(xy 342.0351 -268.275051) (xy 342.076771 -268.308282) (xy 342.113023 -268.347353) (xy 342.143047 -268.39139)
			(xy 342.166173 -268.439411) (xy 342.181883 -268.490341) (xy 342.189826 -268.543045) (xy 342.190324 -268.569694)
			(xy 342.189826 -268.596343) (xy 342.418152 -268.596343) (xy 342.418152 -268.543045) (xy 342.426095 -268.490341)
			(xy 342.441805 -268.439411) (xy 342.464931 -268.39139) (xy 342.494955 -268.347353) (xy 342.531207 -268.308282)
			(xy 342.572878 -268.275051) (xy 342.619036 -268.248402) (xy 342.66865 -268.22893) (xy 342.720612 -268.21707)
			(xy 342.773762 -268.213087) (xy 342.826912 -268.21707) (xy 342.878874 -268.22893) (xy 342.928488 -268.248402)
			(xy 342.974646 -268.275051) (xy 343.016317 -268.308282) (xy 343.052569 -268.347353) (xy 343.082593 -268.39139)
			(xy 343.105719 -268.439411) (xy 343.121429 -268.490341) (xy 343.129372 -268.543045) (xy 343.12987 -268.569694)
			(xy 343.129372 -268.596343) (xy 343.358206 -268.596343) (xy 343.358206 -268.543045) (xy 343.366149 -268.490341)
			(xy 343.381859 -268.439411) (xy 343.404985 -268.39139) (xy 343.435009 -268.347353) (xy 343.471261 -268.308282)
			(xy 343.512932 -268.275051) (xy 343.55909 -268.248402) (xy 343.608704 -268.22893) (xy 343.660666 -268.21707)
			(xy 343.713816 -268.213087) (xy 343.766966 -268.21707) (xy 343.818928 -268.22893) (xy 343.868542 -268.248402)
			(xy 343.9147 -268.275051) (xy 343.956371 -268.308282) (xy 343.992623 -268.347353) (xy 344.022647 -268.39139)
			(xy 344.045773 -268.439411) (xy 344.061483 -268.490341) (xy 344.069426 -268.543045) (xy 344.069924 -268.569694)
			(xy 344.069426 -268.596343) (xy 344.298006 -268.596343) (xy 344.298006 -268.543045) (xy 344.305949 -268.490341)
			(xy 344.321659 -268.439411) (xy 344.344785 -268.39139) (xy 344.374809 -268.347353) (xy 344.411061 -268.308282)
			(xy 344.452732 -268.275051) (xy 344.49889 -268.248402) (xy 344.548504 -268.22893) (xy 344.600466 -268.21707)
			(xy 344.653616 -268.213087) (xy 344.706766 -268.21707) (xy 344.758728 -268.22893) (xy 344.808342 -268.248402)
			(xy 344.8545 -268.275051) (xy 344.896171 -268.308282) (xy 344.932423 -268.347353) (xy 344.962447 -268.39139)
			(xy 344.985573 -268.439411) (xy 345.001283 -268.490341) (xy 345.009226 -268.543045) (xy 345.009724 -268.569694)
			(xy 345.009226 -268.596343) (xy 345.237806 -268.596343) (xy 345.237806 -268.543045) (xy 345.245749 -268.490341)
			(xy 345.261459 -268.439411) (xy 345.284585 -268.39139) (xy 345.314609 -268.347353) (xy 345.350861 -268.308282)
			(xy 345.392532 -268.275051) (xy 345.43869 -268.248402) (xy 345.488304 -268.22893) (xy 345.540266 -268.21707)
			(xy 345.593416 -268.213087) (xy 345.646566 -268.21707) (xy 345.698528 -268.22893) (xy 345.748142 -268.248402)
			(xy 345.7943 -268.275051) (xy 345.835971 -268.308282) (xy 345.872223 -268.347353) (xy 345.902247 -268.39139)
			(xy 345.925373 -268.439411) (xy 345.941083 -268.490341) (xy 345.949026 -268.543045) (xy 345.949524 -268.569694)
			(xy 345.949026 -268.596343) (xy 346.177606 -268.596343) (xy 346.177606 -268.543045) (xy 346.185549 -268.490341)
			(xy 346.201259 -268.439411) (xy 346.224385 -268.39139) (xy 346.254409 -268.347353) (xy 346.290661 -268.308282)
			(xy 346.332332 -268.275051) (xy 346.37849 -268.248402) (xy 346.428104 -268.22893) (xy 346.480066 -268.21707)
			(xy 346.533216 -268.213087) (xy 346.586366 -268.21707) (xy 346.638328 -268.22893) (xy 346.687942 -268.248402)
			(xy 346.7341 -268.275051) (xy 346.775771 -268.308282) (xy 346.812023 -268.347353) (xy 346.842047 -268.39139)
			(xy 346.865173 -268.439411) (xy 346.880883 -268.490341) (xy 346.888826 -268.543045) (xy 346.889324 -268.569694)
			(xy 346.888826 -268.596343) (xy 347.117406 -268.596343) (xy 347.117406 -268.543045) (xy 347.125349 -268.490341)
			(xy 347.141059 -268.439411) (xy 347.164185 -268.39139) (xy 347.194209 -268.347353) (xy 347.230461 -268.308282)
			(xy 347.272132 -268.275051) (xy 347.31829 -268.248402) (xy 347.367904 -268.22893) (xy 347.419866 -268.21707)
			(xy 347.473016 -268.213087) (xy 347.526166 -268.21707) (xy 347.578128 -268.22893) (xy 347.627742 -268.248402)
			(xy 347.6739 -268.275051) (xy 347.715571 -268.308282) (xy 347.751823 -268.347353) (xy 347.781847 -268.39139)
			(xy 347.804973 -268.439411) (xy 347.820683 -268.490341) (xy 347.828626 -268.543045) (xy 347.829124 -268.569694)
			(xy 347.828626 -268.596343) (xy 348.057206 -268.596343) (xy 348.057206 -268.543045) (xy 348.065149 -268.490341)
			(xy 348.080859 -268.439411) (xy 348.103985 -268.39139) (xy 348.134009 -268.347353) (xy 348.170261 -268.308282)
			(xy 348.211932 -268.275051) (xy 348.25809 -268.248402) (xy 348.307704 -268.22893) (xy 348.359666 -268.21707)
			(xy 348.412816 -268.213087) (xy 348.465966 -268.21707) (xy 348.517928 -268.22893) (xy 348.567542 -268.248402)
			(xy 348.6137 -268.275051) (xy 348.655371 -268.308282) (xy 348.691623 -268.347353) (xy 348.721647 -268.39139)
			(xy 348.744773 -268.439411) (xy 348.760483 -268.490341) (xy 348.768426 -268.543045) (xy 348.768924 -268.569694)
			(xy 348.768426 -268.596343) (xy 348.996752 -268.596343) (xy 348.996752 -268.543045) (xy 349.004695 -268.490341)
			(xy 349.020405 -268.439411) (xy 349.043531 -268.39139) (xy 349.073555 -268.347353) (xy 349.109807 -268.308282)
			(xy 349.151478 -268.275051) (xy 349.197636 -268.248402) (xy 349.24725 -268.22893) (xy 349.299212 -268.21707)
			(xy 349.352362 -268.213087) (xy 349.405512 -268.21707) (xy 349.457474 -268.22893) (xy 349.507088 -268.248402)
			(xy 349.553246 -268.275051) (xy 349.594917 -268.308282) (xy 349.631169 -268.347353) (xy 349.661193 -268.39139)
			(xy 349.684319 -268.439411) (xy 349.700029 -268.490341) (xy 349.707972 -268.543045) (xy 349.70847 -268.569694)
			(xy 349.707972 -268.596343) (xy 349.936806 -268.596343) (xy 349.936806 -268.543045) (xy 349.944749 -268.490341)
			(xy 349.960459 -268.439411) (xy 349.983585 -268.39139) (xy 350.013609 -268.347353) (xy 350.049861 -268.308282)
			(xy 350.091532 -268.275051) (xy 350.13769 -268.248402) (xy 350.187304 -268.22893) (xy 350.239266 -268.21707)
			(xy 350.292416 -268.213087) (xy 350.345566 -268.21707) (xy 350.397528 -268.22893) (xy 350.447142 -268.248402)
			(xy 350.4933 -268.275051) (xy 350.534971 -268.308282) (xy 350.571223 -268.347353) (xy 350.601247 -268.39139)
			(xy 350.624373 -268.439411) (xy 350.640083 -268.490341) (xy 350.648026 -268.543045) (xy 350.648524 -268.569694)
			(xy 350.648026 -268.596343) (xy 350.876606 -268.596343) (xy 350.876606 -268.543045) (xy 350.884549 -268.490341)
			(xy 350.900259 -268.439411) (xy 350.923385 -268.39139) (xy 350.953409 -268.347353) (xy 350.989661 -268.308282)
			(xy 351.031332 -268.275051) (xy 351.07749 -268.248402) (xy 351.127104 -268.22893) (xy 351.179066 -268.21707)
			(xy 351.232216 -268.213087) (xy 351.285366 -268.21707) (xy 351.337328 -268.22893) (xy 351.386942 -268.248402)
			(xy 351.4331 -268.275051) (xy 351.474771 -268.308282) (xy 351.511023 -268.347353) (xy 351.541047 -268.39139)
			(xy 351.564173 -268.439411) (xy 351.579883 -268.490341) (xy 351.587826 -268.543045) (xy 351.588324 -268.569694)
			(xy 351.587826 -268.596343) (xy 351.816406 -268.596343) (xy 351.816406 -268.543045) (xy 351.824349 -268.490341)
			(xy 351.840059 -268.439411) (xy 351.863185 -268.39139) (xy 351.893209 -268.347353) (xy 351.929461 -268.308282)
			(xy 351.971132 -268.275051) (xy 352.01729 -268.248402) (xy 352.066904 -268.22893) (xy 352.118866 -268.21707)
			(xy 352.172016 -268.213087) (xy 352.225166 -268.21707) (xy 352.277128 -268.22893) (xy 352.326742 -268.248402)
			(xy 352.3729 -268.275051) (xy 352.414571 -268.308282) (xy 352.450823 -268.347353) (xy 352.480847 -268.39139)
			(xy 352.503973 -268.439411) (xy 352.519683 -268.490341) (xy 352.527626 -268.543045) (xy 352.528124 -268.569694)
			(xy 352.527626 -268.596343) (xy 352.756206 -268.596343) (xy 352.756206 -268.543045) (xy 352.764149 -268.490341)
			(xy 352.779859 -268.439411) (xy 352.802985 -268.39139) (xy 352.833009 -268.347353) (xy 352.869261 -268.308282)
			(xy 352.910932 -268.275051) (xy 352.95709 -268.248402) (xy 353.006704 -268.22893) (xy 353.058666 -268.21707)
			(xy 353.111816 -268.213087) (xy 353.164966 -268.21707) (xy 353.216928 -268.22893) (xy 353.266542 -268.248402)
			(xy 353.3127 -268.275051) (xy 353.354371 -268.308282) (xy 353.390623 -268.347353) (xy 353.420647 -268.39139)
			(xy 353.443773 -268.439411) (xy 353.459483 -268.490341) (xy 353.467426 -268.543045) (xy 353.467924 -268.569694)
			(xy 353.467426 -268.596343) (xy 353.696006 -268.596343) (xy 353.696006 -268.543045) (xy 353.703949 -268.490341)
			(xy 353.719659 -268.439411) (xy 353.742785 -268.39139) (xy 353.772809 -268.347353) (xy 353.809061 -268.308282)
			(xy 353.850732 -268.275051) (xy 353.89689 -268.248402) (xy 353.946504 -268.22893) (xy 353.998466 -268.21707)
			(xy 354.051616 -268.213087) (xy 354.104766 -268.21707) (xy 354.156728 -268.22893) (xy 354.206342 -268.248402)
			(xy 354.2525 -268.275051) (xy 354.294171 -268.308282) (xy 354.330423 -268.347353) (xy 354.360447 -268.39139)
			(xy 354.383573 -268.439411) (xy 354.399283 -268.490341) (xy 354.407226 -268.543045) (xy 354.407724 -268.569694)
			(xy 354.407226 -268.596343) (xy 354.635806 -268.596343) (xy 354.635806 -268.543045) (xy 354.643749 -268.490341)
			(xy 354.659459 -268.439411) (xy 354.682585 -268.39139) (xy 354.712609 -268.347353) (xy 354.748861 -268.308282)
			(xy 354.790532 -268.275051) (xy 354.83669 -268.248402) (xy 354.886304 -268.22893) (xy 354.938266 -268.21707)
			(xy 354.991416 -268.213087) (xy 355.044566 -268.21707) (xy 355.096528 -268.22893) (xy 355.146142 -268.248402)
			(xy 355.1923 -268.275051) (xy 355.233971 -268.308282) (xy 355.270223 -268.347353) (xy 355.300247 -268.39139)
			(xy 355.323373 -268.439411) (xy 355.339083 -268.490341) (xy 355.347026 -268.543045) (xy 355.347524 -268.569694)
			(xy 355.347026 -268.596343) (xy 355.339083 -268.649047) (xy 355.323373 -268.699977) (xy 355.300247 -268.747998)
			(xy 355.270223 -268.792035) (xy 355.233971 -268.831106) (xy 355.1923 -268.864337) (xy 355.146142 -268.890986)
			(xy 355.096528 -268.910458) (xy 355.044566 -268.922318) (xy 354.991416 -268.926302) (xy 354.938266 -268.922318)
			(xy 354.886304 -268.910458) (xy 354.83669 -268.890986) (xy 354.790532 -268.864337) (xy 354.748861 -268.831106)
			(xy 354.712609 -268.792035) (xy 354.682585 -268.747998) (xy 354.659459 -268.699977) (xy 354.643749 -268.649047)
			(xy 354.635806 -268.596343) (xy 354.407226 -268.596343) (xy 354.399283 -268.649047) (xy 354.383573 -268.699977)
			(xy 354.360447 -268.747998) (xy 354.330423 -268.792035) (xy 354.294171 -268.831106) (xy 354.2525 -268.864337)
			(xy 354.206342 -268.890986) (xy 354.156728 -268.910458) (xy 354.104766 -268.922318) (xy 354.051616 -268.926302)
			(xy 353.998466 -268.922318) (xy 353.946504 -268.910458) (xy 353.89689 -268.890986) (xy 353.850732 -268.864337)
			(xy 353.809061 -268.831106) (xy 353.772809 -268.792035) (xy 353.742785 -268.747998) (xy 353.719659 -268.699977)
			(xy 353.703949 -268.649047) (xy 353.696006 -268.596343) (xy 353.467426 -268.596343) (xy 353.459483 -268.649047)
			(xy 353.443773 -268.699977) (xy 353.420647 -268.747998) (xy 353.390623 -268.792035) (xy 353.354371 -268.831106)
			(xy 353.3127 -268.864337) (xy 353.266542 -268.890986) (xy 353.216928 -268.910458) (xy 353.164966 -268.922318)
			(xy 353.111816 -268.926302) (xy 353.058666 -268.922318) (xy 353.006704 -268.910458) (xy 352.95709 -268.890986)
			(xy 352.910932 -268.864337) (xy 352.869261 -268.831106) (xy 352.833009 -268.792035) (xy 352.802985 -268.747998)
			(xy 352.779859 -268.699977) (xy 352.764149 -268.649047) (xy 352.756206 -268.596343) (xy 352.527626 -268.596343)
			(xy 352.519683 -268.649047) (xy 352.503973 -268.699977) (xy 352.480847 -268.747998) (xy 352.450823 -268.792035)
			(xy 352.414571 -268.831106) (xy 352.3729 -268.864337) (xy 352.326742 -268.890986) (xy 352.277128 -268.910458)
			(xy 352.225166 -268.922318) (xy 352.172016 -268.926302) (xy 352.118866 -268.922318) (xy 352.066904 -268.910458)
			(xy 352.01729 -268.890986) (xy 351.971132 -268.864337) (xy 351.929461 -268.831106) (xy 351.893209 -268.792035)
			(xy 351.863185 -268.747998) (xy 351.840059 -268.699977) (xy 351.824349 -268.649047) (xy 351.816406 -268.596343)
			(xy 351.587826 -268.596343) (xy 351.579883 -268.649047) (xy 351.564173 -268.699977) (xy 351.541047 -268.747998)
			(xy 351.511023 -268.792035) (xy 351.474771 -268.831106) (xy 351.4331 -268.864337) (xy 351.386942 -268.890986)
			(xy 351.337328 -268.910458) (xy 351.285366 -268.922318) (xy 351.232216 -268.926302) (xy 351.179066 -268.922318)
			(xy 351.127104 -268.910458) (xy 351.07749 -268.890986) (xy 351.031332 -268.864337) (xy 350.989661 -268.831106)
			(xy 350.953409 -268.792035) (xy 350.923385 -268.747998) (xy 350.900259 -268.699977) (xy 350.884549 -268.649047)
			(xy 350.876606 -268.596343) (xy 350.648026 -268.596343) (xy 350.640083 -268.649047) (xy 350.624373 -268.699977)
			(xy 350.601247 -268.747998) (xy 350.571223 -268.792035) (xy 350.534971 -268.831106) (xy 350.4933 -268.864337)
			(xy 350.447142 -268.890986) (xy 350.397528 -268.910458) (xy 350.345566 -268.922318) (xy 350.292416 -268.926302)
			(xy 350.239266 -268.922318) (xy 350.187304 -268.910458) (xy 350.13769 -268.890986) (xy 350.091532 -268.864337)
			(xy 350.049861 -268.831106) (xy 350.013609 -268.792035) (xy 349.983585 -268.747998) (xy 349.960459 -268.699977)
			(xy 349.944749 -268.649047) (xy 349.936806 -268.596343) (xy 349.707972 -268.596343) (xy 349.700029 -268.649047)
			(xy 349.684319 -268.699977) (xy 349.661193 -268.747998) (xy 349.631169 -268.792035) (xy 349.594917 -268.831106)
			(xy 349.553246 -268.864337) (xy 349.507088 -268.890986) (xy 349.457474 -268.910458) (xy 349.405512 -268.922318)
			(xy 349.352362 -268.926302) (xy 349.299212 -268.922318) (xy 349.24725 -268.910458) (xy 349.197636 -268.890986)
			(xy 349.151478 -268.864337) (xy 349.109807 -268.831106) (xy 349.073555 -268.792035) (xy 349.043531 -268.747998)
			(xy 349.020405 -268.699977) (xy 349.004695 -268.649047) (xy 348.996752 -268.596343) (xy 348.768426 -268.596343)
			(xy 348.760483 -268.649047) (xy 348.744773 -268.699977) (xy 348.721647 -268.747998) (xy 348.691623 -268.792035)
			(xy 348.655371 -268.831106) (xy 348.6137 -268.864337) (xy 348.567542 -268.890986) (xy 348.517928 -268.910458)
			(xy 348.465966 -268.922318) (xy 348.412816 -268.926302) (xy 348.359666 -268.922318) (xy 348.307704 -268.910458)
			(xy 348.25809 -268.890986) (xy 348.211932 -268.864337) (xy 348.170261 -268.831106) (xy 348.134009 -268.792035)
			(xy 348.103985 -268.747998) (xy 348.080859 -268.699977) (xy 348.065149 -268.649047) (xy 348.057206 -268.596343)
			(xy 347.828626 -268.596343) (xy 347.820683 -268.649047) (xy 347.804973 -268.699977) (xy 347.781847 -268.747998)
			(xy 347.751823 -268.792035) (xy 347.715571 -268.831106) (xy 347.6739 -268.864337) (xy 347.627742 -268.890986)
			(xy 347.578128 -268.910458) (xy 347.526166 -268.922318) (xy 347.473016 -268.926302) (xy 347.419866 -268.922318)
			(xy 347.367904 -268.910458) (xy 347.31829 -268.890986) (xy 347.272132 -268.864337) (xy 347.230461 -268.831106)
			(xy 347.194209 -268.792035) (xy 347.164185 -268.747998) (xy 347.141059 -268.699977) (xy 347.125349 -268.649047)
			(xy 347.117406 -268.596343) (xy 346.888826 -268.596343) (xy 346.880883 -268.649047) (xy 346.865173 -268.699977)
			(xy 346.842047 -268.747998) (xy 346.812023 -268.792035) (xy 346.775771 -268.831106) (xy 346.7341 -268.864337)
			(xy 346.687942 -268.890986) (xy 346.638328 -268.910458) (xy 346.586366 -268.922318) (xy 346.533216 -268.926302)
			(xy 346.480066 -268.922318) (xy 346.428104 -268.910458) (xy 346.37849 -268.890986) (xy 346.332332 -268.864337)
			(xy 346.290661 -268.831106) (xy 346.254409 -268.792035) (xy 346.224385 -268.747998) (xy 346.201259 -268.699977)
			(xy 346.185549 -268.649047) (xy 346.177606 -268.596343) (xy 345.949026 -268.596343) (xy 345.941083 -268.649047)
			(xy 345.925373 -268.699977) (xy 345.902247 -268.747998) (xy 345.872223 -268.792035) (xy 345.835971 -268.831106)
			(xy 345.7943 -268.864337) (xy 345.748142 -268.890986) (xy 345.698528 -268.910458) (xy 345.646566 -268.922318)
			(xy 345.593416 -268.926302) (xy 345.540266 -268.922318) (xy 345.488304 -268.910458) (xy 345.43869 -268.890986)
			(xy 345.392532 -268.864337) (xy 345.350861 -268.831106) (xy 345.314609 -268.792035) (xy 345.284585 -268.747998)
			(xy 345.261459 -268.699977) (xy 345.245749 -268.649047) (xy 345.237806 -268.596343) (xy 345.009226 -268.596343)
			(xy 345.001283 -268.649047) (xy 344.985573 -268.699977) (xy 344.962447 -268.747998) (xy 344.932423 -268.792035)
			(xy 344.896171 -268.831106) (xy 344.8545 -268.864337) (xy 344.808342 -268.890986) (xy 344.758728 -268.910458)
			(xy 344.706766 -268.922318) (xy 344.653616 -268.926302) (xy 344.600466 -268.922318) (xy 344.548504 -268.910458)
			(xy 344.49889 -268.890986) (xy 344.452732 -268.864337) (xy 344.411061 -268.831106) (xy 344.374809 -268.792035)
			(xy 344.344785 -268.747998) (xy 344.321659 -268.699977) (xy 344.305949 -268.649047) (xy 344.298006 -268.596343)
			(xy 344.069426 -268.596343) (xy 344.061483 -268.649047) (xy 344.045773 -268.699977) (xy 344.022647 -268.747998)
			(xy 343.992623 -268.792035) (xy 343.956371 -268.831106) (xy 343.9147 -268.864337) (xy 343.868542 -268.890986)
			(xy 343.818928 -268.910458) (xy 343.766966 -268.922318) (xy 343.713816 -268.926302) (xy 343.660666 -268.922318)
			(xy 343.608704 -268.910458) (xy 343.55909 -268.890986) (xy 343.512932 -268.864337) (xy 343.471261 -268.831106)
			(xy 343.435009 -268.792035) (xy 343.404985 -268.747998) (xy 343.381859 -268.699977) (xy 343.366149 -268.649047)
			(xy 343.358206 -268.596343) (xy 343.129372 -268.596343) (xy 343.121429 -268.649047) (xy 343.105719 -268.699977)
			(xy 343.082593 -268.747998) (xy 343.052569 -268.792035) (xy 343.016317 -268.831106) (xy 342.974646 -268.864337)
			(xy 342.928488 -268.890986) (xy 342.878874 -268.910458) (xy 342.826912 -268.922318) (xy 342.773762 -268.926302)
			(xy 342.720612 -268.922318) (xy 342.66865 -268.910458) (xy 342.619036 -268.890986) (xy 342.572878 -268.864337)
			(xy 342.531207 -268.831106) (xy 342.494955 -268.792035) (xy 342.464931 -268.747998) (xy 342.441805 -268.699977)
			(xy 342.426095 -268.649047) (xy 342.418152 -268.596343) (xy 342.189826 -268.596343) (xy 342.181883 -268.649047)
			(xy 342.166173 -268.699977) (xy 342.143047 -268.747998) (xy 342.113023 -268.792035) (xy 342.076771 -268.831106)
			(xy 342.0351 -268.864337) (xy 341.988942 -268.890986) (xy 341.939328 -268.910458) (xy 341.887366 -268.922318)
			(xy 341.834216 -268.926302) (xy 341.781066 -268.922318) (xy 341.729104 -268.910458) (xy 341.67949 -268.890986)
			(xy 341.633332 -268.864337) (xy 341.591661 -268.831106) (xy 341.555409 -268.792035) (xy 341.525385 -268.747998)
			(xy 341.502259 -268.699977) (xy 341.486549 -268.649047) (xy 341.478606 -268.596343) (xy 341.250026 -268.596343)
			(xy 341.242083 -268.649047) (xy 341.226373 -268.699977) (xy 341.203247 -268.747998) (xy 341.173223 -268.792035)
			(xy 341.136971 -268.831106) (xy 341.0953 -268.864337) (xy 341.049142 -268.890986) (xy 340.999528 -268.910458)
			(xy 340.947566 -268.922318) (xy 340.894416 -268.926302) (xy 340.841266 -268.922318) (xy 340.789304 -268.910458)
			(xy 340.73969 -268.890986) (xy 340.693532 -268.864337) (xy 340.651861 -268.831106) (xy 340.615609 -268.792035)
			(xy 340.585585 -268.747998) (xy 340.562459 -268.699977) (xy 340.546749 -268.649047) (xy 340.538806 -268.596343)
			(xy 340.310226 -268.596343) (xy 340.302283 -268.649047) (xy 340.286573 -268.699977) (xy 340.263447 -268.747998)
			(xy 340.233423 -268.792035) (xy 340.197171 -268.831106) (xy 340.1555 -268.864337) (xy 340.109342 -268.890986)
			(xy 340.059728 -268.910458) (xy 340.007766 -268.922318) (xy 339.954616 -268.926302) (xy 339.901466 -268.922318)
			(xy 339.849504 -268.910458) (xy 339.79989 -268.890986) (xy 339.753732 -268.864337) (xy 339.712061 -268.831106)
			(xy 339.675809 -268.792035) (xy 339.645785 -268.747998) (xy 339.622659 -268.699977) (xy 339.606949 -268.649047)
			(xy 339.599006 -268.596343) (xy 339.37956 -268.596343) (xy 339.37956 -268.925802) (xy 339.379964 -268.939191)
			(xy 339.386925 -268.965048) (xy 339.400369 -268.988206) (xy 339.419372 -269.007073) (xy 339.442625 -269.020352)
			(xy 339.468531 -269.027129) (xy 339.481922 -269.027402) (xy 339.484716 -269.027402) (xy 339.511364 -269.027901)
			(xy 339.564064 -269.035846) (xy 339.614991 -269.051557) (xy 339.663008 -269.074683) (xy 339.707042 -269.104707)
			(xy 339.74611 -269.140958) (xy 339.779338 -269.182627) (xy 339.805985 -269.228782) (xy 339.825456 -269.278394)
			(xy 339.837315 -269.330353) (xy 339.841298 -269.3835) (xy 339.8393 -269.410159) (xy 340.068652 -269.410159)
			(xy 340.068652 -269.356861) (xy 340.076595 -269.304157) (xy 340.092305 -269.253227) (xy 340.115431 -269.205206)
			(xy 340.145455 -269.161169) (xy 340.181707 -269.122098) (xy 340.223378 -269.088867) (xy 340.269536 -269.062218)
			(xy 340.31915 -269.042746) (xy 340.371112 -269.030886) (xy 340.424262 -269.026903) (xy 340.477412 -269.030886)
			(xy 340.529374 -269.042746) (xy 340.578988 -269.062218) (xy 340.625146 -269.088867) (xy 340.666817 -269.122098)
			(xy 340.703069 -269.161169) (xy 340.733093 -269.205206) (xy 340.756219 -269.253227) (xy 340.771929 -269.304157)
			(xy 340.779872 -269.356861) (xy 340.78037 -269.38351) (xy 340.779872 -269.410159) (xy 341.008452 -269.410159)
			(xy 341.008452 -269.356861) (xy 341.016395 -269.304157) (xy 341.032105 -269.253227) (xy 341.055231 -269.205206)
			(xy 341.085255 -269.161169) (xy 341.121507 -269.122098) (xy 341.163178 -269.088867) (xy 341.209336 -269.062218)
			(xy 341.25895 -269.042746) (xy 341.310912 -269.030886) (xy 341.364062 -269.026903) (xy 341.417212 -269.030886)
			(xy 341.469174 -269.042746) (xy 341.518788 -269.062218) (xy 341.564946 -269.088867) (xy 341.606617 -269.122098)
			(xy 341.642869 -269.161169) (xy 341.672893 -269.205206) (xy 341.696019 -269.253227) (xy 341.711729 -269.304157)
			(xy 341.719672 -269.356861) (xy 341.72017 -269.38351) (xy 341.719672 -269.410159) (xy 341.948252 -269.410159)
			(xy 341.948252 -269.356861) (xy 341.956195 -269.304157) (xy 341.971905 -269.253227) (xy 341.995031 -269.205206)
			(xy 342.025055 -269.161169) (xy 342.061307 -269.122098) (xy 342.102978 -269.088867) (xy 342.149136 -269.062218)
			(xy 342.19875 -269.042746) (xy 342.250712 -269.030886) (xy 342.303862 -269.026903) (xy 342.357012 -269.030886)
			(xy 342.408974 -269.042746) (xy 342.458588 -269.062218) (xy 342.504746 -269.088867) (xy 342.546417 -269.122098)
			(xy 342.582669 -269.161169) (xy 342.612693 -269.205206) (xy 342.635819 -269.253227) (xy 342.651529 -269.304157)
			(xy 342.659472 -269.356861) (xy 342.65997 -269.38351) (xy 342.659472 -269.410159) (xy 342.888052 -269.410159)
			(xy 342.888052 -269.356861) (xy 342.895995 -269.304157) (xy 342.911705 -269.253227) (xy 342.934831 -269.205206)
			(xy 342.964855 -269.161169) (xy 343.001107 -269.122098) (xy 343.042778 -269.088867) (xy 343.088936 -269.062218)
			(xy 343.13855 -269.042746) (xy 343.190512 -269.030886) (xy 343.243662 -269.026903) (xy 343.296812 -269.030886)
			(xy 343.348774 -269.042746) (xy 343.398388 -269.062218) (xy 343.444546 -269.088867) (xy 343.486217 -269.122098)
			(xy 343.522469 -269.161169) (xy 343.552493 -269.205206) (xy 343.575619 -269.253227) (xy 343.591329 -269.304157)
			(xy 343.599272 -269.356861) (xy 343.59977 -269.38351) (xy 343.599272 -269.410159) (xy 343.827852 -269.410159)
			(xy 343.827852 -269.356861) (xy 343.835795 -269.304157) (xy 343.851505 -269.253227) (xy 343.874631 -269.205206)
			(xy 343.904655 -269.161169) (xy 343.940907 -269.122098) (xy 343.982578 -269.088867) (xy 344.028736 -269.062218)
			(xy 344.07835 -269.042746) (xy 344.130312 -269.030886) (xy 344.183462 -269.026903) (xy 344.236612 -269.030886)
			(xy 344.288574 -269.042746) (xy 344.338188 -269.062218) (xy 344.384346 -269.088867) (xy 344.426017 -269.122098)
			(xy 344.462269 -269.161169) (xy 344.492293 -269.205206) (xy 344.515419 -269.253227) (xy 344.531129 -269.304157)
			(xy 344.539072 -269.356861) (xy 344.53957 -269.38351) (xy 344.539072 -269.410159) (xy 344.767652 -269.410159)
			(xy 344.767652 -269.356861) (xy 344.775595 -269.304157) (xy 344.791305 -269.253227) (xy 344.814431 -269.205206)
			(xy 344.844455 -269.161169) (xy 344.880707 -269.122098) (xy 344.922378 -269.088867) (xy 344.968536 -269.062218)
			(xy 345.01815 -269.042746) (xy 345.070112 -269.030886) (xy 345.123262 -269.026903) (xy 345.176412 -269.030886)
			(xy 345.228374 -269.042746) (xy 345.277988 -269.062218) (xy 345.324146 -269.088867) (xy 345.365817 -269.122098)
			(xy 345.402069 -269.161169) (xy 345.432093 -269.205206) (xy 345.455219 -269.253227) (xy 345.470929 -269.304157)
			(xy 345.478872 -269.356861) (xy 345.47937 -269.38351) (xy 345.478872 -269.410159) (xy 345.707706 -269.410159)
			(xy 345.707706 -269.356861) (xy 345.715649 -269.304157) (xy 345.731359 -269.253227) (xy 345.754485 -269.205206)
			(xy 345.784509 -269.161169) (xy 345.820761 -269.122098) (xy 345.862432 -269.088867) (xy 345.90859 -269.062218)
			(xy 345.958204 -269.042746) (xy 346.010166 -269.030886) (xy 346.063316 -269.026903) (xy 346.116466 -269.030886)
			(xy 346.168428 -269.042746) (xy 346.218042 -269.062218) (xy 346.2642 -269.088867) (xy 346.305871 -269.122098)
			(xy 346.342123 -269.161169) (xy 346.372147 -269.205206) (xy 346.395273 -269.253227) (xy 346.410983 -269.304157)
			(xy 346.418926 -269.356861) (xy 346.419424 -269.38351) (xy 346.418926 -269.410159) (xy 346.647252 -269.410159)
			(xy 346.647252 -269.356861) (xy 346.655195 -269.304157) (xy 346.670905 -269.253227) (xy 346.694031 -269.205206)
			(xy 346.724055 -269.161169) (xy 346.760307 -269.122098) (xy 346.801978 -269.088867) (xy 346.848136 -269.062218)
			(xy 346.89775 -269.042746) (xy 346.949712 -269.030886) (xy 347.002862 -269.026903) (xy 347.056012 -269.030886)
			(xy 347.107974 -269.042746) (xy 347.157588 -269.062218) (xy 347.203746 -269.088867) (xy 347.245417 -269.122098)
			(xy 347.281669 -269.161169) (xy 347.311693 -269.205206) (xy 347.334819 -269.253227) (xy 347.350529 -269.304157)
			(xy 347.358472 -269.356861) (xy 347.35897 -269.38351) (xy 347.358472 -269.410159) (xy 347.587052 -269.410159)
			(xy 347.587052 -269.356861) (xy 347.594995 -269.304157) (xy 347.610705 -269.253227) (xy 347.633831 -269.205206)
			(xy 347.663855 -269.161169) (xy 347.700107 -269.122098) (xy 347.741778 -269.088867) (xy 347.787936 -269.062218)
			(xy 347.83755 -269.042746) (xy 347.889512 -269.030886) (xy 347.942662 -269.026903) (xy 347.995812 -269.030886)
			(xy 348.047774 -269.042746) (xy 348.097388 -269.062218) (xy 348.143546 -269.088867) (xy 348.185217 -269.122098)
			(xy 348.221469 -269.161169) (xy 348.251493 -269.205206) (xy 348.274619 -269.253227) (xy 348.290329 -269.304157)
			(xy 348.298272 -269.356861) (xy 348.29877 -269.38351) (xy 348.298272 -269.410159) (xy 348.526852 -269.410159)
			(xy 348.526852 -269.356861) (xy 348.534795 -269.304157) (xy 348.550505 -269.253227) (xy 348.573631 -269.205206)
			(xy 348.603655 -269.161169) (xy 348.639907 -269.122098) (xy 348.681578 -269.088867) (xy 348.727736 -269.062218)
			(xy 348.77735 -269.042746) (xy 348.829312 -269.030886) (xy 348.882462 -269.026903) (xy 348.935612 -269.030886)
			(xy 348.987574 -269.042746) (xy 349.037188 -269.062218) (xy 349.083346 -269.088867) (xy 349.125017 -269.122098)
			(xy 349.161269 -269.161169) (xy 349.191293 -269.205206) (xy 349.214419 -269.253227) (xy 349.230129 -269.304157)
			(xy 349.238072 -269.356861) (xy 349.23857 -269.38351) (xy 349.238072 -269.410159) (xy 349.46716 -269.410159)
			(xy 349.46716 -269.356861) (xy 349.475103 -269.304157) (xy 349.490813 -269.253227) (xy 349.513939 -269.205206)
			(xy 349.543963 -269.161169) (xy 349.580215 -269.122098) (xy 349.621886 -269.088867) (xy 349.668044 -269.062218)
			(xy 349.717658 -269.042746) (xy 349.76962 -269.030886) (xy 349.82277 -269.026903) (xy 349.87592 -269.030886)
			(xy 349.927882 -269.042746) (xy 349.977496 -269.062218) (xy 350.023654 -269.088867) (xy 350.065325 -269.122098)
			(xy 350.101577 -269.161169) (xy 350.131601 -269.205206) (xy 350.154727 -269.253227) (xy 350.170437 -269.304157)
			(xy 350.17838 -269.356861) (xy 350.178878 -269.38351) (xy 350.17838 -269.410159) (xy 350.406452 -269.410159)
			(xy 350.406452 -269.356861) (xy 350.414395 -269.304157) (xy 350.430105 -269.253227) (xy 350.453231 -269.205206)
			(xy 350.483255 -269.161169) (xy 350.519507 -269.122098) (xy 350.561178 -269.088867) (xy 350.607336 -269.062218)
			(xy 350.65695 -269.042746) (xy 350.708912 -269.030886) (xy 350.762062 -269.026903) (xy 350.815212 -269.030886)
			(xy 350.867174 -269.042746) (xy 350.916788 -269.062218) (xy 350.962946 -269.088867) (xy 351.004617 -269.122098)
			(xy 351.040869 -269.161169) (xy 351.070893 -269.205206) (xy 351.094019 -269.253227) (xy 351.109729 -269.304157)
			(xy 351.117672 -269.356861) (xy 351.11817 -269.38351) (xy 351.117672 -269.410159) (xy 351.346252 -269.410159)
			(xy 351.346252 -269.356861) (xy 351.354195 -269.304157) (xy 351.369905 -269.253227) (xy 351.393031 -269.205206)
			(xy 351.423055 -269.161169) (xy 351.459307 -269.122098) (xy 351.500978 -269.088867) (xy 351.547136 -269.062218)
			(xy 351.59675 -269.042746) (xy 351.648712 -269.030886) (xy 351.701862 -269.026903) (xy 351.755012 -269.030886)
			(xy 351.806974 -269.042746) (xy 351.856588 -269.062218) (xy 351.902746 -269.088867) (xy 351.944417 -269.122098)
			(xy 351.980669 -269.161169) (xy 352.010693 -269.205206) (xy 352.033819 -269.253227) (xy 352.049529 -269.304157)
			(xy 352.057472 -269.356861) (xy 352.05797 -269.38351) (xy 352.057472 -269.410159) (xy 352.286052 -269.410159)
			(xy 352.286052 -269.356861) (xy 352.293995 -269.304157) (xy 352.309705 -269.253227) (xy 352.332831 -269.205206)
			(xy 352.362855 -269.161169) (xy 352.399107 -269.122098) (xy 352.440778 -269.088867) (xy 352.486936 -269.062218)
			(xy 352.53655 -269.042746) (xy 352.588512 -269.030886) (xy 352.641662 -269.026903) (xy 352.694812 -269.030886)
			(xy 352.746774 -269.042746) (xy 352.796388 -269.062218) (xy 352.842546 -269.088867) (xy 352.884217 -269.122098)
			(xy 352.920469 -269.161169) (xy 352.950493 -269.205206) (xy 352.973619 -269.253227) (xy 352.989329 -269.304157)
			(xy 352.997272 -269.356861) (xy 352.99777 -269.38351) (xy 352.997272 -269.410159) (xy 353.225852 -269.410159)
			(xy 353.225852 -269.356861) (xy 353.233795 -269.304157) (xy 353.249505 -269.253227) (xy 353.272631 -269.205206)
			(xy 353.302655 -269.161169) (xy 353.338907 -269.122098) (xy 353.380578 -269.088867) (xy 353.426736 -269.062218)
			(xy 353.47635 -269.042746) (xy 353.528312 -269.030886) (xy 353.581462 -269.026903) (xy 353.634612 -269.030886)
			(xy 353.686574 -269.042746) (xy 353.736188 -269.062218) (xy 353.782346 -269.088867) (xy 353.824017 -269.122098)
			(xy 353.860269 -269.161169) (xy 353.890293 -269.205206) (xy 353.913419 -269.253227) (xy 353.929129 -269.304157)
			(xy 353.937072 -269.356861) (xy 353.93757 -269.38351) (xy 353.937072 -269.410159) (xy 354.165652 -269.410159)
			(xy 354.165652 -269.356861) (xy 354.173595 -269.304157) (xy 354.189305 -269.253227) (xy 354.212431 -269.205206)
			(xy 354.242455 -269.161169) (xy 354.278707 -269.122098) (xy 354.320378 -269.088867) (xy 354.366536 -269.062218)
			(xy 354.41615 -269.042746) (xy 354.468112 -269.030886) (xy 354.521262 -269.026903) (xy 354.574412 -269.030886)
			(xy 354.626374 -269.042746) (xy 354.675988 -269.062218) (xy 354.722146 -269.088867) (xy 354.763817 -269.122098)
			(xy 354.800069 -269.161169) (xy 354.830093 -269.205206) (xy 354.853219 -269.253227) (xy 354.868929 -269.304157)
			(xy 354.876872 -269.356861) (xy 354.87737 -269.38351) (xy 354.876872 -269.410159) (xy 355.105452 -269.410159)
			(xy 355.105452 -269.356861) (xy 355.113395 -269.304157) (xy 355.129105 -269.253227) (xy 355.152231 -269.205206)
			(xy 355.182255 -269.161169) (xy 355.218507 -269.122098) (xy 355.260178 -269.088867) (xy 355.306336 -269.062218)
			(xy 355.35595 -269.042746) (xy 355.407912 -269.030886) (xy 355.461062 -269.026903) (xy 355.514212 -269.030886)
			(xy 355.566174 -269.042746) (xy 355.615788 -269.062218) (xy 355.661946 -269.088867) (xy 355.703617 -269.122098)
			(xy 355.739869 -269.161169) (xy 355.769893 -269.205206) (xy 355.793019 -269.253227) (xy 355.808729 -269.304157)
			(xy 355.816672 -269.356861) (xy 355.81717 -269.38351) (xy 355.816672 -269.410159) (xy 355.808729 -269.462863)
			(xy 355.793019 -269.513793) (xy 355.769893 -269.561814) (xy 355.739869 -269.605851) (xy 355.703617 -269.644922)
			(xy 355.661946 -269.678153) (xy 355.615788 -269.704802) (xy 355.566174 -269.724274) (xy 355.514212 -269.736134)
			(xy 355.461062 -269.740118) (xy 355.407912 -269.736134) (xy 355.35595 -269.724274) (xy 355.306336 -269.704802)
			(xy 355.260178 -269.678153) (xy 355.218507 -269.644922) (xy 355.182255 -269.605851) (xy 355.152231 -269.561814)
			(xy 355.129105 -269.513793) (xy 355.113395 -269.462863) (xy 355.105452 -269.410159) (xy 354.876872 -269.410159)
			(xy 354.868929 -269.462863) (xy 354.853219 -269.513793) (xy 354.830093 -269.561814) (xy 354.800069 -269.605851)
			(xy 354.763817 -269.644922) (xy 354.722146 -269.678153) (xy 354.675988 -269.704802) (xy 354.626374 -269.724274)
			(xy 354.574412 -269.736134) (xy 354.521262 -269.740118) (xy 354.468112 -269.736134) (xy 354.41615 -269.724274)
			(xy 354.366536 -269.704802) (xy 354.320378 -269.678153) (xy 354.278707 -269.644922) (xy 354.242455 -269.605851)
			(xy 354.212431 -269.561814) (xy 354.189305 -269.513793) (xy 354.173595 -269.462863) (xy 354.165652 -269.410159)
			(xy 353.937072 -269.410159) (xy 353.929129 -269.462863) (xy 353.913419 -269.513793) (xy 353.890293 -269.561814)
			(xy 353.860269 -269.605851) (xy 353.824017 -269.644922) (xy 353.782346 -269.678153) (xy 353.736188 -269.704802)
			(xy 353.686574 -269.724274) (xy 353.634612 -269.736134) (xy 353.581462 -269.740118) (xy 353.528312 -269.736134)
			(xy 353.47635 -269.724274) (xy 353.426736 -269.704802) (xy 353.380578 -269.678153) (xy 353.338907 -269.644922)
			(xy 353.302655 -269.605851) (xy 353.272631 -269.561814) (xy 353.249505 -269.513793) (xy 353.233795 -269.462863)
			(xy 353.225852 -269.410159) (xy 352.997272 -269.410159) (xy 352.989329 -269.462863) (xy 352.973619 -269.513793)
			(xy 352.950493 -269.561814) (xy 352.920469 -269.605851) (xy 352.884217 -269.644922) (xy 352.842546 -269.678153)
			(xy 352.796388 -269.704802) (xy 352.746774 -269.724274) (xy 352.694812 -269.736134) (xy 352.641662 -269.740118)
			(xy 352.588512 -269.736134) (xy 352.53655 -269.724274) (xy 352.486936 -269.704802) (xy 352.440778 -269.678153)
			(xy 352.399107 -269.644922) (xy 352.362855 -269.605851) (xy 352.332831 -269.561814) (xy 352.309705 -269.513793)
			(xy 352.293995 -269.462863) (xy 352.286052 -269.410159) (xy 352.057472 -269.410159) (xy 352.049529 -269.462863)
			(xy 352.033819 -269.513793) (xy 352.010693 -269.561814) (xy 351.980669 -269.605851) (xy 351.944417 -269.644922)
			(xy 351.902746 -269.678153) (xy 351.856588 -269.704802) (xy 351.806974 -269.724274) (xy 351.755012 -269.736134)
			(xy 351.701862 -269.740118) (xy 351.648712 -269.736134) (xy 351.59675 -269.724274) (xy 351.547136 -269.704802)
			(xy 351.500978 -269.678153) (xy 351.459307 -269.644922) (xy 351.423055 -269.605851) (xy 351.393031 -269.561814)
			(xy 351.369905 -269.513793) (xy 351.354195 -269.462863) (xy 351.346252 -269.410159) (xy 351.117672 -269.410159)
			(xy 351.109729 -269.462863) (xy 351.094019 -269.513793) (xy 351.070893 -269.561814) (xy 351.040869 -269.605851)
			(xy 351.004617 -269.644922) (xy 350.962946 -269.678153) (xy 350.916788 -269.704802) (xy 350.867174 -269.724274)
			(xy 350.815212 -269.736134) (xy 350.762062 -269.740118) (xy 350.708912 -269.736134) (xy 350.65695 -269.724274)
			(xy 350.607336 -269.704802) (xy 350.561178 -269.678153) (xy 350.519507 -269.644922) (xy 350.483255 -269.605851)
			(xy 350.453231 -269.561814) (xy 350.430105 -269.513793) (xy 350.414395 -269.462863) (xy 350.406452 -269.410159)
			(xy 350.17838 -269.410159) (xy 350.170437 -269.462863) (xy 350.154727 -269.513793) (xy 350.131601 -269.561814)
			(xy 350.101577 -269.605851) (xy 350.065325 -269.644922) (xy 350.023654 -269.678153) (xy 349.977496 -269.704802)
			(xy 349.927882 -269.724274) (xy 349.87592 -269.736134) (xy 349.82277 -269.740118) (xy 349.76962 -269.736134)
			(xy 349.717658 -269.724274) (xy 349.668044 -269.704802) (xy 349.621886 -269.678153) (xy 349.580215 -269.644922)
			(xy 349.543963 -269.605851) (xy 349.513939 -269.561814) (xy 349.490813 -269.513793) (xy 349.475103 -269.462863)
			(xy 349.46716 -269.410159) (xy 349.238072 -269.410159) (xy 349.230129 -269.462863) (xy 349.214419 -269.513793)
			(xy 349.191293 -269.561814) (xy 349.161269 -269.605851) (xy 349.125017 -269.644922) (xy 349.083346 -269.678153)
			(xy 349.037188 -269.704802) (xy 348.987574 -269.724274) (xy 348.935612 -269.736134) (xy 348.882462 -269.740118)
			(xy 348.829312 -269.736134) (xy 348.77735 -269.724274) (xy 348.727736 -269.704802) (xy 348.681578 -269.678153)
			(xy 348.639907 -269.644922) (xy 348.603655 -269.605851) (xy 348.573631 -269.561814) (xy 348.550505 -269.513793)
			(xy 348.534795 -269.462863) (xy 348.526852 -269.410159) (xy 348.298272 -269.410159) (xy 348.290329 -269.462863)
			(xy 348.274619 -269.513793) (xy 348.251493 -269.561814) (xy 348.221469 -269.605851) (xy 348.185217 -269.644922)
			(xy 348.143546 -269.678153) (xy 348.097388 -269.704802) (xy 348.047774 -269.724274) (xy 347.995812 -269.736134)
			(xy 347.942662 -269.740118) (xy 347.889512 -269.736134) (xy 347.83755 -269.724274) (xy 347.787936 -269.704802)
			(xy 347.741778 -269.678153) (xy 347.700107 -269.644922) (xy 347.663855 -269.605851) (xy 347.633831 -269.561814)
			(xy 347.610705 -269.513793) (xy 347.594995 -269.462863) (xy 347.587052 -269.410159) (xy 347.358472 -269.410159)
			(xy 347.350529 -269.462863) (xy 347.334819 -269.513793) (xy 347.311693 -269.561814) (xy 347.281669 -269.605851)
			(xy 347.245417 -269.644922) (xy 347.203746 -269.678153) (xy 347.157588 -269.704802) (xy 347.107974 -269.724274)
			(xy 347.056012 -269.736134) (xy 347.002862 -269.740118) (xy 346.949712 -269.736134) (xy 346.89775 -269.724274)
			(xy 346.848136 -269.704802) (xy 346.801978 -269.678153) (xy 346.760307 -269.644922) (xy 346.724055 -269.605851)
			(xy 346.694031 -269.561814) (xy 346.670905 -269.513793) (xy 346.655195 -269.462863) (xy 346.647252 -269.410159)
			(xy 346.418926 -269.410159) (xy 346.410983 -269.462863) (xy 346.395273 -269.513793) (xy 346.372147 -269.561814)
			(xy 346.342123 -269.605851) (xy 346.305871 -269.644922) (xy 346.2642 -269.678153) (xy 346.218042 -269.704802)
			(xy 346.168428 -269.724274) (xy 346.116466 -269.736134) (xy 346.063316 -269.740118) (xy 346.010166 -269.736134)
			(xy 345.958204 -269.724274) (xy 345.90859 -269.704802) (xy 345.862432 -269.678153) (xy 345.820761 -269.644922)
			(xy 345.784509 -269.605851) (xy 345.754485 -269.561814) (xy 345.731359 -269.513793) (xy 345.715649 -269.462863)
			(xy 345.707706 -269.410159) (xy 345.478872 -269.410159) (xy 345.470929 -269.462863) (xy 345.455219 -269.513793)
			(xy 345.432093 -269.561814) (xy 345.402069 -269.605851) (xy 345.365817 -269.644922) (xy 345.324146 -269.678153)
			(xy 345.277988 -269.704802) (xy 345.228374 -269.724274) (xy 345.176412 -269.736134) (xy 345.123262 -269.740118)
			(xy 345.070112 -269.736134) (xy 345.01815 -269.724274) (xy 344.968536 -269.704802) (xy 344.922378 -269.678153)
			(xy 344.880707 -269.644922) (xy 344.844455 -269.605851) (xy 344.814431 -269.561814) (xy 344.791305 -269.513793)
			(xy 344.775595 -269.462863) (xy 344.767652 -269.410159) (xy 344.539072 -269.410159) (xy 344.531129 -269.462863)
			(xy 344.515419 -269.513793) (xy 344.492293 -269.561814) (xy 344.462269 -269.605851) (xy 344.426017 -269.644922)
			(xy 344.384346 -269.678153) (xy 344.338188 -269.704802) (xy 344.288574 -269.724274) (xy 344.236612 -269.736134)
			(xy 344.183462 -269.740118) (xy 344.130312 -269.736134) (xy 344.07835 -269.724274) (xy 344.028736 -269.704802)
			(xy 343.982578 -269.678153) (xy 343.940907 -269.644922) (xy 343.904655 -269.605851) (xy 343.874631 -269.561814)
			(xy 343.851505 -269.513793) (xy 343.835795 -269.462863) (xy 343.827852 -269.410159) (xy 343.599272 -269.410159)
			(xy 343.591329 -269.462863) (xy 343.575619 -269.513793) (xy 343.552493 -269.561814) (xy 343.522469 -269.605851)
			(xy 343.486217 -269.644922) (xy 343.444546 -269.678153) (xy 343.398388 -269.704802) (xy 343.348774 -269.724274)
			(xy 343.296812 -269.736134) (xy 343.243662 -269.740118) (xy 343.190512 -269.736134) (xy 343.13855 -269.724274)
			(xy 343.088936 -269.704802) (xy 343.042778 -269.678153) (xy 343.001107 -269.644922) (xy 342.964855 -269.605851)
			(xy 342.934831 -269.561814) (xy 342.911705 -269.513793) (xy 342.895995 -269.462863) (xy 342.888052 -269.410159)
			(xy 342.659472 -269.410159) (xy 342.651529 -269.462863) (xy 342.635819 -269.513793) (xy 342.612693 -269.561814)
			(xy 342.582669 -269.605851) (xy 342.546417 -269.644922) (xy 342.504746 -269.678153) (xy 342.458588 -269.704802)
			(xy 342.408974 -269.724274) (xy 342.357012 -269.736134) (xy 342.303862 -269.740118) (xy 342.250712 -269.736134)
			(xy 342.19875 -269.724274) (xy 342.149136 -269.704802) (xy 342.102978 -269.678153) (xy 342.061307 -269.644922)
			(xy 342.025055 -269.605851) (xy 341.995031 -269.561814) (xy 341.971905 -269.513793) (xy 341.956195 -269.462863)
			(xy 341.948252 -269.410159) (xy 341.719672 -269.410159) (xy 341.711729 -269.462863) (xy 341.696019 -269.513793)
			(xy 341.672893 -269.561814) (xy 341.642869 -269.605851) (xy 341.606617 -269.644922) (xy 341.564946 -269.678153)
			(xy 341.518788 -269.704802) (xy 341.469174 -269.724274) (xy 341.417212 -269.736134) (xy 341.364062 -269.740118)
			(xy 341.310912 -269.736134) (xy 341.25895 -269.724274) (xy 341.209336 -269.704802) (xy 341.163178 -269.678153)
			(xy 341.121507 -269.644922) (xy 341.085255 -269.605851) (xy 341.055231 -269.561814) (xy 341.032105 -269.513793)
			(xy 341.016395 -269.462863) (xy 341.008452 -269.410159) (xy 340.779872 -269.410159) (xy 340.771929 -269.462863)
			(xy 340.756219 -269.513793) (xy 340.733093 -269.561814) (xy 340.703069 -269.605851) (xy 340.666817 -269.644922)
			(xy 340.625146 -269.678153) (xy 340.578988 -269.704802) (xy 340.529374 -269.724274) (xy 340.477412 -269.736134)
			(xy 340.424262 -269.740118) (xy 340.371112 -269.736134) (xy 340.31915 -269.724274) (xy 340.269536 -269.704802)
			(xy 340.223378 -269.678153) (xy 340.181707 -269.644922) (xy 340.145455 -269.605851) (xy 340.115431 -269.561814)
			(xy 340.092305 -269.513793) (xy 340.076595 -269.462863) (xy 340.068652 -269.410159) (xy 339.8393 -269.410159)
			(xy 339.837315 -269.436647) (xy 339.825456 -269.488606) (xy 339.805985 -269.538218) (xy 339.779338 -269.584373)
			(xy 339.74611 -269.626042) (xy 339.707042 -269.662293) (xy 339.663008 -269.692317) (xy 339.614991 -269.715443)
			(xy 339.564064 -269.731154) (xy 339.511364 -269.739099) (xy 339.484716 -269.739618) (xy 339.481922 -269.739618)
			(xy 339.468536 -269.739927) (xy 339.442642 -269.746702) (xy 339.419399 -269.759976) (xy 339.400407 -269.778837)
			(xy 339.386971 -269.801988) (xy 339.380017 -269.827835) (xy 339.37956 -269.841218) (xy 339.37956 -270.224229)
			(xy 339.598752 -270.224229) (xy 339.598752 -270.170931) (xy 339.606695 -270.118227) (xy 339.622405 -270.067297)
			(xy 339.645531 -270.019276) (xy 339.675555 -269.975239) (xy 339.711807 -269.936168) (xy 339.753478 -269.902937)
			(xy 339.799636 -269.876288) (xy 339.84925 -269.856816) (xy 339.901212 -269.844956) (xy 339.954362 -269.840973)
			(xy 340.007512 -269.844956) (xy 340.059474 -269.856816) (xy 340.109088 -269.876288) (xy 340.155246 -269.902937)
			(xy 340.196917 -269.936168) (xy 340.233169 -269.975239) (xy 340.263193 -270.019276) (xy 340.286319 -270.067297)
			(xy 340.302029 -270.118227) (xy 340.309972 -270.170931) (xy 340.31047 -270.19758) (xy 340.309972 -270.224229)
			(xy 340.538806 -270.224229) (xy 340.538806 -270.170931) (xy 340.546749 -270.118227) (xy 340.562459 -270.067297)
			(xy 340.585585 -270.019276) (xy 340.615609 -269.975239) (xy 340.651861 -269.936168) (xy 340.693532 -269.902937)
			(xy 340.73969 -269.876288) (xy 340.789304 -269.856816) (xy 340.841266 -269.844956) (xy 340.894416 -269.840973)
			(xy 340.947566 -269.844956) (xy 340.999528 -269.856816) (xy 341.049142 -269.876288) (xy 341.0953 -269.902937)
			(xy 341.136971 -269.936168) (xy 341.173223 -269.975239) (xy 341.203247 -270.019276) (xy 341.226373 -270.067297)
			(xy 341.242083 -270.118227) (xy 341.250026 -270.170931) (xy 341.250524 -270.19758) (xy 341.250026 -270.224229)
			(xy 341.478606 -270.224229) (xy 341.478606 -270.170931) (xy 341.486549 -270.118227) (xy 341.502259 -270.067297)
			(xy 341.525385 -270.019276) (xy 341.555409 -269.975239) (xy 341.591661 -269.936168) (xy 341.633332 -269.902937)
			(xy 341.67949 -269.876288) (xy 341.729104 -269.856816) (xy 341.781066 -269.844956) (xy 341.834216 -269.840973)
			(xy 341.887366 -269.844956) (xy 341.939328 -269.856816) (xy 341.988942 -269.876288) (xy 342.0351 -269.902937)
			(xy 342.076771 -269.936168) (xy 342.113023 -269.975239) (xy 342.143047 -270.019276) (xy 342.166173 -270.067297)
			(xy 342.181883 -270.118227) (xy 342.189826 -270.170931) (xy 342.190324 -270.19758) (xy 342.189826 -270.224229)
			(xy 342.418406 -270.224229) (xy 342.418406 -270.170931) (xy 342.426349 -270.118227) (xy 342.442059 -270.067297)
			(xy 342.465185 -270.019276) (xy 342.495209 -269.975239) (xy 342.531461 -269.936168) (xy 342.573132 -269.902937)
			(xy 342.61929 -269.876288) (xy 342.668904 -269.856816) (xy 342.720866 -269.844956) (xy 342.774016 -269.840973)
			(xy 342.827166 -269.844956) (xy 342.879128 -269.856816) (xy 342.928742 -269.876288) (xy 342.9749 -269.902937)
			(xy 343.016571 -269.936168) (xy 343.052823 -269.975239) (xy 343.082847 -270.019276) (xy 343.105973 -270.067297)
			(xy 343.121683 -270.118227) (xy 343.129626 -270.170931) (xy 343.130124 -270.19758) (xy 343.129626 -270.224229)
			(xy 343.358206 -270.224229) (xy 343.358206 -270.170931) (xy 343.366149 -270.118227) (xy 343.381859 -270.067297)
			(xy 343.404985 -270.019276) (xy 343.435009 -269.975239) (xy 343.471261 -269.936168) (xy 343.512932 -269.902937)
			(xy 343.55909 -269.876288) (xy 343.608704 -269.856816) (xy 343.660666 -269.844956) (xy 343.713816 -269.840973)
			(xy 343.766966 -269.844956) (xy 343.818928 -269.856816) (xy 343.868542 -269.876288) (xy 343.9147 -269.902937)
			(xy 343.956371 -269.936168) (xy 343.992623 -269.975239) (xy 344.022647 -270.019276) (xy 344.045773 -270.067297)
			(xy 344.061483 -270.118227) (xy 344.069426 -270.170931) (xy 344.069924 -270.19758) (xy 344.069426 -270.224229)
			(xy 344.298006 -270.224229) (xy 344.298006 -270.170931) (xy 344.305949 -270.118227) (xy 344.321659 -270.067297)
			(xy 344.344785 -270.019276) (xy 344.374809 -269.975239) (xy 344.411061 -269.936168) (xy 344.452732 -269.902937)
			(xy 344.49889 -269.876288) (xy 344.548504 -269.856816) (xy 344.600466 -269.844956) (xy 344.653616 -269.840973)
			(xy 344.706766 -269.844956) (xy 344.758728 -269.856816) (xy 344.808342 -269.876288) (xy 344.8545 -269.902937)
			(xy 344.896171 -269.936168) (xy 344.932423 -269.975239) (xy 344.962447 -270.019276) (xy 344.985573 -270.067297)
			(xy 345.001283 -270.118227) (xy 345.009226 -270.170931) (xy 345.009724 -270.19758) (xy 345.009226 -270.224229)
			(xy 345.237806 -270.224229) (xy 345.237806 -270.170931) (xy 345.245749 -270.118227) (xy 345.261459 -270.067297)
			(xy 345.284585 -270.019276) (xy 345.314609 -269.975239) (xy 345.350861 -269.936168) (xy 345.392532 -269.902937)
			(xy 345.43869 -269.876288) (xy 345.488304 -269.856816) (xy 345.540266 -269.844956) (xy 345.593416 -269.840973)
			(xy 345.646566 -269.844956) (xy 345.698528 -269.856816) (xy 345.748142 -269.876288) (xy 345.7943 -269.902937)
			(xy 345.835971 -269.936168) (xy 345.872223 -269.975239) (xy 345.902247 -270.019276) (xy 345.925373 -270.067297)
			(xy 345.941083 -270.118227) (xy 345.949026 -270.170931) (xy 345.949524 -270.19758) (xy 345.949026 -270.224229)
			(xy 346.177352 -270.224229) (xy 346.177352 -270.170931) (xy 346.185295 -270.118227) (xy 346.201005 -270.067297)
			(xy 346.224131 -270.019276) (xy 346.254155 -269.975239) (xy 346.290407 -269.936168) (xy 346.332078 -269.902937)
			(xy 346.378236 -269.876288) (xy 346.42785 -269.856816) (xy 346.479812 -269.844956) (xy 346.532962 -269.840973)
			(xy 346.586112 -269.844956) (xy 346.638074 -269.856816) (xy 346.687688 -269.876288) (xy 346.733846 -269.902937)
			(xy 346.775517 -269.936168) (xy 346.811769 -269.975239) (xy 346.841793 -270.019276) (xy 346.864919 -270.067297)
			(xy 346.880629 -270.118227) (xy 346.888572 -270.170931) (xy 346.88907 -270.19758) (xy 346.888572 -270.224229)
			(xy 347.117406 -270.224229) (xy 347.117406 -270.170931) (xy 347.125349 -270.118227) (xy 347.141059 -270.067297)
			(xy 347.164185 -270.019276) (xy 347.194209 -269.975239) (xy 347.230461 -269.936168) (xy 347.272132 -269.902937)
			(xy 347.31829 -269.876288) (xy 347.367904 -269.856816) (xy 347.419866 -269.844956) (xy 347.473016 -269.840973)
			(xy 347.526166 -269.844956) (xy 347.578128 -269.856816) (xy 347.627742 -269.876288) (xy 347.6739 -269.902937)
			(xy 347.715571 -269.936168) (xy 347.751823 -269.975239) (xy 347.781847 -270.019276) (xy 347.804973 -270.067297)
			(xy 347.820683 -270.118227) (xy 347.828626 -270.170931) (xy 347.829124 -270.19758) (xy 347.828626 -270.224229)
			(xy 348.057206 -270.224229) (xy 348.057206 -270.170931) (xy 348.065149 -270.118227) (xy 348.080859 -270.067297)
			(xy 348.103985 -270.019276) (xy 348.134009 -269.975239) (xy 348.170261 -269.936168) (xy 348.211932 -269.902937)
			(xy 348.25809 -269.876288) (xy 348.307704 -269.856816) (xy 348.359666 -269.844956) (xy 348.412816 -269.840973)
			(xy 348.465966 -269.844956) (xy 348.517928 -269.856816) (xy 348.567542 -269.876288) (xy 348.6137 -269.902937)
			(xy 348.655371 -269.936168) (xy 348.691623 -269.975239) (xy 348.721647 -270.019276) (xy 348.744773 -270.067297)
			(xy 348.760483 -270.118227) (xy 348.768426 -270.170931) (xy 348.768924 -270.19758) (xy 348.768426 -270.224229)
			(xy 348.997006 -270.224229) (xy 348.997006 -270.170931) (xy 349.004949 -270.118227) (xy 349.020659 -270.067297)
			(xy 349.043785 -270.019276) (xy 349.073809 -269.975239) (xy 349.110061 -269.936168) (xy 349.151732 -269.902937)
			(xy 349.19789 -269.876288) (xy 349.247504 -269.856816) (xy 349.299466 -269.844956) (xy 349.352616 -269.840973)
			(xy 349.405766 -269.844956) (xy 349.457728 -269.856816) (xy 349.507342 -269.876288) (xy 349.5535 -269.902937)
			(xy 349.595171 -269.936168) (xy 349.631423 -269.975239) (xy 349.661447 -270.019276) (xy 349.684573 -270.067297)
			(xy 349.700283 -270.118227) (xy 349.708226 -270.170931) (xy 349.708724 -270.19758) (xy 349.708226 -270.224229)
			(xy 349.936806 -270.224229) (xy 349.936806 -270.170931) (xy 349.944749 -270.118227) (xy 349.960459 -270.067297)
			(xy 349.983585 -270.019276) (xy 350.013609 -269.975239) (xy 350.049861 -269.936168) (xy 350.091532 -269.902937)
			(xy 350.13769 -269.876288) (xy 350.187304 -269.856816) (xy 350.239266 -269.844956) (xy 350.292416 -269.840973)
			(xy 350.345566 -269.844956) (xy 350.397528 -269.856816) (xy 350.447142 -269.876288) (xy 350.4933 -269.902937)
			(xy 350.534971 -269.936168) (xy 350.571223 -269.975239) (xy 350.601247 -270.019276) (xy 350.624373 -270.067297)
			(xy 350.640083 -270.118227) (xy 350.648026 -270.170931) (xy 350.648524 -270.19758) (xy 350.648026 -270.224229)
			(xy 350.876606 -270.224229) (xy 350.876606 -270.170931) (xy 350.884549 -270.118227) (xy 350.900259 -270.067297)
			(xy 350.923385 -270.019276) (xy 350.953409 -269.975239) (xy 350.989661 -269.936168) (xy 351.031332 -269.902937)
			(xy 351.07749 -269.876288) (xy 351.127104 -269.856816) (xy 351.179066 -269.844956) (xy 351.232216 -269.840973)
			(xy 351.285366 -269.844956) (xy 351.337328 -269.856816) (xy 351.386942 -269.876288) (xy 351.4331 -269.902937)
			(xy 351.474771 -269.936168) (xy 351.511023 -269.975239) (xy 351.541047 -270.019276) (xy 351.564173 -270.067297)
			(xy 351.579883 -270.118227) (xy 351.587826 -270.170931) (xy 351.588324 -270.19758) (xy 351.587826 -270.224229)
			(xy 351.816406 -270.224229) (xy 351.816406 -270.170931) (xy 351.824349 -270.118227) (xy 351.840059 -270.067297)
			(xy 351.863185 -270.019276) (xy 351.893209 -269.975239) (xy 351.929461 -269.936168) (xy 351.971132 -269.902937)
			(xy 352.01729 -269.876288) (xy 352.066904 -269.856816) (xy 352.118866 -269.844956) (xy 352.172016 -269.840973)
			(xy 352.225166 -269.844956) (xy 352.277128 -269.856816) (xy 352.326742 -269.876288) (xy 352.3729 -269.902937)
			(xy 352.414571 -269.936168) (xy 352.450823 -269.975239) (xy 352.480847 -270.019276) (xy 352.503973 -270.067297)
			(xy 352.519683 -270.118227) (xy 352.527626 -270.170931) (xy 352.528124 -270.19758) (xy 352.527626 -270.224229)
			(xy 352.756206 -270.224229) (xy 352.756206 -270.170931) (xy 352.764149 -270.118227) (xy 352.779859 -270.067297)
			(xy 352.802985 -270.019276) (xy 352.833009 -269.975239) (xy 352.869261 -269.936168) (xy 352.910932 -269.902937)
			(xy 352.95709 -269.876288) (xy 353.006704 -269.856816) (xy 353.058666 -269.844956) (xy 353.111816 -269.840973)
			(xy 353.164966 -269.844956) (xy 353.216928 -269.856816) (xy 353.266542 -269.876288) (xy 353.3127 -269.902937)
			(xy 353.354371 -269.936168) (xy 353.390623 -269.975239) (xy 353.420647 -270.019276) (xy 353.443773 -270.067297)
			(xy 353.459483 -270.118227) (xy 353.467426 -270.170931) (xy 353.467924 -270.19758) (xy 353.467426 -270.224229)
			(xy 353.696006 -270.224229) (xy 353.696006 -270.170931) (xy 353.703949 -270.118227) (xy 353.719659 -270.067297)
			(xy 353.742785 -270.019276) (xy 353.772809 -269.975239) (xy 353.809061 -269.936168) (xy 353.850732 -269.902937)
			(xy 353.89689 -269.876288) (xy 353.946504 -269.856816) (xy 353.998466 -269.844956) (xy 354.051616 -269.840973)
			(xy 354.104766 -269.844956) (xy 354.156728 -269.856816) (xy 354.206342 -269.876288) (xy 354.2525 -269.902937)
			(xy 354.294171 -269.936168) (xy 354.330423 -269.975239) (xy 354.360447 -270.019276) (xy 354.383573 -270.067297)
			(xy 354.399283 -270.118227) (xy 354.407226 -270.170931) (xy 354.407724 -270.19758) (xy 354.407226 -270.224229)
			(xy 354.635806 -270.224229) (xy 354.635806 -270.170931) (xy 354.643749 -270.118227) (xy 354.659459 -270.067297)
			(xy 354.682585 -270.019276) (xy 354.712609 -269.975239) (xy 354.748861 -269.936168) (xy 354.790532 -269.902937)
			(xy 354.83669 -269.876288) (xy 354.886304 -269.856816) (xy 354.938266 -269.844956) (xy 354.991416 -269.840973)
			(xy 355.044566 -269.844956) (xy 355.096528 -269.856816) (xy 355.146142 -269.876288) (xy 355.1923 -269.902937)
			(xy 355.233971 -269.936168) (xy 355.270223 -269.975239) (xy 355.300247 -270.019276) (xy 355.323373 -270.067297)
			(xy 355.339083 -270.118227) (xy 355.347026 -270.170931) (xy 355.347524 -270.19758) (xy 355.347026 -270.224229)
			(xy 355.339083 -270.276933) (xy 355.323373 -270.327863) (xy 355.300247 -270.375884) (xy 355.270223 -270.419921)
			(xy 355.233971 -270.458992) (xy 355.1923 -270.492223) (xy 355.146142 -270.518872) (xy 355.096528 -270.538344)
			(xy 355.044566 -270.550204) (xy 354.991416 -270.554188) (xy 354.938266 -270.550204) (xy 354.886304 -270.538344)
			(xy 354.83669 -270.518872) (xy 354.790532 -270.492223) (xy 354.748861 -270.458992) (xy 354.712609 -270.419921)
			(xy 354.682585 -270.375884) (xy 354.659459 -270.327863) (xy 354.643749 -270.276933) (xy 354.635806 -270.224229)
			(xy 354.407226 -270.224229) (xy 354.399283 -270.276933) (xy 354.383573 -270.327863) (xy 354.360447 -270.375884)
			(xy 354.330423 -270.419921) (xy 354.294171 -270.458992) (xy 354.2525 -270.492223) (xy 354.206342 -270.518872)
			(xy 354.156728 -270.538344) (xy 354.104766 -270.550204) (xy 354.051616 -270.554188) (xy 353.998466 -270.550204)
			(xy 353.946504 -270.538344) (xy 353.89689 -270.518872) (xy 353.850732 -270.492223) (xy 353.809061 -270.458992)
			(xy 353.772809 -270.419921) (xy 353.742785 -270.375884) (xy 353.719659 -270.327863) (xy 353.703949 -270.276933)
			(xy 353.696006 -270.224229) (xy 353.467426 -270.224229) (xy 353.459483 -270.276933) (xy 353.443773 -270.327863)
			(xy 353.420647 -270.375884) (xy 353.390623 -270.419921) (xy 353.354371 -270.458992) (xy 353.3127 -270.492223)
			(xy 353.266542 -270.518872) (xy 353.216928 -270.538344) (xy 353.164966 -270.550204) (xy 353.111816 -270.554188)
			(xy 353.058666 -270.550204) (xy 353.006704 -270.538344) (xy 352.95709 -270.518872) (xy 352.910932 -270.492223)
			(xy 352.869261 -270.458992) (xy 352.833009 -270.419921) (xy 352.802985 -270.375884) (xy 352.779859 -270.327863)
			(xy 352.764149 -270.276933) (xy 352.756206 -270.224229) (xy 352.527626 -270.224229) (xy 352.519683 -270.276933)
			(xy 352.503973 -270.327863) (xy 352.480847 -270.375884) (xy 352.450823 -270.419921) (xy 352.414571 -270.458992)
			(xy 352.3729 -270.492223) (xy 352.326742 -270.518872) (xy 352.277128 -270.538344) (xy 352.225166 -270.550204)
			(xy 352.172016 -270.554188) (xy 352.118866 -270.550204) (xy 352.066904 -270.538344) (xy 352.01729 -270.518872)
			(xy 351.971132 -270.492223) (xy 351.929461 -270.458992) (xy 351.893209 -270.419921) (xy 351.863185 -270.375884)
			(xy 351.840059 -270.327863) (xy 351.824349 -270.276933) (xy 351.816406 -270.224229) (xy 351.587826 -270.224229)
			(xy 351.579883 -270.276933) (xy 351.564173 -270.327863) (xy 351.541047 -270.375884) (xy 351.511023 -270.419921)
			(xy 351.474771 -270.458992) (xy 351.4331 -270.492223) (xy 351.386942 -270.518872) (xy 351.337328 -270.538344)
			(xy 351.285366 -270.550204) (xy 351.232216 -270.554188) (xy 351.179066 -270.550204) (xy 351.127104 -270.538344)
			(xy 351.07749 -270.518872) (xy 351.031332 -270.492223) (xy 350.989661 -270.458992) (xy 350.953409 -270.419921)
			(xy 350.923385 -270.375884) (xy 350.900259 -270.327863) (xy 350.884549 -270.276933) (xy 350.876606 -270.224229)
			(xy 350.648026 -270.224229) (xy 350.640083 -270.276933) (xy 350.624373 -270.327863) (xy 350.601247 -270.375884)
			(xy 350.571223 -270.419921) (xy 350.534971 -270.458992) (xy 350.4933 -270.492223) (xy 350.447142 -270.518872)
			(xy 350.397528 -270.538344) (xy 350.345566 -270.550204) (xy 350.292416 -270.554188) (xy 350.239266 -270.550204)
			(xy 350.187304 -270.538344) (xy 350.13769 -270.518872) (xy 350.091532 -270.492223) (xy 350.049861 -270.458992)
			(xy 350.013609 -270.419921) (xy 349.983585 -270.375884) (xy 349.960459 -270.327863) (xy 349.944749 -270.276933)
			(xy 349.936806 -270.224229) (xy 349.708226 -270.224229) (xy 349.700283 -270.276933) (xy 349.684573 -270.327863)
			(xy 349.661447 -270.375884) (xy 349.631423 -270.419921) (xy 349.595171 -270.458992) (xy 349.5535 -270.492223)
			(xy 349.507342 -270.518872) (xy 349.457728 -270.538344) (xy 349.405766 -270.550204) (xy 349.352616 -270.554188)
			(xy 349.299466 -270.550204) (xy 349.247504 -270.538344) (xy 349.19789 -270.518872) (xy 349.151732 -270.492223)
			(xy 349.110061 -270.458992) (xy 349.073809 -270.419921) (xy 349.043785 -270.375884) (xy 349.020659 -270.327863)
			(xy 349.004949 -270.276933) (xy 348.997006 -270.224229) (xy 348.768426 -270.224229) (xy 348.760483 -270.276933)
			(xy 348.744773 -270.327863) (xy 348.721647 -270.375884) (xy 348.691623 -270.419921) (xy 348.655371 -270.458992)
			(xy 348.6137 -270.492223) (xy 348.567542 -270.518872) (xy 348.517928 -270.538344) (xy 348.465966 -270.550204)
			(xy 348.412816 -270.554188) (xy 348.359666 -270.550204) (xy 348.307704 -270.538344) (xy 348.25809 -270.518872)
			(xy 348.211932 -270.492223) (xy 348.170261 -270.458992) (xy 348.134009 -270.419921) (xy 348.103985 -270.375884)
			(xy 348.080859 -270.327863) (xy 348.065149 -270.276933) (xy 348.057206 -270.224229) (xy 347.828626 -270.224229)
			(xy 347.820683 -270.276933) (xy 347.804973 -270.327863) (xy 347.781847 -270.375884) (xy 347.751823 -270.419921)
			(xy 347.715571 -270.458992) (xy 347.6739 -270.492223) (xy 347.627742 -270.518872) (xy 347.578128 -270.538344)
			(xy 347.526166 -270.550204) (xy 347.473016 -270.554188) (xy 347.419866 -270.550204) (xy 347.367904 -270.538344)
			(xy 347.31829 -270.518872) (xy 347.272132 -270.492223) (xy 347.230461 -270.458992) (xy 347.194209 -270.419921)
			(xy 347.164185 -270.375884) (xy 347.141059 -270.327863) (xy 347.125349 -270.276933) (xy 347.117406 -270.224229)
			(xy 346.888572 -270.224229) (xy 346.880629 -270.276933) (xy 346.864919 -270.327863) (xy 346.841793 -270.375884)
			(xy 346.811769 -270.419921) (xy 346.775517 -270.458992) (xy 346.733846 -270.492223) (xy 346.687688 -270.518872)
			(xy 346.638074 -270.538344) (xy 346.586112 -270.550204) (xy 346.532962 -270.554188) (xy 346.479812 -270.550204)
			(xy 346.42785 -270.538344) (xy 346.378236 -270.518872) (xy 346.332078 -270.492223) (xy 346.290407 -270.458992)
			(xy 346.254155 -270.419921) (xy 346.224131 -270.375884) (xy 346.201005 -270.327863) (xy 346.185295 -270.276933)
			(xy 346.177352 -270.224229) (xy 345.949026 -270.224229) (xy 345.941083 -270.276933) (xy 345.925373 -270.327863)
			(xy 345.902247 -270.375884) (xy 345.872223 -270.419921) (xy 345.835971 -270.458992) (xy 345.7943 -270.492223)
			(xy 345.748142 -270.518872) (xy 345.698528 -270.538344) (xy 345.646566 -270.550204) (xy 345.593416 -270.554188)
			(xy 345.540266 -270.550204) (xy 345.488304 -270.538344) (xy 345.43869 -270.518872) (xy 345.392532 -270.492223)
			(xy 345.350861 -270.458992) (xy 345.314609 -270.419921) (xy 345.284585 -270.375884) (xy 345.261459 -270.327863)
			(xy 345.245749 -270.276933) (xy 345.237806 -270.224229) (xy 345.009226 -270.224229) (xy 345.001283 -270.276933)
			(xy 344.985573 -270.327863) (xy 344.962447 -270.375884) (xy 344.932423 -270.419921) (xy 344.896171 -270.458992)
			(xy 344.8545 -270.492223) (xy 344.808342 -270.518872) (xy 344.758728 -270.538344) (xy 344.706766 -270.550204)
			(xy 344.653616 -270.554188) (xy 344.600466 -270.550204) (xy 344.548504 -270.538344) (xy 344.49889 -270.518872)
			(xy 344.452732 -270.492223) (xy 344.411061 -270.458992) (xy 344.374809 -270.419921) (xy 344.344785 -270.375884)
			(xy 344.321659 -270.327863) (xy 344.305949 -270.276933) (xy 344.298006 -270.224229) (xy 344.069426 -270.224229)
			(xy 344.061483 -270.276933) (xy 344.045773 -270.327863) (xy 344.022647 -270.375884) (xy 343.992623 -270.419921)
			(xy 343.956371 -270.458992) (xy 343.9147 -270.492223) (xy 343.868542 -270.518872) (xy 343.818928 -270.538344)
			(xy 343.766966 -270.550204) (xy 343.713816 -270.554188) (xy 343.660666 -270.550204) (xy 343.608704 -270.538344)
			(xy 343.55909 -270.518872) (xy 343.512932 -270.492223) (xy 343.471261 -270.458992) (xy 343.435009 -270.419921)
			(xy 343.404985 -270.375884) (xy 343.381859 -270.327863) (xy 343.366149 -270.276933) (xy 343.358206 -270.224229)
			(xy 343.129626 -270.224229) (xy 343.121683 -270.276933) (xy 343.105973 -270.327863) (xy 343.082847 -270.375884)
			(xy 343.052823 -270.419921) (xy 343.016571 -270.458992) (xy 342.9749 -270.492223) (xy 342.928742 -270.518872)
			(xy 342.879128 -270.538344) (xy 342.827166 -270.550204) (xy 342.774016 -270.554188) (xy 342.720866 -270.550204)
			(xy 342.668904 -270.538344) (xy 342.61929 -270.518872) (xy 342.573132 -270.492223) (xy 342.531461 -270.458992)
			(xy 342.495209 -270.419921) (xy 342.465185 -270.375884) (xy 342.442059 -270.327863) (xy 342.426349 -270.276933)
			(xy 342.418406 -270.224229) (xy 342.189826 -270.224229) (xy 342.181883 -270.276933) (xy 342.166173 -270.327863)
			(xy 342.143047 -270.375884) (xy 342.113023 -270.419921) (xy 342.076771 -270.458992) (xy 342.0351 -270.492223)
			(xy 341.988942 -270.518872) (xy 341.939328 -270.538344) (xy 341.887366 -270.550204) (xy 341.834216 -270.554188)
			(xy 341.781066 -270.550204) (xy 341.729104 -270.538344) (xy 341.67949 -270.518872) (xy 341.633332 -270.492223)
			(xy 341.591661 -270.458992) (xy 341.555409 -270.419921) (xy 341.525385 -270.375884) (xy 341.502259 -270.327863)
			(xy 341.486549 -270.276933) (xy 341.478606 -270.224229) (xy 341.250026 -270.224229) (xy 341.242083 -270.276933)
			(xy 341.226373 -270.327863) (xy 341.203247 -270.375884) (xy 341.173223 -270.419921) (xy 341.136971 -270.458992)
			(xy 341.0953 -270.492223) (xy 341.049142 -270.518872) (xy 340.999528 -270.538344) (xy 340.947566 -270.550204)
			(xy 340.894416 -270.554188) (xy 340.841266 -270.550204) (xy 340.789304 -270.538344) (xy 340.73969 -270.518872)
			(xy 340.693532 -270.492223) (xy 340.651861 -270.458992) (xy 340.615609 -270.419921) (xy 340.585585 -270.375884)
			(xy 340.562459 -270.327863) (xy 340.546749 -270.276933) (xy 340.538806 -270.224229) (xy 340.309972 -270.224229)
			(xy 340.302029 -270.276933) (xy 340.286319 -270.327863) (xy 340.263193 -270.375884) (xy 340.233169 -270.419921)
			(xy 340.196917 -270.458992) (xy 340.155246 -270.492223) (xy 340.109088 -270.518872) (xy 340.059474 -270.538344)
			(xy 340.007512 -270.550204) (xy 339.954362 -270.554188) (xy 339.901212 -270.550204) (xy 339.84925 -270.538344)
			(xy 339.799636 -270.518872) (xy 339.753478 -270.492223) (xy 339.711807 -270.458992) (xy 339.675555 -270.419921)
			(xy 339.645531 -270.375884) (xy 339.622405 -270.327863) (xy 339.606695 -270.276933) (xy 339.598752 -270.224229)
			(xy 339.37956 -270.224229) (xy 339.37956 -270.553688) (xy 339.379962 -270.567078) (xy 339.386921 -270.592938)
			(xy 339.400364 -270.6161) (xy 339.419367 -270.63497) (xy 339.442622 -270.648251) (xy 339.46853 -270.655029)
			(xy 339.481922 -270.655288) (xy 339.484462 -270.655288) (xy 339.511115 -270.655759) (xy 339.563827 -270.663698)
			(xy 339.614767 -270.679406) (xy 339.662796 -270.702531) (xy 339.706842 -270.732557) (xy 339.74592 -270.768813)
			(xy 339.779158 -270.810488) (xy 339.805813 -270.856652) (xy 339.82529 -270.906273) (xy 339.837152 -270.958243)
			(xy 339.841136 -271.0114) (xy 339.839139 -271.038045) (xy 340.068652 -271.038045) (xy 340.068652 -270.984747)
			(xy 340.076595 -270.932043) (xy 340.092305 -270.881113) (xy 340.115431 -270.833092) (xy 340.145455 -270.789055)
			(xy 340.181707 -270.749984) (xy 340.223378 -270.716753) (xy 340.269536 -270.690104) (xy 340.31915 -270.670632)
			(xy 340.371112 -270.658772) (xy 340.424262 -270.654789) (xy 340.477412 -270.658772) (xy 340.529374 -270.670632)
			(xy 340.578988 -270.690104) (xy 340.625146 -270.716753) (xy 340.666817 -270.749984) (xy 340.703069 -270.789055)
			(xy 340.733093 -270.833092) (xy 340.756219 -270.881113) (xy 340.771929 -270.932043) (xy 340.779872 -270.984747)
			(xy 340.78037 -271.011396) (xy 340.779872 -271.038045) (xy 341.008452 -271.038045) (xy 341.008452 -270.984747)
			(xy 341.016395 -270.932043) (xy 341.032105 -270.881113) (xy 341.055231 -270.833092) (xy 341.085255 -270.789055)
			(xy 341.121507 -270.749984) (xy 341.163178 -270.716753) (xy 341.209336 -270.690104) (xy 341.25895 -270.670632)
			(xy 341.310912 -270.658772) (xy 341.364062 -270.654789) (xy 341.417212 -270.658772) (xy 341.469174 -270.670632)
			(xy 341.518788 -270.690104) (xy 341.564946 -270.716753) (xy 341.606617 -270.749984) (xy 341.642869 -270.789055)
			(xy 341.672893 -270.833092) (xy 341.696019 -270.881113) (xy 341.711729 -270.932043) (xy 341.719672 -270.984747)
			(xy 341.72017 -271.011396) (xy 341.719672 -271.038045) (xy 341.948506 -271.038045) (xy 341.948506 -270.984747)
			(xy 341.956449 -270.932043) (xy 341.972159 -270.881113) (xy 341.995285 -270.833092) (xy 342.025309 -270.789055)
			(xy 342.061561 -270.749984) (xy 342.103232 -270.716753) (xy 342.14939 -270.690104) (xy 342.199004 -270.670632)
			(xy 342.250966 -270.658772) (xy 342.304116 -270.654789) (xy 342.357266 -270.658772) (xy 342.409228 -270.670632)
			(xy 342.458842 -270.690104) (xy 342.505 -270.716753) (xy 342.546671 -270.749984) (xy 342.582923 -270.789055)
			(xy 342.612947 -270.833092) (xy 342.636073 -270.881113) (xy 342.651783 -270.932043) (xy 342.659726 -270.984747)
			(xy 342.660224 -271.011396) (xy 342.659726 -271.038045) (xy 342.888052 -271.038045) (xy 342.888052 -270.984747)
			(xy 342.895995 -270.932043) (xy 342.911705 -270.881113) (xy 342.934831 -270.833092) (xy 342.964855 -270.789055)
			(xy 343.001107 -270.749984) (xy 343.042778 -270.716753) (xy 343.088936 -270.690104) (xy 343.13855 -270.670632)
			(xy 343.190512 -270.658772) (xy 343.243662 -270.654789) (xy 343.296812 -270.658772) (xy 343.348774 -270.670632)
			(xy 343.398388 -270.690104) (xy 343.444546 -270.716753) (xy 343.486217 -270.749984) (xy 343.522469 -270.789055)
			(xy 343.552493 -270.833092) (xy 343.575619 -270.881113) (xy 343.591329 -270.932043) (xy 343.599272 -270.984747)
			(xy 343.59977 -271.011396) (xy 343.599272 -271.038045) (xy 343.827852 -271.038045) (xy 343.827852 -270.984747)
			(xy 343.835795 -270.932043) (xy 343.851505 -270.881113) (xy 343.874631 -270.833092) (xy 343.904655 -270.789055)
			(xy 343.940907 -270.749984) (xy 343.982578 -270.716753) (xy 344.028736 -270.690104) (xy 344.07835 -270.670632)
			(xy 344.130312 -270.658772) (xy 344.183462 -270.654789) (xy 344.236612 -270.658772) (xy 344.288574 -270.670632)
			(xy 344.338188 -270.690104) (xy 344.384346 -270.716753) (xy 344.426017 -270.749984) (xy 344.462269 -270.789055)
			(xy 344.492293 -270.833092) (xy 344.515419 -270.881113) (xy 344.531129 -270.932043) (xy 344.539072 -270.984747)
			(xy 344.53957 -271.011396) (xy 344.539072 -271.038045) (xy 344.767652 -271.038045) (xy 344.767652 -270.984747)
			(xy 344.775595 -270.932043) (xy 344.791305 -270.881113) (xy 344.814431 -270.833092) (xy 344.844455 -270.789055)
			(xy 344.880707 -270.749984) (xy 344.922378 -270.716753) (xy 344.968536 -270.690104) (xy 345.01815 -270.670632)
			(xy 345.070112 -270.658772) (xy 345.123262 -270.654789) (xy 345.176412 -270.658772) (xy 345.228374 -270.670632)
			(xy 345.277988 -270.690104) (xy 345.324146 -270.716753) (xy 345.365817 -270.749984) (xy 345.402069 -270.789055)
			(xy 345.432093 -270.833092) (xy 345.455219 -270.881113) (xy 345.470929 -270.932043) (xy 345.478872 -270.984747)
			(xy 345.47937 -271.011396) (xy 345.478872 -271.038045) (xy 345.707452 -271.038045) (xy 345.707452 -270.984747)
			(xy 345.715395 -270.932043) (xy 345.731105 -270.881113) (xy 345.754231 -270.833092) (xy 345.784255 -270.789055)
			(xy 345.820507 -270.749984) (xy 345.862178 -270.716753) (xy 345.908336 -270.690104) (xy 345.95795 -270.670632)
			(xy 346.009912 -270.658772) (xy 346.063062 -270.654789) (xy 346.116212 -270.658772) (xy 346.168174 -270.670632)
			(xy 346.217788 -270.690104) (xy 346.263946 -270.716753) (xy 346.305617 -270.749984) (xy 346.341869 -270.789055)
			(xy 346.371893 -270.833092) (xy 346.395019 -270.881113) (xy 346.410729 -270.932043) (xy 346.418672 -270.984747)
			(xy 346.41917 -271.011396) (xy 346.418672 -271.038045) (xy 346.647252 -271.038045) (xy 346.647252 -270.984747)
			(xy 346.655195 -270.932043) (xy 346.670905 -270.881113) (xy 346.694031 -270.833092) (xy 346.724055 -270.789055)
			(xy 346.760307 -270.749984) (xy 346.801978 -270.716753) (xy 346.848136 -270.690104) (xy 346.89775 -270.670632)
			(xy 346.949712 -270.658772) (xy 347.002862 -270.654789) (xy 347.056012 -270.658772) (xy 347.107974 -270.670632)
			(xy 347.157588 -270.690104) (xy 347.203746 -270.716753) (xy 347.245417 -270.749984) (xy 347.281669 -270.789055)
			(xy 347.311693 -270.833092) (xy 347.334819 -270.881113) (xy 347.350529 -270.932043) (xy 347.358472 -270.984747)
			(xy 347.35897 -271.011396) (xy 347.358472 -271.038045) (xy 347.587052 -271.038045) (xy 347.587052 -270.984747)
			(xy 347.594995 -270.932043) (xy 347.610705 -270.881113) (xy 347.633831 -270.833092) (xy 347.663855 -270.789055)
			(xy 347.700107 -270.749984) (xy 347.741778 -270.716753) (xy 347.787936 -270.690104) (xy 347.83755 -270.670632)
			(xy 347.889512 -270.658772) (xy 347.942662 -270.654789) (xy 347.995812 -270.658772) (xy 348.047774 -270.670632)
			(xy 348.097388 -270.690104) (xy 348.143546 -270.716753) (xy 348.185217 -270.749984) (xy 348.221469 -270.789055)
			(xy 348.251493 -270.833092) (xy 348.274619 -270.881113) (xy 348.290329 -270.932043) (xy 348.298272 -270.984747)
			(xy 348.29877 -271.011396) (xy 348.298272 -271.038045) (xy 348.527106 -271.038045) (xy 348.527106 -270.984747)
			(xy 348.535049 -270.932043) (xy 348.550759 -270.881113) (xy 348.573885 -270.833092) (xy 348.603909 -270.789055)
			(xy 348.640161 -270.749984) (xy 348.681832 -270.716753) (xy 348.72799 -270.690104) (xy 348.777604 -270.670632)
			(xy 348.829566 -270.658772) (xy 348.882716 -270.654789) (xy 348.935866 -270.658772) (xy 348.987828 -270.670632)
			(xy 349.037442 -270.690104) (xy 349.0836 -270.716753) (xy 349.125271 -270.749984) (xy 349.161523 -270.789055)
			(xy 349.191547 -270.833092) (xy 349.214673 -270.881113) (xy 349.230383 -270.932043) (xy 349.238326 -270.984747)
			(xy 349.238824 -271.011396) (xy 349.238326 -271.038045) (xy 349.466906 -271.038045) (xy 349.466906 -270.984747)
			(xy 349.474849 -270.932043) (xy 349.490559 -270.881113) (xy 349.513685 -270.833092) (xy 349.543709 -270.789055)
			(xy 349.579961 -270.749984) (xy 349.621632 -270.716753) (xy 349.66779 -270.690104) (xy 349.717404 -270.670632)
			(xy 349.769366 -270.658772) (xy 349.822516 -270.654789) (xy 349.875666 -270.658772) (xy 349.927628 -270.670632)
			(xy 349.977242 -270.690104) (xy 350.0234 -270.716753) (xy 350.065071 -270.749984) (xy 350.101323 -270.789055)
			(xy 350.131347 -270.833092) (xy 350.154473 -270.881113) (xy 350.170183 -270.932043) (xy 350.178126 -270.984747)
			(xy 350.178624 -271.011396) (xy 350.178126 -271.038045) (xy 350.406452 -271.038045) (xy 350.406452 -270.984747)
			(xy 350.414395 -270.932043) (xy 350.430105 -270.881113) (xy 350.453231 -270.833092) (xy 350.483255 -270.789055)
			(xy 350.519507 -270.749984) (xy 350.561178 -270.716753) (xy 350.607336 -270.690104) (xy 350.65695 -270.670632)
			(xy 350.708912 -270.658772) (xy 350.762062 -270.654789) (xy 350.815212 -270.658772) (xy 350.867174 -270.670632)
			(xy 350.916788 -270.690104) (xy 350.962946 -270.716753) (xy 351.004617 -270.749984) (xy 351.040869 -270.789055)
			(xy 351.070893 -270.833092) (xy 351.094019 -270.881113) (xy 351.109729 -270.932043) (xy 351.117672 -270.984747)
			(xy 351.11817 -271.011396) (xy 351.117672 -271.038045) (xy 351.346252 -271.038045) (xy 351.346252 -270.984747)
			(xy 351.354195 -270.932043) (xy 351.369905 -270.881113) (xy 351.393031 -270.833092) (xy 351.423055 -270.789055)
			(xy 351.459307 -270.749984) (xy 351.500978 -270.716753) (xy 351.547136 -270.690104) (xy 351.59675 -270.670632)
			(xy 351.648712 -270.658772) (xy 351.701862 -270.654789) (xy 351.755012 -270.658772) (xy 351.806974 -270.670632)
			(xy 351.856588 -270.690104) (xy 351.902746 -270.716753) (xy 351.944417 -270.749984) (xy 351.980669 -270.789055)
			(xy 352.010693 -270.833092) (xy 352.033819 -270.881113) (xy 352.049529 -270.932043) (xy 352.057472 -270.984747)
			(xy 352.05797 -271.011396) (xy 352.057472 -271.038045) (xy 352.286052 -271.038045) (xy 352.286052 -270.984747)
			(xy 352.293995 -270.932043) (xy 352.309705 -270.881113) (xy 352.332831 -270.833092) (xy 352.362855 -270.789055)
			(xy 352.399107 -270.749984) (xy 352.440778 -270.716753) (xy 352.486936 -270.690104) (xy 352.53655 -270.670632)
			(xy 352.588512 -270.658772) (xy 352.641662 -270.654789) (xy 352.694812 -270.658772) (xy 352.746774 -270.670632)
			(xy 352.796388 -270.690104) (xy 352.842546 -270.716753) (xy 352.884217 -270.749984) (xy 352.920469 -270.789055)
			(xy 352.950493 -270.833092) (xy 352.973619 -270.881113) (xy 352.989329 -270.932043) (xy 352.997272 -270.984747)
			(xy 352.99777 -271.011396) (xy 352.997272 -271.038045) (xy 353.225852 -271.038045) (xy 353.225852 -270.984747)
			(xy 353.233795 -270.932043) (xy 353.249505 -270.881113) (xy 353.272631 -270.833092) (xy 353.302655 -270.789055)
			(xy 353.338907 -270.749984) (xy 353.380578 -270.716753) (xy 353.426736 -270.690104) (xy 353.47635 -270.670632)
			(xy 353.528312 -270.658772) (xy 353.581462 -270.654789) (xy 353.634612 -270.658772) (xy 353.686574 -270.670632)
			(xy 353.736188 -270.690104) (xy 353.782346 -270.716753) (xy 353.824017 -270.749984) (xy 353.860269 -270.789055)
			(xy 353.890293 -270.833092) (xy 353.913419 -270.881113) (xy 353.929129 -270.932043) (xy 353.937072 -270.984747)
			(xy 353.93757 -271.011396) (xy 353.937072 -271.038045) (xy 354.165652 -271.038045) (xy 354.165652 -270.984747)
			(xy 354.173595 -270.932043) (xy 354.189305 -270.881113) (xy 354.212431 -270.833092) (xy 354.242455 -270.789055)
			(xy 354.278707 -270.749984) (xy 354.320378 -270.716753) (xy 354.366536 -270.690104) (xy 354.41615 -270.670632)
			(xy 354.468112 -270.658772) (xy 354.521262 -270.654789) (xy 354.574412 -270.658772) (xy 354.626374 -270.670632)
			(xy 354.675988 -270.690104) (xy 354.722146 -270.716753) (xy 354.763817 -270.749984) (xy 354.800069 -270.789055)
			(xy 354.830093 -270.833092) (xy 354.853219 -270.881113) (xy 354.868929 -270.932043) (xy 354.876872 -270.984747)
			(xy 354.87737 -271.011396) (xy 354.876872 -271.038045) (xy 355.105452 -271.038045) (xy 355.105452 -270.984747)
			(xy 355.113395 -270.932043) (xy 355.129105 -270.881113) (xy 355.152231 -270.833092) (xy 355.182255 -270.789055)
			(xy 355.218507 -270.749984) (xy 355.260178 -270.716753) (xy 355.306336 -270.690104) (xy 355.35595 -270.670632)
			(xy 355.407912 -270.658772) (xy 355.461062 -270.654789) (xy 355.514212 -270.658772) (xy 355.566174 -270.670632)
			(xy 355.615788 -270.690104) (xy 355.661946 -270.716753) (xy 355.703617 -270.749984) (xy 355.739869 -270.789055)
			(xy 355.769893 -270.833092) (xy 355.793019 -270.881113) (xy 355.808729 -270.932043) (xy 355.816672 -270.984747)
			(xy 355.81717 -271.011396) (xy 355.816672 -271.038045) (xy 355.808729 -271.090749) (xy 355.793019 -271.141679)
			(xy 355.769893 -271.1897) (xy 355.739869 -271.233737) (xy 355.703617 -271.272808) (xy 355.661946 -271.306039)
			(xy 355.615788 -271.332688) (xy 355.566174 -271.35216) (xy 355.514212 -271.36402) (xy 355.461062 -271.368004)
			(xy 355.407912 -271.36402) (xy 355.35595 -271.35216) (xy 355.306336 -271.332688) (xy 355.260178 -271.306039)
			(xy 355.218507 -271.272808) (xy 355.182255 -271.233737) (xy 355.152231 -271.1897) (xy 355.129105 -271.141679)
			(xy 355.113395 -271.090749) (xy 355.105452 -271.038045) (xy 354.876872 -271.038045) (xy 354.868929 -271.090749)
			(xy 354.853219 -271.141679) (xy 354.830093 -271.1897) (xy 354.800069 -271.233737) (xy 354.763817 -271.272808)
			(xy 354.722146 -271.306039) (xy 354.675988 -271.332688) (xy 354.626374 -271.35216) (xy 354.574412 -271.36402)
			(xy 354.521262 -271.368004) (xy 354.468112 -271.36402) (xy 354.41615 -271.35216) (xy 354.366536 -271.332688)
			(xy 354.320378 -271.306039) (xy 354.278707 -271.272808) (xy 354.242455 -271.233737) (xy 354.212431 -271.1897)
			(xy 354.189305 -271.141679) (xy 354.173595 -271.090749) (xy 354.165652 -271.038045) (xy 353.937072 -271.038045)
			(xy 353.929129 -271.090749) (xy 353.913419 -271.141679) (xy 353.890293 -271.1897) (xy 353.860269 -271.233737)
			(xy 353.824017 -271.272808) (xy 353.782346 -271.306039) (xy 353.736188 -271.332688) (xy 353.686574 -271.35216)
			(xy 353.634612 -271.36402) (xy 353.581462 -271.368004) (xy 353.528312 -271.36402) (xy 353.47635 -271.35216)
			(xy 353.426736 -271.332688) (xy 353.380578 -271.306039) (xy 353.338907 -271.272808) (xy 353.302655 -271.233737)
			(xy 353.272631 -271.1897) (xy 353.249505 -271.141679) (xy 353.233795 -271.090749) (xy 353.225852 -271.038045)
			(xy 352.997272 -271.038045) (xy 352.989329 -271.090749) (xy 352.973619 -271.141679) (xy 352.950493 -271.1897)
			(xy 352.920469 -271.233737) (xy 352.884217 -271.272808) (xy 352.842546 -271.306039) (xy 352.796388 -271.332688)
			(xy 352.746774 -271.35216) (xy 352.694812 -271.36402) (xy 352.641662 -271.368004) (xy 352.588512 -271.36402)
			(xy 352.53655 -271.35216) (xy 352.486936 -271.332688) (xy 352.440778 -271.306039) (xy 352.399107 -271.272808)
			(xy 352.362855 -271.233737) (xy 352.332831 -271.1897) (xy 352.309705 -271.141679) (xy 352.293995 -271.090749)
			(xy 352.286052 -271.038045) (xy 352.057472 -271.038045) (xy 352.049529 -271.090749) (xy 352.033819 -271.141679)
			(xy 352.010693 -271.1897) (xy 351.980669 -271.233737) (xy 351.944417 -271.272808) (xy 351.902746 -271.306039)
			(xy 351.856588 -271.332688) (xy 351.806974 -271.35216) (xy 351.755012 -271.36402) (xy 351.701862 -271.368004)
			(xy 351.648712 -271.36402) (xy 351.59675 -271.35216) (xy 351.547136 -271.332688) (xy 351.500978 -271.306039)
			(xy 351.459307 -271.272808) (xy 351.423055 -271.233737) (xy 351.393031 -271.1897) (xy 351.369905 -271.141679)
			(xy 351.354195 -271.090749) (xy 351.346252 -271.038045) (xy 351.117672 -271.038045) (xy 351.109729 -271.090749)
			(xy 351.094019 -271.141679) (xy 351.070893 -271.1897) (xy 351.040869 -271.233737) (xy 351.004617 -271.272808)
			(xy 350.962946 -271.306039) (xy 350.916788 -271.332688) (xy 350.867174 -271.35216) (xy 350.815212 -271.36402)
			(xy 350.762062 -271.368004) (xy 350.708912 -271.36402) (xy 350.65695 -271.35216) (xy 350.607336 -271.332688)
			(xy 350.561178 -271.306039) (xy 350.519507 -271.272808) (xy 350.483255 -271.233737) (xy 350.453231 -271.1897)
			(xy 350.430105 -271.141679) (xy 350.414395 -271.090749) (xy 350.406452 -271.038045) (xy 350.178126 -271.038045)
			(xy 350.170183 -271.090749) (xy 350.154473 -271.141679) (xy 350.131347 -271.1897) (xy 350.101323 -271.233737)
			(xy 350.065071 -271.272808) (xy 350.0234 -271.306039) (xy 349.977242 -271.332688) (xy 349.927628 -271.35216)
			(xy 349.875666 -271.36402) (xy 349.822516 -271.368004) (xy 349.769366 -271.36402) (xy 349.717404 -271.35216)
			(xy 349.66779 -271.332688) (xy 349.621632 -271.306039) (xy 349.579961 -271.272808) (xy 349.543709 -271.233737)
			(xy 349.513685 -271.1897) (xy 349.490559 -271.141679) (xy 349.474849 -271.090749) (xy 349.466906 -271.038045)
			(xy 349.238326 -271.038045) (xy 349.230383 -271.090749) (xy 349.214673 -271.141679) (xy 349.191547 -271.1897)
			(xy 349.161523 -271.233737) (xy 349.125271 -271.272808) (xy 349.0836 -271.306039) (xy 349.037442 -271.332688)
			(xy 348.987828 -271.35216) (xy 348.935866 -271.36402) (xy 348.882716 -271.368004) (xy 348.829566 -271.36402)
			(xy 348.777604 -271.35216) (xy 348.72799 -271.332688) (xy 348.681832 -271.306039) (xy 348.640161 -271.272808)
			(xy 348.603909 -271.233737) (xy 348.573885 -271.1897) (xy 348.550759 -271.141679) (xy 348.535049 -271.090749)
			(xy 348.527106 -271.038045) (xy 348.298272 -271.038045) (xy 348.290329 -271.090749) (xy 348.274619 -271.141679)
			(xy 348.251493 -271.1897) (xy 348.221469 -271.233737) (xy 348.185217 -271.272808) (xy 348.143546 -271.306039)
			(xy 348.097388 -271.332688) (xy 348.047774 -271.35216) (xy 347.995812 -271.36402) (xy 347.942662 -271.368004)
			(xy 347.889512 -271.36402) (xy 347.83755 -271.35216) (xy 347.787936 -271.332688) (xy 347.741778 -271.306039)
			(xy 347.700107 -271.272808) (xy 347.663855 -271.233737) (xy 347.633831 -271.1897) (xy 347.610705 -271.141679)
			(xy 347.594995 -271.090749) (xy 347.587052 -271.038045) (xy 347.358472 -271.038045) (xy 347.350529 -271.090749)
			(xy 347.334819 -271.141679) (xy 347.311693 -271.1897) (xy 347.281669 -271.233737) (xy 347.245417 -271.272808)
			(xy 347.203746 -271.306039) (xy 347.157588 -271.332688) (xy 347.107974 -271.35216) (xy 347.056012 -271.36402)
			(xy 347.002862 -271.368004) (xy 346.949712 -271.36402) (xy 346.89775 -271.35216) (xy 346.848136 -271.332688)
			(xy 346.801978 -271.306039) (xy 346.760307 -271.272808) (xy 346.724055 -271.233737) (xy 346.694031 -271.1897)
			(xy 346.670905 -271.141679) (xy 346.655195 -271.090749) (xy 346.647252 -271.038045) (xy 346.418672 -271.038045)
			(xy 346.410729 -271.090749) (xy 346.395019 -271.141679) (xy 346.371893 -271.1897) (xy 346.341869 -271.233737)
			(xy 346.305617 -271.272808) (xy 346.263946 -271.306039) (xy 346.217788 -271.332688) (xy 346.168174 -271.35216)
			(xy 346.116212 -271.36402) (xy 346.063062 -271.368004) (xy 346.009912 -271.36402) (xy 345.95795 -271.35216)
			(xy 345.908336 -271.332688) (xy 345.862178 -271.306039) (xy 345.820507 -271.272808) (xy 345.784255 -271.233737)
			(xy 345.754231 -271.1897) (xy 345.731105 -271.141679) (xy 345.715395 -271.090749) (xy 345.707452 -271.038045)
			(xy 345.478872 -271.038045) (xy 345.470929 -271.090749) (xy 345.455219 -271.141679) (xy 345.432093 -271.1897)
			(xy 345.402069 -271.233737) (xy 345.365817 -271.272808) (xy 345.324146 -271.306039) (xy 345.277988 -271.332688)
			(xy 345.228374 -271.35216) (xy 345.176412 -271.36402) (xy 345.123262 -271.368004) (xy 345.070112 -271.36402)
			(xy 345.01815 -271.35216) (xy 344.968536 -271.332688) (xy 344.922378 -271.306039) (xy 344.880707 -271.272808)
			(xy 344.844455 -271.233737) (xy 344.814431 -271.1897) (xy 344.791305 -271.141679) (xy 344.775595 -271.090749)
			(xy 344.767652 -271.038045) (xy 344.539072 -271.038045) (xy 344.531129 -271.090749) (xy 344.515419 -271.141679)
			(xy 344.492293 -271.1897) (xy 344.462269 -271.233737) (xy 344.426017 -271.272808) (xy 344.384346 -271.306039)
			(xy 344.338188 -271.332688) (xy 344.288574 -271.35216) (xy 344.236612 -271.36402) (xy 344.183462 -271.368004)
			(xy 344.130312 -271.36402) (xy 344.07835 -271.35216) (xy 344.028736 -271.332688) (xy 343.982578 -271.306039)
			(xy 343.940907 -271.272808) (xy 343.904655 -271.233737) (xy 343.874631 -271.1897) (xy 343.851505 -271.141679)
			(xy 343.835795 -271.090749) (xy 343.827852 -271.038045) (xy 343.599272 -271.038045) (xy 343.591329 -271.090749)
			(xy 343.575619 -271.141679) (xy 343.552493 -271.1897) (xy 343.522469 -271.233737) (xy 343.486217 -271.272808)
			(xy 343.444546 -271.306039) (xy 343.398388 -271.332688) (xy 343.348774 -271.35216) (xy 343.296812 -271.36402)
			(xy 343.243662 -271.368004) (xy 343.190512 -271.36402) (xy 343.13855 -271.35216) (xy 343.088936 -271.332688)
			(xy 343.042778 -271.306039) (xy 343.001107 -271.272808) (xy 342.964855 -271.233737) (xy 342.934831 -271.1897)
			(xy 342.911705 -271.141679) (xy 342.895995 -271.090749) (xy 342.888052 -271.038045) (xy 342.659726 -271.038045)
			(xy 342.651783 -271.090749) (xy 342.636073 -271.141679) (xy 342.612947 -271.1897) (xy 342.582923 -271.233737)
			(xy 342.546671 -271.272808) (xy 342.505 -271.306039) (xy 342.458842 -271.332688) (xy 342.409228 -271.35216)
			(xy 342.357266 -271.36402) (xy 342.304116 -271.368004) (xy 342.250966 -271.36402) (xy 342.199004 -271.35216)
			(xy 342.14939 -271.332688) (xy 342.103232 -271.306039) (xy 342.061561 -271.272808) (xy 342.025309 -271.233737)
			(xy 341.995285 -271.1897) (xy 341.972159 -271.141679) (xy 341.956449 -271.090749) (xy 341.948506 -271.038045)
			(xy 341.719672 -271.038045) (xy 341.711729 -271.090749) (xy 341.696019 -271.141679) (xy 341.672893 -271.1897)
			(xy 341.642869 -271.233737) (xy 341.606617 -271.272808) (xy 341.564946 -271.306039) (xy 341.518788 -271.332688)
			(xy 341.469174 -271.35216) (xy 341.417212 -271.36402) (xy 341.364062 -271.368004) (xy 341.310912 -271.36402)
			(xy 341.25895 -271.35216) (xy 341.209336 -271.332688) (xy 341.163178 -271.306039) (xy 341.121507 -271.272808)
			(xy 341.085255 -271.233737) (xy 341.055231 -271.1897) (xy 341.032105 -271.141679) (xy 341.016395 -271.090749)
			(xy 341.008452 -271.038045) (xy 340.779872 -271.038045) (xy 340.771929 -271.090749) (xy 340.756219 -271.141679)
			(xy 340.733093 -271.1897) (xy 340.703069 -271.233737) (xy 340.666817 -271.272808) (xy 340.625146 -271.306039)
			(xy 340.578988 -271.332688) (xy 340.529374 -271.35216) (xy 340.477412 -271.36402) (xy 340.424262 -271.368004)
			(xy 340.371112 -271.36402) (xy 340.31915 -271.35216) (xy 340.269536 -271.332688) (xy 340.223378 -271.306039)
			(xy 340.181707 -271.272808) (xy 340.145455 -271.233737) (xy 340.115431 -271.1897) (xy 340.092305 -271.141679)
			(xy 340.076595 -271.090749) (xy 340.068652 -271.038045) (xy 339.839139 -271.038045) (xy 339.837152 -271.064557)
			(xy 339.82529 -271.116527) (xy 339.805813 -271.166148) (xy 339.779158 -271.212312) (xy 339.74592 -271.253987)
			(xy 339.706842 -271.290243) (xy 339.662796 -271.320269) (xy 339.614767 -271.343394) (xy 339.563827 -271.359102)
			(xy 339.511115 -271.367041) (xy 339.484462 -271.367504) (xy 339.481922 -271.367504) (xy 339.468536 -271.367813)
			(xy 339.442639 -271.374588) (xy 339.419395 -271.387862) (xy 339.400401 -271.406722) (xy 339.386962 -271.429872)
			(xy 339.380005 -271.45572) (xy 339.37956 -271.469104) (xy 339.37956 -271.615408) (xy 339.467952 -271.7038)
			(xy 339.478126 -271.713375) (xy 339.502476 -271.727054) (xy 339.529622 -271.733617) (xy 339.557531 -271.732573)
			(xy 339.584112 -271.724001) (xy 339.607372 -271.708542) (xy 339.625568 -271.687355) (xy 339.631782 -271.674844)
			(xy 339.642855 -271.652126) (xy 339.670462 -271.609794) (xy 339.703778 -271.571791) (xy 339.742133 -271.538882)
			(xy 339.784757 -271.511728) (xy 339.830792 -271.490874) (xy 339.879314 -271.47674) (xy 339.929347 -271.469609)
			(xy 339.954616 -271.469104) (xy 339.982598 -271.469654) (xy 340.037872 -271.478411) (xy 340.091097 -271.495707)
			(xy 340.14096 -271.521117) (xy 340.186234 -271.554013) (xy 340.225805 -271.593587) (xy 340.258698 -271.638864)
			(xy 340.284103 -271.688729) (xy 340.301395 -271.741955) (xy 340.310148 -271.79723) (xy 340.310724 -271.825212)
			(xy 340.310282 -271.850484) (xy 340.310085 -271.851861) (xy 340.538806 -271.851861) (xy 340.538806 -271.798563)
			(xy 340.546749 -271.745859) (xy 340.562459 -271.694929) (xy 340.585585 -271.646908) (xy 340.615609 -271.602871)
			(xy 340.651861 -271.5638) (xy 340.693532 -271.530569) (xy 340.73969 -271.50392) (xy 340.789304 -271.484448)
			(xy 340.841266 -271.472588) (xy 340.894416 -271.468605) (xy 340.947566 -271.472588) (xy 340.999528 -271.484448)
			(xy 341.049142 -271.50392) (xy 341.0953 -271.530569) (xy 341.136971 -271.5638) (xy 341.173223 -271.602871)
			(xy 341.203247 -271.646908) (xy 341.226373 -271.694929) (xy 341.242083 -271.745859) (xy 341.250026 -271.798563)
			(xy 341.250524 -271.825212) (xy 341.250026 -271.851861) (xy 341.478606 -271.851861) (xy 341.478606 -271.798563)
			(xy 341.486549 -271.745859) (xy 341.502259 -271.694929) (xy 341.525385 -271.646908) (xy 341.555409 -271.602871)
			(xy 341.591661 -271.5638) (xy 341.633332 -271.530569) (xy 341.67949 -271.50392) (xy 341.729104 -271.484448)
			(xy 341.781066 -271.472588) (xy 341.834216 -271.468605) (xy 341.887366 -271.472588) (xy 341.939328 -271.484448)
			(xy 341.988942 -271.50392) (xy 342.0351 -271.530569) (xy 342.076771 -271.5638) (xy 342.113023 -271.602871)
			(xy 342.143047 -271.646908) (xy 342.166173 -271.694929) (xy 342.181883 -271.745859) (xy 342.189826 -271.798563)
			(xy 342.190324 -271.825212) (xy 342.189826 -271.851861) (xy 342.418406 -271.851861) (xy 342.418406 -271.798563)
			(xy 342.426349 -271.745859) (xy 342.442059 -271.694929) (xy 342.465185 -271.646908) (xy 342.495209 -271.602871)
			(xy 342.531461 -271.5638) (xy 342.573132 -271.530569) (xy 342.61929 -271.50392) (xy 342.668904 -271.484448)
			(xy 342.720866 -271.472588) (xy 342.774016 -271.468605) (xy 342.827166 -271.472588) (xy 342.879128 -271.484448)
			(xy 342.928742 -271.50392) (xy 342.9749 -271.530569) (xy 343.016571 -271.5638) (xy 343.052823 -271.602871)
			(xy 343.082847 -271.646908) (xy 343.105973 -271.694929) (xy 343.121683 -271.745859) (xy 343.129626 -271.798563)
			(xy 343.130124 -271.825212) (xy 343.129626 -271.851861) (xy 343.358206 -271.851861) (xy 343.358206 -271.798563)
			(xy 343.366149 -271.745859) (xy 343.381859 -271.694929) (xy 343.404985 -271.646908) (xy 343.435009 -271.602871)
			(xy 343.471261 -271.5638) (xy 343.512932 -271.530569) (xy 343.55909 -271.50392) (xy 343.608704 -271.484448)
			(xy 343.660666 -271.472588) (xy 343.713816 -271.468605) (xy 343.766966 -271.472588) (xy 343.818928 -271.484448)
			(xy 343.868542 -271.50392) (xy 343.9147 -271.530569) (xy 343.956371 -271.5638) (xy 343.992623 -271.602871)
			(xy 344.022647 -271.646908) (xy 344.045773 -271.694929) (xy 344.061483 -271.745859) (xy 344.069426 -271.798563)
			(xy 344.069924 -271.825212) (xy 344.069426 -271.851861) (xy 344.298006 -271.851861) (xy 344.298006 -271.798563)
			(xy 344.305949 -271.745859) (xy 344.321659 -271.694929) (xy 344.344785 -271.646908) (xy 344.374809 -271.602871)
			(xy 344.411061 -271.5638) (xy 344.452732 -271.530569) (xy 344.49889 -271.50392) (xy 344.548504 -271.484448)
			(xy 344.600466 -271.472588) (xy 344.653616 -271.468605) (xy 344.706766 -271.472588) (xy 344.758728 -271.484448)
			(xy 344.808342 -271.50392) (xy 344.8545 -271.530569) (xy 344.896171 -271.5638) (xy 344.932423 -271.602871)
			(xy 344.962447 -271.646908) (xy 344.985573 -271.694929) (xy 345.001283 -271.745859) (xy 345.009226 -271.798563)
			(xy 345.009724 -271.825212) (xy 345.009226 -271.851861) (xy 345.237552 -271.851861) (xy 345.237552 -271.798563)
			(xy 345.245495 -271.745859) (xy 345.261205 -271.694929) (xy 345.284331 -271.646908) (xy 345.314355 -271.602871)
			(xy 345.350607 -271.5638) (xy 345.392278 -271.530569) (xy 345.438436 -271.50392) (xy 345.48805 -271.484448)
			(xy 345.540012 -271.472588) (xy 345.593162 -271.468605) (xy 345.646312 -271.472588) (xy 345.698274 -271.484448)
			(xy 345.747888 -271.50392) (xy 345.794046 -271.530569) (xy 345.835717 -271.5638) (xy 345.871969 -271.602871)
			(xy 345.901993 -271.646908) (xy 345.925119 -271.694929) (xy 345.940829 -271.745859) (xy 345.948772 -271.798563)
			(xy 345.94927 -271.825212) (xy 345.948772 -271.851861) (xy 346.177606 -271.851861) (xy 346.177606 -271.798563)
			(xy 346.185549 -271.745859) (xy 346.201259 -271.694929) (xy 346.224385 -271.646908) (xy 346.254409 -271.602871)
			(xy 346.290661 -271.5638) (xy 346.332332 -271.530569) (xy 346.37849 -271.50392) (xy 346.428104 -271.484448)
			(xy 346.480066 -271.472588) (xy 346.533216 -271.468605) (xy 346.586366 -271.472588) (xy 346.638328 -271.484448)
			(xy 346.687942 -271.50392) (xy 346.7341 -271.530569) (xy 346.775771 -271.5638) (xy 346.812023 -271.602871)
			(xy 346.842047 -271.646908) (xy 346.865173 -271.694929) (xy 346.880883 -271.745859) (xy 346.888826 -271.798563)
			(xy 346.889324 -271.825212) (xy 346.888826 -271.851861) (xy 347.117406 -271.851861) (xy 347.117406 -271.798563)
			(xy 347.125349 -271.745859) (xy 347.141059 -271.694929) (xy 347.164185 -271.646908) (xy 347.194209 -271.602871)
			(xy 347.230461 -271.5638) (xy 347.272132 -271.530569) (xy 347.31829 -271.50392) (xy 347.367904 -271.484448)
			(xy 347.419866 -271.472588) (xy 347.473016 -271.468605) (xy 347.526166 -271.472588) (xy 347.578128 -271.484448)
			(xy 347.627742 -271.50392) (xy 347.6739 -271.530569) (xy 347.715571 -271.5638) (xy 347.751823 -271.602871)
			(xy 347.781847 -271.646908) (xy 347.804973 -271.694929) (xy 347.820683 -271.745859) (xy 347.828626 -271.798563)
			(xy 347.829124 -271.825212) (xy 347.828626 -271.851861) (xy 348.057206 -271.851861) (xy 348.057206 -271.798563)
			(xy 348.065149 -271.745859) (xy 348.080859 -271.694929) (xy 348.103985 -271.646908) (xy 348.134009 -271.602871)
			(xy 348.170261 -271.5638) (xy 348.211932 -271.530569) (xy 348.25809 -271.50392) (xy 348.307704 -271.484448)
			(xy 348.359666 -271.472588) (xy 348.412816 -271.468605) (xy 348.465966 -271.472588) (xy 348.517928 -271.484448)
			(xy 348.567542 -271.50392) (xy 348.6137 -271.530569) (xy 348.655371 -271.5638) (xy 348.691623 -271.602871)
			(xy 348.721647 -271.646908) (xy 348.744773 -271.694929) (xy 348.760483 -271.745859) (xy 348.768426 -271.798563)
			(xy 348.768924 -271.825212) (xy 348.768426 -271.851861) (xy 348.997006 -271.851861) (xy 348.997006 -271.798563)
			(xy 349.004949 -271.745859) (xy 349.020659 -271.694929) (xy 349.043785 -271.646908) (xy 349.073809 -271.602871)
			(xy 349.110061 -271.5638) (xy 349.151732 -271.530569) (xy 349.19789 -271.50392) (xy 349.247504 -271.484448)
			(xy 349.299466 -271.472588) (xy 349.352616 -271.468605) (xy 349.405766 -271.472588) (xy 349.457728 -271.484448)
			(xy 349.507342 -271.50392) (xy 349.5535 -271.530569) (xy 349.595171 -271.5638) (xy 349.631423 -271.602871)
			(xy 349.661447 -271.646908) (xy 349.684573 -271.694929) (xy 349.700283 -271.745859) (xy 349.708226 -271.798563)
			(xy 349.708724 -271.825212) (xy 349.708226 -271.851861) (xy 349.936806 -271.851861) (xy 349.936806 -271.798563)
			(xy 349.944749 -271.745859) (xy 349.960459 -271.694929) (xy 349.983585 -271.646908) (xy 350.013609 -271.602871)
			(xy 350.049861 -271.5638) (xy 350.091532 -271.530569) (xy 350.13769 -271.50392) (xy 350.187304 -271.484448)
			(xy 350.239266 -271.472588) (xy 350.292416 -271.468605) (xy 350.345566 -271.472588) (xy 350.397528 -271.484448)
			(xy 350.447142 -271.50392) (xy 350.4933 -271.530569) (xy 350.534971 -271.5638) (xy 350.571223 -271.602871)
			(xy 350.601247 -271.646908) (xy 350.624373 -271.694929) (xy 350.640083 -271.745859) (xy 350.648026 -271.798563)
			(xy 350.648524 -271.825212) (xy 350.648026 -271.851861) (xy 350.876606 -271.851861) (xy 350.876606 -271.798563)
			(xy 350.884549 -271.745859) (xy 350.900259 -271.694929) (xy 350.923385 -271.646908) (xy 350.953409 -271.602871)
			(xy 350.989661 -271.5638) (xy 351.031332 -271.530569) (xy 351.07749 -271.50392) (xy 351.127104 -271.484448)
			(xy 351.179066 -271.472588) (xy 351.232216 -271.468605) (xy 351.285366 -271.472588) (xy 351.337328 -271.484448)
			(xy 351.386942 -271.50392) (xy 351.4331 -271.530569) (xy 351.474771 -271.5638) (xy 351.511023 -271.602871)
			(xy 351.541047 -271.646908) (xy 351.564173 -271.694929) (xy 351.579883 -271.745859) (xy 351.587826 -271.798563)
			(xy 351.588324 -271.825212) (xy 351.587826 -271.851861) (xy 351.816406 -271.851861) (xy 351.816406 -271.798563)
			(xy 351.824349 -271.745859) (xy 351.840059 -271.694929) (xy 351.863185 -271.646908) (xy 351.893209 -271.602871)
			(xy 351.929461 -271.5638) (xy 351.971132 -271.530569) (xy 352.01729 -271.50392) (xy 352.066904 -271.484448)
			(xy 352.118866 -271.472588) (xy 352.172016 -271.468605) (xy 352.225166 -271.472588) (xy 352.277128 -271.484448)
			(xy 352.326742 -271.50392) (xy 352.3729 -271.530569) (xy 352.414571 -271.5638) (xy 352.450823 -271.602871)
			(xy 352.480847 -271.646908) (xy 352.503973 -271.694929) (xy 352.519683 -271.745859) (xy 352.527626 -271.798563)
			(xy 352.528124 -271.825212) (xy 352.527626 -271.851861) (xy 352.756206 -271.851861) (xy 352.756206 -271.798563)
			(xy 352.764149 -271.745859) (xy 352.779859 -271.694929) (xy 352.802985 -271.646908) (xy 352.833009 -271.602871)
			(xy 352.869261 -271.5638) (xy 352.910932 -271.530569) (xy 352.95709 -271.50392) (xy 353.006704 -271.484448)
			(xy 353.058666 -271.472588) (xy 353.111816 -271.468605) (xy 353.164966 -271.472588) (xy 353.216928 -271.484448)
			(xy 353.266542 -271.50392) (xy 353.3127 -271.530569) (xy 353.354371 -271.5638) (xy 353.390623 -271.602871)
			(xy 353.420647 -271.646908) (xy 353.443773 -271.694929) (xy 353.459483 -271.745859) (xy 353.467426 -271.798563)
			(xy 353.467924 -271.825212) (xy 353.467426 -271.851861) (xy 353.696006 -271.851861) (xy 353.696006 -271.798563)
			(xy 353.703949 -271.745859) (xy 353.719659 -271.694929) (xy 353.742785 -271.646908) (xy 353.772809 -271.602871)
			(xy 353.809061 -271.5638) (xy 353.850732 -271.530569) (xy 353.89689 -271.50392) (xy 353.946504 -271.484448)
			(xy 353.998466 -271.472588) (xy 354.051616 -271.468605) (xy 354.104766 -271.472588) (xy 354.156728 -271.484448)
			(xy 354.206342 -271.50392) (xy 354.2525 -271.530569) (xy 354.294171 -271.5638) (xy 354.330423 -271.602871)
			(xy 354.360447 -271.646908) (xy 354.383573 -271.694929) (xy 354.399283 -271.745859) (xy 354.407226 -271.798563)
			(xy 354.407724 -271.825212) (xy 354.407226 -271.851861) (xy 354.635806 -271.851861) (xy 354.635806 -271.798563)
			(xy 354.643749 -271.745859) (xy 354.659459 -271.694929) (xy 354.682585 -271.646908) (xy 354.712609 -271.602871)
			(xy 354.748861 -271.5638) (xy 354.790532 -271.530569) (xy 354.83669 -271.50392) (xy 354.886304 -271.484448)
			(xy 354.938266 -271.472588) (xy 354.991416 -271.468605) (xy 355.044566 -271.472588) (xy 355.096528 -271.484448)
			(xy 355.146142 -271.50392) (xy 355.1923 -271.530569) (xy 355.233971 -271.5638) (xy 355.270223 -271.602871)
			(xy 355.300247 -271.646908) (xy 355.323373 -271.694929) (xy 355.339083 -271.745859) (xy 355.347026 -271.798563)
			(xy 355.347524 -271.825212) (xy 355.347026 -271.851861) (xy 355.339083 -271.904565) (xy 355.323373 -271.955495)
			(xy 355.300247 -272.003516) (xy 355.270223 -272.047553) (xy 355.233971 -272.086624) (xy 355.1923 -272.119855)
			(xy 355.146142 -272.146504) (xy 355.096528 -272.165976) (xy 355.044566 -272.177836) (xy 354.991416 -272.18182)
			(xy 354.938266 -272.177836) (xy 354.886304 -272.165976) (xy 354.83669 -272.146504) (xy 354.790532 -272.119855)
			(xy 354.748861 -272.086624) (xy 354.712609 -272.047553) (xy 354.682585 -272.003516) (xy 354.659459 -271.955495)
			(xy 354.643749 -271.904565) (xy 354.635806 -271.851861) (xy 354.407226 -271.851861) (xy 354.399283 -271.904565)
			(xy 354.383573 -271.955495) (xy 354.360447 -272.003516) (xy 354.330423 -272.047553) (xy 354.294171 -272.086624)
			(xy 354.2525 -272.119855) (xy 354.206342 -272.146504) (xy 354.156728 -272.165976) (xy 354.104766 -272.177836)
			(xy 354.051616 -272.18182) (xy 353.998466 -272.177836) (xy 353.946504 -272.165976) (xy 353.89689 -272.146504)
			(xy 353.850732 -272.119855) (xy 353.809061 -272.086624) (xy 353.772809 -272.047553) (xy 353.742785 -272.003516)
			(xy 353.719659 -271.955495) (xy 353.703949 -271.904565) (xy 353.696006 -271.851861) (xy 353.467426 -271.851861)
			(xy 353.459483 -271.904565) (xy 353.443773 -271.955495) (xy 353.420647 -272.003516) (xy 353.390623 -272.047553)
			(xy 353.354371 -272.086624) (xy 353.3127 -272.119855) (xy 353.266542 -272.146504) (xy 353.216928 -272.165976)
			(xy 353.164966 -272.177836) (xy 353.111816 -272.18182) (xy 353.058666 -272.177836) (xy 353.006704 -272.165976)
			(xy 352.95709 -272.146504) (xy 352.910932 -272.119855) (xy 352.869261 -272.086624) (xy 352.833009 -272.047553)
			(xy 352.802985 -272.003516) (xy 352.779859 -271.955495) (xy 352.764149 -271.904565) (xy 352.756206 -271.851861)
			(xy 352.527626 -271.851861) (xy 352.519683 -271.904565) (xy 352.503973 -271.955495) (xy 352.480847 -272.003516)
			(xy 352.450823 -272.047553) (xy 352.414571 -272.086624) (xy 352.3729 -272.119855) (xy 352.326742 -272.146504)
			(xy 352.277128 -272.165976) (xy 352.225166 -272.177836) (xy 352.172016 -272.18182) (xy 352.118866 -272.177836)
			(xy 352.066904 -272.165976) (xy 352.01729 -272.146504) (xy 351.971132 -272.119855) (xy 351.929461 -272.086624)
			(xy 351.893209 -272.047553) (xy 351.863185 -272.003516) (xy 351.840059 -271.955495) (xy 351.824349 -271.904565)
			(xy 351.816406 -271.851861) (xy 351.587826 -271.851861) (xy 351.579883 -271.904565) (xy 351.564173 -271.955495)
			(xy 351.541047 -272.003516) (xy 351.511023 -272.047553) (xy 351.474771 -272.086624) (xy 351.4331 -272.119855)
			(xy 351.386942 -272.146504) (xy 351.337328 -272.165976) (xy 351.285366 -272.177836) (xy 351.232216 -272.18182)
			(xy 351.179066 -272.177836) (xy 351.127104 -272.165976) (xy 351.07749 -272.146504) (xy 351.031332 -272.119855)
			(xy 350.989661 -272.086624) (xy 350.953409 -272.047553) (xy 350.923385 -272.003516) (xy 350.900259 -271.955495)
			(xy 350.884549 -271.904565) (xy 350.876606 -271.851861) (xy 350.648026 -271.851861) (xy 350.640083 -271.904565)
			(xy 350.624373 -271.955495) (xy 350.601247 -272.003516) (xy 350.571223 -272.047553) (xy 350.534971 -272.086624)
			(xy 350.4933 -272.119855) (xy 350.447142 -272.146504) (xy 350.397528 -272.165976) (xy 350.345566 -272.177836)
			(xy 350.292416 -272.18182) (xy 350.239266 -272.177836) (xy 350.187304 -272.165976) (xy 350.13769 -272.146504)
			(xy 350.091532 -272.119855) (xy 350.049861 -272.086624) (xy 350.013609 -272.047553) (xy 349.983585 -272.003516)
			(xy 349.960459 -271.955495) (xy 349.944749 -271.904565) (xy 349.936806 -271.851861) (xy 349.708226 -271.851861)
			(xy 349.700283 -271.904565) (xy 349.684573 -271.955495) (xy 349.661447 -272.003516) (xy 349.631423 -272.047553)
			(xy 349.595171 -272.086624) (xy 349.5535 -272.119855) (xy 349.507342 -272.146504) (xy 349.457728 -272.165976)
			(xy 349.405766 -272.177836) (xy 349.352616 -272.18182) (xy 349.299466 -272.177836) (xy 349.247504 -272.165976)
			(xy 349.19789 -272.146504) (xy 349.151732 -272.119855) (xy 349.110061 -272.086624) (xy 349.073809 -272.047553)
			(xy 349.043785 -272.003516) (xy 349.020659 -271.955495) (xy 349.004949 -271.904565) (xy 348.997006 -271.851861)
			(xy 348.768426 -271.851861) (xy 348.760483 -271.904565) (xy 348.744773 -271.955495) (xy 348.721647 -272.003516)
			(xy 348.691623 -272.047553) (xy 348.655371 -272.086624) (xy 348.6137 -272.119855) (xy 348.567542 -272.146504)
			(xy 348.517928 -272.165976) (xy 348.465966 -272.177836) (xy 348.412816 -272.18182) (xy 348.359666 -272.177836)
			(xy 348.307704 -272.165976) (xy 348.25809 -272.146504) (xy 348.211932 -272.119855) (xy 348.170261 -272.086624)
			(xy 348.134009 -272.047553) (xy 348.103985 -272.003516) (xy 348.080859 -271.955495) (xy 348.065149 -271.904565)
			(xy 348.057206 -271.851861) (xy 347.828626 -271.851861) (xy 347.820683 -271.904565) (xy 347.804973 -271.955495)
			(xy 347.781847 -272.003516) (xy 347.751823 -272.047553) (xy 347.715571 -272.086624) (xy 347.6739 -272.119855)
			(xy 347.627742 -272.146504) (xy 347.578128 -272.165976) (xy 347.526166 -272.177836) (xy 347.473016 -272.18182)
			(xy 347.419866 -272.177836) (xy 347.367904 -272.165976) (xy 347.31829 -272.146504) (xy 347.272132 -272.119855)
			(xy 347.230461 -272.086624) (xy 347.194209 -272.047553) (xy 347.164185 -272.003516) (xy 347.141059 -271.955495)
			(xy 347.125349 -271.904565) (xy 347.117406 -271.851861) (xy 346.888826 -271.851861) (xy 346.880883 -271.904565)
			(xy 346.865173 -271.955495) (xy 346.842047 -272.003516) (xy 346.812023 -272.047553) (xy 346.775771 -272.086624)
			(xy 346.7341 -272.119855) (xy 346.687942 -272.146504) (xy 346.638328 -272.165976) (xy 346.586366 -272.177836)
			(xy 346.533216 -272.18182) (xy 346.480066 -272.177836) (xy 346.428104 -272.165976) (xy 346.37849 -272.146504)
			(xy 346.332332 -272.119855) (xy 346.290661 -272.086624) (xy 346.254409 -272.047553) (xy 346.224385 -272.003516)
			(xy 346.201259 -271.955495) (xy 346.185549 -271.904565) (xy 346.177606 -271.851861) (xy 345.948772 -271.851861)
			(xy 345.940829 -271.904565) (xy 345.925119 -271.955495) (xy 345.901993 -272.003516) (xy 345.871969 -272.047553)
			(xy 345.835717 -272.086624) (xy 345.794046 -272.119855) (xy 345.747888 -272.146504) (xy 345.698274 -272.165976)
			(xy 345.646312 -272.177836) (xy 345.593162 -272.18182) (xy 345.540012 -272.177836) (xy 345.48805 -272.165976)
			(xy 345.438436 -272.146504) (xy 345.392278 -272.119855) (xy 345.350607 -272.086624) (xy 345.314355 -272.047553)
			(xy 345.284331 -272.003516) (xy 345.261205 -271.955495) (xy 345.245495 -271.904565) (xy 345.237552 -271.851861)
			(xy 345.009226 -271.851861) (xy 345.001283 -271.904565) (xy 344.985573 -271.955495) (xy 344.962447 -272.003516)
			(xy 344.932423 -272.047553) (xy 344.896171 -272.086624) (xy 344.8545 -272.119855) (xy 344.808342 -272.146504)
			(xy 344.758728 -272.165976) (xy 344.706766 -272.177836) (xy 344.653616 -272.18182) (xy 344.600466 -272.177836)
			(xy 344.548504 -272.165976) (xy 344.49889 -272.146504) (xy 344.452732 -272.119855) (xy 344.411061 -272.086624)
			(xy 344.374809 -272.047553) (xy 344.344785 -272.003516) (xy 344.321659 -271.955495) (xy 344.305949 -271.904565)
			(xy 344.298006 -271.851861) (xy 344.069426 -271.851861) (xy 344.061483 -271.904565) (xy 344.045773 -271.955495)
			(xy 344.022647 -272.003516) (xy 343.992623 -272.047553) (xy 343.956371 -272.086624) (xy 343.9147 -272.119855)
			(xy 343.868542 -272.146504) (xy 343.818928 -272.165976) (xy 343.766966 -272.177836) (xy 343.713816 -272.18182)
			(xy 343.660666 -272.177836) (xy 343.608704 -272.165976) (xy 343.55909 -272.146504) (xy 343.512932 -272.119855)
			(xy 343.471261 -272.086624) (xy 343.435009 -272.047553) (xy 343.404985 -272.003516) (xy 343.381859 -271.955495)
			(xy 343.366149 -271.904565) (xy 343.358206 -271.851861) (xy 343.129626 -271.851861) (xy 343.121683 -271.904565)
			(xy 343.105973 -271.955495) (xy 343.082847 -272.003516) (xy 343.052823 -272.047553) (xy 343.016571 -272.086624)
			(xy 342.9749 -272.119855) (xy 342.928742 -272.146504) (xy 342.879128 -272.165976) (xy 342.827166 -272.177836)
			(xy 342.774016 -272.18182) (xy 342.720866 -272.177836) (xy 342.668904 -272.165976) (xy 342.61929 -272.146504)
			(xy 342.573132 -272.119855) (xy 342.531461 -272.086624) (xy 342.495209 -272.047553) (xy 342.465185 -272.003516)
			(xy 342.442059 -271.955495) (xy 342.426349 -271.904565) (xy 342.418406 -271.851861) (xy 342.189826 -271.851861)
			(xy 342.181883 -271.904565) (xy 342.166173 -271.955495) (xy 342.143047 -272.003516) (xy 342.113023 -272.047553)
			(xy 342.076771 -272.086624) (xy 342.0351 -272.119855) (xy 341.988942 -272.146504) (xy 341.939328 -272.165976)
			(xy 341.887366 -272.177836) (xy 341.834216 -272.18182) (xy 341.781066 -272.177836) (xy 341.729104 -272.165976)
			(xy 341.67949 -272.146504) (xy 341.633332 -272.119855) (xy 341.591661 -272.086624) (xy 341.555409 -272.047553)
			(xy 341.525385 -272.003516) (xy 341.502259 -271.955495) (xy 341.486549 -271.904565) (xy 341.478606 -271.851861)
			(xy 341.250026 -271.851861) (xy 341.242083 -271.904565) (xy 341.226373 -271.955495) (xy 341.203247 -272.003516)
			(xy 341.173223 -272.047553) (xy 341.136971 -272.086624) (xy 341.0953 -272.119855) (xy 341.049142 -272.146504)
			(xy 340.999528 -272.165976) (xy 340.947566 -272.177836) (xy 340.894416 -272.18182) (xy 340.841266 -272.177836)
			(xy 340.789304 -272.165976) (xy 340.73969 -272.146504) (xy 340.693532 -272.119855) (xy 340.651861 -272.086624)
			(xy 340.615609 -272.047553) (xy 340.585585 -272.003516) (xy 340.562459 -271.955495) (xy 340.546749 -271.904565)
			(xy 340.538806 -271.851861) (xy 340.310085 -271.851861) (xy 340.303136 -271.900519) (xy 340.288989 -271.949042)
			(xy 340.268126 -271.995078) (xy 340.240965 -272.037703) (xy 340.208052 -272.076061) (xy 340.170048 -272.109381)
			(xy 340.127715 -272.136995) (xy 340.104984 -272.148046) (xy 340.092543 -272.154351) (xy 340.071432 -272.172562)
			(xy 340.056029 -272.195801) (xy 340.047482 -272.22234) (xy 340.046427 -272.2502) (xy 340.052943 -272.277309)
			(xy 340.066544 -272.301647) (xy 340.076028 -272.311876) (xy 340.127336 -272.363184) (xy 340.134747 -272.369864)
			(xy 340.153183 -272.377436) (xy 340.16315 -272.377916) (xy 340.195662 -272.366232) (xy 340.214978 -272.35062)
			(xy 340.257118 -272.324337) (xy 340.302501 -272.304163) (xy 340.350247 -272.290491) (xy 340.39943 -272.283585)
			(xy 340.424262 -272.283174) (xy 340.45225 -272.283691) (xy 340.507537 -272.292442) (xy 340.560775 -272.309734)
			(xy 340.610652 -272.335142) (xy 340.65594 -272.36804) (xy 340.695523 -272.407618) (xy 340.728428 -272.452901)
			(xy 340.753844 -272.502773) (xy 340.771145 -272.556008) (xy 340.779904 -272.611294) (xy 340.78037 -272.639282)
			(xy 340.77994 -272.664114) (xy 340.779685 -272.665931) (xy 341.008452 -272.665931) (xy 341.008452 -272.612633)
			(xy 341.016395 -272.559929) (xy 341.032105 -272.508999) (xy 341.055231 -272.460978) (xy 341.085255 -272.416941)
			(xy 341.121507 -272.37787) (xy 341.163178 -272.344639) (xy 341.209336 -272.31799) (xy 341.25895 -272.298518)
			(xy 341.310912 -272.286658) (xy 341.364062 -272.282675) (xy 341.417212 -272.286658) (xy 341.469174 -272.298518)
			(xy 341.518788 -272.31799) (xy 341.564946 -272.344639) (xy 341.606617 -272.37787) (xy 341.642869 -272.416941)
			(xy 341.672893 -272.460978) (xy 341.696019 -272.508999) (xy 341.711729 -272.559929) (xy 341.719672 -272.612633)
			(xy 341.72017 -272.639282) (xy 341.719672 -272.665931) (xy 341.948252 -272.665931) (xy 341.948252 -272.612633)
			(xy 341.956195 -272.559929) (xy 341.971905 -272.508999) (xy 341.995031 -272.460978) (xy 342.025055 -272.416941)
			(xy 342.061307 -272.37787) (xy 342.102978 -272.344639) (xy 342.149136 -272.31799) (xy 342.19875 -272.298518)
			(xy 342.250712 -272.286658) (xy 342.303862 -272.282675) (xy 342.357012 -272.286658) (xy 342.408974 -272.298518)
			(xy 342.458588 -272.31799) (xy 342.504746 -272.344639) (xy 342.546417 -272.37787) (xy 342.582669 -272.416941)
			(xy 342.612693 -272.460978) (xy 342.635819 -272.508999) (xy 342.651529 -272.559929) (xy 342.659472 -272.612633)
			(xy 342.65997 -272.639282) (xy 342.659472 -272.665931) (xy 342.888052 -272.665931) (xy 342.888052 -272.612633)
			(xy 342.895995 -272.559929) (xy 342.911705 -272.508999) (xy 342.934831 -272.460978) (xy 342.964855 -272.416941)
			(xy 343.001107 -272.37787) (xy 343.042778 -272.344639) (xy 343.088936 -272.31799) (xy 343.13855 -272.298518)
			(xy 343.190512 -272.286658) (xy 343.243662 -272.282675) (xy 343.296812 -272.286658) (xy 343.348774 -272.298518)
			(xy 343.398388 -272.31799) (xy 343.444546 -272.344639) (xy 343.486217 -272.37787) (xy 343.522469 -272.416941)
			(xy 343.552493 -272.460978) (xy 343.575619 -272.508999) (xy 343.591329 -272.559929) (xy 343.599272 -272.612633)
			(xy 343.59977 -272.639282) (xy 343.599272 -272.665931) (xy 343.827852 -272.665931) (xy 343.827852 -272.612633)
			(xy 343.835795 -272.559929) (xy 343.851505 -272.508999) (xy 343.874631 -272.460978) (xy 343.904655 -272.416941)
			(xy 343.940907 -272.37787) (xy 343.982578 -272.344639) (xy 344.028736 -272.31799) (xy 344.07835 -272.298518)
			(xy 344.130312 -272.286658) (xy 344.183462 -272.282675) (xy 344.236612 -272.286658) (xy 344.288574 -272.298518)
			(xy 344.338188 -272.31799) (xy 344.384346 -272.344639) (xy 344.426017 -272.37787) (xy 344.462269 -272.416941)
			(xy 344.492293 -272.460978) (xy 344.515419 -272.508999) (xy 344.531129 -272.559929) (xy 344.539072 -272.612633)
			(xy 344.53957 -272.639282) (xy 344.539072 -272.665931) (xy 344.767906 -272.665931) (xy 344.767906 -272.612633)
			(xy 344.775849 -272.559929) (xy 344.791559 -272.508999) (xy 344.814685 -272.460978) (xy 344.844709 -272.416941)
			(xy 344.880961 -272.37787) (xy 344.922632 -272.344639) (xy 344.96879 -272.31799) (xy 345.018404 -272.298518)
			(xy 345.070366 -272.286658) (xy 345.123516 -272.282675) (xy 345.176666 -272.286658) (xy 345.228628 -272.298518)
			(xy 345.278242 -272.31799) (xy 345.3244 -272.344639) (xy 345.366071 -272.37787) (xy 345.402323 -272.416941)
			(xy 345.432347 -272.460978) (xy 345.455473 -272.508999) (xy 345.471183 -272.559929) (xy 345.479126 -272.612633)
			(xy 345.479624 -272.639282) (xy 345.479126 -272.665931) (xy 345.707452 -272.665931) (xy 345.707452 -272.612633)
			(xy 345.715395 -272.559929) (xy 345.731105 -272.508999) (xy 345.754231 -272.460978) (xy 345.784255 -272.416941)
			(xy 345.820507 -272.37787) (xy 345.862178 -272.344639) (xy 345.908336 -272.31799) (xy 345.95795 -272.298518)
			(xy 346.009912 -272.286658) (xy 346.063062 -272.282675) (xy 346.116212 -272.286658) (xy 346.168174 -272.298518)
			(xy 346.217788 -272.31799) (xy 346.263946 -272.344639) (xy 346.305617 -272.37787) (xy 346.341869 -272.416941)
			(xy 346.371893 -272.460978) (xy 346.395019 -272.508999) (xy 346.410729 -272.559929) (xy 346.418672 -272.612633)
			(xy 346.41917 -272.639282) (xy 346.418672 -272.665931) (xy 346.647252 -272.665931) (xy 346.647252 -272.612633)
			(xy 346.655195 -272.559929) (xy 346.670905 -272.508999) (xy 346.694031 -272.460978) (xy 346.724055 -272.416941)
			(xy 346.760307 -272.37787) (xy 346.801978 -272.344639) (xy 346.848136 -272.31799) (xy 346.89775 -272.298518)
			(xy 346.949712 -272.286658) (xy 347.002862 -272.282675) (xy 347.056012 -272.286658) (xy 347.107974 -272.298518)
			(xy 347.157588 -272.31799) (xy 347.203746 -272.344639) (xy 347.245417 -272.37787) (xy 347.281669 -272.416941)
			(xy 347.311693 -272.460978) (xy 347.334819 -272.508999) (xy 347.350529 -272.559929) (xy 347.358472 -272.612633)
			(xy 347.35897 -272.639282) (xy 347.358472 -272.665931) (xy 347.587052 -272.665931) (xy 347.587052 -272.612633)
			(xy 347.594995 -272.559929) (xy 347.610705 -272.508999) (xy 347.633831 -272.460978) (xy 347.663855 -272.416941)
			(xy 347.700107 -272.37787) (xy 347.741778 -272.344639) (xy 347.787936 -272.31799) (xy 347.83755 -272.298518)
			(xy 347.889512 -272.286658) (xy 347.942662 -272.282675) (xy 347.995812 -272.286658) (xy 348.047774 -272.298518)
			(xy 348.097388 -272.31799) (xy 348.143546 -272.344639) (xy 348.185217 -272.37787) (xy 348.221469 -272.416941)
			(xy 348.251493 -272.460978) (xy 348.274619 -272.508999) (xy 348.290329 -272.559929) (xy 348.298272 -272.612633)
			(xy 348.29877 -272.639282) (xy 348.298272 -272.665931) (xy 348.526852 -272.665931) (xy 348.526852 -272.612633)
			(xy 348.534795 -272.559929) (xy 348.550505 -272.508999) (xy 348.573631 -272.460978) (xy 348.603655 -272.416941)
			(xy 348.639907 -272.37787) (xy 348.681578 -272.344639) (xy 348.727736 -272.31799) (xy 348.77735 -272.298518)
			(xy 348.829312 -272.286658) (xy 348.882462 -272.282675) (xy 348.935612 -272.286658) (xy 348.987574 -272.298518)
			(xy 349.037188 -272.31799) (xy 349.083346 -272.344639) (xy 349.125017 -272.37787) (xy 349.161269 -272.416941)
			(xy 349.191293 -272.460978) (xy 349.214419 -272.508999) (xy 349.230129 -272.559929) (xy 349.238072 -272.612633)
			(xy 349.23857 -272.639282) (xy 349.238072 -272.665931) (xy 349.466652 -272.665931) (xy 349.466652 -272.612633)
			(xy 349.474595 -272.559929) (xy 349.490305 -272.508999) (xy 349.513431 -272.460978) (xy 349.543455 -272.416941)
			(xy 349.579707 -272.37787) (xy 349.621378 -272.344639) (xy 349.667536 -272.31799) (xy 349.71715 -272.298518)
			(xy 349.769112 -272.286658) (xy 349.822262 -272.282675) (xy 349.875412 -272.286658) (xy 349.927374 -272.298518)
			(xy 349.976988 -272.31799) (xy 350.023146 -272.344639) (xy 350.064817 -272.37787) (xy 350.101069 -272.416941)
			(xy 350.131093 -272.460978) (xy 350.154219 -272.508999) (xy 350.169929 -272.559929) (xy 350.177872 -272.612633)
			(xy 350.17837 -272.639282) (xy 350.177872 -272.665931) (xy 350.406452 -272.665931) (xy 350.406452 -272.612633)
			(xy 350.414395 -272.559929) (xy 350.430105 -272.508999) (xy 350.453231 -272.460978) (xy 350.483255 -272.416941)
			(xy 350.519507 -272.37787) (xy 350.561178 -272.344639) (xy 350.607336 -272.31799) (xy 350.65695 -272.298518)
			(xy 350.708912 -272.286658) (xy 350.762062 -272.282675) (xy 350.815212 -272.286658) (xy 350.867174 -272.298518)
			(xy 350.916788 -272.31799) (xy 350.962946 -272.344639) (xy 351.004617 -272.37787) (xy 351.040869 -272.416941)
			(xy 351.070893 -272.460978) (xy 351.094019 -272.508999) (xy 351.109729 -272.559929) (xy 351.117672 -272.612633)
			(xy 351.11817 -272.639282) (xy 351.117672 -272.665931) (xy 351.346252 -272.665931) (xy 351.346252 -272.612633)
			(xy 351.354195 -272.559929) (xy 351.369905 -272.508999) (xy 351.393031 -272.460978) (xy 351.423055 -272.416941)
			(xy 351.459307 -272.37787) (xy 351.500978 -272.344639) (xy 351.547136 -272.31799) (xy 351.59675 -272.298518)
			(xy 351.648712 -272.286658) (xy 351.701862 -272.282675) (xy 351.755012 -272.286658) (xy 351.806974 -272.298518)
			(xy 351.856588 -272.31799) (xy 351.902746 -272.344639) (xy 351.944417 -272.37787) (xy 351.980669 -272.416941)
			(xy 352.010693 -272.460978) (xy 352.033819 -272.508999) (xy 352.049529 -272.559929) (xy 352.057472 -272.612633)
			(xy 352.05797 -272.639282) (xy 352.057472 -272.665931) (xy 352.286052 -272.665931) (xy 352.286052 -272.612633)
			(xy 352.293995 -272.559929) (xy 352.309705 -272.508999) (xy 352.332831 -272.460978) (xy 352.362855 -272.416941)
			(xy 352.399107 -272.37787) (xy 352.440778 -272.344639) (xy 352.486936 -272.31799) (xy 352.53655 -272.298518)
			(xy 352.588512 -272.286658) (xy 352.641662 -272.282675) (xy 352.694812 -272.286658) (xy 352.746774 -272.298518)
			(xy 352.796388 -272.31799) (xy 352.842546 -272.344639) (xy 352.884217 -272.37787) (xy 352.920469 -272.416941)
			(xy 352.950493 -272.460978) (xy 352.973619 -272.508999) (xy 352.989329 -272.559929) (xy 352.997272 -272.612633)
			(xy 352.99777 -272.639282) (xy 352.997272 -272.665931) (xy 353.225852 -272.665931) (xy 353.225852 -272.612633)
			(xy 353.233795 -272.559929) (xy 353.249505 -272.508999) (xy 353.272631 -272.460978) (xy 353.302655 -272.416941)
			(xy 353.338907 -272.37787) (xy 353.380578 -272.344639) (xy 353.426736 -272.31799) (xy 353.47635 -272.298518)
			(xy 353.528312 -272.286658) (xy 353.581462 -272.282675) (xy 353.634612 -272.286658) (xy 353.686574 -272.298518)
			(xy 353.736188 -272.31799) (xy 353.782346 -272.344639) (xy 353.824017 -272.37787) (xy 353.860269 -272.416941)
			(xy 353.890293 -272.460978) (xy 353.913419 -272.508999) (xy 353.929129 -272.559929) (xy 353.937072 -272.612633)
			(xy 353.93757 -272.639282) (xy 353.937072 -272.665931) (xy 354.165652 -272.665931) (xy 354.165652 -272.612633)
			(xy 354.173595 -272.559929) (xy 354.189305 -272.508999) (xy 354.212431 -272.460978) (xy 354.242455 -272.416941)
			(xy 354.278707 -272.37787) (xy 354.320378 -272.344639) (xy 354.366536 -272.31799) (xy 354.41615 -272.298518)
			(xy 354.468112 -272.286658) (xy 354.521262 -272.282675) (xy 354.574412 -272.286658) (xy 354.626374 -272.298518)
			(xy 354.675988 -272.31799) (xy 354.722146 -272.344639) (xy 354.763817 -272.37787) (xy 354.800069 -272.416941)
			(xy 354.830093 -272.460978) (xy 354.853219 -272.508999) (xy 354.868929 -272.559929) (xy 354.876872 -272.612633)
			(xy 354.87737 -272.639282) (xy 354.876872 -272.665931) (xy 355.105452 -272.665931) (xy 355.105452 -272.612633)
			(xy 355.113395 -272.559929) (xy 355.129105 -272.508999) (xy 355.152231 -272.460978) (xy 355.182255 -272.416941)
			(xy 355.218507 -272.37787) (xy 355.260178 -272.344639) (xy 355.306336 -272.31799) (xy 355.35595 -272.298518)
			(xy 355.407912 -272.286658) (xy 355.461062 -272.282675) (xy 355.514212 -272.286658) (xy 355.566174 -272.298518)
			(xy 355.615788 -272.31799) (xy 355.661946 -272.344639) (xy 355.703617 -272.37787) (xy 355.739869 -272.416941)
			(xy 355.769893 -272.460978) (xy 355.793019 -272.508999) (xy 355.808729 -272.559929) (xy 355.816672 -272.612633)
			(xy 355.81717 -272.639282) (xy 355.816672 -272.665931) (xy 355.808729 -272.718635) (xy 355.793019 -272.769565)
			(xy 355.769893 -272.817586) (xy 355.739869 -272.861623) (xy 355.703617 -272.900694) (xy 355.661946 -272.933925)
			(xy 355.615788 -272.960574) (xy 355.566174 -272.980046) (xy 355.514212 -272.991906) (xy 355.461062 -272.99589)
			(xy 355.407912 -272.991906) (xy 355.35595 -272.980046) (xy 355.306336 -272.960574) (xy 355.260178 -272.933925)
			(xy 355.218507 -272.900694) (xy 355.182255 -272.861623) (xy 355.152231 -272.817586) (xy 355.129105 -272.769565)
			(xy 355.113395 -272.718635) (xy 355.105452 -272.665931) (xy 354.876872 -272.665931) (xy 354.868929 -272.718635)
			(xy 354.853219 -272.769565) (xy 354.830093 -272.817586) (xy 354.800069 -272.861623) (xy 354.763817 -272.900694)
			(xy 354.722146 -272.933925) (xy 354.675988 -272.960574) (xy 354.626374 -272.980046) (xy 354.574412 -272.991906)
			(xy 354.521262 -272.99589) (xy 354.468112 -272.991906) (xy 354.41615 -272.980046) (xy 354.366536 -272.960574)
			(xy 354.320378 -272.933925) (xy 354.278707 -272.900694) (xy 354.242455 -272.861623) (xy 354.212431 -272.817586)
			(xy 354.189305 -272.769565) (xy 354.173595 -272.718635) (xy 354.165652 -272.665931) (xy 353.937072 -272.665931)
			(xy 353.929129 -272.718635) (xy 353.913419 -272.769565) (xy 353.890293 -272.817586) (xy 353.860269 -272.861623)
			(xy 353.824017 -272.900694) (xy 353.782346 -272.933925) (xy 353.736188 -272.960574) (xy 353.686574 -272.980046)
			(xy 353.634612 -272.991906) (xy 353.581462 -272.99589) (xy 353.528312 -272.991906) (xy 353.47635 -272.980046)
			(xy 353.426736 -272.960574) (xy 353.380578 -272.933925) (xy 353.338907 -272.900694) (xy 353.302655 -272.861623)
			(xy 353.272631 -272.817586) (xy 353.249505 -272.769565) (xy 353.233795 -272.718635) (xy 353.225852 -272.665931)
			(xy 352.997272 -272.665931) (xy 352.989329 -272.718635) (xy 352.973619 -272.769565) (xy 352.950493 -272.817586)
			(xy 352.920469 -272.861623) (xy 352.884217 -272.900694) (xy 352.842546 -272.933925) (xy 352.796388 -272.960574)
			(xy 352.746774 -272.980046) (xy 352.694812 -272.991906) (xy 352.641662 -272.99589) (xy 352.588512 -272.991906)
			(xy 352.53655 -272.980046) (xy 352.486936 -272.960574) (xy 352.440778 -272.933925) (xy 352.399107 -272.900694)
			(xy 352.362855 -272.861623) (xy 352.332831 -272.817586) (xy 352.309705 -272.769565) (xy 352.293995 -272.718635)
			(xy 352.286052 -272.665931) (xy 352.057472 -272.665931) (xy 352.049529 -272.718635) (xy 352.033819 -272.769565)
			(xy 352.010693 -272.817586) (xy 351.980669 -272.861623) (xy 351.944417 -272.900694) (xy 351.902746 -272.933925)
			(xy 351.856588 -272.960574) (xy 351.806974 -272.980046) (xy 351.755012 -272.991906) (xy 351.701862 -272.99589)
			(xy 351.648712 -272.991906) (xy 351.59675 -272.980046) (xy 351.547136 -272.960574) (xy 351.500978 -272.933925)
			(xy 351.459307 -272.900694) (xy 351.423055 -272.861623) (xy 351.393031 -272.817586) (xy 351.369905 -272.769565)
			(xy 351.354195 -272.718635) (xy 351.346252 -272.665931) (xy 351.117672 -272.665931) (xy 351.109729 -272.718635)
			(xy 351.094019 -272.769565) (xy 351.070893 -272.817586) (xy 351.040869 -272.861623) (xy 351.004617 -272.900694)
			(xy 350.962946 -272.933925) (xy 350.916788 -272.960574) (xy 350.867174 -272.980046) (xy 350.815212 -272.991906)
			(xy 350.762062 -272.99589) (xy 350.708912 -272.991906) (xy 350.65695 -272.980046) (xy 350.607336 -272.960574)
			(xy 350.561178 -272.933925) (xy 350.519507 -272.900694) (xy 350.483255 -272.861623) (xy 350.453231 -272.817586)
			(xy 350.430105 -272.769565) (xy 350.414395 -272.718635) (xy 350.406452 -272.665931) (xy 350.177872 -272.665931)
			(xy 350.169929 -272.718635) (xy 350.154219 -272.769565) (xy 350.131093 -272.817586) (xy 350.101069 -272.861623)
			(xy 350.064817 -272.900694) (xy 350.023146 -272.933925) (xy 349.976988 -272.960574) (xy 349.927374 -272.980046)
			(xy 349.875412 -272.991906) (xy 349.822262 -272.99589) (xy 349.769112 -272.991906) (xy 349.71715 -272.980046)
			(xy 349.667536 -272.960574) (xy 349.621378 -272.933925) (xy 349.579707 -272.900694) (xy 349.543455 -272.861623)
			(xy 349.513431 -272.817586) (xy 349.490305 -272.769565) (xy 349.474595 -272.718635) (xy 349.466652 -272.665931)
			(xy 349.238072 -272.665931) (xy 349.230129 -272.718635) (xy 349.214419 -272.769565) (xy 349.191293 -272.817586)
			(xy 349.161269 -272.861623) (xy 349.125017 -272.900694) (xy 349.083346 -272.933925) (xy 349.037188 -272.960574)
			(xy 348.987574 -272.980046) (xy 348.935612 -272.991906) (xy 348.882462 -272.99589) (xy 348.829312 -272.991906)
			(xy 348.77735 -272.980046) (xy 348.727736 -272.960574) (xy 348.681578 -272.933925) (xy 348.639907 -272.900694)
			(xy 348.603655 -272.861623) (xy 348.573631 -272.817586) (xy 348.550505 -272.769565) (xy 348.534795 -272.718635)
			(xy 348.526852 -272.665931) (xy 348.298272 -272.665931) (xy 348.290329 -272.718635) (xy 348.274619 -272.769565)
			(xy 348.251493 -272.817586) (xy 348.221469 -272.861623) (xy 348.185217 -272.900694) (xy 348.143546 -272.933925)
			(xy 348.097388 -272.960574) (xy 348.047774 -272.980046) (xy 347.995812 -272.991906) (xy 347.942662 -272.99589)
			(xy 347.889512 -272.991906) (xy 347.83755 -272.980046) (xy 347.787936 -272.960574) (xy 347.741778 -272.933925)
			(xy 347.700107 -272.900694) (xy 347.663855 -272.861623) (xy 347.633831 -272.817586) (xy 347.610705 -272.769565)
			(xy 347.594995 -272.718635) (xy 347.587052 -272.665931) (xy 347.358472 -272.665931) (xy 347.350529 -272.718635)
			(xy 347.334819 -272.769565) (xy 347.311693 -272.817586) (xy 347.281669 -272.861623) (xy 347.245417 -272.900694)
			(xy 347.203746 -272.933925) (xy 347.157588 -272.960574) (xy 347.107974 -272.980046) (xy 347.056012 -272.991906)
			(xy 347.002862 -272.99589) (xy 346.949712 -272.991906) (xy 346.89775 -272.980046) (xy 346.848136 -272.960574)
			(xy 346.801978 -272.933925) (xy 346.760307 -272.900694) (xy 346.724055 -272.861623) (xy 346.694031 -272.817586)
			(xy 346.670905 -272.769565) (xy 346.655195 -272.718635) (xy 346.647252 -272.665931) (xy 346.418672 -272.665931)
			(xy 346.410729 -272.718635) (xy 346.395019 -272.769565) (xy 346.371893 -272.817586) (xy 346.341869 -272.861623)
			(xy 346.305617 -272.900694) (xy 346.263946 -272.933925) (xy 346.217788 -272.960574) (xy 346.168174 -272.980046)
			(xy 346.116212 -272.991906) (xy 346.063062 -272.99589) (xy 346.009912 -272.991906) (xy 345.95795 -272.980046)
			(xy 345.908336 -272.960574) (xy 345.862178 -272.933925) (xy 345.820507 -272.900694) (xy 345.784255 -272.861623)
			(xy 345.754231 -272.817586) (xy 345.731105 -272.769565) (xy 345.715395 -272.718635) (xy 345.707452 -272.665931)
			(xy 345.479126 -272.665931) (xy 345.471183 -272.718635) (xy 345.455473 -272.769565) (xy 345.432347 -272.817586)
			(xy 345.402323 -272.861623) (xy 345.366071 -272.900694) (xy 345.3244 -272.933925) (xy 345.278242 -272.960574)
			(xy 345.228628 -272.980046) (xy 345.176666 -272.991906) (xy 345.123516 -272.99589) (xy 345.070366 -272.991906)
			(xy 345.018404 -272.980046) (xy 344.96879 -272.960574) (xy 344.922632 -272.933925) (xy 344.880961 -272.900694)
			(xy 344.844709 -272.861623) (xy 344.814685 -272.817586) (xy 344.791559 -272.769565) (xy 344.775849 -272.718635)
			(xy 344.767906 -272.665931) (xy 344.539072 -272.665931) (xy 344.531129 -272.718635) (xy 344.515419 -272.769565)
			(xy 344.492293 -272.817586) (xy 344.462269 -272.861623) (xy 344.426017 -272.900694) (xy 344.384346 -272.933925)
			(xy 344.338188 -272.960574) (xy 344.288574 -272.980046) (xy 344.236612 -272.991906) (xy 344.183462 -272.99589)
			(xy 344.130312 -272.991906) (xy 344.07835 -272.980046) (xy 344.028736 -272.960574) (xy 343.982578 -272.933925)
			(xy 343.940907 -272.900694) (xy 343.904655 -272.861623) (xy 343.874631 -272.817586) (xy 343.851505 -272.769565)
			(xy 343.835795 -272.718635) (xy 343.827852 -272.665931) (xy 343.599272 -272.665931) (xy 343.591329 -272.718635)
			(xy 343.575619 -272.769565) (xy 343.552493 -272.817586) (xy 343.522469 -272.861623) (xy 343.486217 -272.900694)
			(xy 343.444546 -272.933925) (xy 343.398388 -272.960574) (xy 343.348774 -272.980046) (xy 343.296812 -272.991906)
			(xy 343.243662 -272.99589) (xy 343.190512 -272.991906) (xy 343.13855 -272.980046) (xy 343.088936 -272.960574)
			(xy 343.042778 -272.933925) (xy 343.001107 -272.900694) (xy 342.964855 -272.861623) (xy 342.934831 -272.817586)
			(xy 342.911705 -272.769565) (xy 342.895995 -272.718635) (xy 342.888052 -272.665931) (xy 342.659472 -272.665931)
			(xy 342.651529 -272.718635) (xy 342.635819 -272.769565) (xy 342.612693 -272.817586) (xy 342.582669 -272.861623)
			(xy 342.546417 -272.900694) (xy 342.504746 -272.933925) (xy 342.458588 -272.960574) (xy 342.408974 -272.980046)
			(xy 342.357012 -272.991906) (xy 342.303862 -272.99589) (xy 342.250712 -272.991906) (xy 342.19875 -272.980046)
			(xy 342.149136 -272.960574) (xy 342.102978 -272.933925) (xy 342.061307 -272.900694) (xy 342.025055 -272.861623)
			(xy 341.995031 -272.817586) (xy 341.971905 -272.769565) (xy 341.956195 -272.718635) (xy 341.948252 -272.665931)
			(xy 341.719672 -272.665931) (xy 341.711729 -272.718635) (xy 341.696019 -272.769565) (xy 341.672893 -272.817586)
			(xy 341.642869 -272.861623) (xy 341.606617 -272.900694) (xy 341.564946 -272.933925) (xy 341.518788 -272.960574)
			(xy 341.469174 -272.980046) (xy 341.417212 -272.991906) (xy 341.364062 -272.99589) (xy 341.310912 -272.991906)
			(xy 341.25895 -272.980046) (xy 341.209336 -272.960574) (xy 341.163178 -272.933925) (xy 341.121507 -272.900694)
			(xy 341.085255 -272.861623) (xy 341.055231 -272.817586) (xy 341.032105 -272.769565) (xy 341.016395 -272.718635)
			(xy 341.008452 -272.665931) (xy 340.779685 -272.665931) (xy 340.773041 -272.713296) (xy 340.759374 -272.761042)
			(xy 340.739204 -272.806426) (xy 340.712923 -272.848566) (xy 340.697312 -272.867882) (xy 340.667594 -272.903442)
			(xy 340.861904 -273.097752) (xy 340.883748 -273.097244) (xy 340.894416 -273.09699) (xy 340.927179 -273.097758)
			(xy 340.991596 -273.10977) (xy 341.022432 -273.120866) (xy 341.031068 -273.124168) (xy 341.697564 -273.124168)
		)
		(stroke
			(width 0)
			(type solid)
		)
		(fill yes)
		(layer "In15.Cu")
		(net "PVCCINFAON_CPU0")
	)
)
